(kicad_pcb
	(version 20260206)
	(generator "pcbnew")
	(generator_version "10.0")
	(general
		(thickness 1.6)
		(legacy_teardrops no)
	)
	(paper "A4")
	(layers
		(0 "F.Cu" signal "TOP")
		(4 "In1.Cu" signal "L2GND")
		(6 "In2.Cu" signal "L3")
		(8 "In3.Cu" signal "L4VCC")
		(10 "In4.Cu" signal "L5VCC")
		(12 "In5.Cu" signal "L6")
		(14 "In6.Cu" signal "L7GND")
		(2 "B.Cu" signal "BOTTOM")
		(9 "F.Adhes" user "F.Adhesive")
		(11 "B.Adhes" user "B.Adhesive")
		(13 "F.Paste" user "Package Geometry/Pastemask Top")
		(15 "B.Paste" user "Package Geometry/Pastemask Bottom")
		(5 "F.SilkS" user "Ref Des/Silkscreen Top")
		(7 "B.SilkS" user "Ref Des/Silkscreen Bottom")
		(1 "F.Mask" user "Board Geometry/Soldermask Top")
		(3 "B.Mask" user "Board Geometry/Soldermask Bottom")
		(17 "Dwgs.User" user "User.Drawings")
		(19 "Cmts.User" user "User.Comments")
		(21 "Eco1.User" user "User.Eco1")
		(23 "Eco2.User" user "User.Eco2")
		(25 "Edge.Cuts" user "Board Geometry/Outline")
		(27 "Margin" user)
		(31 "F.CrtYd" user "Package Geometry/Place Bound Top")
		(29 "B.CrtYd" user "Package Geometry/Place Bound Bottom")
		(35 "F.Fab" user "Ref Des/Assembly Top")
		(33 "B.Fab" user "Ref Des/Assembly Bottom")
	)
	(setup
		(pad_to_mask_clearance 0)
		(allow_soldermask_bridges_in_footprints no)
		(tenting
			(front yes)
			(back yes)
		)
		(covering
			(front no)
			(back no)
		)
		(plugging
			(front no)
			(back no)
		)
		(capping no)
		(filling no)
		(pcbplotparams
			(layerselection 0x00000000_00000000_55555555_5755f5ff)
			(plot_on_all_layers_selection 0x00000000_00000000_00000000_00000000)
			(disableapertmacros no)
			(usegerberextensions no)
			(usegerberattributes yes)
			(usegerberadvancedattributes yes)
			(creategerberjobfile yes)
			(dashed_line_dash_ratio 12)
			(dashed_line_gap_ratio 3)
			(svgprecision 4)
			(plotframeref no)
			(mode 1)
			(useauxorigin no)
			(pdf_front_fp_property_popups yes)
			(pdf_back_fp_property_popups yes)
			(pdf_metadata yes)
			(pdf_single_document no)
			(dxfpolygonmode yes)
			(dxfimperialunits yes)
			(dxfusepcbnewfont yes)
			(psnegative no)
			(psa4output no)
			(plot_black_and_white yes)
			(sketchpadsonfab no)
			(plotpadnumbers no)
			(hidednponfab no)
			(sketchdnponfab yes)
			(crossoutdnponfab yes)
			(subtractmaskfromsilk no)
			(outputformat 1)
			(mirror no)
			(drillshape 1)
			(scaleselection 1)
			(outputdirectory "")
		)
	)
	(footprint ""
		(layer "F.Cu")
		(at 289.433 -162.433)
		(property "Reference" "TP140"
			(at 0 0 0)
			(layer "F.SilkS")
			(hide yes)
			(effects
				(font
					(size 1.27 1.27)
				)
			)
		)
		(property "Value" "TPAD28"
			(at 0.0127 -1.8034 0)
			(unlocked yes)
			(layer "F.Fab")
			(hide yes)
			(effects
				(font
					(size 1.016 1.016)
					(thickness 0.1524)
				)
			)
		)
		(property "Device Type" "TPAD28"
			(at 0.0127 -3.3274 0)
			(unlocked yes)
			(layer "F.Fab")
			(hide yes)
			(effects
				(font
					(size 1.016 1.016)
					(thickness 0.1524)
				)
			)
		)
		(duplicate_pad_numbers_are_jumpers no)
		(fp_poly
			(pts
				(arc
					(start 0.3556 0)
					(mid -0.3556 0)
					(end 0.3556 0)
				)
			)
			(stroke
				(width 0)
				(type default)
			)
			(fill no)
			(layer "F.CrtYd")
		)
		(fp_poly
			(pts
				(arc
					(start 0.6096 0)
					(mid -0.6096 0)
					(end 0.6096 0)
				)
			)
			(stroke
				(width 0)
				(type default)
			)
			(fill no)
			(layer "F.Fab")
		)
		(pad "1" smd circle
			(at 0 0)
			(size 0.7112 0.7112)
			(layers "F.Cu" "F.Mask" "F.Paste")
			(net "TP_BMC_GPIOE3")
		)
	)
	(footprint ""
		(layer "F.Cu")
		(at 292.0746 -153.5938 -90)
		(property "Reference" "C232"
			(at 0 0 270)
			(layer "F.SilkS")
			(hide yes)
			(effects
				(font
					(size 1.27 1.27)
				)
			)
		)
		(property "Value" "SC1U6D3V3KX-2GP"
			(at 0 -2.8194 270)
			(unlocked yes)
			(layer "F.Fab")
			(hide yes)
			(effects
				(font
					(size 1.016 1.016)
					(thickness 0.1524)
				)
			)
		)
		(property "Device Type" "C603H36"
			(at 0 -4.3434 270)
			(unlocked yes)
			(layer "F.Fab")
			(hide yes)
			(effects
				(font
					(size 1.016 1.016)
					(thickness 0.1524)
				)
			)
		)
		(duplicate_pad_numbers_are_jumpers no)
		(fp_line
			(start 0.508 0)
			(end -0.508 0)
			(stroke
				(width 0.2032)
				(type default)
			)
			(layer "F.SilkS")
		)
		(fp_rect
			(start -0.5842 1.3335)
			(end 0.5842 -1.3335)
			(stroke
				(width 0)
				(type default)
			)
			(fill no)
			(layer "F.CrtYd")
		)
		(fp_rect
			(start -0.5842 1.3335)
			(end 0.5842 -1.3335)
			(stroke
				(width 0)
				(type default)
			)
			(fill no)
			(layer "F.Fab")
		)
		(pad "1" smd custom
			(at 0 -0.762 270)
			(size 0.2159 0.2159)
			(layers "F.Cu" "F.Mask" "F.Paste")
			(net "P3V3_STBY")
			(options
				(clearance outline)
				(anchor circle)
			)
			(primitives
				(gr_poly
					(pts
						(arc
							(start -0.3302 -0.4318)
							(mid -0.402042 -0.402042)
							(end -0.4318 -0.3302)
						)
						(arc
							(start -0.4318 0.3302)
							(mid -0.402042 0.402042)
							(end -0.3302 0.4318)
						)
						(arc
							(start 0.3302 0.4318)
							(mid 0.402042 0.402042)
							(end 0.4318 0.3302)
						)
						(arc
							(start 0.4318 -0.3302)
							(mid 0.402042 -0.402042)
							(end 0.3302 -0.4318)
						)
					)
					(width 0)
					(fill yes)
				)
			)
		)
		(pad "2" smd custom
			(at 0 0.762 270)
			(size 0.2159 0.2159)
			(layers "F.Cu" "F.Mask" "F.Paste")
			(net "GND")
			(options
				(clearance outline)
				(anchor circle)
			)
			(primitives
				(gr_poly
					(pts
						(arc
							(start -0.3302 -0.4318)
							(mid -0.402042 -0.402042)
							(end -0.4318 -0.3302)
						)
						(arc
							(start -0.4318 0.3302)
							(mid -0.402042 0.402042)
							(end -0.3302 0.4318)
						)
						(arc
							(start 0.3302 0.4318)
							(mid 0.402042 0.402042)
							(end 0.4318 0.3302)
						)
						(arc
							(start 0.4318 -0.3302)
							(mid 0.402042 -0.402042)
							(end 0.3302 -0.4318)
						)
					)
					(width 0)
					(fill yes)
				)
			)
		)
	)
	(footprint ""
		(layer "F.Cu")
		(at 116.586 -76.708)
		(property "Reference" "STP104"
			(at 0 0 0)
			(layer "F.SilkS")
			(hide yes)
			(effects
				(font
					(size 1.27 1.27)
				)
			)
		)
		(property "Value" "TPAD28"
			(at 0.0127 -1.8034 0)
			(unlocked yes)
			(layer "F.Fab")
			(hide yes)
			(effects
				(font
					(size 1.016 1.016)
					(thickness 0.1524)
				)
			)
		)
		(property "Device Type" "TPAD28"
			(at 0.0127 -3.3274 0)
			(unlocked yes)
			(layer "F.Fab")
			(hide yes)
			(effects
				(font
					(size 1.016 1.016)
					(thickness 0.1524)
				)
			)
		)
		(duplicate_pad_numbers_are_jumpers no)
		(fp_poly
			(pts
				(arc
					(start 0.3556 0)
					(mid -0.3556 0)
					(end 0.3556 0)
				)
			)
			(stroke
				(width 0)
				(type default)
			)
			(fill no)
			(layer "F.CrtYd")
		)
		(fp_poly
			(pts
				(arc
					(start 0.6096 0)
					(mid -0.6096 0)
					(end 0.6096 0)
				)
			)
			(stroke
				(width 0)
				(type default)
			)
			(fill no)
			(layer "F.Fab")
		)
		(pad "1" smd circle
			(at 0 0)
			(size 0.7112 0.7112)
			(layers "F.Cu" "F.Mask" "F.Paste")
			(net "TEST_MUX_37")
		)
	)
	(footprint ""
		(layer "F.Cu")
		(at 136.271 -98.806 180)
		(property "Reference" "SC1267"
			(at 0 0 180)
			(layer "F.SilkS")
			(hide yes)
			(effects
				(font
					(size 1.27 1.27)
				)
			)
		)
		(property "Value" "SCD01U10V1KX-GP"
			(at -2.8321 -1.7399 180)
			(unlocked yes)
			(layer "F.Fab")
			(hide yes)
			(effects
				(font
					(size 1.016 1.016)
					(thickness 0.1524)
				)
			)
		)
		(property "Device Type" "C0201H13"
			(at -2.8321 -3.2639 180)
			(unlocked yes)
			(layer "F.Fab")
			(hide yes)
			(effects
				(font
					(size 1.016 1.016)
					(thickness 0.1524)
				)
			)
		)
		(duplicate_pad_numbers_are_jumpers no)
		(fp_rect
			(start -0.2794 0.6477)
			(end 0.2794 -0.6477)
			(stroke
				(width 0)
				(type default)
			)
			(fill no)
			(layer "F.CrtYd")
		)
		(fp_rect
			(start -0.2794 0.6477)
			(end 0.2794 -0.6477)
			(stroke
				(width 0)
				(type default)
			)
			(fill no)
			(layer "F.Fab")
		)
		(pad "1" smd custom
			(at 0 -0.2794 180)
			(size 0.0762 0.0762)
			(layers "F.Cu" "F.Mask" "F.Paste")
			(net "3X24_SAS_TX20_N")
			(options
				(clearance outline)
				(anchor circle)
			)
			(primitives
				(gr_poly
					(pts
						(arc
							(start 0.1524 -0.127)
							(mid 0.137521 -0.162921)
							(end 0.1016 -0.1778)
						)
						(arc
							(start -0.1016 -0.1778)
							(mid -0.137521 -0.162921)
							(end -0.1524 -0.127)
						)
						(arc
							(start -0.1524 0.127)
							(mid -0.137521 0.162921)
							(end -0.1016 0.1778)
						)
						(arc
							(start 0.1016 0.1778)
							(mid 0.137521 0.162921)
							(end 0.1524 0.127)
						)
					)
					(width 0)
					(fill yes)
				)
			)
		)
		(pad "2" smd custom
			(at 0 0.2794 180)
			(size 0.0762 0.0762)
			(layers "F.Cu" "F.Mask" "F.Paste")
			(net "SAS_EXP_GF_TX_DN0")
			(options
				(clearance outline)
				(anchor circle)
			)
			(primitives
				(gr_poly
					(pts
						(arc
							(start 0.1524 -0.127)
							(mid 0.137521 -0.162921)
							(end 0.1016 -0.1778)
						)
						(arc
							(start -0.1016 -0.1778)
							(mid -0.137521 -0.162921)
							(end -0.1524 -0.127)
						)
						(arc
							(start -0.1524 0.127)
							(mid -0.137521 0.162921)
							(end -0.1016 0.1778)
						)
						(arc
							(start 0.1016 0.1778)
							(mid 0.137521 0.162921)
							(end 0.1524 0.127)
						)
					)
					(width 0)
					(fill yes)
				)
			)
		)
	)
	(footprint ""
		(layer "F.Cu")
		(at 152.247092 -100.359464 -90)
		(property "Reference" "SL16"
			(at 0 0 270)
			(layer "F.SilkS")
			(hide yes)
			(effects
				(font
					(size 1.27 1.27)
				)
			)
		)
		(property "Value" "MPZ2012S300AT-GP"
			(at 0 -4.2418 270)
			(unlocked yes)
			(layer "F.Fab")
			(hide yes)
			(effects
				(font
					(size 1.016 1.016)
					(thickness 0.1524)
				)
			)
		)
		(property "Device Type" "L805H42"
			(at 0 -5.7912 270)
			(unlocked yes)
			(layer "F.Fab")
			(hide yes)
			(effects
				(font
					(size 1.016 1.016)
					(thickness 0.1524)
				)
			)
		)
		(duplicate_pad_numbers_are_jumpers no)
		(fp_line
			(start -0.889 1.7018)
			(end -0.889 -1.7018)
			(stroke
				(width 0.1524)
				(type default)
			)
			(layer "F.SilkS")
		)
		(fp_line
			(start 0.889 1.7018)
			(end -0.889 1.7018)
			(stroke
				(width 0.1524)
				(type default)
			)
			(layer "F.SilkS")
		)
		(fp_line
			(start -0.889 -1.7018)
			(end 0.889 -1.7018)
			(stroke
				(width 0.1524)
				(type default)
			)
			(layer "F.SilkS")
		)
		(fp_line
			(start 0.889 -1.7018)
			(end 0.889 1.7018)
			(stroke
				(width 0.1524)
				(type default)
			)
			(layer "F.SilkS")
		)
		(fp_rect
			(start -0.9652 1.778)
			(end 0.9652 -1.778)
			(stroke
				(width 0)
				(type default)
			)
			(fill no)
			(layer "F.CrtYd")
		)
		(fp_rect
			(start -0.9652 1.778)
			(end 0.9652 -1.778)
			(stroke
				(width 0)
				(type default)
			)
			(fill no)
			(layer "F.Fab")
		)
		(pad "1" smd rect
			(at 0 -0.9652 270)
			(size 1.397 1.143)
			(layers "F.Cu" "F.Mask" "F.Paste")
			(net "P0V9_E")
		)
		(pad "2" smd rect
			(at 0 0.9652 270)
			(size 1.397 1.143)
			(layers "F.Cu" "F.Mask" "F.Paste")
			(net "GB_VDDA")
		)
	)
	(footprint ""
		(layer "F.Cu")
		(at 118.364 -34.798)
		(property "Reference" "STP13"
			(at 0 0 0)
			(layer "F.SilkS")
			(hide yes)
			(effects
				(font
					(size 1.27 1.27)
				)
			)
		)
		(property "Value" "TPAD28"
			(at 0.0127 -1.8034 0)
			(unlocked yes)
			(layer "F.Fab")
			(hide yes)
			(effects
				(font
					(size 1.016 1.016)
					(thickness 0.1524)
				)
			)
		)
		(property "Device Type" "TPAD28"
			(at 0.0127 -3.3274 0)
			(unlocked yes)
			(layer "F.Fab")
			(hide yes)
			(effects
				(font
					(size 1.016 1.016)
					(thickness 0.1524)
				)
			)
		)
		(duplicate_pad_numbers_are_jumpers no)
		(fp_poly
			(pts
				(arc
					(start 0.3556 0)
					(mid -0.3556 0)
					(end 0.3556 0)
				)
			)
			(stroke
				(width 0)
				(type default)
			)
			(fill no)
			(layer "F.CrtYd")
		)
		(fp_poly
			(pts
				(arc
					(start 0.6096 0)
					(mid -0.6096 0)
					(end 0.6096 0)
				)
			)
			(stroke
				(width 0)
				(type default)
			)
			(fill no)
			(layer "F.Fab")
		)
		(pad "1" smd circle
			(at 0 0)
			(size 0.7112 0.7112)
			(layers "F.Cu" "F.Mask" "F.Paste")
			(net "IOC_GPIO_31")
		)
	)
	(footprint ""
		(layer "F.Cu")
		(at 79.4766 -14.4018 90)
		(property "Reference" "PC210"
			(at 0 0 90)
			(layer "F.SilkS")
			(hide yes)
			(effects
				(font
					(size 1.27 1.27)
				)
			)
		)
		(property "Value" "SCD01U50V3KX-4GP"
			(at 0 -2.8194 90)
			(unlocked yes)
			(layer "F.Fab")
			(hide yes)
			(effects
				(font
					(size 1.016 1.016)
					(thickness 0.1524)
				)
			)
		)
		(property "Device Type" "C603H36"
			(at 0 -4.3434 90)
			(unlocked yes)
			(layer "F.Fab")
			(hide yes)
			(effects
				(font
					(size 1.016 1.016)
					(thickness 0.1524)
				)
			)
		)
		(duplicate_pad_numbers_are_jumpers no)
		(fp_line
			(start 0.508 0)
			(end -0.508 0)
			(stroke
				(width 0.2032)
				(type default)
			)
			(layer "F.SilkS")
		)
		(fp_rect
			(start -0.5842 1.3335)
			(end 0.5842 -1.3335)
			(stroke
				(width 0)
				(type default)
			)
			(fill no)
			(layer "F.CrtYd")
		)
		(fp_rect
			(start -0.5842 1.3335)
			(end 0.5842 -1.3335)
			(stroke
				(width 0)
				(type default)
			)
			(fill no)
			(layer "F.Fab")
		)
		(pad "1" smd custom
			(at 0 -0.762 90)
			(size 0.2159 0.2159)
			(layers "F.Cu" "F.Mask" "F.Paste")
			(net "VT235_VDDH")
			(options
				(clearance outline)
				(anchor circle)
			)
			(primitives
				(gr_poly
					(pts
						(arc
							(start -0.3302 -0.4318)
							(mid -0.402042 -0.402042)
							(end -0.4318 -0.3302)
						)
						(arc
							(start -0.4318 0.3302)
							(mid -0.402042 0.402042)
							(end -0.3302 0.4318)
						)
						(arc
							(start 0.3302 0.4318)
							(mid 0.402042 0.402042)
							(end 0.4318 0.3302)
						)
						(arc
							(start 0.4318 -0.3302)
							(mid 0.402042 -0.402042)
							(end 0.3302 -0.4318)
						)
					)
					(width 0)
					(fill yes)
				)
			)
		)
		(pad "2" smd custom
			(at 0 0.762 90)
			(size 0.2159 0.2159)
			(layers "F.Cu" "F.Mask" "F.Paste")
			(net "GND")
			(options
				(clearance outline)
				(anchor circle)
			)
			(primitives
				(gr_poly
					(pts
						(arc
							(start -0.3302 -0.4318)
							(mid -0.402042 -0.402042)
							(end -0.4318 -0.3302)
						)
						(arc
							(start -0.4318 0.3302)
							(mid -0.402042 0.402042)
							(end -0.3302 0.4318)
						)
						(arc
							(start 0.3302 0.4318)
							(mid 0.402042 0.402042)
							(end 0.4318 0.3302)
						)
						(arc
							(start 0.4318 -0.3302)
							(mid 0.402042 -0.402042)
							(end 0.3302 -0.4318)
						)
					)
					(width 0)
					(fill yes)
				)
			)
		)
	)
	(footprint ""
		(layer "F.Cu")
		(at 93.345 -221.361)
		(property "Reference" "SC433"
			(at 0 0 0)
			(layer "F.SilkS")
			(hide yes)
			(effects
				(font
					(size 1.27 1.27)
				)
			)
		)
		(property "Value" "SCD1U16V2KX-3GP"
			(at 1.1811 -2.7051 0)
			(unlocked yes)
			(layer "F.Fab")
			(hide yes)
			(effects
				(font
					(size 1.016 1.016)
					(thickness 0.1524)
				)
			)
		)
		(property "Device Type" "C402H22"
			(at 1.1811 -4.2291 0)
			(unlocked yes)
			(layer "F.Fab")
			(hide yes)
			(effects
				(font
					(size 1.016 1.016)
					(thickness 0.1524)
				)
			)
		)
		(duplicate_pad_numbers_are_jumpers no)
		(fp_rect
			(start -0.4318 0.9525)
			(end 0.4318 -0.9525)
			(stroke
				(width 0)
				(type default)
			)
			(fill no)
			(layer "F.CrtYd")
		)
		(fp_rect
			(start -0.4318 0.9525)
			(end 0.4318 -0.9525)
			(stroke
				(width 0)
				(type default)
			)
			(fill no)
			(layer "F.Fab")
		)
		(pad "1" smd custom
			(at 0 -0.4445)
			(size 0.1524 0.1524)
			(layers "F.Cu" "F.Mask" "F.Paste")
			(net "P3V3_STBY")
			(options
				(clearance outline)
				(anchor circle)
			)
			(primitives
				(gr_poly
					(pts
						(arc
							(start 0.3048 -0.2032)
							(mid 0.275042 -0.275042)
							(end 0.2032 -0.3048)
						)
						(arc
							(start -0.2032 -0.3048)
							(mid -0.275042 -0.275042)
							(end -0.3048 -0.2032)
						)
						(arc
							(start -0.3048 0.2032)
							(mid -0.275042 0.275042)
							(end -0.2032 0.3048)
						)
						(arc
							(start 0.2032 0.3048)
							(mid 0.275042 0.275042)
							(end 0.3048 0.2032)
						)
					)
					(width 0)
					(fill yes)
				)
			)
		)
		(pad "2" smd custom
			(at 0 0.4445)
			(size 0.1524 0.1524)
			(layers "F.Cu" "F.Mask" "F.Paste")
			(net "GND")
			(options
				(clearance outline)
				(anchor circle)
			)
			(primitives
				(gr_poly
					(pts
						(arc
							(start 0.3048 -0.2032)
							(mid 0.275042 -0.275042)
							(end 0.2032 -0.3048)
						)
						(arc
							(start -0.2032 -0.3048)
							(mid -0.275042 -0.275042)
							(end -0.3048 -0.2032)
						)
						(arc
							(start -0.3048 0.2032)
							(mid -0.275042 0.275042)
							(end -0.2032 0.3048)
						)
						(arc
							(start 0.2032 0.3048)
							(mid 0.275042 0.275042)
							(end 0.3048 0.2032)
						)
					)
					(width 0)
					(fill yes)
				)
			)
		)
	)
	(footprint ""
		(layer "F.Cu")
		(at 295.7068 -191.8208)
		(property "Reference" "C185"
			(at 0 0 0)
			(layer "F.SilkS")
			(hide yes)
			(effects
				(font
					(size 1.27 1.27)
				)
			)
		)
		(property "Value" "SCD1U16V2KX-3GP"
			(at 1.1811 -2.7051 0)
			(unlocked yes)
			(layer "F.Fab")
			(hide yes)
			(effects
				(font
					(size 1.016 1.016)
					(thickness 0.1524)
				)
			)
		)
		(property "Device Type" "C402H22"
			(at 1.1811 -4.2291 0)
			(unlocked yes)
			(layer "F.Fab")
			(hide yes)
			(effects
				(font
					(size 1.016 1.016)
					(thickness 0.1524)
				)
			)
		)
		(duplicate_pad_numbers_are_jumpers no)
		(fp_rect
			(start -0.4318 0.9525)
			(end 0.4318 -0.9525)
			(stroke
				(width 0)
				(type default)
			)
			(fill no)
			(layer "F.CrtYd")
		)
		(fp_rect
			(start -0.4318 0.9525)
			(end 0.4318 -0.9525)
			(stroke
				(width 0)
				(type default)
			)
			(fill no)
			(layer "F.Fab")
		)
		(pad "1" smd custom
			(at 0 -0.4445)
			(size 0.1524 0.1524)
			(layers "F.Cu" "F.Mask" "F.Paste")
			(net "P1V53_STBY")
			(options
				(clearance outline)
				(anchor circle)
			)
			(primitives
				(gr_poly
					(pts
						(arc
							(start 0.3048 -0.2032)
							(mid 0.275042 -0.275042)
							(end 0.2032 -0.3048)
						)
						(arc
							(start -0.2032 -0.3048)
							(mid -0.275042 -0.275042)
							(end -0.3048 -0.2032)
						)
						(arc
							(start -0.3048 0.2032)
							(mid -0.275042 0.275042)
							(end -0.2032 0.3048)
						)
						(arc
							(start 0.2032 0.3048)
							(mid 0.275042 0.275042)
							(end 0.3048 0.2032)
						)
					)
					(width 0)
					(fill yes)
				)
			)
		)
		(pad "2" smd custom
			(at 0 0.4445)
			(size 0.1524 0.1524)
			(layers "F.Cu" "F.Mask" "F.Paste")
			(net "GND")
			(options
				(clearance outline)
				(anchor circle)
			)
			(primitives
				(gr_poly
					(pts
						(arc
							(start 0.3048 -0.2032)
							(mid 0.275042 -0.275042)
							(end 0.2032 -0.3048)
						)
						(arc
							(start -0.2032 -0.3048)
							(mid -0.275042 -0.275042)
							(end -0.3048 -0.2032)
						)
						(arc
							(start -0.3048 0.2032)
							(mid -0.275042 0.275042)
							(end -0.2032 0.3048)
						)
						(arc
							(start 0.2032 0.3048)
							(mid 0.275042 0.275042)
							(end 0.3048 0.2032)
						)
					)
					(width 0)
					(fill yes)
				)
			)
		)
	)
	(footprint ""
		(layer "F.Cu")
		(at 183.4388 -51.308 -90)
		(property "Reference" "C312"
			(at 0 0 270)
			(layer "F.SilkS")
			(hide yes)
			(effects
				(font
					(size 1.27 1.27)
				)
			)
		)
		(property "Value" "SCD1U25V3KX-GP"
			(at 0 -2.8194 270)
			(unlocked yes)
			(layer "F.Fab")
			(hide yes)
			(effects
				(font
					(size 1.016 1.016)
					(thickness 0.1524)
				)
			)
		)
		(property "Device Type" "C603H36"
			(at 0 -4.3434 270)
			(unlocked yes)
			(layer "F.Fab")
			(hide yes)
			(effects
				(font
					(size 1.016 1.016)
					(thickness 0.1524)
				)
			)
		)
		(duplicate_pad_numbers_are_jumpers no)
		(fp_line
			(start 0.508 0)
			(end -0.508 0)
			(stroke
				(width 0.2032)
				(type default)
			)
			(layer "F.SilkS")
		)
		(fp_rect
			(start -0.5842 1.3335)
			(end 0.5842 -1.3335)
			(stroke
				(width 0)
				(type default)
			)
			(fill no)
			(layer "F.CrtYd")
		)
		(fp_rect
			(start -0.5842 1.3335)
			(end 0.5842 -1.3335)
			(stroke
				(width 0)
				(type default)
			)
			(fill no)
			(layer "F.Fab")
		)
		(pad "1" smd custom
			(at 0 -0.762 270)
			(size 0.2159 0.2159)
			(layers "F.Cu" "F.Mask" "F.Paste")
			(net "PRSNT_AND_2")
			(options
				(clearance outline)
				(anchor circle)
			)
			(primitives
				(gr_poly
					(pts
						(arc
							(start -0.3302 -0.4318)
							(mid -0.402042 -0.402042)
							(end -0.4318 -0.3302)
						)
						(arc
							(start -0.4318 0.3302)
							(mid -0.402042 0.402042)
							(end -0.3302 0.4318)
						)
						(arc
							(start 0.3302 0.4318)
							(mid 0.402042 0.402042)
							(end 0.4318 0.3302)
						)
						(arc
							(start 0.4318 -0.3302)
							(mid 0.402042 -0.402042)
							(end 0.3302 -0.4318)
						)
					)
					(width 0)
					(fill yes)
				)
			)
		)
		(pad "2" smd custom
			(at 0 0.762 270)
			(size 0.2159 0.2159)
			(layers "F.Cu" "F.Mask" "F.Paste")
			(net "GND")
			(options
				(clearance outline)
				(anchor circle)
			)
			(primitives
				(gr_poly
					(pts
						(arc
							(start -0.3302 -0.4318)
							(mid -0.402042 -0.402042)
							(end -0.4318 -0.3302)
						)
						(arc
							(start -0.4318 0.3302)
							(mid -0.402042 0.402042)
							(end -0.3302 0.4318)
						)
						(arc
							(start 0.3302 0.4318)
							(mid 0.402042 0.402042)
							(end 0.4318 0.3302)
						)
						(arc
							(start 0.4318 -0.3302)
							(mid 0.402042 -0.402042)
							(end 0.3302 -0.4318)
						)
					)
					(width 0)
					(fill yes)
				)
			)
		)
	)
	(footprint ""
		(layer "F.Cu")
		(at 274.193 -168.021 90)
		(property "Reference" "R448"
			(at 0 0 90)
			(layer "F.SilkS")
			(hide yes)
			(effects
				(font
					(size 1.27 1.27)
				)
			)
		)
		(property "Value" "10KR2F-2-GP"
			(at 0.064008 -3.993896 90)
			(unlocked yes)
			(layer "F.Fab")
			(hide yes)
			(effects
				(font
					(size 1.016 1.016)
					(thickness 0.1524)
				)
			)
		)
		(property "Device Type" "R402H16"
			(at 0.064008 -5.517896 90)
			(unlocked yes)
			(layer "F.Fab")
			(hide yes)
			(effects
				(font
					(size 1.016 1.016)
					(thickness 0.1524)
				)
			)
		)
		(duplicate_pad_numbers_are_jumpers no)
		(fp_line
			(start 0.508 -0.9398)
			(end -0.508 -0.9398)
			(stroke
				(width 0.1524)
				(type default)
			)
			(layer "F.SilkS")
		)
		(fp_line
			(start -0.508 -0.9398)
			(end -0.508 0.9398)
			(stroke
				(width 0.1524)
				(type default)
			)
			(layer "F.SilkS")
		)
		(fp_rect
			(start -0.508 0.9398)
			(end 0.508 -0.9398)
			(stroke
				(width 0)
				(type default)
			)
			(fill no)
			(layer "F.CrtYd")
		)
		(fp_rect
			(start -0.508 0.9398)
			(end 0.508 -0.9398)
			(stroke
				(width 0)
				(type default)
			)
			(fill no)
			(layer "F.Fab")
		)
		(pad "1" smd custom
			(at 0 -0.4445 90)
			(size 0.1397 0.1397)
			(layers "F.Cu" "F.Mask" "F.Paste")
			(net "P3V3_STBY")
			(options
				(clearance outline)
				(anchor circle)
			)
			(primitives
				(gr_poly
					(pts
						(arc
							(start -0.1778 -0.2794)
							(mid -0.249642 -0.249642)
							(end -0.2794 -0.1778)
						)
						(arc
							(start -0.2794 0.1778)
							(mid -0.249642 0.249642)
							(end -0.1778 0.2794)
						)
						(arc
							(start 0.1778 0.2794)
							(mid 0.249642 0.249642)
							(end 0.2794 0.1778)
						)
						(arc
							(start 0.2794 -0.1778)
							(mid 0.249642 -0.249642)
							(end 0.1778 -0.2794)
						)
					)
					(width 0)
					(fill yes)
				)
			)
		)
		(pad "2" smd custom
			(at 0 0.4445 90)
			(size 0.1397 0.1397)
			(layers "F.Cu" "F.Mask" "F.Paste")
			(net "I2C_BMC_10G_ALERT#")
			(options
				(clearance outline)
				(anchor circle)
			)
			(primitives
				(gr_poly
					(pts
						(arc
							(start -0.1778 -0.2794)
							(mid -0.249642 -0.249642)
							(end -0.2794 -0.1778)
						)
						(arc
							(start -0.2794 0.1778)
							(mid -0.249642 0.249642)
							(end -0.1778 0.2794)
						)
						(arc
							(start 0.1778 0.2794)
							(mid 0.249642 0.249642)
							(end 0.2794 0.1778)
						)
						(arc
							(start 0.2794 -0.1778)
							(mid 0.249642 -0.249642)
							(end 0.1778 -0.2794)
						)
					)
					(width 0)
					(fill yes)
				)
			)
		)
	)
	(footprint ""
		(layer "F.Cu")
		(at 193.802 -116.205)
		(property "Reference" "PR7889"
			(at 0 0 0)
			(layer "F.SilkS")
			(hide yes)
			(effects
				(font
					(size 1.27 1.27)
				)
			)
		)
		(property "Value" "4K75R2F-1-GP"
			(at 0.064008 -3.993896 0)
			(unlocked yes)
			(layer "F.Fab")
			(hide yes)
			(effects
				(font
					(size 1.016 1.016)
					(thickness 0.1524)
				)
			)
		)
		(property "Device Type" "R402H16"
			(at 0.064008 -5.517896 0)
			(unlocked yes)
			(layer "F.Fab")
			(hide yes)
			(effects
				(font
					(size 1.016 1.016)
					(thickness 0.1524)
				)
			)
		)
		(duplicate_pad_numbers_are_jumpers no)
		(fp_line
			(start -0.508 -0.9398)
			(end -0.508 0.9398)
			(stroke
				(width 0.1524)
				(type default)
			)
			(layer "F.SilkS")
		)
		(fp_line
			(start 0.508 -0.9398)
			(end -0.508 -0.9398)
			(stroke
				(width 0.1524)
				(type default)
			)
			(layer "F.SilkS")
		)
		(fp_rect
			(start -0.508 0.9398)
			(end 0.508 -0.9398)
			(stroke
				(width 0)
				(type default)
			)
			(fill no)
			(layer "F.CrtYd")
		)
		(fp_rect
			(start -0.508 0.9398)
			(end 0.508 -0.9398)
			(stroke
				(width 0)
				(type default)
			)
			(fill no)
			(layer "F.Fab")
		)
		(pad "1" smd custom
			(at 0 -0.4445)
			(size 0.1397 0.1397)
			(layers "F.Cu" "F.Mask" "F.Paste")
			(net "P3V3_STBY")
			(options
				(clearance outline)
				(anchor circle)
			)
			(primitives
				(gr_poly
					(pts
						(arc
							(start -0.1778 -0.2794)
							(mid -0.249642 -0.249642)
							(end -0.2794 -0.1778)
						)
						(arc
							(start -0.2794 0.1778)
							(mid -0.249642 0.249642)
							(end -0.1778 0.2794)
						)
						(arc
							(start 0.1778 0.2794)
							(mid 0.249642 0.249642)
							(end 0.2794 0.1778)
						)
						(arc
							(start 0.2794 -0.1778)
							(mid 0.249642 -0.249642)
							(end 0.1778 -0.2794)
						)
					)
					(width 0)
					(fill yes)
				)
			)
		)
		(pad "2" smd custom
			(at 0 0.4445)
			(size 0.1397 0.1397)
			(layers "F.Cu" "F.Mask" "F.Paste")
			(net "P1V5_E_EN_R")
			(options
				(clearance outline)
				(anchor circle)
			)
			(primitives
				(gr_poly
					(pts
						(arc
							(start -0.1778 -0.2794)
							(mid -0.249642 -0.249642)
							(end -0.2794 -0.1778)
						)
						(arc
							(start -0.2794 0.1778)
							(mid -0.249642 0.249642)
							(end -0.1778 0.2794)
						)
						(arc
							(start 0.1778 0.2794)
							(mid 0.249642 0.249642)
							(end 0.2794 0.1778)
						)
						(arc
							(start 0.2794 -0.1778)
							(mid 0.249642 -0.249642)
							(end 0.1778 -0.2794)
						)
					)
					(width 0)
					(fill yes)
				)
			)
		)
	)
	(footprint ""
		(layer "F.Cu")
		(at 32.424116 -76.442062 180)
		(property "Reference" "R673"
			(at 0 0 180)
			(layer "F.SilkS")
			(hide yes)
			(effects
				(font
					(size 1.27 1.27)
				)
			)
		)
		(property "Value" "300R3F-GP"
			(at -0.0254 -2.5146 180)
			(unlocked yes)
			(layer "F.Fab")
			(hide yes)
			(effects
				(font
					(size 1.016 1.016)
					(thickness 0.1524)
				)
			)
		)
		(property "Device Type" "R603H22"
			(at -0.0254 -4.0386 180)
			(unlocked yes)
			(layer "F.Fab")
			(hide yes)
			(effects
				(font
					(size 1.016 1.016)
					(thickness 0.1524)
				)
			)
		)
		(duplicate_pad_numbers_are_jumpers no)
		(fp_line
			(start 0.2032 0)
			(end 0.4826 0)
			(stroke
				(width 0.2032)
				(type default)
			)
			(layer "F.SilkS")
		)
		(fp_line
			(start -0.4826 0)
			(end -0.2032 0)
			(stroke
				(width 0.2032)
				(type default)
			)
			(layer "F.SilkS")
		)
		(fp_rect
			(start -0.5842 1.3335)
			(end 0.5842 -1.3335)
			(stroke
				(width 0)
				(type default)
			)
			(fill no)
			(layer "F.CrtYd")
		)
		(fp_rect
			(start -0.5842 1.3335)
			(end 0.5842 -1.3335)
			(stroke
				(width 0)
				(type default)
			)
			(fill no)
			(layer "F.Fab")
		)
		(pad "1" smd custom
			(at 0 -0.762 180)
			(size 0.2159 0.2159)
			(layers "F.Cu" "F.Mask" "F.Paste")
			(net "P3V3_STBY")
			(options
				(clearance outline)
				(anchor circle)
			)
			(primitives
				(gr_poly
					(pts
						(arc
							(start -0.3302 -0.4318)
							(mid -0.402042 -0.402042)
							(end -0.4318 -0.3302)
						)
						(arc
							(start -0.4318 0.3302)
							(mid -0.402042 0.402042)
							(end -0.3302 0.4318)
						)
						(arc
							(start 0.3302 0.4318)
							(mid 0.402042 0.402042)
							(end 0.4318 0.3302)
						)
						(arc
							(start 0.4318 -0.3302)
							(mid 0.402042 -0.402042)
							(end 0.3302 -0.4318)
						)
					)
					(width 0)
					(fill yes)
				)
			)
		)
		(pad "2" smd custom
			(at 0 0.762 180)
			(size 0.2159 0.2159)
			(layers "F.Cu" "F.Mask" "F.Paste")
			(net "INTA_LED_RED_C")
			(options
				(clearance outline)
				(anchor circle)
			)
			(primitives
				(gr_poly
					(pts
						(arc
							(start -0.3302 -0.4318)
							(mid -0.402042 -0.402042)
							(end -0.4318 -0.3302)
						)
						(arc
							(start -0.4318 0.3302)
							(mid -0.402042 0.402042)
							(end -0.3302 0.4318)
						)
						(arc
							(start 0.3302 0.4318)
							(mid 0.402042 0.402042)
							(end 0.4318 0.3302)
						)
						(arc
							(start 0.4318 -0.3302)
							(mid 0.402042 -0.402042)
							(end 0.3302 -0.4318)
						)
					)
					(width 0)
					(fill yes)
				)
			)
		)
	)
	(footprint ""
		(layer "F.Cu")
		(at 271.999964 -8.279892)
		(property "Reference" "SKT1"
			(at 0 0 0)
			(layer "F.SilkS")
			(hide yes)
			(effects
				(font
					(size 1.27 1.27)
				)
			)
		)
		(property "Value" "SKT-USB-250-GP"
			(at -10.033 -1.3716 0)
			(unlocked yes)
			(layer "F.Fab")
			(hide yes)
			(effects
				(font
					(size 1.016 1.016)
					(thickness 0.1524)
				)
			)
		)
		(property "Device Type" "67643-3911"
			(at -10.033 -2.8956 0)
			(unlocked yes)
			(layer "F.Fab")
			(hide yes)
			(effects
				(font
					(size 1.016 1.016)
					(thickness 0.1524)
				)
			)
		)
		(duplicate_pad_numbers_are_jumpers no)
		(fp_line
			(start -8.1788 -1.4605)
			(end -7.4549 -1.4605)
			(stroke
				(width 0.1524)
				(type default)
			)
			(layer "F.SilkS")
		)
		(fp_line
			(start -8.1788 1.4605)
			(end -8.1788 -1.4605)
			(stroke
				(width 0.1524)
				(type default)
			)
			(layer "F.SilkS")
		)
		(fp_line
			(start -7.4549 -5.2324)
			(end 7.4549 -5.2324)
			(stroke
				(width 0.1524)
				(type default)
			)
			(layer "F.SilkS")
		)
		(fp_line
			(start -7.4549 -1.4605)
			(end -7.4549 -5.2324)
			(stroke
				(width 0.1524)
				(type default)
			)
			(layer "F.SilkS")
		)
		(fp_line
			(start -7.4549 1.4605)
			(end -8.1788 1.4605)
			(stroke
				(width 0.1524)
				(type default)
			)
			(layer "F.SilkS")
		)
		(fp_line
			(start -7.4549 10.279888)
			(end 7.4549 10.279888)
			(stroke
				(width 0.1524)
				(type default)
			)
			(layer "F.SilkS")
		)
		(fp_line
			(start -7.4549 10.541)
			(end -7.4549 1.4605)
			(stroke
				(width 0.1524)
				(type default)
			)
			(layer "F.SilkS")
		)
		(fp_line
			(start 7.4549 -5.2324)
			(end 7.4549 -1.4605)
			(stroke
				(width 0.1524)
				(type default)
			)
			(layer "F.SilkS")
		)
		(fp_line
			(start 7.4549 -1.4605)
			(end 8.1788 -1.4605)
			(stroke
				(width 0.1524)
				(type default)
			)
			(layer "F.SilkS")
		)
		(fp_line
			(start 7.4549 1.4605)
			(end 7.4549 10.541)
			(stroke
				(width 0.1524)
				(type default)
			)
			(layer "F.SilkS")
		)
		(fp_line
			(start 7.4549 10.541)
			(end -7.4549 10.541)
			(stroke
				(width 0.1524)
				(type default)
			)
			(layer "F.SilkS")
		)
		(fp_line
			(start 8.1788 -1.4605)
			(end 8.1788 1.4605)
			(stroke
				(width 0.1524)
				(type default)
			)
			(layer "F.SilkS")
		)
		(fp_line
			(start 8.1788 1.4605)
			(end 7.4549 1.4605)
			(stroke
				(width 0.1524)
				(type default)
			)
			(layer "F.SilkS")
		)
		(fp_arc
			(start 0 -3.000756)
			(mid 2.041429 -2.709926)
			(end 0 -2.419096)
			(stroke
				(width 0.3048)
				(type default)
			)
			(layer "F.SilkS")
		)
		(fp_arc
			(start 0 -2.419096)
			(mid -2.041429 -2.709926)
			(end 0 -3.000756)
			(stroke
				(width 0.3048)
				(type default)
			)
			(layer "F.SilkS")
		)
		(fp_circle
			(center -6.569964 0)
			(end -4.855464 0)
			(stroke
				(width 0.3048)
				(type default)
			)
			(fill no)
			(layer "F.SilkS")
		)
		(fp_circle
			(center -3.50012 -2.709926)
			(end -2.45872 -2.709926)
			(stroke
				(width 0.3048)
				(type default)
			)
			(fill no)
			(layer "F.SilkS")
		)
		(fp_circle
			(center 3.50012 -2.709926)
			(end 4.54152 -2.709926)
			(stroke
				(width 0.3048)
				(type default)
			)
			(fill no)
			(layer "F.SilkS")
		)
		(fp_circle
			(center 6.569964 0)
			(end 8.284464 0)
			(stroke
				(width 0.3048)
				(type default)
			)
			(fill no)
			(layer "F.SilkS")
		)
		(fp_poly
			(pts
				(xy -7.2009 10.287) (xy -7.2009 0.7493) (xy -7.8486 0.7493) (xy -7.8486 -0.7493) (xy -7.2009 -0.7493)
				(xy -7.2009 -4.9784) (xy 7.2009 -4.9784) (xy 7.2009 -0.7493) (xy 7.8486 -0.7493) (xy 7.8486 0.7493)
				(xy 7.2009 0.7493) (xy 7.2009 10.287)
			)
			(stroke
				(width 0)
				(type default)
			)
			(fill no)
			(layer "F.CrtYd")
		)
		(fp_poly
			(pts
				(xy -7.2009 10.287) (xy -7.2009 0.7493) (xy -7.8486 0.7493) (xy -7.8486 -0.7493) (xy -7.2009 -0.7493)
				(xy -7.2009 -4.9784) (xy 7.2009 -4.9784) (xy 7.2009 -4.4323) (xy 7.7089 -4.4323) (xy 7.7089 -5.4864)
				(xy -7.7089 -5.4864) (xy -7.7089 -1.7145) (xy -8.4328 -1.7145) (xy -8.4328 1.7145) (xy -7.7089 1.7145)
				(xy -7.7089 10.795) (xy 7.7089 10.795) (xy 7.7089 1.7145) (xy 8.4328 1.7145) (xy 8.4328 -1.7145)
				(xy 7.7089 -1.7145) (xy 7.7089 -4.4196) (xy 7.2009 -4.4196) (xy 7.2009 -0.7493) (xy 7.8486 -0.7493)
				(xy 7.8486 0.7493) (xy 7.2009 0.7493) (xy 7.2009 10.287)
			)
			(stroke
				(width 0)
				(type default)
			)
			(fill no)
			(layer "F.CrtYd")
		)
		(fp_poly
			(pts
				(xy -7.7089 10.795) (xy -7.7089 1.7145) (xy -8.4328 1.7145) (xy -8.4328 -1.7145) (xy -7.7089 -1.7145)
				(xy -7.7089 -5.4864) (xy 7.7089 -5.4864) (xy 7.7089 -1.7145) (xy 8.4328 -1.7145) (xy 8.4328 1.7145)
				(xy 7.7089 1.7145) (xy 7.7089 10.795)
			)
			(stroke
				(width 0)
				(type default)
			)
			(fill no)
			(layer "F.Fab")
		)
		(pad "1" thru_hole circle
			(at -3.50012 -2.709926)
			(size 1.3716 1.3716)
			(drill 0.9652)
			(layers "*.Cu" "*.Mask")
			(remove_unused_layers no)
			(net "P5V_USB")
			(clearance 0.1524)
			(thermal_gap 0.1524)
		)
		(pad "2" thru_hole circle
			(at -0.999998 -2.709926)
			(size 1.3716 1.3716)
			(drill 0.9652)
			(layers "*.Cu" "*.Mask")
			(remove_unused_layers no)
			(net "USB_P1_F_DN1")
			(clearance 0.1524)
			(thermal_gap 0.1524)
		)
		(pad "3" thru_hole circle
			(at 0.999998 -2.709926)
			(size 1.3716 1.3716)
			(drill 0.9652)
			(layers "*.Cu" "*.Mask")
			(remove_unused_layers no)
			(net "USB_P1_F_DP1")
			(clearance 0.1524)
			(thermal_gap 0.1524)
		)
		(pad "4" thru_hole circle
			(at 3.50012 -2.709926)
			(size 1.3716 1.3716)
			(drill 0.9652)
			(layers "*.Cu" "*.Mask")
			(remove_unused_layers no)
			(net "GND")
			(clearance 0.1524)
			(thermal_gap 0.1524)
		)
		(pad "5" thru_hole circle
			(at 6.569964 0)
			(size 2.7178 2.7178)
			(drill 2.3114)
			(layers "*.Cu" "*.Mask")
			(remove_unused_layers no)
			(net "AGND_USB")
			(clearance 0.1524)
			(thermal_gap 0.1524)
		)
		(pad "6" thru_hole circle
			(at -6.569964 0)
			(size 2.7178 2.7178)
			(drill 2.3114)
			(layers "*.Cu" "*.Mask")
			(remove_unused_layers no)
			(net "AGND_USB")
			(clearance 0.1524)
			(thermal_gap 0.1524)
		)
	)
	(footprint ""
		(layer "F.Cu")
		(at 335.661 -108.458 90)
		(property "Reference" "PR15"
			(at 0 0 90)
			(layer "F.SilkS")
			(hide yes)
			(effects
				(font
					(size 1.27 1.27)
				)
			)
		)
		(property "Value" "3D01R5F-GP"
			(at 0 -8.9535 90)
			(unlocked yes)
			(layer "F.Fab")
			(hide yes)
			(effects
				(font
					(size 1.27 1.016)
					(thickness 0.1524)
				)
			)
		)
		(property "Device Type" "R805H24"
			(at 0 -10.6299 90)
			(unlocked yes)
			(layer "F.Fab")
			(hide yes)
			(effects
				(font
					(size 1.27 1.016)
					(thickness 0.1524)
				)
			)
		)
		(duplicate_pad_numbers_are_jumpers no)
		(fp_line
			(start 0.889 -1.7018)
			(end -0.889 -1.7018)
			(stroke
				(width 0.1524)
				(type default)
			)
			(layer "F.SilkS")
		)
		(fp_line
			(start 0.889 -1.7018)
			(end 0.889 -0.381)
			(stroke
				(width 0.1524)
				(type default)
			)
			(layer "F.SilkS")
		)
		(fp_line
			(start -0.889 -1.7018)
			(end -0.889 0.2794)
			(stroke
				(width 0.1524)
				(type default)
			)
			(layer "F.SilkS")
		)
		(fp_line
			(start -0.889 0.0762)
			(end -0.889 1.7018)
			(stroke
				(width 0.1524)
				(type default)
			)
			(layer "F.SilkS")
		)
		(fp_line
			(start 0.889 1.7018)
			(end 0.889 -0.508)
			(stroke
				(width 0.1524)
				(type default)
			)
			(layer "F.SilkS")
		)
		(fp_line
			(start -0.889 1.7018)
			(end 0.889 1.7018)
			(stroke
				(width 0.1524)
				(type default)
			)
			(layer "F.SilkS")
		)
		(fp_poly
			(pts
				(xy 0.9652 -1.778) (xy 0.9652 1.778) (xy -0.9652 1.778) (xy -0.9652 -1.778)
			)
			(stroke
				(width 0)
				(type default)
			)
			(fill no)
			(layer "F.CrtYd")
		)
		(fp_rect
			(start -0.9652 1.778)
			(end 0.9652 -1.778)
			(stroke
				(width 0)
				(type default)
			)
			(fill no)
			(layer "F.Fab")
		)
		(pad "1" smd rect
			(at 0 -0.9652 90)
			(size 1.397 1.143)
			(layers "F.Cu" "F.Mask" "F.Paste")
			(net "P5V_STBY__SNB")
		)
		(pad "2" smd rect
			(at 0 0.9652 90)
			(size 1.397 1.143)
			(layers "F.Cu" "F.Mask" "F.Paste")
			(net "GND")
		)
	)
	(footprint ""
		(layer "F.Cu")
		(at 188.599318 -138.802872)
		(property "Reference" "SC1109"
			(at 0 0 0)
			(layer "F.SilkS")
			(hide yes)
			(effects
				(font
					(size 1.27 1.27)
				)
			)
		)
		(property "Value" "SCD01U50V2KX-1GP"
			(at 1.1811 -2.7051 0)
			(unlocked yes)
			(layer "F.Fab")
			(hide yes)
			(effects
				(font
					(size 1.016 1.016)
					(thickness 0.1524)
				)
			)
		)
		(property "Device Type" "C402H22"
			(at 1.1811 -4.2291 0)
			(unlocked yes)
			(layer "F.Fab")
			(hide yes)
			(effects
				(font
					(size 1.016 1.016)
					(thickness 0.1524)
				)
			)
		)
		(duplicate_pad_numbers_are_jumpers no)
		(fp_rect
			(start -0.4318 0.9525)
			(end 0.4318 -0.9525)
			(stroke
				(width 0)
				(type default)
			)
			(fill no)
			(layer "F.CrtYd")
		)
		(fp_rect
			(start -0.4318 0.9525)
			(end 0.4318 -0.9525)
			(stroke
				(width 0)
				(type default)
			)
			(fill no)
			(layer "F.Fab")
		)
		(pad "1" smd custom
			(at 0 -0.4445)
			(size 0.1524 0.1524)
			(layers "F.Cu" "F.Mask" "F.Paste")
			(net "P1V8_E")
			(options
				(clearance outline)
				(anchor circle)
			)
			(primitives
				(gr_poly
					(pts
						(arc
							(start 0.3048 -0.2032)
							(mid 0.275042 -0.275042)
							(end 0.2032 -0.3048)
						)
						(arc
							(start -0.2032 -0.3048)
							(mid -0.275042 -0.275042)
							(end -0.3048 -0.2032)
						)
						(arc
							(start -0.3048 0.2032)
							(mid -0.275042 0.275042)
							(end -0.2032 0.3048)
						)
						(arc
							(start 0.2032 0.3048)
							(mid 0.275042 0.275042)
							(end 0.3048 0.2032)
						)
					)
					(width 0)
					(fill yes)
				)
			)
		)
		(pad "2" smd custom
			(at 0 0.4445)
			(size 0.1524 0.1524)
			(layers "F.Cu" "F.Mask" "F.Paste")
			(net "GND")
			(options
				(clearance outline)
				(anchor circle)
			)
			(primitives
				(gr_poly
					(pts
						(arc
							(start 0.3048 -0.2032)
							(mid 0.275042 -0.275042)
							(end 0.2032 -0.3048)
						)
						(arc
							(start -0.2032 -0.3048)
							(mid -0.275042 -0.275042)
							(end -0.3048 -0.2032)
						)
						(arc
							(start -0.3048 0.2032)
							(mid -0.275042 0.275042)
							(end -0.2032 0.3048)
						)
						(arc
							(start 0.2032 0.3048)
							(mid 0.275042 0.275042)
							(end 0.3048 0.2032)
						)
					)
					(width 0)
					(fill yes)
				)
			)
		)
	)
	(footprint ""
		(layer "F.Cu")
		(at 330.191872 -167.585136)
		(property "Reference" "R312"
			(at 0 0 0)
			(layer "F.SilkS")
			(hide yes)
			(effects
				(font
					(size 1.27 1.27)
				)
			)
		)
		(property "Value" "0R2J-2-GP"
			(at 0.064008 -3.993896 0)
			(unlocked yes)
			(layer "F.Fab")
			(hide yes)
			(effects
				(font
					(size 1.016 1.016)
					(thickness 0.1524)
				)
			)
		)
		(property "Device Type" "R402H16"
			(at 0.064008 -5.517896 0)
			(unlocked yes)
			(layer "F.Fab")
			(hide yes)
			(effects
				(font
					(size 1.016 1.016)
					(thickness 0.1524)
				)
			)
		)
		(duplicate_pad_numbers_are_jumpers no)
		(fp_line
			(start -0.508 -0.9398)
			(end -0.508 0.9398)
			(stroke
				(width 0.1524)
				(type default)
			)
			(layer "F.SilkS")
		)
		(fp_line
			(start 0.508 -0.9398)
			(end -0.508 -0.9398)
			(stroke
				(width 0.1524)
				(type default)
			)
			(layer "F.SilkS")
		)
		(fp_rect
			(start -0.508 0.9398)
			(end 0.508 -0.9398)
			(stroke
				(width 0)
				(type default)
			)
			(fill no)
			(layer "F.CrtYd")
		)
		(fp_rect
			(start -0.508 0.9398)
			(end 0.508 -0.9398)
			(stroke
				(width 0)
				(type default)
			)
			(fill no)
			(layer "F.Fab")
		)
		(pad "1" smd custom
			(at 0 -0.4445)
			(size 0.1397 0.1397)
			(layers "F.Cu" "F.Mask" "F.Paste")
			(net "CPU_S_TXD")
			(options
				(clearance outline)
				(anchor circle)
			)
			(primitives
				(gr_poly
					(pts
						(arc
							(start -0.1778 -0.2794)
							(mid -0.249642 -0.249642)
							(end -0.2794 -0.1778)
						)
						(arc
							(start -0.2794 0.1778)
							(mid -0.249642 0.249642)
							(end -0.1778 0.2794)
						)
						(arc
							(start 0.1778 0.2794)
							(mid 0.249642 0.249642)
							(end 0.2794 0.1778)
						)
						(arc
							(start 0.2794 -0.1778)
							(mid 0.249642 -0.249642)
							(end 0.1778 -0.2794)
						)
					)
					(width 0)
					(fill yes)
				)
			)
		)
		(pad "2" smd custom
			(at 0 0.4445)
			(size 0.1397 0.1397)
			(layers "F.Cu" "F.Mask" "F.Paste")
			(net "CPU_UART_TX_R")
			(options
				(clearance outline)
				(anchor circle)
			)
			(primitives
				(gr_poly
					(pts
						(arc
							(start -0.1778 -0.2794)
							(mid -0.249642 -0.249642)
							(end -0.2794 -0.1778)
						)
						(arc
							(start -0.2794 0.1778)
							(mid -0.249642 0.249642)
							(end -0.1778 0.2794)
						)
						(arc
							(start 0.1778 0.2794)
							(mid 0.249642 0.249642)
							(end 0.2794 0.1778)
						)
						(arc
							(start 0.2794 -0.1778)
							(mid 0.249642 -0.249642)
							(end 0.1778 -0.2794)
						)
					)
					(width 0)
					(fill yes)
				)
			)
		)
	)
	(footprint ""
		(layer "F.Cu")
		(at 220.218 -110.363)
		(property "Reference" "PR126"
			(at 0 0 0)
			(layer "F.SilkS")
			(hide yes)
			(effects
				(font
					(size 1.27 1.27)
				)
			)
		)
		(property "Value" "0R2J-2-GP"
			(at 0.064008 -3.993896 0)
			(unlocked yes)
			(layer "F.Fab")
			(hide yes)
			(effects
				(font
					(size 1.016 1.016)
					(thickness 0.1524)
				)
			)
		)
		(property "Device Type" "R402H16"
			(at 0.064008 -5.517896 0)
			(unlocked yes)
			(layer "F.Fab")
			(hide yes)
			(effects
				(font
					(size 1.016 1.016)
					(thickness 0.1524)
				)
			)
		)
		(duplicate_pad_numbers_are_jumpers no)
		(fp_line
			(start -0.508 -0.9398)
			(end -0.508 0.9398)
			(stroke
				(width 0.1524)
				(type default)
			)
			(layer "F.SilkS")
		)
		(fp_line
			(start 0.508 -0.9398)
			(end -0.508 -0.9398)
			(stroke
				(width 0.1524)
				(type default)
			)
			(layer "F.SilkS")
		)
		(fp_rect
			(start -0.508 0.9398)
			(end 0.508 -0.9398)
			(stroke
				(width 0)
				(type default)
			)
			(fill no)
			(layer "F.CrtYd")
		)
		(fp_rect
			(start -0.508 0.9398)
			(end 0.508 -0.9398)
			(stroke
				(width 0)
				(type default)
			)
			(fill no)
			(layer "F.Fab")
		)
		(pad "1" smd custom
			(at 0 -0.4445)
			(size 0.1397 0.1397)
			(layers "F.Cu" "F.Mask" "F.Paste")
			(net "P1V8_C_PG")
			(options
				(clearance outline)
				(anchor circle)
			)
			(primitives
				(gr_poly
					(pts
						(arc
							(start -0.1778 -0.2794)
							(mid -0.249642 -0.249642)
							(end -0.2794 -0.1778)
						)
						(arc
							(start -0.2794 0.1778)
							(mid -0.249642 0.249642)
							(end -0.1778 0.2794)
						)
						(arc
							(start 0.1778 0.2794)
							(mid 0.249642 0.249642)
							(end 0.2794 0.1778)
						)
						(arc
							(start 0.2794 -0.1778)
							(mid 0.249642 -0.249642)
							(end 0.1778 -0.2794)
						)
					)
					(width 0)
					(fill yes)
				)
			)
		)
		(pad "2" smd custom
			(at 0 0.4445)
			(size 0.1397 0.1397)
			(layers "F.Cu" "F.Mask" "F.Paste")
			(net "TPS74801_1V5_C_EN")
			(options
				(clearance outline)
				(anchor circle)
			)
			(primitives
				(gr_poly
					(pts
						(arc
							(start -0.1778 -0.2794)
							(mid -0.249642 -0.249642)
							(end -0.2794 -0.1778)
						)
						(arc
							(start -0.2794 0.1778)
							(mid -0.249642 0.249642)
							(end -0.1778 0.2794)
						)
						(arc
							(start 0.1778 0.2794)
							(mid 0.249642 0.249642)
							(end 0.2794 0.1778)
						)
						(arc
							(start 0.2794 -0.1778)
							(mid 0.249642 -0.249642)
							(end 0.1778 -0.2794)
						)
					)
					(width 0)
					(fill yes)
				)
			)
		)
	)
	(footprint ""
		(layer "F.Cu")
		(at 316.401958 -65.913 90)
		(property "Reference" "R225"
			(at 0 0 90)
			(layer "F.SilkS")
			(hide yes)
			(effects
				(font
					(size 1.27 1.27)
				)
			)
		)
		(property "Value" "0R2J-2-GP"
			(at 0.064008 -3.993896 90)
			(unlocked yes)
			(layer "F.Fab")
			(hide yes)
			(effects
				(font
					(size 1.016 1.016)
					(thickness 0.1524)
				)
			)
		)
		(property "Device Type" "R402H16"
			(at 0.064008 -5.517896 90)
			(unlocked yes)
			(layer "F.Fab")
			(hide yes)
			(effects
				(font
					(size 1.016 1.016)
					(thickness 0.1524)
				)
			)
		)
		(duplicate_pad_numbers_are_jumpers no)
		(fp_line
			(start 0.508 -0.9398)
			(end -0.508 -0.9398)
			(stroke
				(width 0.1524)
				(type default)
			)
			(layer "F.SilkS")
		)
		(fp_line
			(start -0.508 -0.9398)
			(end -0.508 0.9398)
			(stroke
				(width 0.1524)
				(type default)
			)
			(layer "F.SilkS")
		)
		(fp_rect
			(start -0.508 0.9398)
			(end 0.508 -0.9398)
			(stroke
				(width 0)
				(type default)
			)
			(fill no)
			(layer "F.CrtYd")
		)
		(fp_rect
			(start -0.508 0.9398)
			(end 0.508 -0.9398)
			(stroke
				(width 0)
				(type default)
			)
			(fill no)
			(layer "F.Fab")
		)
		(pad "1" smd custom
			(at 0 -0.4445 90)
			(size 0.1397 0.1397)
			(layers "F.Cu" "F.Mask" "F.Paste")
			(net "NCSI_10G_RXD1_R")
			(options
				(clearance outline)
				(anchor circle)
			)
			(primitives
				(gr_poly
					(pts
						(arc
							(start -0.1778 -0.2794)
							(mid -0.249642 -0.249642)
							(end -0.2794 -0.1778)
						)
						(arc
							(start -0.2794 0.1778)
							(mid -0.249642 0.249642)
							(end -0.1778 0.2794)
						)
						(arc
							(start 0.1778 0.2794)
							(mid 0.249642 0.249642)
							(end 0.2794 0.1778)
						)
						(arc
							(start 0.2794 -0.1778)
							(mid 0.249642 -0.249642)
							(end 0.1778 -0.2794)
						)
					)
					(width 0)
					(fill yes)
				)
			)
		)
		(pad "2" smd custom
			(at 0 0.4445 90)
			(size 0.1397 0.1397)
			(layers "F.Cu" "F.Mask" "F.Paste")
			(net "NCSI_10G_RXD1")
			(options
				(clearance outline)
				(anchor circle)
			)
			(primitives
				(gr_poly
					(pts
						(arc
							(start -0.1778 -0.2794)
							(mid -0.249642 -0.249642)
							(end -0.2794 -0.1778)
						)
						(arc
							(start -0.2794 0.1778)
							(mid -0.249642 0.249642)
							(end -0.1778 0.2794)
						)
						(arc
							(start 0.1778 0.2794)
							(mid 0.249642 0.249642)
							(end 0.2794 0.1778)
						)
						(arc
							(start 0.2794 -0.1778)
							(mid 0.249642 -0.249642)
							(end 0.1778 -0.2794)
						)
					)
					(width 0)
					(fill yes)
				)
			)
		)
	)
	(footprint ""
		(layer "F.Cu")
		(at 82.41919 -62.832488 180)
		(property "Reference" "SL2"
			(at 0 0 180)
			(layer "F.SilkS")
			(hide yes)
			(effects
				(font
					(size 1.27 1.27)
				)
			)
		)
		(property "Value" "MPZ2012S601AT-GP"
			(at 0 -4.2418 180)
			(unlocked yes)
			(layer "F.Fab")
			(hide yes)
			(effects
				(font
					(size 1.016 1.016)
					(thickness 0.1524)
				)
			)
		)
		(property "Device Type" "L805H42"
			(at 0 -5.7912 180)
			(unlocked yes)
			(layer "F.Fab")
			(hide yes)
			(effects
				(font
					(size 1.016 1.016)
					(thickness 0.1524)
				)
			)
		)
		(duplicate_pad_numbers_are_jumpers no)
		(fp_line
			(start 0.889 1.7018)
			(end -0.889 1.7018)
			(stroke
				(width 0.1524)
				(type default)
			)
			(layer "F.SilkS")
		)
		(fp_line
			(start 0.889 -1.7018)
			(end 0.889 1.7018)
			(stroke
				(width 0.1524)
				(type default)
			)
			(layer "F.SilkS")
		)
		(fp_line
			(start -0.889 1.7018)
			(end -0.889 -1.7018)
			(stroke
				(width 0.1524)
				(type default)
			)
			(layer "F.SilkS")
		)
		(fp_line
			(start -0.889 -1.7018)
			(end 0.889 -1.7018)
			(stroke
				(width 0.1524)
				(type default)
			)
			(layer "F.SilkS")
		)
		(fp_rect
			(start -0.9652 1.778)
			(end 0.9652 -1.778)
			(stroke
				(width 0)
				(type default)
			)
			(fill no)
			(layer "F.CrtYd")
		)
		(fp_rect
			(start -0.9652 1.778)
			(end 0.9652 -1.778)
			(stroke
				(width 0)
				(type default)
			)
			(fill no)
			(layer "F.Fab")
		)
		(pad "1" smd rect
			(at 0 -0.9652 180)
			(size 1.397 1.143)
			(layers "F.Cu" "F.Mask" "F.Paste")
			(net "SYS_PLL_VDD")
		)
		(pad "2" smd rect
			(at 0 0.9652 180)
			(size 1.397 1.143)
			(layers "F.Cu" "F.Mask" "F.Paste")
			(net "P1V8_C")
		)
	)
	(footprint ""
		(layer "F.Cu")
		(at 190.300102 -258.59994 180)
		(property "Reference" "GF7"
			(at 0 0 180)
			(layer "F.SilkS")
			(hide yes)
			(effects
				(font
					(size 1.27 1.27)
				)
			)
		)
		(property "Value" "GF-PCIE-36P-GP"
			(at -5.118354 -8.09879 180)
			(unlocked yes)
			(layer "F.Fab")
			(hide yes)
			(effects
				(font
					(size 1.016 1.016)
					(thickness 0.1524)
				)
			)
		)
		(property "Device Type" "GF-PCIE-36P"
			(at -5.118354 -9.62279 180)
			(unlocked yes)
			(layer "F.Fab")
			(hide yes)
			(effects
				(font
					(size 1.016 1.016)
					(thickness 0.1524)
				)
			)
		)
		(duplicate_pad_numbers_are_jumpers no)
		(fp_rect
			(start -13.8811 2.032)
			(end 9.8933 -6.223)
			(stroke
				(width 0)
				(type default)
			)
			(fill no)
			(layer "B.CrtYd")
		)
		(fp_rect
			(start -13.8811 2.032)
			(end 9.8933 -6.223)
			(stroke
				(width 0)
				(type default)
			)
			(fill no)
			(layer "F.CrtYd")
		)
		(fp_rect
			(start -13.8811 2.032)
			(end 9.8933 -6.223)
			(stroke
				(width 0)
				(type default)
			)
			(fill no)
			(layer "B.Fab")
		)
		(fp_rect
			(start -13.8811 2.032)
			(end 9.8933 -6.223)
			(stroke
				(width 0)
				(type default)
			)
			(fill no)
			(layer "F.Fab")
		)
		(fp_text user "02 Do not mirror"
			(at -10.94613 2.91084 180)
			(unlocked yes)
			(layer "F.Fab")
			(effects
				(font
					(size 1.016 1.016)
					(thickness 0.1524)
				)
				(justify left)
			)
		)
		(pad "A1" smd rect
			(at -11.49985 -2.0955 180)
			(size 0.7112 3.2004)
			(drill
				(offset 0 -0.4953)
			)
			(layers "F.Cu" "F.Mask" "F.Paste")
			(net "PCIE_MATED#_B")
		)
		(pad "A2" smd rect
			(at -10.50036 -2.0955 180)
			(size 0.7112 4.191)
			(layers "F.Cu" "F.Mask" "F.Paste")
			(net "P12V_PCIE")
		)
		(pad "A3" smd rect
			(at -9.4996 -2.0955 180)
			(size 0.7112 4.191)
			(layers "F.Cu" "F.Mask" "F.Paste")
			(net "P12V_PCIE")
		)
		(pad "A4" smd rect
			(at -8.50011 -2.0955 180)
			(size 0.7112 4.191)
			(layers "F.Cu" "F.Mask" "F.Paste")
			(net "P12V_PCIE")
		)
		(pad "A5" smd rect
			(at -7.49935 -2.0955 180)
			(size 0.7112 4.191)
			(layers "F.Cu" "F.Mask" "F.Paste")
			(net "P12V_PCIE")
		)
		(pad "A6" smd rect
			(at -6.49986 -2.0955 180)
			(size 0.7112 4.191)
			(layers "F.Cu" "F.Mask" "F.Paste")
			(net "P12V_PCIE")
		)
		(pad "A7" smd rect
			(at -5.50037 -2.0955 180)
			(size 0.7112 4.191)
			(layers "F.Cu" "F.Mask" "F.Paste")
			(net "P12V_PCIE")
		)
		(pad "A8" smd rect
			(at -4.49961 -2.0955 180)
			(size 0.7112 4.191)
			(layers "F.Cu" "F.Mask" "F.Paste")
			(net "P12V_PCIE")
		)
		(pad "A9" smd rect
			(at -3.50012 -2.0955 180)
			(size 0.7112 4.191)
			(layers "F.Cu" "F.Mask" "F.Paste")
			(net "Net_208")
		)
		(pad "A10" smd rect
			(at -2.49936 -2.0955 180)
			(size 0.7112 4.191)
			(layers "F.Cu" "F.Mask" "F.Paste")
			(net "Net_209")
		)
		(pad "A11" smd rect
			(at -1.49987 -2.0955 180)
			(size 0.7112 4.191)
			(layers "F.Cu" "F.Mask" "F.Paste")
			(net "Net_210")
		)
		(pad "A12" smd rect
			(at 1.49987 -2.0955 180)
			(size 0.7112 4.191)
			(layers "F.Cu" "F.Mask" "F.Paste")
			(net "Net_196")
		)
		(pad "A13" smd rect
			(at 2.50063 -2.0955 180)
			(size 0.7112 4.191)
			(layers "F.Cu" "F.Mask" "F.Paste")
			(net "GND")
		)
		(pad "A14" smd rect
			(at 3.50012 -2.0955 180)
			(size 0.7112 4.191)
			(layers "F.Cu" "F.Mask" "F.Paste")
			(net "Net_197")
		)
		(pad "A15" smd rect
			(at 4.49961 -2.0955 180)
			(size 0.7112 4.191)
			(layers "F.Cu" "F.Mask" "F.Paste")
			(net "Net_198")
		)
		(pad "A16" smd rect
			(at 5.50037 -2.0955 180)
			(size 0.7112 4.191)
			(layers "F.Cu" "F.Mask" "F.Paste")
			(net "GND")
		)
		(pad "A17" smd rect
			(at 6.49986 -2.0955 180)
			(size 0.7112 4.191)
			(layers "F.Cu" "F.Mask" "F.Paste")
			(net "Net_199")
		)
		(pad "A18" smd rect
			(at 7.50062 -2.0955 180)
			(size 0.7112 4.191)
			(layers "F.Cu" "F.Mask" "F.Paste")
			(net "GND")
		)
		(pad "B1" smd rect
			(at -11.49985 -2.3495 180)
			(size 0.7112 4.191)
			(drill
				(offset 0 0.254)
			)
			(layers "F.Cu" "F.Mask" "F.Paste")
			(net "GND")
		)
		(pad "B2" smd rect
			(at -10.50036 -2.3495 180)
			(size 0.7112 4.191)
			(drill
				(offset 0 0.254)
			)
			(layers "F.Cu" "F.Mask" "F.Paste")
			(net "GND")
		)
		(pad "B3" smd rect
			(at -9.4996 -2.3495 180)
			(size 0.7112 4.191)
			(drill
				(offset 0 0.254)
			)
			(layers "F.Cu" "F.Mask" "F.Paste")
			(net "GND")
		)
		(pad "B4" smd rect
			(at -8.50011 -2.3495 180)
			(size 0.7112 4.191)
			(drill
				(offset 0 0.254)
			)
			(layers "F.Cu" "F.Mask" "F.Paste")
			(net "GND")
		)
		(pad "B5" smd rect
			(at -7.49935 -2.3495 180)
			(size 0.7112 4.191)
			(drill
				(offset 0 0.254)
			)
			(layers "F.Cu" "F.Mask" "F.Paste")
			(net "GND")
		)
		(pad "B6" smd rect
			(at -6.49986 -2.3495 180)
			(size 0.7112 4.191)
			(drill
				(offset 0 0.254)
			)
			(layers "F.Cu" "F.Mask" "F.Paste")
			(net "GND")
		)
		(pad "B7" smd rect
			(at -5.50037 -2.3495 180)
			(size 0.7112 4.191)
			(drill
				(offset 0 0.254)
			)
			(layers "F.Cu" "F.Mask" "F.Paste")
			(net "GND")
		)
		(pad "B8" smd rect
			(at -4.49961 -2.3495 180)
			(size 0.7112 4.191)
			(drill
				(offset 0 0.254)
			)
			(layers "F.Cu" "F.Mask" "F.Paste")
			(net "Net_205")
		)
		(pad "B9" smd rect
			(at -3.50012 -2.3495 180)
			(size 0.7112 4.191)
			(drill
				(offset 0 0.254)
			)
			(layers "F.Cu" "F.Mask" "F.Paste")
			(net "Net_206")
		)
		(pad "B10" smd rect
			(at -2.49936 -2.3495 180)
			(size 0.7112 4.191)
			(drill
				(offset 0 0.254)
			)
			(layers "F.Cu" "F.Mask" "F.Paste")
			(net "Net_207")
		)
		(pad "B11" smd rect
			(at -1.49987 -2.3495 180)
			(size 0.7112 4.191)
			(drill
				(offset 0 0.254)
			)
			(layers "F.Cu" "F.Mask" "F.Paste")
			(net "Net_204")
		)
		(pad "B12" smd rect
			(at 1.49987 -2.3495 180)
			(size 0.7112 4.191)
			(drill
				(offset 0 0.254)
			)
			(layers "F.Cu" "F.Mask" "F.Paste")
			(net "GND")
		)
		(pad "B13" smd rect
			(at 2.50063 -2.3495 180)
			(size 0.7112 4.191)
			(drill
				(offset 0 0.254)
			)
			(layers "F.Cu" "F.Mask" "F.Paste")
			(net "Net_200")
		)
		(pad "B14" smd rect
			(at 3.50012 -2.3495 180)
			(size 0.7112 4.191)
			(drill
				(offset 0 0.254)
			)
			(layers "F.Cu" "F.Mask" "F.Paste")
			(net "Net_201")
		)
		(pad "B15" smd rect
			(at 4.49961 -2.3495 180)
			(size 0.7112 4.191)
			(drill
				(offset 0 0.254)
			)
			(layers "F.Cu" "F.Mask" "F.Paste")
			(net "GND")
		)
		(pad "B16" smd rect
			(at 5.50037 -2.3495 180)
			(size 0.7112 4.191)
			(drill
				(offset 0 0.254)
			)
			(layers "F.Cu" "F.Mask" "F.Paste")
			(net "Net_202")
		)
		(pad "B17" smd rect
			(at 6.49986 -2.3495 180)
			(size 0.7112 3.2004)
			(drill
				(offset 0 -0.2413)
			)
			(layers "F.Cu" "F.Mask" "F.Paste")
			(net "Net_203")
		)
		(pad "B18" smd rect
			(at 7.50062 -2.3495 180)
			(size 0.7112 4.191)
			(drill
				(offset 0 0.254)
			)
			(layers "F.Cu" "F.Mask" "F.Paste")
			(net "GND")
		)
		(zone
			(layer "F.Cu")
			(hatch none 0.5)
			(connect_pads
				(clearance 0)
			)
			(min_thickness 0.25)
			(keepout
				(tracks allowed)
				(vias not_allowed)
				(pads allowed)
				(copperpour not_allowed)
				(footprints allowed)
			)
			(placement
				(enabled no)
				(sheetname "")
			)
			(fill
				(thermal_gap 0.5)
				(thermal_bridge_width 0.5)
				(island_removal_mode 0)
			)
			(polygon
				(pts
					(xy 203.170282 -259.61594) (xy 181.427882 -259.61594) (xy 181.427882 -253.39294) (xy 203.170282 -253.39294)
				)
			)
		)
		(zone
			(layer "F.Cu")
			(hatch none 0.5)
			(connect_pads
				(clearance 0)
			)
			(min_thickness 0.25)
			(keepout
				(tracks not_allowed)
				(vias allowed)
				(pads allowed)
				(copperpour not_allowed)
				(footprints allowed)
			)
			(placement
				(enabled no)
				(sheetname "")
			)
			(fill
				(thermal_gap 0.5)
				(thermal_bridge_width 0.5)
				(island_removal_mode 0)
			)
			(polygon
				(pts
					(xy 203.170282 -258.59994) (xy 203.170282 -259.61594) (xy 181.427882 -259.61594) (xy 181.427882 -258.59994)
				)
			)
		)
		(zone
			(layer "B.Cu")
			(hatch none 0.5)
			(connect_pads
				(clearance 0)
			)
			(min_thickness 0.25)
			(keepout
				(tracks not_allowed)
				(vias allowed)
				(pads allowed)
				(copperpour not_allowed)
				(footprints allowed)
			)
			(placement
				(enabled no)
				(sheetname "")
			)
			(fill
				(thermal_gap 0.5)
				(thermal_bridge_width 0.5)
				(island_removal_mode 0)
			)
			(polygon
				(pts
					(xy 203.170282 -259.61594) (xy 181.427882 -259.61594) (xy 181.427882 -258.59994) (xy 203.170282 -258.59994)
				)
			)
		)
		(zone
			(layer "B.Cu")
			(hatch none 0.5)
			(connect_pads
				(clearance 0)
			)
			(min_thickness 0.25)
			(keepout
				(tracks allowed)
				(vias not_allowed)
				(pads allowed)
				(copperpour not_allowed)
				(footprints allowed)
			)
			(placement
				(enabled no)
				(sheetname "")
			)
			(fill
				(thermal_gap 0.5)
				(thermal_bridge_width 0.5)
				(island_removal_mode 0)
			)
			(polygon
				(pts
					(xy 203.170282 -259.61594) (xy 181.427882 -259.61594) (xy 181.427882 -253.39294) (xy 203.170282 -253.39294)
				)
			)
		)
	)
	(footprint ""
		(layer "F.Cu")
		(at 349.123 -108.204)
		(property "Reference" "PC8"
			(at 0 0 0)
			(layer "F.SilkS")
			(hide yes)
			(effects
				(font
					(size 1.27 1.27)
				)
			)
		)
		(property "Value" "SC22U25V5MX-GP"
			(at -0.0762 -6.1214 0)
			(unlocked yes)
			(layer "F.Fab")
			(hide yes)
			(effects
				(font
					(size 1.016 1.016)
					(thickness 0.1524)
				)
			)
		)
		(property "Device Type" "C805H58"
			(at -0.0762 -8.1534 0)
			(unlocked yes)
			(layer "F.Fab")
			(hide yes)
			(effects
				(font
					(size 1.016 1.016)
					(thickness 0.1524)
				)
			)
		)
		(duplicate_pad_numbers_are_jumpers no)
		(fp_line
			(start 0.635 0)
			(end -0.635 0)
			(stroke
				(width 0.508)
				(type default)
			)
			(layer "F.SilkS")
		)
		(fp_rect
			(start -0.9652 1.778)
			(end 0.9652 -1.778)
			(stroke
				(width 0)
				(type default)
			)
			(fill no)
			(layer "F.CrtYd")
		)
		(fp_poly
			(pts
				(xy -0.9652 -1.778) (xy 0.9652 -1.778) (xy 0.9652 1.778) (xy -0.9652 1.778)
			)
			(stroke
				(width 0)
				(type default)
			)
			(fill no)
			(layer "F.Fab")
		)
		(pad "1" smd rect
			(at 0 -0.9652)
			(size 1.397 1.143)
			(layers "F.Cu" "F.Mask" "F.Paste")
			(net "P5V_STBY_VIN")
		)
		(pad "2" smd rect
			(at 0 0.9652)
			(size 1.397 1.143)
			(layers "F.Cu" "F.Mask" "F.Paste")
			(net "GND")
		)
	)
	(footprint ""
		(layer "F.Cu")
		(at 318.008 -172.72 -90)
		(property "Reference" "R802"
			(at 0 0 270)
			(layer "F.SilkS")
			(hide yes)
			(effects
				(font
					(size 1.27 1.27)
				)
			)
		)
		(property "Value" "4K7R2F-GP"
			(at 0.064008 -3.993896 270)
			(unlocked yes)
			(layer "F.Fab")
			(hide yes)
			(effects
				(font
					(size 1.016 1.016)
					(thickness 0.1524)
				)
			)
		)
		(property "Device Type" "R402H16"
			(at 0.064008 -5.517896 270)
			(unlocked yes)
			(layer "F.Fab")
			(hide yes)
			(effects
				(font
					(size 1.016 1.016)
					(thickness 0.1524)
				)
			)
		)
		(duplicate_pad_numbers_are_jumpers no)
		(fp_line
			(start -0.508 -0.9398)
			(end -0.508 0.9398)
			(stroke
				(width 0.1524)
				(type default)
			)
			(layer "F.SilkS")
		)
		(fp_line
			(start 0.508 -0.9398)
			(end -0.508 -0.9398)
			(stroke
				(width 0.1524)
				(type default)
			)
			(layer "F.SilkS")
		)
		(fp_rect
			(start -0.508 0.9398)
			(end 0.508 -0.9398)
			(stroke
				(width 0)
				(type default)
			)
			(fill no)
			(layer "F.CrtYd")
		)
		(fp_rect
			(start -0.508 0.9398)
			(end 0.508 -0.9398)
			(stroke
				(width 0)
				(type default)
			)
			(fill no)
			(layer "F.Fab")
		)
		(pad "1" smd custom
			(at 0 -0.4445 270)
			(size 0.1397 0.1397)
			(layers "F.Cu" "F.Mask" "F.Paste")
			(net "P3V3_STBY")
			(options
				(clearance outline)
				(anchor circle)
			)
			(primitives
				(gr_poly
					(pts
						(arc
							(start -0.1778 -0.2794)
							(mid -0.249642 -0.249642)
							(end -0.2794 -0.1778)
						)
						(arc
							(start -0.2794 0.1778)
							(mid -0.249642 0.249642)
							(end -0.1778 0.2794)
						)
						(arc
							(start 0.1778 0.2794)
							(mid 0.249642 0.249642)
							(end 0.2794 0.1778)
						)
						(arc
							(start 0.2794 -0.1778)
							(mid 0.249642 -0.249642)
							(end 0.1778 -0.2794)
						)
					)
					(width 0)
					(fill yes)
				)
			)
		)
		(pad "2" smd custom
			(at 0 0.4445 270)
			(size 0.1397 0.1397)
			(layers "F.Cu" "F.Mask" "F.Paste")
			(net "JTAG_BMC_TDI")
			(options
				(clearance outline)
				(anchor circle)
			)
			(primitives
				(gr_poly
					(pts
						(arc
							(start -0.1778 -0.2794)
							(mid -0.249642 -0.249642)
							(end -0.2794 -0.1778)
						)
						(arc
							(start -0.2794 0.1778)
							(mid -0.249642 0.249642)
							(end -0.1778 0.2794)
						)
						(arc
							(start 0.1778 0.2794)
							(mid 0.249642 0.249642)
							(end 0.2794 0.1778)
						)
						(arc
							(start 0.2794 -0.1778)
							(mid 0.249642 -0.249642)
							(end 0.1778 -0.2794)
						)
					)
					(width 0)
					(fill yes)
				)
			)
		)
	)
	(footprint ""
		(layer "F.Cu")
		(at 182.426864 -38.172136 180)
		(property "Reference" "R391"
			(at 0 0 180)
			(layer "F.SilkS")
			(hide yes)
			(effects
				(font
					(size 1.27 1.27)
				)
			)
		)
		(property "Value" "4K75R2F-1-GP"
			(at 0.064008 -3.993896 180)
			(unlocked yes)
			(layer "F.Fab")
			(hide yes)
			(effects
				(font
					(size 1.016 1.016)
					(thickness 0.1524)
				)
			)
		)
		(property "Device Type" "R402H16"
			(at 0.064008 -5.517896 180)
			(unlocked yes)
			(layer "F.Fab")
			(hide yes)
			(effects
				(font
					(size 1.016 1.016)
					(thickness 0.1524)
				)
			)
		)
		(duplicate_pad_numbers_are_jumpers no)
		(fp_line
			(start 0.508 -0.9398)
			(end -0.508 -0.9398)
			(stroke
				(width 0.1524)
				(type default)
			)
			(layer "F.SilkS")
		)
		(fp_line
			(start -0.508 -0.9398)
			(end -0.508 0.9398)
			(stroke
				(width 0.1524)
				(type default)
			)
			(layer "F.SilkS")
		)
		(fp_rect
			(start -0.508 0.9398)
			(end 0.508 -0.9398)
			(stroke
				(width 0)
				(type default)
			)
			(fill no)
			(layer "F.CrtYd")
		)
		(fp_rect
			(start -0.508 0.9398)
			(end 0.508 -0.9398)
			(stroke
				(width 0)
				(type default)
			)
			(fill no)
			(layer "F.Fab")
		)
		(pad "1" smd custom
			(at 0 -0.4445 180)
			(size 0.1397 0.1397)
			(layers "F.Cu" "F.Mask" "F.Paste")
			(net "PHY_AD1")
			(options
				(clearance outline)
				(anchor circle)
			)
			(primitives
				(gr_poly
					(pts
						(arc
							(start -0.1778 -0.2794)
							(mid -0.249642 -0.249642)
							(end -0.2794 -0.1778)
						)
						(arc
							(start -0.2794 0.1778)
							(mid -0.249642 0.249642)
							(end -0.1778 0.2794)
						)
						(arc
							(start 0.1778 0.2794)
							(mid 0.249642 0.249642)
							(end 0.2794 0.1778)
						)
						(arc
							(start 0.2794 -0.1778)
							(mid 0.249642 -0.249642)
							(end 0.1778 -0.2794)
						)
					)
					(width 0)
					(fill yes)
				)
			)
		)
		(pad "2" smd custom
			(at 0 0.4445 180)
			(size 0.1397 0.1397)
			(layers "F.Cu" "F.Mask" "F.Paste")
			(net "GND")
			(options
				(clearance outline)
				(anchor circle)
			)
			(primitives
				(gr_poly
					(pts
						(arc
							(start -0.1778 -0.2794)
							(mid -0.249642 -0.249642)
							(end -0.2794 -0.1778)
						)
						(arc
							(start -0.2794 0.1778)
							(mid -0.249642 0.249642)
							(end -0.1778 0.2794)
						)
						(arc
							(start 0.1778 0.2794)
							(mid 0.249642 0.249642)
							(end 0.2794 0.1778)
						)
						(arc
							(start 0.2794 -0.1778)
							(mid 0.249642 -0.249642)
							(end 0.1778 -0.2794)
						)
					)
					(width 0)
					(fill yes)
				)
			)
		)
	)
	(footprint ""
		(layer "F.Cu")
		(at 318.893952 -58.547 -90)
		(property "Reference" "R213"
			(at 0 0 270)
			(layer "F.SilkS")
			(hide yes)
			(effects
				(font
					(size 1.27 1.27)
				)
			)
		)
		(property "Value" "0R2J-2-GP"
			(at 0.064008 -3.993896 270)
			(unlocked yes)
			(layer "F.Fab")
			(hide yes)
			(effects
				(font
					(size 1.016 1.016)
					(thickness 0.1524)
				)
			)
		)
		(property "Device Type" "R402H16"
			(at 0.064008 -5.517896 270)
			(unlocked yes)
			(layer "F.Fab")
			(hide yes)
			(effects
				(font
					(size 1.016 1.016)
					(thickness 0.1524)
				)
			)
		)
		(duplicate_pad_numbers_are_jumpers no)
		(fp_line
			(start -0.508 -0.9398)
			(end -0.508 0.9398)
			(stroke
				(width 0.1524)
				(type default)
			)
			(layer "F.SilkS")
		)
		(fp_line
			(start 0.508 -0.9398)
			(end -0.508 -0.9398)
			(stroke
				(width 0.1524)
				(type default)
			)
			(layer "F.SilkS")
		)
		(fp_rect
			(start -0.508 0.9398)
			(end 0.508 -0.9398)
			(stroke
				(width 0)
				(type default)
			)
			(fill no)
			(layer "F.CrtYd")
		)
		(fp_rect
			(start -0.508 0.9398)
			(end 0.508 -0.9398)
			(stroke
				(width 0)
				(type default)
			)
			(fill no)
			(layer "F.Fab")
		)
		(pad "1" smd custom
			(at 0 -0.4445 270)
			(size 0.1397 0.1397)
			(layers "F.Cu" "F.Mask" "F.Paste")
			(net "NCSI_10G_TXEN")
			(options
				(clearance outline)
				(anchor circle)
			)
			(primitives
				(gr_poly
					(pts
						(arc
							(start -0.1778 -0.2794)
							(mid -0.249642 -0.249642)
							(end -0.2794 -0.1778)
						)
						(arc
							(start -0.2794 0.1778)
							(mid -0.249642 0.249642)
							(end -0.1778 0.2794)
						)
						(arc
							(start 0.1778 0.2794)
							(mid 0.249642 0.249642)
							(end 0.2794 0.1778)
						)
						(arc
							(start 0.2794 -0.1778)
							(mid 0.249642 -0.249642)
							(end 0.1778 -0.2794)
						)
					)
					(width 0)
					(fill yes)
				)
			)
		)
		(pad "2" smd custom
			(at 0 0.4445 270)
			(size 0.1397 0.1397)
			(layers "F.Cu" "F.Mask" "F.Paste")
			(net "NCSI_10G_TXEN_R")
			(options
				(clearance outline)
				(anchor circle)
			)
			(primitives
				(gr_poly
					(pts
						(arc
							(start -0.1778 -0.2794)
							(mid -0.249642 -0.249642)
							(end -0.2794 -0.1778)
						)
						(arc
							(start -0.2794 0.1778)
							(mid -0.249642 0.249642)
							(end -0.1778 0.2794)
						)
						(arc
							(start 0.1778 0.2794)
							(mid 0.249642 0.249642)
							(end 0.2794 0.1778)
						)
						(arc
							(start 0.2794 -0.1778)
							(mid 0.249642 -0.249642)
							(end 0.1778 -0.2794)
						)
					)
					(width 0)
					(fill yes)
				)
			)
		)
	)
	(footprint ""
		(layer "F.Cu")
		(at 152.247092 -104.550464 -90)
		(property "Reference" "SL18"
			(at 0 0 270)
			(layer "F.SilkS")
			(hide yes)
			(effects
				(font
					(size 1.27 1.27)
				)
			)
		)
		(property "Value" "MPZ2012S300AT-GP"
			(at 0 -4.2418 270)
			(unlocked yes)
			(layer "F.Fab")
			(hide yes)
			(effects
				(font
					(size 1.016 1.016)
					(thickness 0.1524)
				)
			)
		)
		(property "Device Type" "L805H42"
			(at 0 -5.7912 270)
			(unlocked yes)
			(layer "F.Fab")
			(hide yes)
			(effects
				(font
					(size 1.016 1.016)
					(thickness 0.1524)
				)
			)
		)
		(duplicate_pad_numbers_are_jumpers no)
		(fp_line
			(start -0.889 1.7018)
			(end -0.889 -1.7018)
			(stroke
				(width 0.1524)
				(type default)
			)
			(layer "F.SilkS")
		)
		(fp_line
			(start 0.889 1.7018)
			(end -0.889 1.7018)
			(stroke
				(width 0.1524)
				(type default)
			)
			(layer "F.SilkS")
		)
		(fp_line
			(start -0.889 -1.7018)
			(end 0.889 -1.7018)
			(stroke
				(width 0.1524)
				(type default)
			)
			(layer "F.SilkS")
		)
		(fp_line
			(start 0.889 -1.7018)
			(end 0.889 1.7018)
			(stroke
				(width 0.1524)
				(type default)
			)
			(layer "F.SilkS")
		)
		(fp_rect
			(start -0.9652 1.778)
			(end 0.9652 -1.778)
			(stroke
				(width 0)
				(type default)
			)
			(fill no)
			(layer "F.CrtYd")
		)
		(fp_rect
			(start -0.9652 1.778)
			(end 0.9652 -1.778)
			(stroke
				(width 0)
				(type default)
			)
			(fill no)
			(layer "F.Fab")
		)
		(pad "1" smd rect
			(at 0 -0.9652 270)
			(size 1.397 1.143)
			(layers "F.Cu" "F.Mask" "F.Paste")
			(net "P0V9_E")
		)
		(pad "2" smd rect
			(at 0 0.9652 270)
			(size 1.397 1.143)
			(layers "F.Cu" "F.Mask" "F.Paste")
			(net "GB_VDDA")
		)
	)
	(footprint ""
		(layer "F.Cu")
		(at 257.483864 -228.210872 -90)
		(property "Reference" "PC101"
			(at 0 0 270)
			(layer "F.SilkS")
			(hide yes)
			(effects
				(font
					(size 1.27 1.27)
				)
			)
		)
		(property "Value" "SCD1U16V2KX-3GP"
			(at 1.1811 -2.7051 270)
			(unlocked yes)
			(layer "F.Fab")
			(hide yes)
			(effects
				(font
					(size 1.016 1.016)
					(thickness 0.1524)
				)
			)
		)
		(property "Device Type" "C402H22"
			(at 1.1811 -4.2291 270)
			(unlocked yes)
			(layer "F.Fab")
			(hide yes)
			(effects
				(font
					(size 1.016 1.016)
					(thickness 0.1524)
				)
			)
		)
		(duplicate_pad_numbers_are_jumpers no)
		(fp_rect
			(start -0.4318 0.9525)
			(end 0.4318 -0.9525)
			(stroke
				(width 0)
				(type default)
			)
			(fill no)
			(layer "F.CrtYd")
		)
		(fp_rect
			(start -0.4318 0.9525)
			(end 0.4318 -0.9525)
			(stroke
				(width 0)
				(type default)
			)
			(fill no)
			(layer "F.Fab")
		)
		(pad "1" smd custom
			(at 0 -0.4445 270)
			(size 0.1524 0.1524)
			(layers "F.Cu" "F.Mask" "F.Paste")
			(net "TPS74801_1V26_STBY_EN")
			(options
				(clearance outline)
				(anchor circle)
			)
			(primitives
				(gr_poly
					(pts
						(arc
							(start 0.3048 -0.2032)
							(mid 0.275042 -0.275042)
							(end 0.2032 -0.3048)
						)
						(arc
							(start -0.2032 -0.3048)
							(mid -0.275042 -0.275042)
							(end -0.3048 -0.2032)
						)
						(arc
							(start -0.3048 0.2032)
							(mid -0.275042 0.275042)
							(end -0.2032 0.3048)
						)
						(arc
							(start 0.2032 0.3048)
							(mid 0.275042 0.275042)
							(end 0.3048 0.2032)
						)
					)
					(width 0)
					(fill yes)
				)
			)
		)
		(pad "2" smd custom
			(at 0 0.4445 270)
			(size 0.1524 0.1524)
			(layers "F.Cu" "F.Mask" "F.Paste")
			(net "GND")
			(options
				(clearance outline)
				(anchor circle)
			)
			(primitives
				(gr_poly
					(pts
						(arc
							(start 0.3048 -0.2032)
							(mid 0.275042 -0.275042)
							(end 0.2032 -0.3048)
						)
						(arc
							(start -0.2032 -0.3048)
							(mid -0.275042 -0.275042)
							(end -0.3048 -0.2032)
						)
						(arc
							(start -0.3048 0.2032)
							(mid -0.275042 0.275042)
							(end -0.2032 0.3048)
						)
						(arc
							(start 0.2032 0.3048)
							(mid 0.275042 0.275042)
							(end 0.3048 0.2032)
						)
					)
					(width 0)
					(fill yes)
				)
			)
		)
	)
	(footprint ""
		(layer "F.Cu")
		(at 111.51997 -78.7146)
		(property "Reference" "STP67"
			(at 0 0 0)
			(layer "F.SilkS")
			(hide yes)
			(effects
				(font
					(size 1.27 1.27)
				)
			)
		)
		(property "Value" "TPAD28"
			(at 0.0127 -1.8034 0)
			(unlocked yes)
			(layer "F.Fab")
			(hide yes)
			(effects
				(font
					(size 1.016 1.016)
					(thickness 0.1524)
				)
			)
		)
		(property "Device Type" "TPAD28"
			(at 0.0127 -3.3274 0)
			(unlocked yes)
			(layer "F.Fab")
			(hide yes)
			(effects
				(font
					(size 1.016 1.016)
					(thickness 0.1524)
				)
			)
		)
		(duplicate_pad_numbers_are_jumpers no)
		(fp_poly
			(pts
				(arc
					(start 0.3556 0)
					(mid -0.3556 0)
					(end 0.3556 0)
				)
			)
			(stroke
				(width 0)
				(type default)
			)
			(fill no)
			(layer "F.CrtYd")
		)
		(fp_poly
			(pts
				(arc
					(start 0.6096 0)
					(mid -0.6096 0)
					(end 0.6096 0)
				)
			)
			(stroke
				(width 0)
				(type default)
			)
			(fill no)
			(layer "F.Fab")
		)
		(pad "1" smd circle
			(at 0 0)
			(size 0.7112 0.7112)
			(layers "F.Cu" "F.Mask" "F.Paste")
			(net "EXP_TEST_MUX29")
		)
	)
	(footprint ""
		(layer "F.Cu")
		(at 318.008 -164.338 -90)
		(property "Reference" "R263"
			(at 0 0 270)
			(layer "F.SilkS")
			(hide yes)
			(effects
				(font
					(size 1.27 1.27)
				)
			)
		)
		(property "Value" "10KR2F-2-GP"
			(at 0.064008 -3.993896 270)
			(unlocked yes)
			(layer "F.Fab")
			(hide yes)
			(effects
				(font
					(size 1.016 1.016)
					(thickness 0.1524)
				)
			)
		)
		(property "Device Type" "R402H16"
			(at 0.064008 -5.517896 270)
			(unlocked yes)
			(layer "F.Fab")
			(hide yes)
			(effects
				(font
					(size 1.016 1.016)
					(thickness 0.1524)
				)
			)
		)
		(duplicate_pad_numbers_are_jumpers no)
		(fp_line
			(start -0.508 -0.9398)
			(end -0.508 0.9398)
			(stroke
				(width 0.1524)
				(type default)
			)
			(layer "F.SilkS")
		)
		(fp_line
			(start 0.508 -0.9398)
			(end -0.508 -0.9398)
			(stroke
				(width 0.1524)
				(type default)
			)
			(layer "F.SilkS")
		)
		(fp_rect
			(start -0.508 0.9398)
			(end 0.508 -0.9398)
			(stroke
				(width 0)
				(type default)
			)
			(fill no)
			(layer "F.CrtYd")
		)
		(fp_rect
			(start -0.508 0.9398)
			(end 0.508 -0.9398)
			(stroke
				(width 0)
				(type default)
			)
			(fill no)
			(layer "F.Fab")
		)
		(pad "1" smd custom
			(at 0 -0.4445 270)
			(size 0.1397 0.1397)
			(layers "F.Cu" "F.Mask" "F.Paste")
			(net "P3V3_STBY")
			(options
				(clearance outline)
				(anchor circle)
			)
			(primitives
				(gr_poly
					(pts
						(arc
							(start -0.1778 -0.2794)
							(mid -0.249642 -0.249642)
							(end -0.2794 -0.1778)
						)
						(arc
							(start -0.2794 0.1778)
							(mid -0.249642 0.249642)
							(end -0.1778 0.2794)
						)
						(arc
							(start 0.1778 0.2794)
							(mid 0.249642 0.249642)
							(end 0.2794 0.1778)
						)
						(arc
							(start 0.2794 -0.1778)
							(mid 0.249642 -0.249642)
							(end 0.1778 -0.2794)
						)
					)
					(width 0)
					(fill yes)
				)
			)
		)
		(pad "2" smd custom
			(at 0 0.4445 270)
			(size 0.1397 0.1397)
			(layers "F.Cu" "F.Mask" "F.Paste")
			(net "PU_BMC0_SDA12")
			(options
				(clearance outline)
				(anchor circle)
			)
			(primitives
				(gr_poly
					(pts
						(arc
							(start -0.1778 -0.2794)
							(mid -0.249642 -0.249642)
							(end -0.2794 -0.1778)
						)
						(arc
							(start -0.2794 0.1778)
							(mid -0.249642 0.249642)
							(end -0.1778 0.2794)
						)
						(arc
							(start 0.1778 0.2794)
							(mid 0.249642 0.249642)
							(end 0.2794 0.1778)
						)
						(arc
							(start 0.2794 -0.1778)
							(mid 0.249642 -0.249642)
							(end 0.1778 -0.2794)
						)
					)
					(width 0)
					(fill yes)
				)
			)
		)
	)
	(footprint ""
		(layer "F.Cu")
		(at 254.762 -136.779)
		(property "Reference" "R7907"
			(at 0 0 0)
			(layer "F.SilkS")
			(hide yes)
			(effects
				(font
					(size 1.27 1.27)
				)
			)
		)
		(property "Value" "0R2J-2-GP"
			(at 0.064008 -3.993896 0)
			(unlocked yes)
			(layer "F.Fab")
			(hide yes)
			(effects
				(font
					(size 1.016 1.016)
					(thickness 0.1524)
				)
			)
		)
		(property "Device Type" "R402H16"
			(at 0.064008 -5.517896 0)
			(unlocked yes)
			(layer "F.Fab")
			(hide yes)
			(effects
				(font
					(size 1.016 1.016)
					(thickness 0.1524)
				)
			)
		)
		(duplicate_pad_numbers_are_jumpers no)
		(fp_line
			(start -0.508 -0.9398)
			(end -0.508 0.9398)
			(stroke
				(width 0.1524)
				(type default)
			)
			(layer "F.SilkS")
		)
		(fp_line
			(start 0.508 -0.9398)
			(end -0.508 -0.9398)
			(stroke
				(width 0.1524)
				(type default)
			)
			(layer "F.SilkS")
		)
		(fp_rect
			(start -0.508 0.9398)
			(end 0.508 -0.9398)
			(stroke
				(width 0)
				(type default)
			)
			(fill no)
			(layer "F.CrtYd")
		)
		(fp_rect
			(start -0.508 0.9398)
			(end 0.508 -0.9398)
			(stroke
				(width 0)
				(type default)
			)
			(fill no)
			(layer "F.Fab")
		)
		(pad "1" smd custom
			(at 0 -0.4445)
			(size 0.1397 0.1397)
			(layers "F.Cu" "F.Mask" "F.Paste")
			(net "CPU_BMC_UART_TX")
			(options
				(clearance outline)
				(anchor circle)
			)
			(primitives
				(gr_poly
					(pts
						(arc
							(start -0.1778 -0.2794)
							(mid -0.249642 -0.249642)
							(end -0.2794 -0.1778)
						)
						(arc
							(start -0.2794 0.1778)
							(mid -0.249642 0.249642)
							(end -0.1778 0.2794)
						)
						(arc
							(start 0.1778 0.2794)
							(mid 0.249642 0.249642)
							(end 0.2794 0.1778)
						)
						(arc
							(start 0.2794 -0.1778)
							(mid 0.249642 -0.249642)
							(end 0.1778 -0.2794)
						)
					)
					(width 0)
					(fill yes)
				)
			)
		)
		(pad "2" smd custom
			(at 0 0.4445)
			(size 0.1397 0.1397)
			(layers "F.Cu" "F.Mask" "F.Paste")
			(net "CPU_U193_PIN5_TX")
			(options
				(clearance outline)
				(anchor circle)
			)
			(primitives
				(gr_poly
					(pts
						(arc
							(start -0.1778 -0.2794)
							(mid -0.249642 -0.249642)
							(end -0.2794 -0.1778)
						)
						(arc
							(start -0.2794 0.1778)
							(mid -0.249642 0.249642)
							(end -0.1778 0.2794)
						)
						(arc
							(start 0.1778 0.2794)
							(mid 0.249642 0.249642)
							(end 0.2794 0.1778)
						)
						(arc
							(start 0.2794 -0.1778)
							(mid 0.249642 -0.249642)
							(end 0.1778 -0.2794)
						)
					)
					(width 0)
					(fill yes)
				)
			)
		)
	)
	(footprint ""
		(layer "F.Cu")
		(at 134.50697 -98.806 180)
		(property "Reference" "SC1269"
			(at 0 0 180)
			(layer "F.SilkS")
			(hide yes)
			(effects
				(font
					(size 1.27 1.27)
				)
			)
		)
		(property "Value" "SCD01U10V1KX-GP"
			(at -2.8321 -1.7399 180)
			(unlocked yes)
			(layer "F.Fab")
			(hide yes)
			(effects
				(font
					(size 1.016 1.016)
					(thickness 0.1524)
				)
			)
		)
		(property "Device Type" "C0201H13"
			(at -2.8321 -3.2639 180)
			(unlocked yes)
			(layer "F.Fab")
			(hide yes)
			(effects
				(font
					(size 1.016 1.016)
					(thickness 0.1524)
				)
			)
		)
		(duplicate_pad_numbers_are_jumpers no)
		(fp_rect
			(start -0.2794 0.6477)
			(end 0.2794 -0.6477)
			(stroke
				(width 0)
				(type default)
			)
			(fill no)
			(layer "F.CrtYd")
		)
		(fp_rect
			(start -0.2794 0.6477)
			(end 0.2794 -0.6477)
			(stroke
				(width 0)
				(type default)
			)
			(fill no)
			(layer "F.Fab")
		)
		(pad "1" smd custom
			(at 0 -0.2794 180)
			(size 0.0762 0.0762)
			(layers "F.Cu" "F.Mask" "F.Paste")
			(net "3X24_SAS_TX21_N")
			(options
				(clearance outline)
				(anchor circle)
			)
			(primitives
				(gr_poly
					(pts
						(arc
							(start 0.1524 -0.127)
							(mid 0.137521 -0.162921)
							(end 0.1016 -0.1778)
						)
						(arc
							(start -0.1016 -0.1778)
							(mid -0.137521 -0.162921)
							(end -0.1524 -0.127)
						)
						(arc
							(start -0.1524 0.127)
							(mid -0.137521 0.162921)
							(end -0.1016 0.1778)
						)
						(arc
							(start 0.1016 0.1778)
							(mid 0.137521 0.162921)
							(end 0.1524 0.127)
						)
					)
					(width 0)
					(fill yes)
				)
			)
		)
		(pad "2" smd custom
			(at 0 0.2794 180)
			(size 0.0762 0.0762)
			(layers "F.Cu" "F.Mask" "F.Paste")
			(net "SAS_EXP_GF_TX_DN1")
			(options
				(clearance outline)
				(anchor circle)
			)
			(primitives
				(gr_poly
					(pts
						(arc
							(start 0.1524 -0.127)
							(mid 0.137521 -0.162921)
							(end 0.1016 -0.1778)
						)
						(arc
							(start -0.1016 -0.1778)
							(mid -0.137521 -0.162921)
							(end -0.1524 -0.127)
						)
						(arc
							(start -0.1524 0.127)
							(mid -0.137521 0.162921)
							(end -0.1016 0.1778)
						)
						(arc
							(start 0.1016 0.1778)
							(mid 0.137521 0.162921)
							(end 0.1524 0.127)
						)
					)
					(width 0)
					(fill yes)
				)
			)
		)
	)
	(footprint ""
		(layer "F.Cu")
		(at 198.755 -97.917 -90)
		(property "Reference" "PC238"
			(at 0 0 270)
			(layer "F.SilkS")
			(hide yes)
			(effects
				(font
					(size 1.27 1.27)
				)
			)
		)
		(property "Value" "SC47U6D3V5MX-1-GP"
			(at -0.0762 -6.1214 270)
			(unlocked yes)
			(layer "F.Fab")
			(hide yes)
			(effects
				(font
					(size 1.016 1.016)
					(thickness 0.1524)
				)
			)
		)
		(property "Device Type" "C805H54"
			(at -0.0762 -8.1534 270)
			(unlocked yes)
			(layer "F.Fab")
			(hide yes)
			(effects
				(font
					(size 1.016 1.016)
					(thickness 0.1524)
				)
			)
		)
		(duplicate_pad_numbers_are_jumpers no)
		(fp_line
			(start 0.635 0)
			(end -0.635 0)
			(stroke
				(width 0.508)
				(type default)
			)
			(layer "F.SilkS")
		)
		(fp_rect
			(start -0.9652 1.778)
			(end 0.9652 -1.778)
			(stroke
				(width 0)
				(type default)
			)
			(fill no)
			(layer "F.CrtYd")
		)
		(fp_poly
			(pts
				(xy -0.9652 -1.778) (xy 0.9652 -1.778) (xy 0.9652 1.778) (xy -0.9652 1.778)
			)
			(stroke
				(width 0)
				(type default)
			)
			(fill no)
			(layer "F.Fab")
		)
		(pad "1" smd rect
			(at 0 -0.9652 270)
			(size 1.397 1.143)
			(layers "F.Cu" "F.Mask" "F.Paste")
			(net "P1V5_E")
		)
		(pad "2" smd rect
			(at 0 0.9652 270)
			(size 1.397 1.143)
			(layers "F.Cu" "F.Mask" "F.Paste")
			(net "GND")
		)
	)
	(footprint ""
		(layer "F.Cu")
		(at 268.351 -218.059 90)
		(property "Reference" "PC96"
			(at 0 0 90)
			(layer "F.SilkS")
			(hide yes)
			(effects
				(font
					(size 1.27 1.27)
				)
			)
		)
		(property "Value" "SC10U6D3V5KX-1GP"
			(at -0.0762 -6.1214 90)
			(unlocked yes)
			(layer "F.Fab")
			(hide yes)
			(effects
				(font
					(size 1.016 1.016)
					(thickness 0.1524)
				)
			)
		)
		(property "Device Type" "C805H54"
			(at -0.0762 -8.1534 90)
			(unlocked yes)
			(layer "F.Fab")
			(hide yes)
			(effects
				(font
					(size 1.016 1.016)
					(thickness 0.1524)
				)
			)
		)
		(duplicate_pad_numbers_are_jumpers no)
		(fp_line
			(start 0.635 0)
			(end -0.635 0)
			(stroke
				(width 0.508)
				(type default)
			)
			(layer "F.SilkS")
		)
		(fp_rect
			(start -0.9652 1.778)
			(end 0.9652 -1.778)
			(stroke
				(width 0)
				(type default)
			)
			(fill no)
			(layer "F.CrtYd")
		)
		(fp_poly
			(pts
				(xy -0.9652 -1.778) (xy 0.9652 -1.778) (xy 0.9652 1.778) (xy -0.9652 1.778)
			)
			(stroke
				(width 0)
				(type default)
			)
			(fill no)
			(layer "F.Fab")
		)
		(pad "1" smd rect
			(at 0 -0.9652 90)
			(size 1.397 1.143)
			(layers "F.Cu" "F.Mask" "F.Paste")
			(net "TPS74801_1V26_STBY_OUT")
		)
		(pad "2" smd rect
			(at 0 0.9652 90)
			(size 1.397 1.143)
			(layers "F.Cu" "F.Mask" "F.Paste")
			(net "GND")
		)
	)
	(footprint ""
		(layer "F.Cu")
		(at 311.531 -110.236)
		(property "Reference" "PC33"
			(at 0 0 0)
			(layer "F.SilkS")
			(hide yes)
			(effects
				(font
					(size 1.27 1.27)
				)
			)
		)
		(property "Value" "SC1U10V2KX-1GP"
			(at 1.1811 -2.7051 0)
			(unlocked yes)
			(layer "F.Fab")
			(hide yes)
			(effects
				(font
					(size 1.016 1.016)
					(thickness 0.1524)
				)
			)
		)
		(property "Device Type" "C402H22"
			(at 1.1811 -4.2291 0)
			(unlocked yes)
			(layer "F.Fab")
			(hide yes)
			(effects
				(font
					(size 1.016 1.016)
					(thickness 0.1524)
				)
			)
		)
		(duplicate_pad_numbers_are_jumpers no)
		(fp_rect
			(start -0.4318 0.9525)
			(end 0.4318 -0.9525)
			(stroke
				(width 0)
				(type default)
			)
			(fill no)
			(layer "F.CrtYd")
		)
		(fp_rect
			(start -0.4318 0.9525)
			(end 0.4318 -0.9525)
			(stroke
				(width 0)
				(type default)
			)
			(fill no)
			(layer "F.Fab")
		)
		(pad "1" smd custom
			(at 0 -0.4445)
			(size 0.1524 0.1524)
			(layers "F.Cu" "F.Mask" "F.Paste")
			(net "AGND_P3V3_STBY")
			(options
				(clearance outline)
				(anchor circle)
			)
			(primitives
				(gr_poly
					(pts
						(arc
							(start 0.3048 -0.2032)
							(mid 0.275042 -0.275042)
							(end 0.2032 -0.3048)
						)
						(arc
							(start -0.2032 -0.3048)
							(mid -0.275042 -0.275042)
							(end -0.3048 -0.2032)
						)
						(arc
							(start -0.3048 0.2032)
							(mid -0.275042 0.275042)
							(end -0.2032 0.3048)
						)
						(arc
							(start 0.2032 0.3048)
							(mid 0.275042 0.275042)
							(end 0.3048 0.2032)
						)
					)
					(width 0)
					(fill yes)
				)
			)
		)
		(pad "2" smd custom
			(at 0 0.4445)
			(size 0.1524 0.1524)
			(layers "F.Cu" "F.Mask" "F.Paste")
			(net "P3V3_STBY_ROVP")
			(options
				(clearance outline)
				(anchor circle)
			)
			(primitives
				(gr_poly
					(pts
						(arc
							(start 0.3048 -0.2032)
							(mid 0.275042 -0.275042)
							(end 0.2032 -0.3048)
						)
						(arc
							(start -0.2032 -0.3048)
							(mid -0.275042 -0.275042)
							(end -0.3048 -0.2032)
						)
						(arc
							(start -0.3048 0.2032)
							(mid -0.275042 0.275042)
							(end -0.2032 0.3048)
						)
						(arc
							(start 0.2032 0.3048)
							(mid 0.275042 0.275042)
							(end 0.3048 0.2032)
						)
					)
					(width 0)
					(fill yes)
				)
			)
		)
	)
	(footprint ""
		(layer "F.Cu")
		(at 187.833 -140.589 -90)
		(property "Reference" "SR764"
			(at 0 0 270)
			(layer "F.SilkS")
			(hide yes)
			(effects
				(font
					(size 1.27 1.27)
				)
			)
		)
		(property "Value" "0R2J-2-GP"
			(at 0.064008 -3.993896 270)
			(unlocked yes)
			(layer "F.Fab")
			(hide yes)
			(effects
				(font
					(size 1.016 1.016)
					(thickness 0.1524)
				)
			)
		)
		(property "Device Type" "R402H16"
			(at 0.064008 -5.517896 270)
			(unlocked yes)
			(layer "F.Fab")
			(hide yes)
			(effects
				(font
					(size 1.016 1.016)
					(thickness 0.1524)
				)
			)
		)
		(duplicate_pad_numbers_are_jumpers no)
		(fp_line
			(start -0.508 -0.9398)
			(end -0.508 0.9398)
			(stroke
				(width 0.1524)
				(type default)
			)
			(layer "F.SilkS")
		)
		(fp_line
			(start 0.508 -0.9398)
			(end -0.508 -0.9398)
			(stroke
				(width 0.1524)
				(type default)
			)
			(layer "F.SilkS")
		)
		(fp_rect
			(start -0.508 0.9398)
			(end 0.508 -0.9398)
			(stroke
				(width 0)
				(type default)
			)
			(fill no)
			(layer "F.CrtYd")
		)
		(fp_rect
			(start -0.508 0.9398)
			(end 0.508 -0.9398)
			(stroke
				(width 0)
				(type default)
			)
			(fill no)
			(layer "F.Fab")
		)
		(pad "1" smd custom
			(at 0 -0.4445 270)
			(size 0.1397 0.1397)
			(layers "F.Cu" "F.Mask" "F.Paste")
			(net "EXP_EEPROM_WP")
			(options
				(clearance outline)
				(anchor circle)
			)
			(primitives
				(gr_poly
					(pts
						(arc
							(start -0.1778 -0.2794)
							(mid -0.249642 -0.249642)
							(end -0.2794 -0.1778)
						)
						(arc
							(start -0.2794 0.1778)
							(mid -0.249642 0.249642)
							(end -0.1778 0.2794)
						)
						(arc
							(start 0.1778 0.2794)
							(mid 0.249642 0.249642)
							(end 0.2794 0.1778)
						)
						(arc
							(start 0.2794 -0.1778)
							(mid 0.249642 -0.249642)
							(end 0.1778 -0.2794)
						)
					)
					(width 0)
					(fill yes)
				)
			)
		)
		(pad "2" smd custom
			(at 0 0.4445 270)
			(size 0.1397 0.1397)
			(layers "F.Cu" "F.Mask" "F.Paste")
			(net "GND")
			(options
				(clearance outline)
				(anchor circle)
			)
			(primitives
				(gr_poly
					(pts
						(arc
							(start -0.1778 -0.2794)
							(mid -0.249642 -0.249642)
							(end -0.2794 -0.1778)
						)
						(arc
							(start -0.2794 0.1778)
							(mid -0.249642 0.249642)
							(end -0.1778 0.2794)
						)
						(arc
							(start 0.1778 0.2794)
							(mid 0.249642 0.249642)
							(end 0.2794 0.1778)
						)
						(arc
							(start 0.2794 -0.1778)
							(mid 0.249642 -0.249642)
							(end 0.1778 -0.2794)
						)
					)
					(width 0)
					(fill yes)
				)
			)
		)
	)
	(footprint ""
		(layer "F.Cu")
		(at 94.215966 -61.468)
		(property "Reference" "STP32"
			(at 0 0 0)
			(layer "F.SilkS")
			(hide yes)
			(effects
				(font
					(size 1.27 1.27)
				)
			)
		)
		(property "Value" "TPAD28"
			(at 0.0127 -1.8034 0)
			(unlocked yes)
			(layer "F.Fab")
			(hide yes)
			(effects
				(font
					(size 1.016 1.016)
					(thickness 0.1524)
				)
			)
		)
		(property "Device Type" "TPAD28"
			(at 0.0127 -3.3274 0)
			(unlocked yes)
			(layer "F.Fab")
			(hide yes)
			(effects
				(font
					(size 1.016 1.016)
					(thickness 0.1524)
				)
			)
		)
		(duplicate_pad_numbers_are_jumpers no)
		(fp_poly
			(pts
				(arc
					(start 0.3556 0)
					(mid -0.3556 0)
					(end 0.3556 0)
				)
			)
			(stroke
				(width 0)
				(type default)
			)
			(fill no)
			(layer "F.CrtYd")
		)
		(fp_poly
			(pts
				(arc
					(start 0.6096 0)
					(mid -0.6096 0)
					(end 0.6096 0)
				)
			)
			(stroke
				(width 0)
				(type default)
			)
			(fill no)
			(layer "F.Fab")
		)
		(pad "1" smd circle
			(at 0 0)
			(size 0.7112 0.7112)
			(layers "F.Cu" "F.Mask" "F.Paste")
			(net "ICE0_TDI")
		)
	)
	(footprint ""
		(layer "F.Cu")
		(at 50.8 -103.251 -90)
		(property "Reference" "SCN5"
			(at 0 0 270)
			(layer "F.SilkS")
			(hide yes)
			(effects
				(font
					(size 1.27 1.27)
				)
			)
		)
		(property "Value" "JWT-CON4-S24-GP"
			(at -7.3787 1.4351 270)
			(unlocked yes)
			(layer "F.Fab")
			(hide yes)
			(effects
				(font
					(size 1.016 1.016)
					(thickness 0.1524)
				)
			)
		)
		(property "Device Type" "A2541WV0-1QX4PA-6T"
			(at -7.3787 -0.0889 270)
			(unlocked yes)
			(layer "F.Fab")
			(hide yes)
			(effects
				(font
					(size 1.016 1.016)
					(thickness 0.1524)
				)
			)
		)
		(duplicate_pad_numbers_are_jumpers no)
		(fp_line
			(start -5.334 1.524)
			(end 5.334 1.524)
			(stroke
				(width 0.1524)
				(type default)
			)
			(layer "F.SilkS")
		)
		(fp_line
			(start 5.334 1.524)
			(end 5.334 -1.524)
			(stroke
				(width 0.1524)
				(type default)
			)
			(layer "F.SilkS")
		)
		(fp_line
			(start -5.334 -1.524)
			(end -5.334 1.524)
			(stroke
				(width 0.1524)
				(type default)
			)
			(layer "F.SilkS")
		)
		(fp_line
			(start 5.334 -1.524)
			(end -5.334 -1.524)
			(stroke
				(width 0.1524)
				(type default)
			)
			(layer "F.SilkS")
		)
		(fp_line
			(start -5.461 -1.651)
			(end -5.461 -0.381)
			(stroke
				(width 0.4064)
				(type default)
			)
			(layer "F.SilkS")
		)
		(fp_line
			(start -4.191 -1.651)
			(end -5.461 -1.651)
			(stroke
				(width 0.4064)
				(type default)
			)
			(layer "F.SilkS")
		)
		(fp_circle
			(center -3.81 0)
			(end -3.81 -1.0668)
			(stroke
				(width 0.3048)
				(type default)
			)
			(fill no)
			(layer "F.SilkS")
		)
		(fp_circle
			(center -1.27 0)
			(end -1.27 -1.0668)
			(stroke
				(width 0.3048)
				(type default)
			)
			(fill no)
			(layer "F.SilkS")
		)
		(fp_circle
			(center 1.27 0)
			(end 1.27 -1.0668)
			(stroke
				(width 0.3048)
				(type default)
			)
			(fill no)
			(layer "F.SilkS")
		)
		(fp_circle
			(center 3.81 0)
			(end 3.81 -1.0668)
			(stroke
				(width 0.3048)
				(type default)
			)
			(fill no)
			(layer "F.SilkS")
		)
		(fp_rect
			(start -5.08 1.27)
			(end 5.08 -1.27)
			(stroke
				(width 0)
				(type default)
			)
			(fill no)
			(layer "F.CrtYd")
		)
		(fp_poly
			(pts
				(xy -5.588 1.778) (xy -5.588 -1.778) (xy 5.588 -1.778) (xy 5.588 1.2573) (xy 5.08 1.2573) (xy 5.08 -1.27)
				(xy -5.08 -1.27) (xy -5.08 1.27) (xy 5.588 1.27) (xy 5.588 1.778)
			)
			(stroke
				(width 0)
				(type default)
			)
			(fill no)
			(layer "F.CrtYd")
		)
		(fp_rect
			(start -5.588 1.778)
			(end 5.588 -1.778)
			(stroke
				(width 0)
				(type default)
			)
			(fill no)
			(layer "F.Fab")
		)
		(pad "1" thru_hole circle
			(at -3.81 0 270)
			(size 1.4224 1.4224)
			(drill 1.016)
			(layers "*.Cu" "*.Mask")
			(remove_unused_layers no)
			(net "P5V_STBY")
			(clearance 0.1524)
			(thermal_gap 0.1524)
		)
		(pad "2" thru_hole circle
			(at -1.27 0 270)
			(size 1.4224 1.4224)
			(drill 1.016)
			(layers "*.Cu" "*.Mask")
			(remove_unused_layers no)
			(net "SAS_SDBTX_R")
			(clearance 0.1524)
			(thermal_gap 0.1524)
		)
		(pad "3" thru_hole circle
			(at 1.27 0 270)
			(size 1.4224 1.4224)
			(drill 1.016)
			(layers "*.Cu" "*.Mask")
			(remove_unused_layers no)
			(net "SAS_SDBRX_R")
			(clearance 0.1524)
			(thermal_gap 0.1524)
		)
		(pad "4" thru_hole circle
			(at 3.81 0 270)
			(size 1.4224 1.4224)
			(drill 1.016)
			(layers "*.Cu" "*.Mask")
			(remove_unused_layers no)
			(net "GND")
			(clearance 0.1524)
			(thermal_gap 0.1524)
		)
	)
	(footprint ""
		(layer "F.Cu")
		(at 200.025 -197.231 180)
		(property "Reference" "C264"
			(at 0 0 180)
			(layer "F.SilkS")
			(hide yes)
			(effects
				(font
					(size 1.27 1.27)
				)
			)
		)
		(property "Value" "SCD1U16V2KX-3GP"
			(at 1.1811 -2.7051 180)
			(unlocked yes)
			(layer "F.Fab")
			(hide yes)
			(effects
				(font
					(size 1.016 1.016)
					(thickness 0.1524)
				)
			)
		)
		(property "Device Type" "C402H22"
			(at 1.1811 -4.2291 180)
			(unlocked yes)
			(layer "F.Fab")
			(hide yes)
			(effects
				(font
					(size 1.016 1.016)
					(thickness 0.1524)
				)
			)
		)
		(duplicate_pad_numbers_are_jumpers no)
		(fp_rect
			(start -0.4318 0.9525)
			(end 0.4318 -0.9525)
			(stroke
				(width 0)
				(type default)
			)
			(fill no)
			(layer "F.CrtYd")
		)
		(fp_rect
			(start -0.4318 0.9525)
			(end 0.4318 -0.9525)
			(stroke
				(width 0)
				(type default)
			)
			(fill no)
			(layer "F.Fab")
		)
		(pad "1" smd custom
			(at 0 -0.4445 180)
			(size 0.1524 0.1524)
			(layers "F.Cu" "F.Mask" "F.Paste")
			(net "P3V3_STBY")
			(options
				(clearance outline)
				(anchor circle)
			)
			(primitives
				(gr_poly
					(pts
						(arc
							(start 0.3048 -0.2032)
							(mid 0.275042 -0.275042)
							(end 0.2032 -0.3048)
						)
						(arc
							(start -0.2032 -0.3048)
							(mid -0.275042 -0.275042)
							(end -0.3048 -0.2032)
						)
						(arc
							(start -0.3048 0.2032)
							(mid -0.275042 0.275042)
							(end -0.2032 0.3048)
						)
						(arc
							(start 0.2032 0.3048)
							(mid 0.275042 0.275042)
							(end 0.3048 0.2032)
						)
					)
					(width 0)
					(fill yes)
				)
			)
		)
		(pad "2" smd custom
			(at 0 0.4445 180)
			(size 0.1524 0.1524)
			(layers "F.Cu" "F.Mask" "F.Paste")
			(net "GND")
			(options
				(clearance outline)
				(anchor circle)
			)
			(primitives
				(gr_poly
					(pts
						(arc
							(start 0.3048 -0.2032)
							(mid 0.275042 -0.275042)
							(end 0.2032 -0.3048)
						)
						(arc
							(start -0.2032 -0.3048)
							(mid -0.275042 -0.275042)
							(end -0.3048 -0.2032)
						)
						(arc
							(start -0.3048 0.2032)
							(mid -0.275042 0.275042)
							(end -0.2032 0.3048)
						)
						(arc
							(start 0.2032 0.3048)
							(mid 0.275042 0.275042)
							(end 0.3048 0.2032)
						)
					)
					(width 0)
					(fill yes)
				)
			)
		)
	)
	(footprint ""
		(layer "F.Cu")
		(at 300.482 -60.198 -90)
		(property "Reference" "R209"
			(at 0 0 270)
			(layer "F.SilkS")
			(hide yes)
			(effects
				(font
					(size 1.27 1.27)
				)
			)
		)
		(property "Value" "0R2J-2-GP"
			(at 0.064008 -3.993896 270)
			(unlocked yes)
			(layer "F.Fab")
			(hide yes)
			(effects
				(font
					(size 1.016 1.016)
					(thickness 0.1524)
				)
			)
		)
		(property "Device Type" "R402H16"
			(at 0.064008 -5.517896 270)
			(unlocked yes)
			(layer "F.Fab")
			(hide yes)
			(effects
				(font
					(size 1.016 1.016)
					(thickness 0.1524)
				)
			)
		)
		(duplicate_pad_numbers_are_jumpers no)
		(fp_line
			(start -0.508 -0.9398)
			(end -0.508 0.9398)
			(stroke
				(width 0.1524)
				(type default)
			)
			(layer "F.SilkS")
		)
		(fp_line
			(start 0.508 -0.9398)
			(end -0.508 -0.9398)
			(stroke
				(width 0.1524)
				(type default)
			)
			(layer "F.SilkS")
		)
		(fp_rect
			(start -0.508 0.9398)
			(end 0.508 -0.9398)
			(stroke
				(width 0)
				(type default)
			)
			(fill no)
			(layer "F.CrtYd")
		)
		(fp_rect
			(start -0.508 0.9398)
			(end 0.508 -0.9398)
			(stroke
				(width 0)
				(type default)
			)
			(fill no)
			(layer "F.Fab")
		)
		(pad "1" smd custom
			(at 0 -0.4445 270)
			(size 0.1397 0.1397)
			(layers "F.Cu" "F.Mask" "F.Paste")
			(net "SMB_LAN_ALERT_N")
			(options
				(clearance outline)
				(anchor circle)
			)
			(primitives
				(gr_poly
					(pts
						(arc
							(start -0.1778 -0.2794)
							(mid -0.249642 -0.249642)
							(end -0.2794 -0.1778)
						)
						(arc
							(start -0.2794 0.1778)
							(mid -0.249642 0.249642)
							(end -0.1778 0.2794)
						)
						(arc
							(start 0.1778 0.2794)
							(mid 0.249642 0.249642)
							(end 0.2794 0.1778)
						)
						(arc
							(start 0.2794 -0.1778)
							(mid 0.249642 -0.249642)
							(end 0.1778 -0.2794)
						)
					)
					(width 0)
					(fill yes)
				)
			)
		)
		(pad "2" smd custom
			(at 0 0.4445 270)
			(size 0.1397 0.1397)
			(layers "F.Cu" "F.Mask" "F.Paste")
			(net "I2C_BMC_10G_ALERT#")
			(options
				(clearance outline)
				(anchor circle)
			)
			(primitives
				(gr_poly
					(pts
						(arc
							(start -0.1778 -0.2794)
							(mid -0.249642 -0.249642)
							(end -0.2794 -0.1778)
						)
						(arc
							(start -0.2794 0.1778)
							(mid -0.249642 0.249642)
							(end -0.1778 0.2794)
						)
						(arc
							(start 0.1778 0.2794)
							(mid 0.249642 0.249642)
							(end 0.2794 0.1778)
						)
						(arc
							(start 0.2794 -0.1778)
							(mid 0.249642 -0.249642)
							(end 0.1778 -0.2794)
						)
					)
					(width 0)
					(fill yes)
				)
			)
		)
	)
	(footprint ""
		(layer "F.Cu")
		(at 316.865 -167.894 -90)
		(property "Reference" "R460"
			(at 0 0 270)
			(layer "F.SilkS")
			(hide yes)
			(effects
				(font
					(size 1.27 1.27)
				)
			)
		)
		(property "Value" "0R2J-2-GP"
			(at 0.064008 -3.993896 270)
			(unlocked yes)
			(layer "F.Fab")
			(hide yes)
			(effects
				(font
					(size 1.016 1.016)
					(thickness 0.1524)
				)
			)
		)
		(property "Device Type" "R402H16"
			(at 0.064008 -5.517896 270)
			(unlocked yes)
			(layer "F.Fab")
			(hide yes)
			(effects
				(font
					(size 1.016 1.016)
					(thickness 0.1524)
				)
			)
		)
		(duplicate_pad_numbers_are_jumpers no)
		(fp_line
			(start -0.508 -0.9398)
			(end -0.508 0.9398)
			(stroke
				(width 0.1524)
				(type default)
			)
			(layer "F.SilkS")
		)
		(fp_line
			(start 0.508 -0.9398)
			(end -0.508 -0.9398)
			(stroke
				(width 0.1524)
				(type default)
			)
			(layer "F.SilkS")
		)
		(fp_rect
			(start -0.508 0.9398)
			(end 0.508 -0.9398)
			(stroke
				(width 0)
				(type default)
			)
			(fill no)
			(layer "F.CrtYd")
		)
		(fp_rect
			(start -0.508 0.9398)
			(end 0.508 -0.9398)
			(stroke
				(width 0)
				(type default)
			)
			(fill no)
			(layer "F.Fab")
		)
		(pad "1" smd custom
			(at 0 -0.4445 270)
			(size 0.1397 0.1397)
			(layers "F.Cu" "F.Mask" "F.Paste")
			(net "BMC_I2C_B_SDA")
			(options
				(clearance outline)
				(anchor circle)
			)
			(primitives
				(gr_poly
					(pts
						(arc
							(start -0.1778 -0.2794)
							(mid -0.249642 -0.249642)
							(end -0.2794 -0.1778)
						)
						(arc
							(start -0.2794 0.1778)
							(mid -0.249642 0.249642)
							(end -0.1778 0.2794)
						)
						(arc
							(start 0.1778 0.2794)
							(mid 0.249642 0.249642)
							(end 0.2794 0.1778)
						)
						(arc
							(start 0.2794 -0.1778)
							(mid 0.249642 -0.249642)
							(end 0.1778 -0.2794)
						)
					)
					(width 0)
					(fill yes)
				)
			)
		)
		(pad "2" smd custom
			(at 0 0.4445 270)
			(size 0.1397 0.1397)
			(layers "F.Cu" "F.Mask" "F.Paste")
			(net "BMC0_SMB7_DAT")
			(options
				(clearance outline)
				(anchor circle)
			)
			(primitives
				(gr_poly
					(pts
						(arc
							(start -0.1778 -0.2794)
							(mid -0.249642 -0.249642)
							(end -0.2794 -0.1778)
						)
						(arc
							(start -0.2794 0.1778)
							(mid -0.249642 0.249642)
							(end -0.1778 0.2794)
						)
						(arc
							(start 0.1778 0.2794)
							(mid 0.249642 0.249642)
							(end 0.2794 0.1778)
						)
						(arc
							(start 0.2794 -0.1778)
							(mid 0.249642 -0.249642)
							(end 0.1778 -0.2794)
						)
					)
					(width 0)
					(fill yes)
				)
			)
		)
	)
	(footprint ""
		(layer "F.Cu")
		(at 63.881 -227.076)
		(property "Reference" "Q23"
			(at 0 0 0)
			(layer "F.SilkS")
			(hide yes)
			(effects
				(font
					(size 1.27 1.27)
				)
			)
		)
		(property "Value" "PSMN0R9-25YLC-GP"
			(at -4.2799 -0.4572 0)
			(unlocked yes)
			(layer "F.Fab")
			(hide yes)
			(effects
				(font
					(size 1.016 1.016)
					(thickness 0.1524)
				)
			)
		)
		(property "Device Type" "LFPAK-5PH48-U"
			(at -4.2799 -1.9812 0)
			(unlocked yes)
			(layer "F.Fab")
			(hide yes)
			(effects
				(font
					(size 1.016 1.016)
					(thickness 0.1524)
				)
			)
		)
		(duplicate_pad_numbers_are_jumpers no)
		(fp_line
			(start -2.7559 -6.5532)
			(end -2.7559 1.0668)
			(stroke
				(width 0.1524)
				(type default)
			)
			(layer "F.SilkS")
		)
		(fp_line
			(start -2.7559 1.0668)
			(end 2.7559 1.0668)
			(stroke
				(width 0.1524)
				(type default)
			)
			(layer "F.SilkS")
		)
		(fp_line
			(start -1.7272 1.1684)
			(end -2.1082 1.1684)
			(stroke
				(width 0.3302)
				(type default)
			)
			(layer "F.SilkS")
		)
		(fp_line
			(start 2.7559 -6.5532)
			(end -2.7559 -6.5532)
			(stroke
				(width 0.1524)
				(type default)
			)
			(layer "F.SilkS")
		)
		(fp_line
			(start 2.7559 1.0668)
			(end 2.7559 -6.5532)
			(stroke
				(width 0.1524)
				(type default)
			)
			(layer "F.SilkS")
		)
		(fp_poly
			(pts
				(xy -2.3368 1.5748) (xy -1.905 1.143) (xy -1.4732 1.5748)
			)
			(stroke
				(width 0)
				(type default)
			)
			(fill yes)
			(layer "F.SilkS")
		)
		(fp_poly
			(pts
				(xy -2.5019 -4.02971) (xy -0.3302 -4.02971) (xy -0.3302 -6.30301) (xy -2.5019 -6.30301)
			)
			(stroke
				(width 0)
				(type default)
			)
			(fill yes)
			(layer "F.Paste")
		)
		(fp_poly
			(pts
				(xy -2.5019 -1.09601) (xy -0.3302 -1.09601) (xy -0.3302 -3.36931) (xy -2.5019 -3.36931)
			)
			(stroke
				(width 0)
				(type default)
			)
			(fill yes)
			(layer "F.Paste")
		)
		(fp_poly
			(pts
				(xy 0.3302 -4.02971) (xy 2.5019 -4.02971) (xy 2.5019 -6.30301) (xy 0.3302 -6.30301)
			)
			(stroke
				(width 0)
				(type default)
			)
			(fill yes)
			(layer "F.Paste")
		)
		(fp_poly
			(pts
				(xy 0.3302 -1.09601) (xy 2.5019 -1.09601) (xy 2.5019 -3.36931) (xy 0.3302 -3.36931)
			)
			(stroke
				(width 0)
				(type default)
			)
			(fill yes)
			(layer "F.Paste")
		)
		(fp_rect
			(start -2.4511 0.3048)
			(end 2.4511 -5.6896)
			(stroke
				(width 0)
				(type default)
			)
			(fill no)
			(layer "F.CrtYd")
		)
		(fp_poly
			(pts
				(xy -3.0099 1.3208) (xy -3.0099 -6.8072) (xy 3.0099 -6.8072) (xy 3.0099 -1.016) (xy 2.4511 -1.016)
				(xy 2.4511 -5.6896) (xy -2.4511 -5.6896) (xy -2.4511 0.3048) (xy 2.4511 0.3048) (xy 2.4511 -1.0033)
				(xy 3.0099 -1.0033) (xy 3.0099 1.3208)
			)
			(stroke
				(width 0)
				(type default)
			)
			(fill no)
			(layer "F.CrtYd")
		)
		(fp_rect
			(start -3.0099 1.3208)
			(end 3.0099 -6.8072)
			(stroke
				(width 0)
				(type default)
			)
			(fill no)
			(layer "F.Fab")
		)
		(pad "1" smd rect
			(at -1.905 0)
			(size 0.762 1.6256)
			(layers "F.Cu" "F.Mask" "F.Paste")
			(net "P12V")
		)
		(pad "2" smd rect
			(at -0.635 0)
			(size 0.762 1.6256)
			(layers "F.Cu" "F.Mask" "F.Paste")
			(net "P12V")
		)
		(pad "3" smd rect
			(at 0.635 0)
			(size 0.762 1.6256)
			(layers "F.Cu" "F.Mask" "F.Paste")
			(net "P12V")
		)
		(pad "4" smd rect
			(at 1.905 0)
			(size 0.762 1.6256)
			(layers "F.Cu" "F.Mask" "F.Paste")
			(net "MB0_12V_CTRL_GATE1")
		)
		(pad "5" smd rect
			(at 0 -3.69951)
			(size 5.0038 5.207)
			(layers "F.Cu" "F.Mask" "F.Paste")
			(net "MB0_P12V_MAIN_R")
		)
	)
	(footprint ""
		(layer "F.Cu")
		(at 269.748 -30.607 -90)
		(property "Reference" "PL5"
			(at 0 0 270)
			(layer "F.SilkS")
			(hide yes)
			(effects
				(font
					(size 1.27 1.27)
				)
			)
		)
		(property "Value" "IND-2D2UH-122-GP"
			(at -5.2451 -0.6604 270)
			(unlocked yes)
			(layer "F.Fab")
			(hide yes)
			(effects
				(font
					(size 1.016 1.016)
					(thickness 0.1524)
				)
			)
		)
		(property "Device Type" "L686647H119"
			(at -5.2451 -2.1844 270)
			(unlocked yes)
			(layer "F.Fab")
			(hide yes)
			(effects
				(font
					(size 1.016 1.016)
					(thickness 0.1524)
				)
			)
		)
		(duplicate_pad_numbers_are_jumpers no)
		(fp_line
			(start -4.318 3.4925)
			(end -4.318 -3.4925)
			(stroke
				(width 0.1524)
				(type default)
			)
			(layer "F.SilkS")
		)
		(fp_line
			(start 4.318 3.4925)
			(end -4.318 3.4925)
			(stroke
				(width 0.1524)
				(type default)
			)
			(layer "F.SilkS")
		)
		(fp_line
			(start -4.318 -3.4925)
			(end 4.318 -3.4925)
			(stroke
				(width 0.1524)
				(type default)
			)
			(layer "F.SilkS")
		)
		(fp_line
			(start 4.318 -3.4925)
			(end 4.318 3.4925)
			(stroke
				(width 0.1524)
				(type default)
			)
			(layer "F.SilkS")
		)
		(fp_rect
			(start -3.429 3.2385)
			(end 3.429 -3.2385)
			(stroke
				(width 0)
				(type default)
			)
			(fill no)
			(layer "F.CrtYd")
		)
		(fp_poly
			(pts
				(xy -4.3942 -3.7465) (xy 4.3942 -3.7465) (xy 4.3942 3.7465) (xy -4.3942 3.7465) (xy -4.3942 3.2385)
				(xy 3.429 3.2385) (xy 3.429 -3.2385) (xy -3.429 -3.2385) (xy -3.429 3.2258) (xy -4.3942 3.2258)
			)
			(stroke
				(width 0)
				(type default)
			)
			(fill no)
			(layer "F.CrtYd")
		)
		(fp_rect
			(start -4.3942 3.7465)
			(end 4.3942 -3.7465)
			(stroke
				(width 0)
				(type default)
			)
			(fill no)
			(layer "F.Fab")
		)
		(pad "1" smd rect
			(at -3.1115 0 270)
			(size 2.159 3.429)
			(drill
				(offset 0.127 0)
			)
			(layers "F.Cu" "F.Mask" "F.Paste")
			(net "P1V8_STBY_LL")
		)
		(pad "2" smd rect
			(at 3.1115 0 270)
			(size 2.159 3.429)
			(drill
				(offset -0.127 0)
			)
			(layers "F.Cu" "F.Mask" "F.Paste")
			(net "P1V8_STBY")
		)
	)
	(footprint ""
		(layer "F.Cu")
		(at 285.496 -163.703)
		(property "Reference" "TP133"
			(at 0 0 0)
			(layer "F.SilkS")
			(hide yes)
			(effects
				(font
					(size 1.27 1.27)
				)
			)
		)
		(property "Value" "TPAD28"
			(at 0.0127 -1.8034 0)
			(unlocked yes)
			(layer "F.Fab")
			(hide yes)
			(effects
				(font
					(size 1.016 1.016)
					(thickness 0.1524)
				)
			)
		)
		(property "Device Type" "TPAD28"
			(at 0.0127 -3.3274 0)
			(unlocked yes)
			(layer "F.Fab")
			(hide yes)
			(effects
				(font
					(size 1.016 1.016)
					(thickness 0.1524)
				)
			)
		)
		(duplicate_pad_numbers_are_jumpers no)
		(fp_poly
			(pts
				(arc
					(start 0.3556 0)
					(mid -0.3556 0)
					(end 0.3556 0)
				)
			)
			(stroke
				(width 0)
				(type default)
			)
			(fill no)
			(layer "F.CrtYd")
		)
		(fp_poly
			(pts
				(arc
					(start 0.6096 0)
					(mid -0.6096 0)
					(end 0.6096 0)
				)
			)
			(stroke
				(width 0)
				(type default)
			)
			(fill no)
			(layer "F.Fab")
		)
		(pad "1" smd circle
			(at 0 0)
			(size 0.7112 0.7112)
			(layers "F.Cu" "F.Mask" "F.Paste")
			(net "TP_BMC_GPIOF4")
		)
	)
	(footprint ""
		(layer "F.Cu")
		(at 316.401958 -64.77 90)
		(property "Reference" "R224"
			(at 0 0 90)
			(layer "F.SilkS")
			(hide yes)
			(effects
				(font
					(size 1.27 1.27)
				)
			)
		)
		(property "Value" "0R2J-2-GP"
			(at 0.064008 -3.993896 90)
			(unlocked yes)
			(layer "F.Fab")
			(hide yes)
			(effects
				(font
					(size 1.016 1.016)
					(thickness 0.1524)
				)
			)
		)
		(property "Device Type" "R402H16"
			(at 0.064008 -5.517896 90)
			(unlocked yes)
			(layer "F.Fab")
			(hide yes)
			(effects
				(font
					(size 1.016 1.016)
					(thickness 0.1524)
				)
			)
		)
		(duplicate_pad_numbers_are_jumpers no)
		(fp_line
			(start 0.508 -0.9398)
			(end -0.508 -0.9398)
			(stroke
				(width 0.1524)
				(type default)
			)
			(layer "F.SilkS")
		)
		(fp_line
			(start -0.508 -0.9398)
			(end -0.508 0.9398)
			(stroke
				(width 0.1524)
				(type default)
			)
			(layer "F.SilkS")
		)
		(fp_rect
			(start -0.508 0.9398)
			(end 0.508 -0.9398)
			(stroke
				(width 0)
				(type default)
			)
			(fill no)
			(layer "F.CrtYd")
		)
		(fp_rect
			(start -0.508 0.9398)
			(end 0.508 -0.9398)
			(stroke
				(width 0)
				(type default)
			)
			(fill no)
			(layer "F.Fab")
		)
		(pad "1" smd custom
			(at 0 -0.4445 90)
			(size 0.1397 0.1397)
			(layers "F.Cu" "F.Mask" "F.Paste")
			(net "NCSI_10G_RXD0_R")
			(options
				(clearance outline)
				(anchor circle)
			)
			(primitives
				(gr_poly
					(pts
						(arc
							(start -0.1778 -0.2794)
							(mid -0.249642 -0.249642)
							(end -0.2794 -0.1778)
						)
						(arc
							(start -0.2794 0.1778)
							(mid -0.249642 0.249642)
							(end -0.1778 0.2794)
						)
						(arc
							(start 0.1778 0.2794)
							(mid 0.249642 0.249642)
							(end 0.2794 0.1778)
						)
						(arc
							(start 0.2794 -0.1778)
							(mid 0.249642 -0.249642)
							(end 0.1778 -0.2794)
						)
					)
					(width 0)
					(fill yes)
				)
			)
		)
		(pad "2" smd custom
			(at 0 0.4445 90)
			(size 0.1397 0.1397)
			(layers "F.Cu" "F.Mask" "F.Paste")
			(net "NCSI_10G_RXD0")
			(options
				(clearance outline)
				(anchor circle)
			)
			(primitives
				(gr_poly
					(pts
						(arc
							(start -0.1778 -0.2794)
							(mid -0.249642 -0.249642)
							(end -0.2794 -0.1778)
						)
						(arc
							(start -0.2794 0.1778)
							(mid -0.249642 0.249642)
							(end -0.1778 0.2794)
						)
						(arc
							(start 0.1778 0.2794)
							(mid 0.249642 0.249642)
							(end 0.2794 0.1778)
						)
						(arc
							(start 0.2794 -0.1778)
							(mid 0.249642 -0.249642)
							(end 0.1778 -0.2794)
						)
					)
					(width 0)
					(fill yes)
				)
			)
		)
	)
	(footprint ""
		(layer "F.Cu")
		(at 337.566 -75.692 -90)
		(property "Reference" "R680"
			(at 0 0 270)
			(layer "F.SilkS")
			(hide yes)
			(effects
				(font
					(size 1.27 1.27)
				)
			)
		)
		(property "Value" "0R2J-2-GP"
			(at 0.064008 -3.993896 270)
			(unlocked yes)
			(layer "F.Fab")
			(hide yes)
			(effects
				(font
					(size 1.016 1.016)
					(thickness 0.1524)
				)
			)
		)
		(property "Device Type" "R402H16"
			(at 0.064008 -5.517896 270)
			(unlocked yes)
			(layer "F.Fab")
			(hide yes)
			(effects
				(font
					(size 1.016 1.016)
					(thickness 0.1524)
				)
			)
		)
		(duplicate_pad_numbers_are_jumpers no)
		(fp_line
			(start -0.508 -0.9398)
			(end -0.508 0.9398)
			(stroke
				(width 0.1524)
				(type default)
			)
			(layer "F.SilkS")
		)
		(fp_line
			(start 0.508 -0.9398)
			(end -0.508 -0.9398)
			(stroke
				(width 0.1524)
				(type default)
			)
			(layer "F.SilkS")
		)
		(fp_rect
			(start -0.508 0.9398)
			(end 0.508 -0.9398)
			(stroke
				(width 0)
				(type default)
			)
			(fill no)
			(layer "F.CrtYd")
		)
		(fp_rect
			(start -0.508 0.9398)
			(end 0.508 -0.9398)
			(stroke
				(width 0)
				(type default)
			)
			(fill no)
			(layer "F.Fab")
		)
		(pad "1" smd custom
			(at 0 -0.4445 270)
			(size 0.1397 0.1397)
			(layers "F.Cu" "F.Mask" "F.Paste")
			(net "ROMD1_R")
			(options
				(clearance outline)
				(anchor circle)
			)
			(primitives
				(gr_poly
					(pts
						(arc
							(start -0.1778 -0.2794)
							(mid -0.249642 -0.249642)
							(end -0.2794 -0.1778)
						)
						(arc
							(start -0.2794 0.1778)
							(mid -0.249642 0.249642)
							(end -0.1778 0.2794)
						)
						(arc
							(start 0.1778 0.2794)
							(mid 0.249642 0.249642)
							(end 0.2794 0.1778)
						)
						(arc
							(start 0.2794 -0.1778)
							(mid 0.249642 -0.249642)
							(end 0.1778 -0.2794)
						)
					)
					(width 0)
					(fill yes)
				)
			)
		)
		(pad "2" smd custom
			(at 0 0.4445 270)
			(size 0.1397 0.1397)
			(layers "F.Cu" "F.Mask" "F.Paste")
			(net "ROMD1_R_R")
			(options
				(clearance outline)
				(anchor circle)
			)
			(primitives
				(gr_poly
					(pts
						(arc
							(start -0.1778 -0.2794)
							(mid -0.249642 -0.249642)
							(end -0.2794 -0.1778)
						)
						(arc
							(start -0.2794 0.1778)
							(mid -0.249642 0.249642)
							(end -0.1778 0.2794)
						)
						(arc
							(start 0.1778 0.2794)
							(mid 0.249642 0.249642)
							(end 0.2794 0.1778)
						)
						(arc
							(start 0.2794 -0.1778)
							(mid 0.249642 -0.249642)
							(end 0.1778 -0.2794)
						)
					)
					(width 0)
					(fill yes)
				)
			)
		)
	)
	(footprint ""
		(layer "F.Cu")
		(at 90.5002 -3.683)
		(property "Reference" "PC197"
			(at 0 0 0)
			(layer "F.SilkS")
			(hide yes)
			(effects
				(font
					(size 1.27 1.27)
				)
			)
		)
		(property "Value" "SC22U6D3V6KX-2-GP"
			(at -0.0762 -5.1308 0)
			(unlocked yes)
			(layer "F.Fab")
			(hide yes)
			(effects
				(font
					(size 1.016 1.016)
					(thickness 0.1524)
				)
			)
		)
		(property "Device Type" "C1206H71"
			(at -0.127 -6.6548 0)
			(unlocked yes)
			(layer "F.Fab")
			(hide yes)
			(effects
				(font
					(size 1.016 1.016)
					(thickness 0.1524)
				)
			)
		)
		(duplicate_pad_numbers_are_jumpers no)
		(fp_line
			(start -1.016 -2.2352)
			(end 1.016 -2.2352)
			(stroke
				(width 0.1524)
				(type default)
			)
			(layer "F.SilkS")
		)
		(fp_line
			(start -1.016 -0.8382)
			(end -1.016 -2.2352)
			(stroke
				(width 0.1524)
				(type default)
			)
			(layer "F.SilkS")
		)
		(fp_line
			(start -1.016 2.2352)
			(end -1.016 0.8382)
			(stroke
				(width 0.1524)
				(type default)
			)
			(layer "F.SilkS")
		)
		(fp_line
			(start 1.016 -2.2352)
			(end 1.016 -0.8382)
			(stroke
				(width 0.1524)
				(type default)
			)
			(layer "F.SilkS")
		)
		(fp_line
			(start 1.016 0.8382)
			(end 1.016 2.2352)
			(stroke
				(width 0.1524)
				(type default)
			)
			(layer "F.SilkS")
		)
		(fp_line
			(start 1.016 2.2352)
			(end -1.016 2.2352)
			(stroke
				(width 0.1524)
				(type default)
			)
			(layer "F.SilkS")
		)
		(fp_rect
			(start -1.0922 2.3114)
			(end 1.0922 -2.3114)
			(stroke
				(width 0)
				(type default)
			)
			(fill no)
			(layer "F.CrtYd")
		)
		(fp_poly
			(pts
				(xy 1.0922 -2.3114) (xy 1.0922 2.3114) (xy -1.0922 2.3114) (xy -1.0922 -2.3114)
			)
			(stroke
				(width 0)
				(type default)
			)
			(fill no)
			(layer "F.Fab")
		)
		(pad "1" smd rect
			(at 0 -1.397)
			(size 1.651 1.27)
			(layers "F.Cu" "F.Mask" "F.Paste")
			(net "P0V955_C")
		)
		(pad "2" smd rect
			(at 0 1.397)
			(size 1.651 1.27)
			(layers "F.Cu" "F.Mask" "F.Paste")
			(net "GND")
		)
	)
	(footprint ""
		(layer "F.Cu")
		(at 95.89897 -83.947 90)
		(property "Reference" "SR797"
			(at 0 0 90)
			(layer "F.SilkS")
			(hide yes)
			(effects
				(font
					(size 1.27 1.27)
				)
			)
		)
		(property "Value" "4K75R2F-1-GP"
			(at 0.064008 -3.993896 90)
			(unlocked yes)
			(layer "F.Fab")
			(hide yes)
			(effects
				(font
					(size 1.016 1.016)
					(thickness 0.1524)
				)
			)
		)
		(property "Device Type" "R402H16"
			(at 0.064008 -5.517896 90)
			(unlocked yes)
			(layer "F.Fab")
			(hide yes)
			(effects
				(font
					(size 1.016 1.016)
					(thickness 0.1524)
				)
			)
		)
		(duplicate_pad_numbers_are_jumpers no)
		(fp_line
			(start 0.508 -0.9398)
			(end -0.508 -0.9398)
			(stroke
				(width 0.1524)
				(type default)
			)
			(layer "F.SilkS")
		)
		(fp_line
			(start -0.508 -0.9398)
			(end -0.508 0.9398)
			(stroke
				(width 0.1524)
				(type default)
			)
			(layer "F.SilkS")
		)
		(fp_rect
			(start -0.508 0.9398)
			(end 0.508 -0.9398)
			(stroke
				(width 0)
				(type default)
			)
			(fill no)
			(layer "F.CrtYd")
		)
		(fp_rect
			(start -0.508 0.9398)
			(end 0.508 -0.9398)
			(stroke
				(width 0)
				(type default)
			)
			(fill no)
			(layer "F.Fab")
		)
		(pad "1" smd custom
			(at 0 -0.4445 90)
			(size 0.1397 0.1397)
			(layers "F.Cu" "F.Mask" "F.Paste")
			(net "P1V8_E")
			(options
				(clearance outline)
				(anchor circle)
			)
			(primitives
				(gr_poly
					(pts
						(arc
							(start -0.1778 -0.2794)
							(mid -0.249642 -0.249642)
							(end -0.2794 -0.1778)
						)
						(arc
							(start -0.2794 0.1778)
							(mid -0.249642 0.249642)
							(end -0.1778 0.2794)
						)
						(arc
							(start 0.1778 0.2794)
							(mid 0.249642 0.249642)
							(end 0.2794 0.1778)
						)
						(arc
							(start 0.2794 -0.1778)
							(mid 0.249642 -0.249642)
							(end 0.1778 -0.2794)
						)
					)
					(width 0)
					(fill yes)
				)
			)
		)
		(pad "2" smd custom
			(at 0 0.4445 90)
			(size 0.1397 0.1397)
			(layers "F.Cu" "F.Mask" "F.Paste")
			(net "EXP_CLK_SEL1")
			(options
				(clearance outline)
				(anchor circle)
			)
			(primitives
				(gr_poly
					(pts
						(arc
							(start -0.1778 -0.2794)
							(mid -0.249642 -0.249642)
							(end -0.2794 -0.1778)
						)
						(arc
							(start -0.2794 0.1778)
							(mid -0.249642 0.249642)
							(end -0.1778 0.2794)
						)
						(arc
							(start 0.1778 0.2794)
							(mid 0.249642 0.249642)
							(end 0.2794 0.1778)
						)
						(arc
							(start 0.2794 -0.1778)
							(mid 0.249642 -0.249642)
							(end 0.1778 -0.2794)
						)
					)
					(width 0)
					(fill yes)
				)
			)
		)
	)
	(footprint ""
		(layer "F.Cu")
		(at 340.516718 -157.330648 -90)
		(property "Reference" "R228"
			(at 0 0 270)
			(layer "F.SilkS")
			(hide yes)
			(effects
				(font
					(size 1.27 1.27)
				)
			)
		)
		(property "Value" "4K7R2F-GP"
			(at 0.064008 -3.993896 270)
			(unlocked yes)
			(layer "F.Fab")
			(hide yes)
			(effects
				(font
					(size 1.016 1.016)
					(thickness 0.1524)
				)
			)
		)
		(property "Device Type" "R402H16"
			(at 0.064008 -5.517896 270)
			(unlocked yes)
			(layer "F.Fab")
			(hide yes)
			(effects
				(font
					(size 1.016 1.016)
					(thickness 0.1524)
				)
			)
		)
		(duplicate_pad_numbers_are_jumpers no)
		(fp_line
			(start -0.508 -0.9398)
			(end -0.508 0.9398)
			(stroke
				(width 0.1524)
				(type default)
			)
			(layer "F.SilkS")
		)
		(fp_line
			(start 0.508 -0.9398)
			(end -0.508 -0.9398)
			(stroke
				(width 0.1524)
				(type default)
			)
			(layer "F.SilkS")
		)
		(fp_rect
			(start -0.508 0.9398)
			(end 0.508 -0.9398)
			(stroke
				(width 0)
				(type default)
			)
			(fill no)
			(layer "F.CrtYd")
		)
		(fp_rect
			(start -0.508 0.9398)
			(end 0.508 -0.9398)
			(stroke
				(width 0)
				(type default)
			)
			(fill no)
			(layer "F.Fab")
		)
		(pad "1" smd custom
			(at 0 -0.4445 270)
			(size 0.1397 0.1397)
			(layers "F.Cu" "F.Mask" "F.Paste")
			(net "P3V3_STBY")
			(options
				(clearance outline)
				(anchor circle)
			)
			(primitives
				(gr_poly
					(pts
						(arc
							(start -0.1778 -0.2794)
							(mid -0.249642 -0.249642)
							(end -0.2794 -0.1778)
						)
						(arc
							(start -0.2794 0.1778)
							(mid -0.249642 0.249642)
							(end -0.1778 0.2794)
						)
						(arc
							(start 0.1778 0.2794)
							(mid 0.249642 0.249642)
							(end 0.2794 0.1778)
						)
						(arc
							(start 0.2794 -0.1778)
							(mid 0.249642 -0.249642)
							(end 0.1778 -0.2794)
						)
					)
					(width 0)
					(fill yes)
				)
			)
		)
		(pad "2" smd custom
			(at 0 0.4445 270)
			(size 0.1397 0.1397)
			(layers "F.Cu" "F.Mask" "F.Paste")
			(net "USB_EN_2")
			(options
				(clearance outline)
				(anchor circle)
			)
			(primitives
				(gr_poly
					(pts
						(arc
							(start -0.1778 -0.2794)
							(mid -0.249642 -0.249642)
							(end -0.2794 -0.1778)
						)
						(arc
							(start -0.2794 0.1778)
							(mid -0.249642 0.249642)
							(end -0.1778 0.2794)
						)
						(arc
							(start 0.1778 0.2794)
							(mid 0.249642 0.249642)
							(end 0.2794 0.1778)
						)
						(arc
							(start 0.2794 -0.1778)
							(mid 0.249642 -0.249642)
							(end 0.1778 -0.2794)
						)
					)
					(width 0)
					(fill yes)
				)
			)
		)
	)
	(footprint ""
		(layer "F.Cu")
		(at 48.14697 -144.399)
		(property "Reference" "SR791"
			(at 0 0 0)
			(layer "F.SilkS")
			(hide yes)
			(effects
				(font
					(size 1.27 1.27)
				)
			)
		)
		(property "Value" "4K7R2F-GP"
			(at 0.064008 -3.993896 0)
			(unlocked yes)
			(layer "F.Fab")
			(hide yes)
			(effects
				(font
					(size 1.016 1.016)
					(thickness 0.1524)
				)
			)
		)
		(property "Device Type" "R402H16"
			(at 0.064008 -5.517896 0)
			(unlocked yes)
			(layer "F.Fab")
			(hide yes)
			(effects
				(font
					(size 1.016 1.016)
					(thickness 0.1524)
				)
			)
		)
		(duplicate_pad_numbers_are_jumpers no)
		(fp_line
			(start -0.508 -0.9398)
			(end -0.508 0.9398)
			(stroke
				(width 0.1524)
				(type default)
			)
			(layer "F.SilkS")
		)
		(fp_line
			(start 0.508 -0.9398)
			(end -0.508 -0.9398)
			(stroke
				(width 0.1524)
				(type default)
			)
			(layer "F.SilkS")
		)
		(fp_rect
			(start -0.508 0.9398)
			(end 0.508 -0.9398)
			(stroke
				(width 0)
				(type default)
			)
			(fill no)
			(layer "F.CrtYd")
		)
		(fp_rect
			(start -0.508 0.9398)
			(end 0.508 -0.9398)
			(stroke
				(width 0)
				(type default)
			)
			(fill no)
			(layer "F.Fab")
		)
		(pad "1" smd custom
			(at 0 -0.4445)
			(size 0.1397 0.1397)
			(layers "F.Cu" "F.Mask" "F.Paste")
			(net "P1V8_E")
			(options
				(clearance outline)
				(anchor circle)
			)
			(primitives
				(gr_poly
					(pts
						(arc
							(start -0.1778 -0.2794)
							(mid -0.249642 -0.249642)
							(end -0.2794 -0.1778)
						)
						(arc
							(start -0.2794 0.1778)
							(mid -0.249642 0.249642)
							(end -0.1778 0.2794)
						)
						(arc
							(start 0.1778 0.2794)
							(mid 0.249642 0.249642)
							(end 0.2794 0.1778)
						)
						(arc
							(start 0.2794 -0.1778)
							(mid 0.249642 -0.249642)
							(end 0.1778 -0.2794)
						)
					)
					(width 0)
					(fill yes)
				)
			)
		)
		(pad "2" smd custom
			(at 0 0.4445)
			(size 0.1397 0.1397)
			(layers "F.Cu" "F.Mask" "F.Paste")
			(net "EXP_RESET_N")
			(options
				(clearance outline)
				(anchor circle)
			)
			(primitives
				(gr_poly
					(pts
						(arc
							(start -0.1778 -0.2794)
							(mid -0.249642 -0.249642)
							(end -0.2794 -0.1778)
						)
						(arc
							(start -0.2794 0.1778)
							(mid -0.249642 0.249642)
							(end -0.1778 0.2794)
						)
						(arc
							(start 0.1778 0.2794)
							(mid 0.249642 0.249642)
							(end 0.2794 0.1778)
						)
						(arc
							(start 0.2794 -0.1778)
							(mid 0.249642 -0.249642)
							(end 0.1778 -0.2794)
						)
					)
					(width 0)
					(fill yes)
				)
			)
		)
	)
	(footprint ""
		(layer "F.Cu")
		(at 23.064216 -207.06588 -90)
		(property "Reference" "R571"
			(at 0 0 270)
			(layer "F.SilkS")
			(hide yes)
			(effects
				(font
					(size 1.27 1.27)
				)
			)
		)
		(property "Value" "4K7R2F-GP"
			(at 0.064008 -3.993896 270)
			(unlocked yes)
			(layer "F.Fab")
			(hide yes)
			(effects
				(font
					(size 1.016 1.016)
					(thickness 0.1524)
				)
			)
		)
		(property "Device Type" "R402H16"
			(at 0.064008 -5.517896 270)
			(unlocked yes)
			(layer "F.Fab")
			(hide yes)
			(effects
				(font
					(size 1.016 1.016)
					(thickness 0.1524)
				)
			)
		)
		(duplicate_pad_numbers_are_jumpers no)
		(fp_line
			(start -0.508 -0.9398)
			(end -0.508 0.9398)
			(stroke
				(width 0.1524)
				(type default)
			)
			(layer "F.SilkS")
		)
		(fp_line
			(start 0.508 -0.9398)
			(end -0.508 -0.9398)
			(stroke
				(width 0.1524)
				(type default)
			)
			(layer "F.SilkS")
		)
		(fp_rect
			(start -0.508 0.9398)
			(end 0.508 -0.9398)
			(stroke
				(width 0)
				(type default)
			)
			(fill no)
			(layer "F.CrtYd")
		)
		(fp_rect
			(start -0.508 0.9398)
			(end 0.508 -0.9398)
			(stroke
				(width 0)
				(type default)
			)
			(fill no)
			(layer "F.Fab")
		)
		(pad "1" smd custom
			(at 0 -0.4445 270)
			(size 0.1397 0.1397)
			(layers "F.Cu" "F.Mask" "F.Paste")
			(net "VOL_SEN_ADDR_U17")
			(options
				(clearance outline)
				(anchor circle)
			)
			(primitives
				(gr_poly
					(pts
						(arc
							(start -0.1778 -0.2794)
							(mid -0.249642 -0.249642)
							(end -0.2794 -0.1778)
						)
						(arc
							(start -0.2794 0.1778)
							(mid -0.249642 0.249642)
							(end -0.1778 0.2794)
						)
						(arc
							(start 0.1778 0.2794)
							(mid 0.249642 0.249642)
							(end 0.2794 0.1778)
						)
						(arc
							(start 0.2794 -0.1778)
							(mid 0.249642 -0.249642)
							(end 0.1778 -0.2794)
						)
					)
					(width 0)
					(fill yes)
				)
			)
		)
		(pad "2" smd custom
			(at 0 0.4445 270)
			(size 0.1397 0.1397)
			(layers "F.Cu" "F.Mask" "F.Paste")
			(net "GND")
			(options
				(clearance outline)
				(anchor circle)
			)
			(primitives
				(gr_poly
					(pts
						(arc
							(start -0.1778 -0.2794)
							(mid -0.249642 -0.249642)
							(end -0.2794 -0.1778)
						)
						(arc
							(start -0.2794 0.1778)
							(mid -0.249642 0.249642)
							(end -0.1778 0.2794)
						)
						(arc
							(start 0.1778 0.2794)
							(mid 0.249642 0.249642)
							(end 0.2794 0.1778)
						)
						(arc
							(start 0.2794 -0.1778)
							(mid 0.249642 -0.249642)
							(end 0.1778 -0.2794)
						)
					)
					(width 0)
					(fill yes)
				)
			)
		)
	)
	(footprint ""
		(layer "F.Cu")
		(at 256.794 -126.619)
		(property "Reference" "R7900"
			(at 0 0 0)
			(layer "F.SilkS")
			(hide yes)
			(effects
				(font
					(size 1.27 1.27)
				)
			)
		)
		(property "Value" "0R2J-2-GP"
			(at 0.064008 -3.993896 0)
			(unlocked yes)
			(layer "F.Fab")
			(hide yes)
			(effects
				(font
					(size 1.016 1.016)
					(thickness 0.1524)
				)
			)
		)
		(property "Device Type" "R402H16"
			(at 0.064008 -5.517896 0)
			(unlocked yes)
			(layer "F.Fab")
			(hide yes)
			(effects
				(font
					(size 1.016 1.016)
					(thickness 0.1524)
				)
			)
		)
		(duplicate_pad_numbers_are_jumpers no)
		(fp_line
			(start -0.508 -0.9398)
			(end -0.508 0.9398)
			(stroke
				(width 0.1524)
				(type default)
			)
			(layer "F.SilkS")
		)
		(fp_line
			(start 0.508 -0.9398)
			(end -0.508 -0.9398)
			(stroke
				(width 0.1524)
				(type default)
			)
			(layer "F.SilkS")
		)
		(fp_rect
			(start -0.508 0.9398)
			(end 0.508 -0.9398)
			(stroke
				(width 0)
				(type default)
			)
			(fill no)
			(layer "F.CrtYd")
		)
		(fp_rect
			(start -0.508 0.9398)
			(end 0.508 -0.9398)
			(stroke
				(width 0)
				(type default)
			)
			(fill no)
			(layer "F.Fab")
		)
		(pad "1" smd custom
			(at 0 -0.4445)
			(size 0.1397 0.1397)
			(layers "F.Cu" "F.Mask" "F.Paste")
			(net "CPU_U192_PIN2_TX")
			(options
				(clearance outline)
				(anchor circle)
			)
			(primitives
				(gr_poly
					(pts
						(arc
							(start -0.1778 -0.2794)
							(mid -0.249642 -0.249642)
							(end -0.2794 -0.1778)
						)
						(arc
							(start -0.2794 0.1778)
							(mid -0.249642 0.249642)
							(end -0.1778 0.2794)
						)
						(arc
							(start 0.1778 0.2794)
							(mid 0.249642 0.249642)
							(end 0.2794 0.1778)
						)
						(arc
							(start 0.2794 -0.1778)
							(mid 0.249642 -0.249642)
							(end 0.1778 -0.2794)
						)
					)
					(width 0)
					(fill yes)
				)
			)
		)
		(pad "2" smd custom
			(at 0 0.4445)
			(size 0.1397 0.1397)
			(layers "F.Cu" "F.Mask" "F.Paste")
			(net "CPU_TXD")
			(options
				(clearance outline)
				(anchor circle)
			)
			(primitives
				(gr_poly
					(pts
						(arc
							(start -0.1778 -0.2794)
							(mid -0.249642 -0.249642)
							(end -0.2794 -0.1778)
						)
						(arc
							(start -0.2794 0.1778)
							(mid -0.249642 0.249642)
							(end -0.1778 0.2794)
						)
						(arc
							(start 0.1778 0.2794)
							(mid 0.249642 0.249642)
							(end 0.2794 0.1778)
						)
						(arc
							(start 0.2794 -0.1778)
							(mid 0.249642 -0.249642)
							(end 0.1778 -0.2794)
						)
					)
					(width 0)
					(fill yes)
				)
			)
		)
	)
	(footprint ""
		(layer "F.Cu")
		(at 208.407 -97.028 -90)
		(property "Reference" "PC144"
			(at 0 0 270)
			(layer "F.SilkS")
			(hide yes)
			(effects
				(font
					(size 1.27 1.27)
				)
			)
		)
		(property "Value" "SC10U6D3V5KX-1GP"
			(at -0.0762 -6.1214 270)
			(unlocked yes)
			(layer "F.Fab")
			(hide yes)
			(effects
				(font
					(size 1.016 1.016)
					(thickness 0.1524)
				)
			)
		)
		(property "Device Type" "C805H54"
			(at -0.0762 -8.1534 270)
			(unlocked yes)
			(layer "F.Fab")
			(hide yes)
			(effects
				(font
					(size 1.016 1.016)
					(thickness 0.1524)
				)
			)
		)
		(duplicate_pad_numbers_are_jumpers no)
		(fp_line
			(start 0.635 0)
			(end -0.635 0)
			(stroke
				(width 0.508)
				(type default)
			)
			(layer "F.SilkS")
		)
		(fp_rect
			(start -0.9652 1.778)
			(end 0.9652 -1.778)
			(stroke
				(width 0)
				(type default)
			)
			(fill no)
			(layer "F.CrtYd")
		)
		(fp_poly
			(pts
				(xy -0.9652 -1.778) (xy 0.9652 -1.778) (xy 0.9652 1.778) (xy -0.9652 1.778)
			)
			(stroke
				(width 0)
				(type default)
			)
			(fill no)
			(layer "F.Fab")
		)
		(pad "1" smd rect
			(at 0 -0.9652 270)
			(size 1.397 1.143)
			(layers "F.Cu" "F.Mask" "F.Paste")
			(net "P1V5_C")
		)
		(pad "2" smd rect
			(at 0 0.9652 270)
			(size 1.397 1.143)
			(layers "F.Cu" "F.Mask" "F.Paste")
			(net "GND")
		)
	)
	(footprint ""
		(layer "F.Cu")
		(at 104.15397 -114.3 180)
		(property "Reference" "SC1088"
			(at 0 0 180)
			(layer "F.SilkS")
			(hide yes)
			(effects
				(font
					(size 1.27 1.27)
				)
			)
		)
		(property "Value" "SCD01U10V1KX-GP"
			(at -2.8321 -1.7399 180)
			(unlocked yes)
			(layer "F.Fab")
			(hide yes)
			(effects
				(font
					(size 1.016 1.016)
					(thickness 0.1524)
				)
			)
		)
		(property "Device Type" "C0201H13"
			(at -2.8321 -3.2639 180)
			(unlocked yes)
			(layer "F.Fab")
			(hide yes)
			(effects
				(font
					(size 1.016 1.016)
					(thickness 0.1524)
				)
			)
		)
		(duplicate_pad_numbers_are_jumpers no)
		(fp_rect
			(start -0.2794 0.6477)
			(end 0.2794 -0.6477)
			(stroke
				(width 0)
				(type default)
			)
			(fill no)
			(layer "F.CrtYd")
		)
		(fp_rect
			(start -0.2794 0.6477)
			(end 0.2794 -0.6477)
			(stroke
				(width 0)
				(type default)
			)
			(fill no)
			(layer "F.Fab")
		)
		(pad "1" smd custom
			(at 0 -0.2794 180)
			(size 0.0762 0.0762)
			(layers "F.Cu" "F.Mask" "F.Paste")
			(net "SAS_HDD_TX10_P")
			(options
				(clearance outline)
				(anchor circle)
			)
			(primitives
				(gr_poly
					(pts
						(arc
							(start 0.1524 -0.127)
							(mid 0.137521 -0.162921)
							(end 0.1016 -0.1778)
						)
						(arc
							(start -0.1016 -0.1778)
							(mid -0.137521 -0.162921)
							(end -0.1524 -0.127)
						)
						(arc
							(start -0.1524 0.127)
							(mid -0.137521 0.162921)
							(end -0.1016 0.1778)
						)
						(arc
							(start 0.1016 0.1778)
							(mid 0.137521 0.162921)
							(end 0.1524 0.127)
						)
					)
					(width 0)
					(fill yes)
				)
			)
		)
		(pad "2" smd custom
			(at 0 0.2794 180)
			(size 0.0762 0.0762)
			(layers "F.Cu" "F.Mask" "F.Paste")
			(net "SAS_EXP_GF_TX_DP14")
			(options
				(clearance outline)
				(anchor circle)
			)
			(primitives
				(gr_poly
					(pts
						(arc
							(start 0.1524 -0.127)
							(mid 0.137521 -0.162921)
							(end 0.1016 -0.1778)
						)
						(arc
							(start -0.1016 -0.1778)
							(mid -0.137521 -0.162921)
							(end -0.1524 -0.127)
						)
						(arc
							(start -0.1524 0.127)
							(mid -0.137521 0.162921)
							(end -0.1016 0.1778)
						)
						(arc
							(start 0.1016 0.1778)
							(mid 0.137521 0.162921)
							(end 0.1524 0.127)
						)
					)
					(width 0)
					(fill yes)
				)
			)
		)
	)
	(footprint ""
		(layer "F.Cu")
		(at 274.193 -179.705 90)
		(property "Reference" "R363"
			(at 0 0 90)
			(layer "F.SilkS")
			(hide yes)
			(effects
				(font
					(size 1.27 1.27)
				)
			)
		)
		(property "Value" "3K3R2F-2-GP"
			(at 0.064008 -3.993896 90)
			(unlocked yes)
			(layer "F.Fab")
			(hide yes)
			(effects
				(font
					(size 1.016 1.016)
					(thickness 0.1524)
				)
			)
		)
		(property "Device Type" "R402H16"
			(at 0.064008 -5.517896 90)
			(unlocked yes)
			(layer "F.Fab")
			(hide yes)
			(effects
				(font
					(size 1.016 1.016)
					(thickness 0.1524)
				)
			)
		)
		(duplicate_pad_numbers_are_jumpers no)
		(fp_line
			(start 0.508 -0.9398)
			(end -0.508 -0.9398)
			(stroke
				(width 0.1524)
				(type default)
			)
			(layer "F.SilkS")
		)
		(fp_line
			(start -0.508 -0.9398)
			(end -0.508 0.9398)
			(stroke
				(width 0.1524)
				(type default)
			)
			(layer "F.SilkS")
		)
		(fp_rect
			(start -0.508 0.9398)
			(end 0.508 -0.9398)
			(stroke
				(width 0)
				(type default)
			)
			(fill no)
			(layer "F.CrtYd")
		)
		(fp_rect
			(start -0.508 0.9398)
			(end 0.508 -0.9398)
			(stroke
				(width 0)
				(type default)
			)
			(fill no)
			(layer "F.Fab")
		)
		(pad "1" smd custom
			(at 0 -0.4445 90)
			(size 0.1397 0.1397)
			(layers "F.Cu" "F.Mask" "F.Paste")
			(net "P3V3_STBY")
			(options
				(clearance outline)
				(anchor circle)
			)
			(primitives
				(gr_poly
					(pts
						(arc
							(start -0.1778 -0.2794)
							(mid -0.249642 -0.249642)
							(end -0.2794 -0.1778)
						)
						(arc
							(start -0.2794 0.1778)
							(mid -0.249642 0.249642)
							(end -0.1778 0.2794)
						)
						(arc
							(start 0.1778 0.2794)
							(mid 0.249642 0.249642)
							(end 0.2794 0.1778)
						)
						(arc
							(start 0.2794 -0.1778)
							(mid 0.249642 -0.249642)
							(end 0.1778 -0.2794)
						)
					)
					(width 0)
					(fill yes)
				)
			)
		)
		(pad "2" smd custom
			(at 0 0.4445 90)
			(size 0.1397 0.1397)
			(layers "F.Cu" "F.Mask" "F.Paste")
			(net "ROMA6")
			(options
				(clearance outline)
				(anchor circle)
			)
			(primitives
				(gr_poly
					(pts
						(arc
							(start -0.1778 -0.2794)
							(mid -0.249642 -0.249642)
							(end -0.2794 -0.1778)
						)
						(arc
							(start -0.2794 0.1778)
							(mid -0.249642 0.249642)
							(end -0.1778 0.2794)
						)
						(arc
							(start 0.1778 0.2794)
							(mid 0.249642 0.249642)
							(end 0.2794 0.1778)
						)
						(arc
							(start 0.2794 -0.1778)
							(mid 0.249642 -0.249642)
							(end 0.1778 -0.2794)
						)
					)
					(width 0)
					(fill yes)
				)
			)
		)
	)
	(footprint ""
		(layer "F.Cu")
		(at 278.511 -182.118)
		(property "Reference" "TP96"
			(at 0 0 0)
			(layer "F.SilkS")
			(hide yes)
			(effects
				(font
					(size 1.27 1.27)
				)
			)
		)
		(property "Value" "TPAD28"
			(at 0.0127 -1.8034 0)
			(unlocked yes)
			(layer "F.Fab")
			(hide yes)
			(effects
				(font
					(size 1.016 1.016)
					(thickness 0.1524)
				)
			)
		)
		(property "Device Type" "TPAD28"
			(at 0.0127 -3.3274 0)
			(unlocked yes)
			(layer "F.Fab")
			(hide yes)
			(effects
				(font
					(size 1.016 1.016)
					(thickness 0.1524)
				)
			)
		)
		(duplicate_pad_numbers_are_jumpers no)
		(fp_poly
			(pts
				(arc
					(start 0.3556 0)
					(mid -0.3556 0)
					(end 0.3556 0)
				)
			)
			(stroke
				(width 0)
				(type default)
			)
			(fill no)
			(layer "F.CrtYd")
		)
		(fp_poly
			(pts
				(arc
					(start 0.6096 0)
					(mid -0.6096 0)
					(end 0.6096 0)
				)
			)
			(stroke
				(width 0)
				(type default)
			)
			(fill no)
			(layer "F.Fab")
		)
		(pad "1" smd circle
			(at 0 0)
			(size 0.7112 0.7112)
			(layers "F.Cu" "F.Mask" "F.Paste")
			(net "TP_BMC_GPIOR4")
		)
	)
	(footprint ""
		(layer "F.Cu")
		(at 78.8924 -6.985 90)
		(property "Reference" "PC205"
			(at 0 0 90)
			(layer "F.SilkS")
			(hide yes)
			(effects
				(font
					(size 1.27 1.27)
				)
			)
		)
		(property "Value" "SC10U25V6KX-1GP"
			(at -0.0762 -5.1308 90)
			(unlocked yes)
			(layer "F.Fab")
			(hide yes)
			(effects
				(font
					(size 1.016 1.016)
					(thickness 0.1524)
				)
			)
		)
		(property "Device Type" "C1206H71"
			(at -0.127 -6.6548 90)
			(unlocked yes)
			(layer "F.Fab")
			(hide yes)
			(effects
				(font
					(size 1.016 1.016)
					(thickness 0.1524)
				)
			)
		)
		(duplicate_pad_numbers_are_jumpers no)
		(fp_line
			(start 1.016 -2.2352)
			(end 1.016 -0.8382)
			(stroke
				(width 0.1524)
				(type default)
			)
			(layer "F.SilkS")
		)
		(fp_line
			(start -1.016 -2.2352)
			(end 1.016 -2.2352)
			(stroke
				(width 0.1524)
				(type default)
			)
			(layer "F.SilkS")
		)
		(fp_line
			(start -1.016 -0.8382)
			(end -1.016 -2.2352)
			(stroke
				(width 0.1524)
				(type default)
			)
			(layer "F.SilkS")
		)
		(fp_line
			(start 1.016 0.8382)
			(end 1.016 2.2352)
			(stroke
				(width 0.1524)
				(type default)
			)
			(layer "F.SilkS")
		)
		(fp_line
			(start 1.016 2.2352)
			(end -1.016 2.2352)
			(stroke
				(width 0.1524)
				(type default)
			)
			(layer "F.SilkS")
		)
		(fp_line
			(start -1.016 2.2352)
			(end -1.016 0.8382)
			(stroke
				(width 0.1524)
				(type default)
			)
			(layer "F.SilkS")
		)
		(fp_rect
			(start -1.0922 2.3114)
			(end 1.0922 -2.3114)
			(stroke
				(width 0)
				(type default)
			)
			(fill no)
			(layer "F.CrtYd")
		)
		(fp_poly
			(pts
				(xy 1.0922 -2.3114) (xy 1.0922 2.3114) (xy -1.0922 2.3114) (xy -1.0922 -2.3114)
			)
			(stroke
				(width 0)
				(type default)
			)
			(fill no)
			(layer "F.Fab")
		)
		(pad "1" smd rect
			(at 0 -1.397 90)
			(size 1.651 1.27)
			(layers "F.Cu" "F.Mask" "F.Paste")
			(net "VT235_VDDH")
		)
		(pad "2" smd rect
			(at 0 1.397 90)
			(size 1.651 1.27)
			(layers "F.Cu" "F.Mask" "F.Paste")
			(net "GND")
		)
	)
	(footprint ""
		(layer "F.Cu")
		(at 223.393 -112.395 180)
		(property "Reference" "R603"
			(at 0 0 180)
			(layer "F.SilkS")
			(hide yes)
			(effects
				(font
					(size 1.27 1.27)
				)
			)
		)
		(property "Value" "4K7R2F-GP"
			(at 0.064008 -3.993896 180)
			(unlocked yes)
			(layer "F.Fab")
			(hide yes)
			(effects
				(font
					(size 1.016 1.016)
					(thickness 0.1524)
				)
			)
		)
		(property "Device Type" "R402H16"
			(at 0.064008 -5.517896 180)
			(unlocked yes)
			(layer "F.Fab")
			(hide yes)
			(effects
				(font
					(size 1.016 1.016)
					(thickness 0.1524)
				)
			)
		)
		(duplicate_pad_numbers_are_jumpers no)
		(fp_line
			(start 0.508 -0.9398)
			(end -0.508 -0.9398)
			(stroke
				(width 0.1524)
				(type default)
			)
			(layer "F.SilkS")
		)
		(fp_line
			(start -0.508 -0.9398)
			(end -0.508 0.9398)
			(stroke
				(width 0.1524)
				(type default)
			)
			(layer "F.SilkS")
		)
		(fp_rect
			(start -0.508 0.9398)
			(end 0.508 -0.9398)
			(stroke
				(width 0)
				(type default)
			)
			(fill no)
			(layer "F.CrtYd")
		)
		(fp_rect
			(start -0.508 0.9398)
			(end 0.508 -0.9398)
			(stroke
				(width 0)
				(type default)
			)
			(fill no)
			(layer "F.Fab")
		)
		(pad "1" smd custom
			(at 0 -0.4445 180)
			(size 0.1397 0.1397)
			(layers "F.Cu" "F.Mask" "F.Paste")
			(net "P1V8_STBY")
			(options
				(clearance outline)
				(anchor circle)
			)
			(primitives
				(gr_poly
					(pts
						(arc
							(start -0.1778 -0.2794)
							(mid -0.249642 -0.249642)
							(end -0.2794 -0.1778)
						)
						(arc
							(start -0.2794 0.1778)
							(mid -0.249642 0.249642)
							(end -0.1778 0.2794)
						)
						(arc
							(start 0.1778 0.2794)
							(mid 0.249642 0.249642)
							(end 0.2794 0.1778)
						)
						(arc
							(start 0.2794 -0.1778)
							(mid 0.249642 -0.249642)
							(end 0.1778 -0.2794)
						)
					)
					(width 0)
					(fill yes)
				)
			)
		)
		(pad "2" smd custom
			(at 0 0.4445 180)
			(size 0.1397 0.1397)
			(layers "F.Cu" "F.Mask" "F.Paste")
			(net "P1V8_PG_R_2")
			(options
				(clearance outline)
				(anchor circle)
			)
			(primitives
				(gr_poly
					(pts
						(arc
							(start -0.1778 -0.2794)
							(mid -0.249642 -0.249642)
							(end -0.2794 -0.1778)
						)
						(arc
							(start -0.2794 0.1778)
							(mid -0.249642 0.249642)
							(end -0.1778 0.2794)
						)
						(arc
							(start 0.1778 0.2794)
							(mid 0.249642 0.249642)
							(end 0.2794 0.1778)
						)
						(arc
							(start 0.2794 -0.1778)
							(mid 0.249642 -0.249642)
							(end 0.1778 -0.2794)
						)
					)
					(width 0)
					(fill yes)
				)
			)
		)
	)
	(footprint ""
		(layer "F.Cu")
		(at 261.239 -43.942 90)
		(property "Reference" "PR55"
			(at 0 0 90)
			(layer "F.SilkS")
			(hide yes)
			(effects
				(font
					(size 1.27 1.27)
				)
			)
		)
		(property "Value" "619KR2F-GP"
			(at 0.064008 -3.993896 90)
			(unlocked yes)
			(layer "F.Fab")
			(hide yes)
			(effects
				(font
					(size 1.016 1.016)
					(thickness 0.1524)
				)
			)
		)
		(property "Device Type" "R402H16"
			(at 0.064008 -5.517896 90)
			(unlocked yes)
			(layer "F.Fab")
			(hide yes)
			(effects
				(font
					(size 1.016 1.016)
					(thickness 0.1524)
				)
			)
		)
		(duplicate_pad_numbers_are_jumpers no)
		(fp_line
			(start 0.508 -0.9398)
			(end -0.508 -0.9398)
			(stroke
				(width 0.1524)
				(type default)
			)
			(layer "F.SilkS")
		)
		(fp_line
			(start -0.508 -0.9398)
			(end -0.508 0.9398)
			(stroke
				(width 0.1524)
				(type default)
			)
			(layer "F.SilkS")
		)
		(fp_rect
			(start -0.508 0.9398)
			(end 0.508 -0.9398)
			(stroke
				(width 0)
				(type default)
			)
			(fill no)
			(layer "F.CrtYd")
		)
		(fp_rect
			(start -0.508 0.9398)
			(end 0.508 -0.9398)
			(stroke
				(width 0)
				(type default)
			)
			(fill no)
			(layer "F.Fab")
		)
		(pad "1" smd custom
			(at 0 -0.4445 90)
			(size 0.1397 0.1397)
			(layers "F.Cu" "F.Mask" "F.Paste")
			(net "AGND_P1V8_STBY")
			(options
				(clearance outline)
				(anchor circle)
			)
			(primitives
				(gr_poly
					(pts
						(arc
							(start -0.1778 -0.2794)
							(mid -0.249642 -0.249642)
							(end -0.2794 -0.1778)
						)
						(arc
							(start -0.2794 0.1778)
							(mid -0.249642 0.249642)
							(end -0.1778 0.2794)
						)
						(arc
							(start 0.1778 0.2794)
							(mid 0.249642 0.249642)
							(end 0.2794 0.1778)
						)
						(arc
							(start 0.2794 -0.1778)
							(mid 0.249642 -0.249642)
							(end 0.1778 -0.2794)
						)
					)
					(width 0)
					(fill yes)
				)
			)
		)
		(pad "2" smd custom
			(at 0 0.4445 90)
			(size 0.1397 0.1397)
			(layers "F.Cu" "F.Mask" "F.Paste")
			(net "P1V8_STBY_RF")
			(options
				(clearance outline)
				(anchor circle)
			)
			(primitives
				(gr_poly
					(pts
						(arc
							(start -0.1778 -0.2794)
							(mid -0.249642 -0.249642)
							(end -0.2794 -0.1778)
						)
						(arc
							(start -0.2794 0.1778)
							(mid -0.249642 0.249642)
							(end -0.1778 0.2794)
						)
						(arc
							(start 0.1778 0.2794)
							(mid 0.249642 0.249642)
							(end 0.2794 0.1778)
						)
						(arc
							(start 0.2794 -0.1778)
							(mid 0.249642 -0.249642)
							(end 0.1778 -0.2794)
						)
					)
					(width 0)
					(fill yes)
				)
			)
		)
	)
	(footprint ""
		(layer "F.Cu")
		(at 307.086 -160.655)
		(property "Reference" "R471"
			(at 0 0 0)
			(layer "F.SilkS")
			(hide yes)
			(effects
				(font
					(size 1.27 1.27)
				)
			)
		)
		(property "Value" "0R2J-2-GP"
			(at 0.064008 -3.993896 0)
			(unlocked yes)
			(layer "F.Fab")
			(hide yes)
			(effects
				(font
					(size 1.016 1.016)
					(thickness 0.1524)
				)
			)
		)
		(property "Device Type" "R402H16"
			(at 0.064008 -5.517896 0)
			(unlocked yes)
			(layer "F.Fab")
			(hide yes)
			(effects
				(font
					(size 1.016 1.016)
					(thickness 0.1524)
				)
			)
		)
		(duplicate_pad_numbers_are_jumpers no)
		(fp_line
			(start -0.508 -0.9398)
			(end -0.508 0.9398)
			(stroke
				(width 0.1524)
				(type default)
			)
			(layer "F.SilkS")
		)
		(fp_line
			(start 0.508 -0.9398)
			(end -0.508 -0.9398)
			(stroke
				(width 0.1524)
				(type default)
			)
			(layer "F.SilkS")
		)
		(fp_rect
			(start -0.508 0.9398)
			(end 0.508 -0.9398)
			(stroke
				(width 0)
				(type default)
			)
			(fill no)
			(layer "F.CrtYd")
		)
		(fp_rect
			(start -0.508 0.9398)
			(end 0.508 -0.9398)
			(stroke
				(width 0)
				(type default)
			)
			(fill no)
			(layer "F.Fab")
		)
		(pad "1" smd custom
			(at 0 -0.4445)
			(size 0.1397 0.1397)
			(layers "F.Cu" "F.Mask" "F.Paste")
			(net "BMC0_SMB10_CLK")
			(options
				(clearance outline)
				(anchor circle)
			)
			(primitives
				(gr_poly
					(pts
						(arc
							(start -0.1778 -0.2794)
							(mid -0.249642 -0.249642)
							(end -0.2794 -0.1778)
						)
						(arc
							(start -0.2794 0.1778)
							(mid -0.249642 0.249642)
							(end -0.1778 0.2794)
						)
						(arc
							(start 0.1778 0.2794)
							(mid 0.249642 0.249642)
							(end 0.2794 0.1778)
						)
						(arc
							(start 0.2794 -0.1778)
							(mid 0.249642 -0.249642)
							(end 0.1778 -0.2794)
						)
					)
					(width 0)
					(fill yes)
				)
			)
		)
		(pad "2" smd custom
			(at 0 0.4445)
			(size 0.1397 0.1397)
			(layers "F.Cu" "F.Mask" "F.Paste")
			(net "BMC_I2C_SCL_10")
			(options
				(clearance outline)
				(anchor circle)
			)
			(primitives
				(gr_poly
					(pts
						(arc
							(start -0.1778 -0.2794)
							(mid -0.249642 -0.249642)
							(end -0.2794 -0.1778)
						)
						(arc
							(start -0.2794 0.1778)
							(mid -0.249642 0.249642)
							(end -0.1778 0.2794)
						)
						(arc
							(start 0.1778 0.2794)
							(mid 0.249642 0.249642)
							(end 0.2794 0.1778)
						)
						(arc
							(start 0.2794 -0.1778)
							(mid 0.249642 -0.249642)
							(end 0.1778 -0.2794)
						)
					)
					(width 0)
					(fill yes)
				)
			)
		)
	)
	(footprint ""
		(layer "F.Cu")
		(at 67.945 -51.054 180)
		(property "Reference" "SL7"
			(at 0 0 180)
			(layer "F.SilkS")
			(hide yes)
			(effects
				(font
					(size 1.27 1.27)
				)
			)
		)
		(property "Value" "MPZ2012S601AT-GP"
			(at 0 -4.2418 180)
			(unlocked yes)
			(layer "F.Fab")
			(hide yes)
			(effects
				(font
					(size 1.016 1.016)
					(thickness 0.1524)
				)
			)
		)
		(property "Device Type" "L805H42"
			(at 0 -5.7912 180)
			(unlocked yes)
			(layer "F.Fab")
			(hide yes)
			(effects
				(font
					(size 1.016 1.016)
					(thickness 0.1524)
				)
			)
		)
		(duplicate_pad_numbers_are_jumpers no)
		(fp_line
			(start 0.889 1.7018)
			(end -0.889 1.7018)
			(stroke
				(width 0.1524)
				(type default)
			)
			(layer "F.SilkS")
		)
		(fp_line
			(start 0.889 -1.7018)
			(end 0.889 1.7018)
			(stroke
				(width 0.1524)
				(type default)
			)
			(layer "F.SilkS")
		)
		(fp_line
			(start -0.889 1.7018)
			(end -0.889 -1.7018)
			(stroke
				(width 0.1524)
				(type default)
			)
			(layer "F.SilkS")
		)
		(fp_line
			(start -0.889 -1.7018)
			(end 0.889 -1.7018)
			(stroke
				(width 0.1524)
				(type default)
			)
			(layer "F.SilkS")
		)
		(fp_rect
			(start -0.9652 1.778)
			(end 0.9652 -1.778)
			(stroke
				(width 0)
				(type default)
			)
			(fill no)
			(layer "F.CrtYd")
		)
		(fp_rect
			(start -0.9652 1.778)
			(end 0.9652 -1.778)
			(stroke
				(width 0)
				(type default)
			)
			(fill no)
			(layer "F.Fab")
		)
		(pad "1" smd rect
			(at 0 -0.9652 180)
			(size 1.397 1.143)
			(layers "F.Cu" "F.Mask" "F.Paste")
			(net "SAS0_VDDH")
		)
		(pad "2" smd rect
			(at 0 0.9652 180)
			(size 1.397 1.143)
			(layers "F.Cu" "F.Mask" "F.Paste")
			(net "P1V8_C")
		)
	)
	(footprint ""
		(layer "F.Cu")
		(at 96.52 -227.711 90)
		(property "Reference" "U188"
			(at 0 0 90)
			(layer "F.SilkS")
			(hide yes)
			(effects
				(font
					(size 1.27 1.27)
				)
			)
		)
		(property "Value" "PCA9552PW-GP"
			(at 0 -12.1412 90)
			(unlocked yes)
			(layer "F.Fab")
			(hide yes)
			(effects
				(font
					(size 1.016 1.016)
					(thickness 0.1524)
				)
			)
		)
		(property "Device Type" "TSOIC24H44"
			(at 0 -13.6652 90)
			(unlocked yes)
			(layer "F.Fab")
			(hide yes)
			(effects
				(font
					(size 1.016 1.016)
					(thickness 0.1524)
				)
			)
		)
		(duplicate_pad_numbers_are_jumpers no)
		(fp_line
			(start 3.683 -1.778)
			(end 3.683 1.778)
			(stroke
				(width 0.1524)
				(type default)
			)
			(layer "F.SilkS")
		)
		(fp_line
			(start -4.1148 -1.778)
			(end 3.683 -1.778)
			(stroke
				(width 0.1524)
				(type default)
			)
			(layer "F.SilkS")
		)
		(fp_line
			(start -4.1148 -1.778)
			(end -4.1148 1.778)
			(stroke
				(width 0.1524)
				(type default)
			)
			(layer "F.SilkS")
		)
		(fp_line
			(start -3.8354 0)
			(end -4.1148 -0.2794)
			(stroke
				(width 0.1524)
				(type default)
			)
			(layer "F.SilkS")
		)
		(fp_line
			(start -3.8354 0)
			(end -4.1148 0.2794)
			(stroke
				(width 0.1524)
				(type default)
			)
			(layer "F.SilkS")
		)
		(fp_line
			(start 3.683 1.778)
			(end -4.1148 1.778)
			(stroke
				(width 0.1524)
				(type default)
			)
			(layer "F.SilkS")
		)
		(fp_line
			(start -4.0386 1.778)
			(end -4.0386 3.556)
			(stroke
				(width 0.3556)
				(type default)
			)
			(layer "F.SilkS")
		)
		(fp_poly
			(pts
				(xy -3.7592 -1.778) (xy 3.683 -1.778) (xy 3.683 1.778) (xy -3.7592 1.778)
			)
			(stroke
				(width 0)
				(type default)
			)
			(fill yes)
			(layer "F.SilkS")
		)
		(fp_poly
			(pts
				(xy -4.22656 3.81) (xy 4.22656 3.81) (xy 4.22656 -3.81) (xy -4.22656 -3.81)
			)
			(stroke
				(width 0)
				(type default)
			)
			(fill no)
			(layer "F.CrtYd")
		)
		(fp_poly
			(pts
				(xy -4.22656 -3.81) (xy 4.22656 -3.81) (xy 4.22656 3.81) (xy -4.22656 3.81)
			)
			(stroke
				(width 0)
				(type default)
			)
			(fill no)
			(layer "F.Fab")
		)
		(pad "1" smd rect
			(at -3.57632 2.8194 90)
			(size 0.3556 1.524)
			(layers "F.Cu" "F.Mask" "F.Paste")
			(net "IO_EXP_HDD_FAULT_A0")
		)
		(pad "2" smd rect
			(at -2.92608 2.8194 90)
			(size 0.3556 1.524)
			(layers "F.Cu" "F.Mask" "F.Paste")
			(net "IO_EXP_HDD_FAULT_A1")
		)
		(pad "3" smd rect
			(at -2.27584 2.8194 90)
			(size 0.3556 1.524)
			(layers "F.Cu" "F.Mask" "F.Paste")
			(net "IO_EXP_HDD_FAULT_A2")
		)
		(pad "4" smd rect
			(at -1.6256 2.8194 90)
			(size 0.3556 1.524)
			(layers "F.Cu" "F.Mask" "F.Paste")
			(net "SAS_HDD_LED_0")
		)
		(pad "5" smd rect
			(at -0.97536 2.8194 90)
			(size 0.3556 1.524)
			(layers "F.Cu" "F.Mask" "F.Paste")
			(net "SAS_HDD_LED_1")
		)
		(pad "6" smd rect
			(at -0.32512 2.8194 90)
			(size 0.3556 1.524)
			(layers "F.Cu" "F.Mask" "F.Paste")
			(net "SAS_HDD_LED_2")
		)
		(pad "7" smd rect
			(at 0.32512 2.8194 90)
			(size 0.3556 1.524)
			(layers "F.Cu" "F.Mask" "F.Paste")
			(net "SAS_HDD_LED_3")
		)
		(pad "8" smd rect
			(at 0.97536 2.8194 90)
			(size 0.3556 1.524)
			(layers "F.Cu" "F.Mask" "F.Paste")
			(net "SAS_HDD_LED_4")
		)
		(pad "9" smd rect
			(at 1.6256 2.8194 90)
			(size 0.3556 1.524)
			(layers "F.Cu" "F.Mask" "F.Paste")
			(net "SAS_HDD_LED_5")
		)
		(pad "10" smd rect
			(at 2.27584 2.8194 90)
			(size 0.3556 1.524)
			(layers "F.Cu" "F.Mask" "F.Paste")
			(net "SAS_HDD_LED_6")
		)
		(pad "11" smd rect
			(at 2.92608 2.8194 90)
			(size 0.3556 1.524)
			(layers "F.Cu" "F.Mask" "F.Paste")
			(net "SAS_HDD_LED_7")
		)
		(pad "12" smd rect
			(at 3.57632 2.8194 90)
			(size 0.3556 1.524)
			(layers "F.Cu" "F.Mask" "F.Paste")
			(net "GND")
		)
		(pad "13" smd rect
			(at 3.57632 -2.8194 90)
			(size 0.3556 1.524)
			(layers "F.Cu" "F.Mask" "F.Paste")
			(net "SAS_HDD_LED_8")
		)
		(pad "14" smd rect
			(at 2.92608 -2.8194 90)
			(size 0.3556 1.524)
			(layers "F.Cu" "F.Mask" "F.Paste")
			(net "SAS_HDD_LED_9")
		)
		(pad "15" smd rect
			(at 2.27584 -2.8194 90)
			(size 0.3556 1.524)
			(layers "F.Cu" "F.Mask" "F.Paste")
			(net "SAS_HDD_LED_10")
		)
		(pad "16" smd rect
			(at 1.6256 -2.8194 90)
			(size 0.3556 1.524)
			(layers "F.Cu" "F.Mask" "F.Paste")
			(net "SAS_HDD_LED_11")
		)
		(pad "17" smd rect
			(at 0.97536 -2.8194 90)
			(size 0.3556 1.524)
			(layers "F.Cu" "F.Mask" "F.Paste")
			(net "SAS_HDD_LED_12")
		)
		(pad "18" smd rect
			(at 0.32512 -2.8194 90)
			(size 0.3556 1.524)
			(layers "F.Cu" "F.Mask" "F.Paste")
			(net "SAS_HDD_LED_13")
		)
		(pad "19" smd rect
			(at -0.32512 -2.8194 90)
			(size 0.3556 1.524)
			(layers "F.Cu" "F.Mask" "F.Paste")
			(net "SAS_HDD_LED_14")
		)
		(pad "20" smd rect
			(at -0.97536 -2.8194 90)
			(size 0.3556 1.524)
			(layers "F.Cu" "F.Mask" "F.Paste")
			(net "SAS_HDD_LED_15")
		)
		(pad "21" smd rect
			(at -1.6256 -2.8194 90)
			(size 0.3556 1.524)
			(layers "F.Cu" "F.Mask" "F.Paste")
			(net "I2C_IO_EXP_RESET#_FLT")
		)
		(pad "22" smd rect
			(at -2.27584 -2.8194 90)
			(size 0.3556 1.524)
			(layers "F.Cu" "F.Mask" "F.Paste")
			(net "FAULT_SCL")
		)
		(pad "23" smd rect
			(at -2.92608 -2.8194 90)
			(size 0.3556 1.524)
			(layers "F.Cu" "F.Mask" "F.Paste")
			(net "FAULT_SDA")
		)
		(pad "24" smd rect
			(at -3.57632 -2.8194 90)
			(size 0.3556 1.524)
			(layers "F.Cu" "F.Mask" "F.Paste")
			(net "P3V3_STBY")
		)
	)
	(footprint ""
		(layer "F.Cu")
		(at 100.85197 -78.105)
		(property "Reference" "STP98"
			(at 0 0 0)
			(layer "F.SilkS")
			(hide yes)
			(effects
				(font
					(size 1.27 1.27)
				)
			)
		)
		(property "Value" "TPAD28"
			(at 0.0127 -1.8034 0)
			(unlocked yes)
			(layer "F.Fab")
			(hide yes)
			(effects
				(font
					(size 1.016 1.016)
					(thickness 0.1524)
				)
			)
		)
		(property "Device Type" "TPAD28"
			(at 0.0127 -3.3274 0)
			(unlocked yes)
			(layer "F.Fab")
			(hide yes)
			(effects
				(font
					(size 1.016 1.016)
					(thickness 0.1524)
				)
			)
		)
		(duplicate_pad_numbers_are_jumpers no)
		(fp_poly
			(pts
				(arc
					(start 0.3556 0)
					(mid -0.3556 0)
					(end 0.3556 0)
				)
			)
			(stroke
				(width 0)
				(type default)
			)
			(fill no)
			(layer "F.CrtYd")
		)
		(fp_poly
			(pts
				(arc
					(start 0.6096 0)
					(mid -0.6096 0)
					(end 0.6096 0)
				)
			)
			(stroke
				(width 0)
				(type default)
			)
			(fill no)
			(layer "F.Fab")
		)
		(pad "1" smd circle
			(at 0 0)
			(size 0.7112 0.7112)
			(layers "F.Cu" "F.Mask" "F.Paste")
			(net "LSI_PROCMON")
		)
	)
	(footprint ""
		(layer "F.Cu")
		(at 87.757 -226.822 -90)
		(property "Reference" "SR266"
			(at 0 0 270)
			(layer "F.SilkS")
			(hide yes)
			(effects
				(font
					(size 1.27 1.27)
				)
			)
		)
		(property "Value" "4K7R2F-GP"
			(at 0.064008 -3.993896 270)
			(unlocked yes)
			(layer "F.Fab")
			(hide yes)
			(effects
				(font
					(size 1.016 1.016)
					(thickness 0.1524)
				)
			)
		)
		(property "Device Type" "R402H16"
			(at 0.064008 -5.517896 270)
			(unlocked yes)
			(layer "F.Fab")
			(hide yes)
			(effects
				(font
					(size 1.016 1.016)
					(thickness 0.1524)
				)
			)
		)
		(duplicate_pad_numbers_are_jumpers no)
		(fp_line
			(start -0.508 -0.9398)
			(end -0.508 0.9398)
			(stroke
				(width 0.1524)
				(type default)
			)
			(layer "F.SilkS")
		)
		(fp_line
			(start 0.508 -0.9398)
			(end -0.508 -0.9398)
			(stroke
				(width 0.1524)
				(type default)
			)
			(layer "F.SilkS")
		)
		(fp_rect
			(start -0.508 0.9398)
			(end 0.508 -0.9398)
			(stroke
				(width 0)
				(type default)
			)
			(fill no)
			(layer "F.CrtYd")
		)
		(fp_rect
			(start -0.508 0.9398)
			(end 0.508 -0.9398)
			(stroke
				(width 0)
				(type default)
			)
			(fill no)
			(layer "F.Fab")
		)
		(pad "1" smd custom
			(at 0 -0.4445 270)
			(size 0.1397 0.1397)
			(layers "F.Cu" "F.Mask" "F.Paste")
			(net "I2C_IO_EXP_RESET#_FLT")
			(options
				(clearance outline)
				(anchor circle)
			)
			(primitives
				(gr_poly
					(pts
						(arc
							(start -0.1778 -0.2794)
							(mid -0.249642 -0.249642)
							(end -0.2794 -0.1778)
						)
						(arc
							(start -0.2794 0.1778)
							(mid -0.249642 0.249642)
							(end -0.1778 0.2794)
						)
						(arc
							(start 0.1778 0.2794)
							(mid 0.249642 0.249642)
							(end 0.2794 0.1778)
						)
						(arc
							(start 0.2794 -0.1778)
							(mid 0.249642 -0.249642)
							(end 0.1778 -0.2794)
						)
					)
					(width 0)
					(fill yes)
				)
			)
		)
		(pad "2" smd custom
			(at 0 0.4445 270)
			(size 0.1397 0.1397)
			(layers "F.Cu" "F.Mask" "F.Paste")
			(net "P3V3_STBY")
			(options
				(clearance outline)
				(anchor circle)
			)
			(primitives
				(gr_poly
					(pts
						(arc
							(start -0.1778 -0.2794)
							(mid -0.249642 -0.249642)
							(end -0.2794 -0.1778)
						)
						(arc
							(start -0.2794 0.1778)
							(mid -0.249642 0.249642)
							(end -0.1778 0.2794)
						)
						(arc
							(start 0.1778 0.2794)
							(mid 0.249642 0.249642)
							(end 0.2794 0.1778)
						)
						(arc
							(start 0.2794 -0.1778)
							(mid 0.249642 -0.249642)
							(end 0.1778 -0.2794)
						)
					)
					(width 0)
					(fill yes)
				)
			)
		)
	)
	(footprint ""
		(layer "F.Cu")
		(at 261.293864 -218.558872 180)
		(property "Reference" "PR86"
			(at 0 0 180)
			(layer "F.SilkS")
			(hide yes)
			(effects
				(font
					(size 1.27 1.27)
				)
			)
		)
		(property "Value" "2K74R2F-GP"
			(at 0.064008 -3.993896 180)
			(unlocked yes)
			(layer "F.Fab")
			(hide yes)
			(effects
				(font
					(size 1.016 1.016)
					(thickness 0.1524)
				)
			)
		)
		(property "Device Type" "R402H16"
			(at 0.064008 -5.517896 180)
			(unlocked yes)
			(layer "F.Fab")
			(hide yes)
			(effects
				(font
					(size 1.016 1.016)
					(thickness 0.1524)
				)
			)
		)
		(duplicate_pad_numbers_are_jumpers no)
		(fp_line
			(start 0.508 -0.9398)
			(end -0.508 -0.9398)
			(stroke
				(width 0.1524)
				(type default)
			)
			(layer "F.SilkS")
		)
		(fp_line
			(start -0.508 -0.9398)
			(end -0.508 0.9398)
			(stroke
				(width 0.1524)
				(type default)
			)
			(layer "F.SilkS")
		)
		(fp_rect
			(start -0.508 0.9398)
			(end 0.508 -0.9398)
			(stroke
				(width 0)
				(type default)
			)
			(fill no)
			(layer "F.CrtYd")
		)
		(fp_rect
			(start -0.508 0.9398)
			(end 0.508 -0.9398)
			(stroke
				(width 0)
				(type default)
			)
			(fill no)
			(layer "F.Fab")
		)
		(pad "1" smd custom
			(at 0 -0.4445 180)
			(size 0.1397 0.1397)
			(layers "F.Cu" "F.Mask" "F.Paste")
			(net "TPS74801_1V26_STBY_OUT")
			(options
				(clearance outline)
				(anchor circle)
			)
			(primitives
				(gr_poly
					(pts
						(arc
							(start -0.1778 -0.2794)
							(mid -0.249642 -0.249642)
							(end -0.2794 -0.1778)
						)
						(arc
							(start -0.2794 0.1778)
							(mid -0.249642 0.249642)
							(end -0.1778 0.2794)
						)
						(arc
							(start 0.1778 0.2794)
							(mid 0.249642 0.249642)
							(end 0.2794 0.1778)
						)
						(arc
							(start 0.2794 -0.1778)
							(mid 0.249642 -0.249642)
							(end 0.1778 -0.2794)
						)
					)
					(width 0)
					(fill yes)
				)
			)
		)
		(pad "2" smd custom
			(at 0 0.4445 180)
			(size 0.1397 0.1397)
			(layers "F.Cu" "F.Mask" "F.Paste")
			(net "TPS74801_1V26_STBY_FB")
			(options
				(clearance outline)
				(anchor circle)
			)
			(primitives
				(gr_poly
					(pts
						(arc
							(start -0.1778 -0.2794)
							(mid -0.249642 -0.249642)
							(end -0.2794 -0.1778)
						)
						(arc
							(start -0.2794 0.1778)
							(mid -0.249642 0.249642)
							(end -0.1778 0.2794)
						)
						(arc
							(start 0.1778 0.2794)
							(mid 0.249642 0.249642)
							(end 0.2794 0.1778)
						)
						(arc
							(start 0.2794 -0.1778)
							(mid 0.249642 -0.249642)
							(end 0.1778 -0.2794)
						)
					)
					(width 0)
					(fill yes)
				)
			)
		)
	)
	(footprint ""
		(layer "F.Cu")
		(at 202.565 -142.494 -90)
		(property "Reference" "SR760"
			(at 0 0 270)
			(layer "F.SilkS")
			(hide yes)
			(effects
				(font
					(size 1.27 1.27)
				)
			)
		)
		(property "Value" "4K7R2F-GP"
			(at 0.064008 -3.993896 270)
			(unlocked yes)
			(layer "F.Fab")
			(hide yes)
			(effects
				(font
					(size 1.016 1.016)
					(thickness 0.1524)
				)
			)
		)
		(property "Device Type" "R402H16"
			(at 0.064008 -5.517896 270)
			(unlocked yes)
			(layer "F.Fab")
			(hide yes)
			(effects
				(font
					(size 1.016 1.016)
					(thickness 0.1524)
				)
			)
		)
		(duplicate_pad_numbers_are_jumpers no)
		(fp_line
			(start -0.508 -0.9398)
			(end -0.508 0.9398)
			(stroke
				(width 0.1524)
				(type default)
			)
			(layer "F.SilkS")
		)
		(fp_line
			(start 0.508 -0.9398)
			(end -0.508 -0.9398)
			(stroke
				(width 0.1524)
				(type default)
			)
			(layer "F.SilkS")
		)
		(fp_rect
			(start -0.508 0.9398)
			(end 0.508 -0.9398)
			(stroke
				(width 0)
				(type default)
			)
			(fill no)
			(layer "F.CrtYd")
		)
		(fp_rect
			(start -0.508 0.9398)
			(end 0.508 -0.9398)
			(stroke
				(width 0)
				(type default)
			)
			(fill no)
			(layer "F.Fab")
		)
		(pad "1" smd custom
			(at 0 -0.4445 270)
			(size 0.1397 0.1397)
			(layers "F.Cu" "F.Mask" "F.Paste")
			(net "P1V8_E")
			(options
				(clearance outline)
				(anchor circle)
			)
			(primitives
				(gr_poly
					(pts
						(arc
							(start -0.1778 -0.2794)
							(mid -0.249642 -0.249642)
							(end -0.2794 -0.1778)
						)
						(arc
							(start -0.2794 0.1778)
							(mid -0.249642 0.249642)
							(end -0.1778 0.2794)
						)
						(arc
							(start 0.1778 0.2794)
							(mid 0.249642 0.249642)
							(end 0.2794 0.1778)
						)
						(arc
							(start 0.2794 -0.1778)
							(mid 0.249642 -0.249642)
							(end 0.1778 -0.2794)
						)
					)
					(width 0)
					(fill yes)
				)
			)
		)
		(pad "2" smd custom
			(at 0 0.4445 270)
			(size 0.1397 0.1397)
			(layers "F.Cu" "F.Mask" "F.Paste")
			(net "EXP_EEPROM_A2")
			(options
				(clearance outline)
				(anchor circle)
			)
			(primitives
				(gr_poly
					(pts
						(arc
							(start -0.1778 -0.2794)
							(mid -0.249642 -0.249642)
							(end -0.2794 -0.1778)
						)
						(arc
							(start -0.2794 0.1778)
							(mid -0.249642 0.249642)
							(end -0.1778 0.2794)
						)
						(arc
							(start 0.1778 0.2794)
							(mid 0.249642 0.249642)
							(end 0.2794 0.1778)
						)
						(arc
							(start 0.2794 -0.1778)
							(mid 0.249642 -0.249642)
							(end 0.1778 -0.2794)
						)
					)
					(width 0)
					(fill yes)
				)
			)
		)
	)
	(footprint ""
		(layer "F.Cu")
		(at 274.193 -181.737 90)
		(property "Reference" "R343"
			(at 0 0 90)
			(layer "F.SilkS")
			(hide yes)
			(effects
				(font
					(size 1.27 1.27)
				)
			)
		)
		(property "Value" "3K3R2F-2-GP"
			(at 0.064008 -3.993896 90)
			(unlocked yes)
			(layer "F.Fab")
			(hide yes)
			(effects
				(font
					(size 1.016 1.016)
					(thickness 0.1524)
				)
			)
		)
		(property "Device Type" "R402H16"
			(at 0.064008 -5.517896 90)
			(unlocked yes)
			(layer "F.Fab")
			(hide yes)
			(effects
				(font
					(size 1.016 1.016)
					(thickness 0.1524)
				)
			)
		)
		(duplicate_pad_numbers_are_jumpers no)
		(fp_line
			(start 0.508 -0.9398)
			(end -0.508 -0.9398)
			(stroke
				(width 0.1524)
				(type default)
			)
			(layer "F.SilkS")
		)
		(fp_line
			(start -0.508 -0.9398)
			(end -0.508 0.9398)
			(stroke
				(width 0.1524)
				(type default)
			)
			(layer "F.SilkS")
		)
		(fp_rect
			(start -0.508 0.9398)
			(end 0.508 -0.9398)
			(stroke
				(width 0)
				(type default)
			)
			(fill no)
			(layer "F.CrtYd")
		)
		(fp_rect
			(start -0.508 0.9398)
			(end 0.508 -0.9398)
			(stroke
				(width 0)
				(type default)
			)
			(fill no)
			(layer "F.Fab")
		)
		(pad "1" smd custom
			(at 0 -0.4445 90)
			(size 0.1397 0.1397)
			(layers "F.Cu" "F.Mask" "F.Paste")
			(net "P3V3_STBY")
			(options
				(clearance outline)
				(anchor circle)
			)
			(primitives
				(gr_poly
					(pts
						(arc
							(start -0.1778 -0.2794)
							(mid -0.249642 -0.249642)
							(end -0.2794 -0.1778)
						)
						(arc
							(start -0.2794 0.1778)
							(mid -0.249642 0.249642)
							(end -0.1778 0.2794)
						)
						(arc
							(start 0.1778 0.2794)
							(mid 0.249642 0.249642)
							(end 0.2794 0.1778)
						)
						(arc
							(start 0.2794 -0.1778)
							(mid 0.249642 -0.249642)
							(end 0.1778 -0.2794)
						)
					)
					(width 0)
					(fill yes)
				)
			)
		)
		(pad "2" smd custom
			(at 0 0.4445 90)
			(size 0.1397 0.1397)
			(layers "F.Cu" "F.Mask" "F.Paste")
			(net "ROMA1")
			(options
				(clearance outline)
				(anchor circle)
			)
			(primitives
				(gr_poly
					(pts
						(arc
							(start -0.1778 -0.2794)
							(mid -0.249642 -0.249642)
							(end -0.2794 -0.1778)
						)
						(arc
							(start -0.2794 0.1778)
							(mid -0.249642 0.249642)
							(end -0.1778 0.2794)
						)
						(arc
							(start 0.1778 0.2794)
							(mid 0.249642 0.249642)
							(end 0.2794 0.1778)
						)
						(arc
							(start 0.2794 -0.1778)
							(mid 0.249642 -0.249642)
							(end 0.1778 -0.2794)
						)
					)
					(width 0)
					(fill yes)
				)
			)
		)
	)
	(footprint ""
		(layer "F.Cu")
		(at 109.074966 -65.8876 180)
		(property "Reference" "SR863"
			(at 0 0 180)
			(layer "F.SilkS")
			(hide yes)
			(effects
				(font
					(size 1.27 1.27)
				)
			)
		)
		(property "Value" "0R2J-2-GP"
			(at 0.064008 -3.993896 180)
			(unlocked yes)
			(layer "F.Fab")
			(hide yes)
			(effects
				(font
					(size 1.016 1.016)
					(thickness 0.1524)
				)
			)
		)
		(property "Device Type" "R402H16"
			(at 0.064008 -5.517896 180)
			(unlocked yes)
			(layer "F.Fab")
			(hide yes)
			(effects
				(font
					(size 1.016 1.016)
					(thickness 0.1524)
				)
			)
		)
		(duplicate_pad_numbers_are_jumpers no)
		(fp_line
			(start 0.508 -0.9398)
			(end -0.508 -0.9398)
			(stroke
				(width 0.1524)
				(type default)
			)
			(layer "F.SilkS")
		)
		(fp_line
			(start -0.508 -0.9398)
			(end -0.508 0.9398)
			(stroke
				(width 0.1524)
				(type default)
			)
			(layer "F.SilkS")
		)
		(fp_rect
			(start -0.508 0.9398)
			(end 0.508 -0.9398)
			(stroke
				(width 0)
				(type default)
			)
			(fill no)
			(layer "F.CrtYd")
		)
		(fp_rect
			(start -0.508 0.9398)
			(end 0.508 -0.9398)
			(stroke
				(width 0)
				(type default)
			)
			(fill no)
			(layer "F.Fab")
		)
		(pad "1" smd custom
			(at 0 -0.4445 180)
			(size 0.1397 0.1397)
			(layers "F.Cu" "F.Mask" "F.Paste")
			(net "JTAG_IOC_TDI")
			(options
				(clearance outline)
				(anchor circle)
			)
			(primitives
				(gr_poly
					(pts
						(arc
							(start -0.1778 -0.2794)
							(mid -0.249642 -0.249642)
							(end -0.2794 -0.1778)
						)
						(arc
							(start -0.2794 0.1778)
							(mid -0.249642 0.249642)
							(end -0.1778 0.2794)
						)
						(arc
							(start 0.1778 0.2794)
							(mid 0.249642 0.249642)
							(end 0.2794 0.1778)
						)
						(arc
							(start 0.2794 -0.1778)
							(mid 0.249642 -0.249642)
							(end 0.1778 -0.2794)
						)
					)
					(width 0)
					(fill yes)
				)
			)
		)
		(pad "2" smd custom
			(at 0 0.4445 180)
			(size 0.1397 0.1397)
			(layers "F.Cu" "F.Mask" "F.Paste")
			(net "JTAG_IOC_L_TDI")
			(options
				(clearance outline)
				(anchor circle)
			)
			(primitives
				(gr_poly
					(pts
						(arc
							(start -0.1778 -0.2794)
							(mid -0.249642 -0.249642)
							(end -0.2794 -0.1778)
						)
						(arc
							(start -0.2794 0.1778)
							(mid -0.249642 0.249642)
							(end -0.1778 0.2794)
						)
						(arc
							(start 0.1778 0.2794)
							(mid 0.249642 0.249642)
							(end 0.2794 0.1778)
						)
						(arc
							(start 0.2794 -0.1778)
							(mid 0.249642 -0.249642)
							(end 0.1778 -0.2794)
						)
					)
					(width 0)
					(fill yes)
				)
			)
		)
	)
	(footprint ""
		(layer "F.Cu")
		(at 100.819966 -64.897)
		(property "Reference" "SR648"
			(at 0 0 0)
			(layer "F.SilkS")
			(hide yes)
			(effects
				(font
					(size 1.27 1.27)
				)
			)
		)
		(property "Value" "4K7R2F-GP"
			(at 0.064008 -3.993896 0)
			(unlocked yes)
			(layer "F.Fab")
			(hide yes)
			(effects
				(font
					(size 1.016 1.016)
					(thickness 0.1524)
				)
			)
		)
		(property "Device Type" "R402H16"
			(at 0.064008 -5.517896 0)
			(unlocked yes)
			(layer "F.Fab")
			(hide yes)
			(effects
				(font
					(size 1.016 1.016)
					(thickness 0.1524)
				)
			)
		)
		(duplicate_pad_numbers_are_jumpers no)
		(fp_line
			(start -0.508 -0.9398)
			(end -0.508 0.9398)
			(stroke
				(width 0.1524)
				(type default)
			)
			(layer "F.SilkS")
		)
		(fp_line
			(start 0.508 -0.9398)
			(end -0.508 -0.9398)
			(stroke
				(width 0.1524)
				(type default)
			)
			(layer "F.SilkS")
		)
		(fp_rect
			(start -0.508 0.9398)
			(end 0.508 -0.9398)
			(stroke
				(width 0)
				(type default)
			)
			(fill no)
			(layer "F.CrtYd")
		)
		(fp_rect
			(start -0.508 0.9398)
			(end 0.508 -0.9398)
			(stroke
				(width 0)
				(type default)
			)
			(fill no)
			(layer "F.Fab")
		)
		(pad "1" smd custom
			(at 0 -0.4445)
			(size 0.1397 0.1397)
			(layers "F.Cu" "F.Mask" "F.Paste")
			(net "P1V8_C")
			(options
				(clearance outline)
				(anchor circle)
			)
			(primitives
				(gr_poly
					(pts
						(arc
							(start -0.1778 -0.2794)
							(mid -0.249642 -0.249642)
							(end -0.2794 -0.1778)
						)
						(arc
							(start -0.2794 0.1778)
							(mid -0.249642 0.249642)
							(end -0.1778 0.2794)
						)
						(arc
							(start 0.1778 0.2794)
							(mid 0.249642 0.249642)
							(end 0.2794 0.1778)
						)
						(arc
							(start 0.2794 -0.1778)
							(mid 0.249642 -0.249642)
							(end 0.1778 -0.2794)
						)
					)
					(width 0)
					(fill yes)
				)
			)
		)
		(pad "2" smd custom
			(at 0 0.4445)
			(size 0.1397 0.1397)
			(layers "F.Cu" "F.Mask" "F.Paste")
			(net "IOC_RESET#")
			(options
				(clearance outline)
				(anchor circle)
			)
			(primitives
				(gr_poly
					(pts
						(arc
							(start -0.1778 -0.2794)
							(mid -0.249642 -0.249642)
							(end -0.2794 -0.1778)
						)
						(arc
							(start -0.2794 0.1778)
							(mid -0.249642 0.249642)
							(end -0.1778 0.2794)
						)
						(arc
							(start 0.1778 0.2794)
							(mid 0.249642 0.249642)
							(end 0.2794 0.1778)
						)
						(arc
							(start 0.2794 -0.1778)
							(mid 0.249642 -0.249642)
							(end 0.1778 -0.2794)
						)
					)
					(width 0)
					(fill yes)
				)
			)
		)
	)
	(footprint ""
		(layer "F.Cu")
		(at 243.3193 -111.6838 180)
		(property "Reference" "SR934"
			(at 0 0 180)
			(layer "F.SilkS")
			(hide yes)
			(effects
				(font
					(size 1.27 1.27)
				)
			)
		)
		(property "Value" "0R2J-2-GP"
			(at 0.064008 -3.993896 180)
			(unlocked yes)
			(layer "F.Fab")
			(hide yes)
			(effects
				(font
					(size 1.016 1.016)
					(thickness 0.1524)
				)
			)
		)
		(property "Device Type" "R402H16"
			(at 0.064008 -5.517896 180)
			(unlocked yes)
			(layer "F.Fab")
			(hide yes)
			(effects
				(font
					(size 1.016 1.016)
					(thickness 0.1524)
				)
			)
		)
		(duplicate_pad_numbers_are_jumpers no)
		(fp_line
			(start 0.508 -0.9398)
			(end -0.508 -0.9398)
			(stroke
				(width 0.1524)
				(type default)
			)
			(layer "F.SilkS")
		)
		(fp_line
			(start -0.508 -0.9398)
			(end -0.508 0.9398)
			(stroke
				(width 0.1524)
				(type default)
			)
			(layer "F.SilkS")
		)
		(fp_rect
			(start -0.508 0.9398)
			(end 0.508 -0.9398)
			(stroke
				(width 0)
				(type default)
			)
			(fill no)
			(layer "F.CrtYd")
		)
		(fp_rect
			(start -0.508 0.9398)
			(end 0.508 -0.9398)
			(stroke
				(width 0)
				(type default)
			)
			(fill no)
			(layer "F.Fab")
		)
		(pad "1" smd custom
			(at 0 -0.4445 180)
			(size 0.1397 0.1397)
			(layers "F.Cu" "F.Mask" "F.Paste")
			(net "EXP_SMART_RX")
			(options
				(clearance outline)
				(anchor circle)
			)
			(primitives
				(gr_poly
					(pts
						(arc
							(start -0.1778 -0.2794)
							(mid -0.249642 -0.249642)
							(end -0.2794 -0.1778)
						)
						(arc
							(start -0.2794 0.1778)
							(mid -0.249642 0.249642)
							(end -0.1778 0.2794)
						)
						(arc
							(start 0.1778 0.2794)
							(mid 0.249642 0.249642)
							(end 0.2794 0.1778)
						)
						(arc
							(start 0.2794 -0.1778)
							(mid 0.249642 -0.249642)
							(end 0.1778 -0.2794)
						)
					)
					(width 0)
					(fill yes)
				)
			)
		)
		(pad "2" smd custom
			(at 0 0.4445 180)
			(size 0.1397 0.1397)
			(layers "F.Cu" "F.Mask" "F.Paste")
			(net "EXP_SMART_RX_R")
			(options
				(clearance outline)
				(anchor circle)
			)
			(primitives
				(gr_poly
					(pts
						(arc
							(start -0.1778 -0.2794)
							(mid -0.249642 -0.249642)
							(end -0.2794 -0.1778)
						)
						(arc
							(start -0.2794 0.1778)
							(mid -0.249642 0.249642)
							(end -0.1778 0.2794)
						)
						(arc
							(start 0.1778 0.2794)
							(mid 0.249642 0.249642)
							(end 0.2794 0.1778)
						)
						(arc
							(start 0.2794 -0.1778)
							(mid 0.249642 -0.249642)
							(end 0.1778 -0.2794)
						)
					)
					(width 0)
					(fill yes)
				)
			)
		)
	)
	(footprint ""
		(layer "F.Cu")
		(at 194.056 -166.878 180)
		(property "Reference" "Q11"
			(at 0 0 180)
			(layer "F.SilkS")
			(hide yes)
			(effects
				(font
					(size 1.27 1.27)
				)
			)
		)
		(property "Value" "2N7002A-7-GP"
			(at 0.127 -8.9662 180)
			(unlocked yes)
			(layer "F.Fab")
			(hide yes)
			(effects
				(font
					(size 1.016 1.016)
					(thickness 0.1524)
				)
			)
		)
		(property "Device Type" "SOT23DGS2D4H48"
			(at 0.127 -10.4902 180)
			(unlocked yes)
			(layer "F.Fab")
			(hide yes)
			(effects
				(font
					(size 1.016 1.016)
					(thickness 0.1524)
				)
			)
		)
		(duplicate_pad_numbers_are_jumpers no)
		(fp_line
			(start 1.651 1.778)
			(end 1.651 -1.778)
			(stroke
				(width 0.1524)
				(type default)
			)
			(layer "F.SilkS")
		)
		(fp_line
			(start 1.651 -1.778)
			(end -1.651 -1.778)
			(stroke
				(width 0.1524)
				(type default)
			)
			(layer "F.SilkS")
		)
		(fp_line
			(start -1.651 1.778)
			(end 1.651 1.778)
			(stroke
				(width 0.1524)
				(type default)
			)
			(layer "F.SilkS")
		)
		(fp_line
			(start -1.651 -1.778)
			(end -1.651 1.778)
			(stroke
				(width 0.1524)
				(type default)
			)
			(layer "F.SilkS")
		)
		(fp_poly
			(pts
				(xy -1.778 1.8796) (xy -1.778 -1.8796) (xy 1.778 -1.8796) (xy 1.778 1.8796)
			)
			(stroke
				(width 0)
				(type default)
			)
			(fill no)
			(layer "F.CrtYd")
		)
		(fp_poly
			(pts
				(xy -1.778 1.8796) (xy -1.778 -1.8796) (xy 1.778 -1.8796) (xy 1.778 1.8796)
			)
			(stroke
				(width 0)
				(type default)
			)
			(fill no)
			(layer "F.Fab")
		)
		(pad "D" smd custom
			(at 0 -0.9525 180)
			(size 0.1905 0.1905)
			(layers "F.Cu" "F.Mask" "F.Paste")
			(net "P3V3_PG_R")
			(options
				(clearance outline)
				(anchor circle)
			)
			(primitives
				(gr_poly
					(pts
						(arc
							(start -0.1778 0.5715)
							(mid -0.321484 0.511984)
							(end -0.381 0.3683)
						)
						(arc
							(start -0.381 -0.3683)
							(mid -0.321484 -0.511984)
							(end -0.1778 -0.5715)
						)
						(arc
							(start 0.1778 -0.5715)
							(mid 0.321484 -0.511984)
							(end 0.381 -0.3683)
						)
						(arc
							(start 0.381 0.3683)
							(mid 0.321484 0.511984)
							(end 0.1778 0.5715)
						)
					)
					(width 0)
					(fill yes)
				)
			)
		)
		(pad "G" smd custom
			(at -0.98425 0.9525 180)
			(size 0.1905 0.1905)
			(layers "F.Cu" "F.Mask" "F.Paste")
			(net "P3V3_STBY_B1")
			(options
				(clearance outline)
				(anchor circle)
			)
			(primitives
				(gr_poly
					(pts
						(arc
							(start -0.1778 0.5715)
							(mid -0.321484 0.511984)
							(end -0.381 0.3683)
						)
						(arc
							(start -0.381 -0.3683)
							(mid -0.321484 -0.511984)
							(end -0.1778 -0.5715)
						)
						(arc
							(start 0.1778 -0.5715)
							(mid 0.321484 -0.511984)
							(end 0.381 -0.3683)
						)
						(arc
							(start 0.381 0.3683)
							(mid 0.321484 0.511984)
							(end 0.1778 0.5715)
						)
					)
					(width 0)
					(fill yes)
				)
			)
		)
		(pad "S" smd custom
			(at 0.98425 0.9525 180)
			(size 0.1905 0.1905)
			(layers "F.Cu" "F.Mask" "F.Paste")
			(net "GND")
			(options
				(clearance outline)
				(anchor circle)
			)
			(primitives
				(gr_poly
					(pts
						(arc
							(start -0.1778 0.5715)
							(mid -0.321484 0.511984)
							(end -0.381 0.3683)
						)
						(arc
							(start -0.381 -0.3683)
							(mid -0.321484 -0.511984)
							(end -0.1778 -0.5715)
						)
						(arc
							(start 0.1778 -0.5715)
							(mid 0.321484 -0.511984)
							(end 0.381 -0.3683)
						)
						(arc
							(start 0.381 0.3683)
							(mid 0.321484 0.511984)
							(end 0.1778 0.5715)
						)
					)
					(width 0)
					(fill yes)
				)
			)
		)
	)
	(footprint ""
		(layer "F.Cu")
		(at 45.593 -219.456)
		(property "Reference" "R9021"
			(at 0 0 0)
			(layer "F.SilkS")
			(hide yes)
			(effects
				(font
					(size 1.27 1.27)
				)
			)
		)
		(property "Value" "42K2R2F-L-GP"
			(at 0.064008 -3.993896 0)
			(unlocked yes)
			(layer "F.Fab")
			(hide yes)
			(effects
				(font
					(size 1.016 1.016)
					(thickness 0.1524)
				)
			)
		)
		(property "Device Type" "R402H16"
			(at 0.064008 -5.517896 0)
			(unlocked yes)
			(layer "F.Fab")
			(hide yes)
			(effects
				(font
					(size 1.016 1.016)
					(thickness 0.1524)
				)
			)
		)
		(duplicate_pad_numbers_are_jumpers no)
		(fp_line
			(start -0.508 -0.9398)
			(end -0.508 0.9398)
			(stroke
				(width 0.1524)
				(type default)
			)
			(layer "F.SilkS")
		)
		(fp_line
			(start 0.508 -0.9398)
			(end -0.508 -0.9398)
			(stroke
				(width 0.1524)
				(type default)
			)
			(layer "F.SilkS")
		)
		(fp_rect
			(start -0.508 0.9398)
			(end 0.508 -0.9398)
			(stroke
				(width 0)
				(type default)
			)
			(fill no)
			(layer "F.CrtYd")
		)
		(fp_rect
			(start -0.508 0.9398)
			(end 0.508 -0.9398)
			(stroke
				(width 0)
				(type default)
			)
			(fill no)
			(layer "F.Fab")
		)
		(pad "1" smd custom
			(at 0 -0.4445)
			(size 0.1397 0.1397)
			(layers "F.Cu" "F.Mask" "F.Paste")
			(net "MB0_ISET_R")
			(options
				(clearance outline)
				(anchor circle)
			)
			(primitives
				(gr_poly
					(pts
						(arc
							(start -0.1778 -0.2794)
							(mid -0.249642 -0.249642)
							(end -0.2794 -0.1778)
						)
						(arc
							(start -0.2794 0.1778)
							(mid -0.249642 0.249642)
							(end -0.1778 0.2794)
						)
						(arc
							(start 0.1778 0.2794)
							(mid 0.249642 0.249642)
							(end 0.2794 0.1778)
						)
						(arc
							(start 0.2794 -0.1778)
							(mid 0.249642 -0.249642)
							(end 0.1778 -0.2794)
						)
					)
					(width 0)
					(fill yes)
				)
			)
		)
		(pad "2" smd custom
			(at 0 0.4445)
			(size 0.1397 0.1397)
			(layers "F.Cu" "F.Mask" "F.Paste")
			(net "AGND_CURRENT_MON")
			(options
				(clearance outline)
				(anchor circle)
			)
			(primitives
				(gr_poly
					(pts
						(arc
							(start -0.1778 -0.2794)
							(mid -0.249642 -0.249642)
							(end -0.2794 -0.1778)
						)
						(arc
							(start -0.2794 0.1778)
							(mid -0.249642 0.249642)
							(end -0.1778 0.2794)
						)
						(arc
							(start 0.1778 0.2794)
							(mid 0.249642 0.249642)
							(end 0.2794 0.1778)
						)
						(arc
							(start 0.2794 -0.1778)
							(mid 0.249642 -0.249642)
							(end 0.1778 -0.2794)
						)
					)
					(width 0)
					(fill yes)
				)
			)
		)
	)
	(footprint ""
		(layer "F.Cu")
		(at 274.193 -177.673 90)
		(property "Reference" "R361"
			(at 0 0 90)
			(layer "F.SilkS")
			(hide yes)
			(effects
				(font
					(size 1.27 1.27)
				)
			)
		)
		(property "Value" "3K3R2F-2-GP"
			(at 0.064008 -3.993896 90)
			(unlocked yes)
			(layer "F.Fab")
			(hide yes)
			(effects
				(font
					(size 1.016 1.016)
					(thickness 0.1524)
				)
			)
		)
		(property "Device Type" "R402H16"
			(at 0.064008 -5.517896 90)
			(unlocked yes)
			(layer "F.Fab")
			(hide yes)
			(effects
				(font
					(size 1.016 1.016)
					(thickness 0.1524)
				)
			)
		)
		(duplicate_pad_numbers_are_jumpers no)
		(fp_line
			(start 0.508 -0.9398)
			(end -0.508 -0.9398)
			(stroke
				(width 0.1524)
				(type default)
			)
			(layer "F.SilkS")
		)
		(fp_line
			(start -0.508 -0.9398)
			(end -0.508 0.9398)
			(stroke
				(width 0.1524)
				(type default)
			)
			(layer "F.SilkS")
		)
		(fp_rect
			(start -0.508 0.9398)
			(end 0.508 -0.9398)
			(stroke
				(width 0)
				(type default)
			)
			(fill no)
			(layer "F.CrtYd")
		)
		(fp_rect
			(start -0.508 0.9398)
			(end 0.508 -0.9398)
			(stroke
				(width 0)
				(type default)
			)
			(fill no)
			(layer "F.Fab")
		)
		(pad "1" smd custom
			(at 0 -0.4445 90)
			(size 0.1397 0.1397)
			(layers "F.Cu" "F.Mask" "F.Paste")
			(net "P3V3_STBY")
			(options
				(clearance outline)
				(anchor circle)
			)
			(primitives
				(gr_poly
					(pts
						(arc
							(start -0.1778 -0.2794)
							(mid -0.249642 -0.249642)
							(end -0.2794 -0.1778)
						)
						(arc
							(start -0.2794 0.1778)
							(mid -0.249642 0.249642)
							(end -0.1778 0.2794)
						)
						(arc
							(start 0.1778 0.2794)
							(mid 0.249642 0.249642)
							(end 0.2794 0.1778)
						)
						(arc
							(start 0.2794 -0.1778)
							(mid 0.249642 -0.249642)
							(end 0.1778 -0.2794)
						)
					)
					(width 0)
					(fill yes)
				)
			)
		)
		(pad "2" smd custom
			(at 0 0.4445 90)
			(size 0.1397 0.1397)
			(layers "F.Cu" "F.Mask" "F.Paste")
			(net "ROMA21")
			(options
				(clearance outline)
				(anchor circle)
			)
			(primitives
				(gr_poly
					(pts
						(arc
							(start -0.1778 -0.2794)
							(mid -0.249642 -0.249642)
							(end -0.2794 -0.1778)
						)
						(arc
							(start -0.2794 0.1778)
							(mid -0.249642 0.249642)
							(end -0.1778 0.2794)
						)
						(arc
							(start 0.1778 0.2794)
							(mid 0.249642 0.249642)
							(end 0.2794 0.1778)
						)
						(arc
							(start 0.2794 -0.1778)
							(mid 0.249642 -0.249642)
							(end 0.1778 -0.2794)
						)
					)
					(width 0)
					(fill yes)
				)
			)
		)
	)
	(footprint ""
		(layer "F.Cu")
		(at 303.320958 -60.452 -90)
		(property "Reference" "R205"
			(at 0 0 270)
			(layer "F.SilkS")
			(hide yes)
			(effects
				(font
					(size 1.27 1.27)
				)
			)
		)
		(property "Value" "0R2J-2-GP"
			(at 0.064008 -3.993896 270)
			(unlocked yes)
			(layer "F.Fab")
			(hide yes)
			(effects
				(font
					(size 1.016 1.016)
					(thickness 0.1524)
				)
			)
		)
		(property "Device Type" "R402H16"
			(at 0.064008 -5.517896 270)
			(unlocked yes)
			(layer "F.Fab")
			(hide yes)
			(effects
				(font
					(size 1.016 1.016)
					(thickness 0.1524)
				)
			)
		)
		(duplicate_pad_numbers_are_jumpers no)
		(fp_line
			(start -0.508 -0.9398)
			(end -0.508 0.9398)
			(stroke
				(width 0.1524)
				(type default)
			)
			(layer "F.SilkS")
		)
		(fp_line
			(start 0.508 -0.9398)
			(end -0.508 -0.9398)
			(stroke
				(width 0.1524)
				(type default)
			)
			(layer "F.SilkS")
		)
		(fp_rect
			(start -0.508 0.9398)
			(end 0.508 -0.9398)
			(stroke
				(width 0)
				(type default)
			)
			(fill no)
			(layer "F.CrtYd")
		)
		(fp_rect
			(start -0.508 0.9398)
			(end 0.508 -0.9398)
			(stroke
				(width 0)
				(type default)
			)
			(fill no)
			(layer "F.Fab")
		)
		(pad "1" smd custom
			(at 0 -0.4445 270)
			(size 0.1397 0.1397)
			(layers "F.Cu" "F.Mask" "F.Paste")
			(net "SAS_I2C_C_10G_SCL")
			(options
				(clearance outline)
				(anchor circle)
			)
			(primitives
				(gr_poly
					(pts
						(arc
							(start -0.1778 -0.2794)
							(mid -0.249642 -0.249642)
							(end -0.2794 -0.1778)
						)
						(arc
							(start -0.2794 0.1778)
							(mid -0.249642 0.249642)
							(end -0.1778 0.2794)
						)
						(arc
							(start 0.1778 0.2794)
							(mid 0.249642 0.249642)
							(end 0.2794 0.1778)
						)
						(arc
							(start 0.2794 -0.1778)
							(mid 0.249642 -0.249642)
							(end 0.1778 -0.2794)
						)
					)
					(width 0)
					(fill yes)
				)
			)
		)
		(pad "2" smd custom
			(at 0 0.4445 270)
			(size 0.1397 0.1397)
			(layers "F.Cu" "F.Mask" "F.Paste")
			(net "BMC_10G_SCL_2")
			(options
				(clearance outline)
				(anchor circle)
			)
			(primitives
				(gr_poly
					(pts
						(arc
							(start -0.1778 -0.2794)
							(mid -0.249642 -0.249642)
							(end -0.2794 -0.1778)
						)
						(arc
							(start -0.2794 0.1778)
							(mid -0.249642 0.249642)
							(end -0.1778 0.2794)
						)
						(arc
							(start 0.1778 0.2794)
							(mid 0.249642 0.249642)
							(end 0.2794 0.1778)
						)
						(arc
							(start 0.2794 -0.1778)
							(mid 0.249642 -0.249642)
							(end 0.1778 -0.2794)
						)
					)
					(width 0)
					(fill yes)
				)
			)
		)
	)
	(footprint ""
		(layer "F.Cu")
		(at 35.052 -79.248 -90)
		(property "Reference" "R677"
			(at 0 0 270)
			(layer "F.SilkS")
			(hide yes)
			(effects
				(font
					(size 1.27 1.27)
				)
			)
		)
		(property "Value" "1KR2F-3-GP"
			(at 0.064008 -3.993896 270)
			(unlocked yes)
			(layer "F.Fab")
			(hide yes)
			(effects
				(font
					(size 1.016 1.016)
					(thickness 0.1524)
				)
			)
		)
		(property "Device Type" "R402H16"
			(at 0.064008 -5.517896 270)
			(unlocked yes)
			(layer "F.Fab")
			(hide yes)
			(effects
				(font
					(size 1.016 1.016)
					(thickness 0.1524)
				)
			)
		)
		(duplicate_pad_numbers_are_jumpers no)
		(fp_line
			(start -0.508 -0.9398)
			(end -0.508 0.9398)
			(stroke
				(width 0.1524)
				(type default)
			)
			(layer "F.SilkS")
		)
		(fp_line
			(start 0.508 -0.9398)
			(end -0.508 -0.9398)
			(stroke
				(width 0.1524)
				(type default)
			)
			(layer "F.SilkS")
		)
		(fp_rect
			(start -0.508 0.9398)
			(end 0.508 -0.9398)
			(stroke
				(width 0)
				(type default)
			)
			(fill no)
			(layer "F.CrtYd")
		)
		(fp_rect
			(start -0.508 0.9398)
			(end 0.508 -0.9398)
			(stroke
				(width 0)
				(type default)
			)
			(fill no)
			(layer "F.Fab")
		)
		(pad "1" smd custom
			(at 0 -0.4445 270)
			(size 0.1397 0.1397)
			(layers "F.Cu" "F.Mask" "F.Paste")
			(net "INTA_LED_BLUE_B")
			(options
				(clearance outline)
				(anchor circle)
			)
			(primitives
				(gr_poly
					(pts
						(arc
							(start -0.1778 -0.2794)
							(mid -0.249642 -0.249642)
							(end -0.2794 -0.1778)
						)
						(arc
							(start -0.2794 0.1778)
							(mid -0.249642 0.249642)
							(end -0.1778 0.2794)
						)
						(arc
							(start 0.1778 0.2794)
							(mid 0.249642 0.249642)
							(end 0.2794 0.1778)
						)
						(arc
							(start 0.2794 -0.1778)
							(mid 0.249642 -0.249642)
							(end 0.1778 -0.2794)
						)
					)
					(width 0)
					(fill yes)
				)
			)
		)
		(pad "2" smd custom
			(at 0 0.4445 270)
			(size 0.1397 0.1397)
			(layers "F.Cu" "F.Mask" "F.Paste")
			(net "GND")
			(options
				(clearance outline)
				(anchor circle)
			)
			(primitives
				(gr_poly
					(pts
						(arc
							(start -0.1778 -0.2794)
							(mid -0.249642 -0.249642)
							(end -0.2794 -0.1778)
						)
						(arc
							(start -0.2794 0.1778)
							(mid -0.249642 0.249642)
							(end -0.1778 0.2794)
						)
						(arc
							(start 0.1778 0.2794)
							(mid 0.249642 0.249642)
							(end 0.2794 0.1778)
						)
						(arc
							(start 0.2794 -0.1778)
							(mid 0.249642 -0.249642)
							(end 0.1778 -0.2794)
						)
					)
					(width 0)
					(fill yes)
				)
			)
		)
	)
	(footprint ""
		(layer "F.Cu")
		(at 14.928088 -202.185016)
		(property "Reference" "SR579"
			(at 0 0 0)
			(layer "F.SilkS")
			(hide yes)
			(effects
				(font
					(size 1.27 1.27)
				)
			)
		)
		(property "Value" "4K7R2F-GP"
			(at 0.064008 -3.993896 0)
			(unlocked yes)
			(layer "F.Fab")
			(hide yes)
			(effects
				(font
					(size 1.016 1.016)
					(thickness 0.1524)
				)
			)
		)
		(property "Device Type" "R402H16"
			(at 0.064008 -5.517896 0)
			(unlocked yes)
			(layer "F.Fab")
			(hide yes)
			(effects
				(font
					(size 1.016 1.016)
					(thickness 0.1524)
				)
			)
		)
		(duplicate_pad_numbers_are_jumpers no)
		(fp_line
			(start -0.508 -0.9398)
			(end -0.508 0.9398)
			(stroke
				(width 0.1524)
				(type default)
			)
			(layer "F.SilkS")
		)
		(fp_line
			(start 0.508 -0.9398)
			(end -0.508 -0.9398)
			(stroke
				(width 0.1524)
				(type default)
			)
			(layer "F.SilkS")
		)
		(fp_rect
			(start -0.508 0.9398)
			(end 0.508 -0.9398)
			(stroke
				(width 0)
				(type default)
			)
			(fill no)
			(layer "F.CrtYd")
		)
		(fp_rect
			(start -0.508 0.9398)
			(end 0.508 -0.9398)
			(stroke
				(width 0)
				(type default)
			)
			(fill no)
			(layer "F.Fab")
		)
		(pad "1" smd custom
			(at 0 -0.4445)
			(size 0.1397 0.1397)
			(layers "F.Cu" "F.Mask" "F.Paste")
			(net "BMC_I2C_SDA_10")
			(options
				(clearance outline)
				(anchor circle)
			)
			(primitives
				(gr_poly
					(pts
						(arc
							(start -0.1778 -0.2794)
							(mid -0.249642 -0.249642)
							(end -0.2794 -0.1778)
						)
						(arc
							(start -0.2794 0.1778)
							(mid -0.249642 0.249642)
							(end -0.1778 0.2794)
						)
						(arc
							(start 0.1778 0.2794)
							(mid 0.249642 0.249642)
							(end 0.2794 0.1778)
						)
						(arc
							(start 0.2794 -0.1778)
							(mid 0.249642 -0.249642)
							(end 0.1778 -0.2794)
						)
					)
					(width 0)
					(fill yes)
				)
			)
		)
		(pad "2" smd custom
			(at 0 0.4445)
			(size 0.1397 0.1397)
			(layers "F.Cu" "F.Mask" "F.Paste")
			(net "P3V3_STBY")
			(options
				(clearance outline)
				(anchor circle)
			)
			(primitives
				(gr_poly
					(pts
						(arc
							(start -0.1778 -0.2794)
							(mid -0.249642 -0.249642)
							(end -0.2794 -0.1778)
						)
						(arc
							(start -0.2794 0.1778)
							(mid -0.249642 0.249642)
							(end -0.1778 0.2794)
						)
						(arc
							(start 0.1778 0.2794)
							(mid 0.249642 0.249642)
							(end 0.2794 0.1778)
						)
						(arc
							(start 0.2794 -0.1778)
							(mid 0.249642 -0.249642)
							(end 0.1778 -0.2794)
						)
					)
					(width 0)
					(fill yes)
				)
			)
		)
	)
	(footprint ""
		(layer "F.Cu")
		(at 284.979872 -215.591136 180)
		(property "Reference" "PC87"
			(at 0 0 180)
			(layer "F.SilkS")
			(hide yes)
			(effects
				(font
					(size 1.27 1.27)
				)
			)
		)
		(property "Value" "SC470P50V2KX-3GP"
			(at 1.1811 -2.7051 180)
			(unlocked yes)
			(layer "F.Fab")
			(hide yes)
			(effects
				(font
					(size 1.016 1.016)
					(thickness 0.1524)
				)
			)
		)
		(property "Device Type" "C402H22"
			(at 1.1811 -4.2291 180)
			(unlocked yes)
			(layer "F.Fab")
			(hide yes)
			(effects
				(font
					(size 1.016 1.016)
					(thickness 0.1524)
				)
			)
		)
		(duplicate_pad_numbers_are_jumpers no)
		(fp_rect
			(start -0.4318 0.9525)
			(end 0.4318 -0.9525)
			(stroke
				(width 0)
				(type default)
			)
			(fill no)
			(layer "F.CrtYd")
		)
		(fp_rect
			(start -0.4318 0.9525)
			(end 0.4318 -0.9525)
			(stroke
				(width 0)
				(type default)
			)
			(fill no)
			(layer "F.Fab")
		)
		(pad "1" smd custom
			(at 0 -0.4445 180)
			(size 0.1524 0.1524)
			(layers "F.Cu" "F.Mask" "F.Paste")
			(net "GND")
			(options
				(clearance outline)
				(anchor circle)
			)
			(primitives
				(gr_poly
					(pts
						(arc
							(start 0.3048 -0.2032)
							(mid 0.275042 -0.275042)
							(end 0.2032 -0.3048)
						)
						(arc
							(start -0.2032 -0.3048)
							(mid -0.275042 -0.275042)
							(end -0.3048 -0.2032)
						)
						(arc
							(start -0.3048 0.2032)
							(mid -0.275042 0.275042)
							(end -0.2032 0.3048)
						)
						(arc
							(start 0.2032 0.3048)
							(mid 0.275042 0.275042)
							(end 0.3048 0.2032)
						)
					)
					(width 0)
					(fill yes)
				)
			)
		)
		(pad "2" smd custom
			(at 0 0.4445 180)
			(size 0.1524 0.1524)
			(layers "F.Cu" "F.Mask" "F.Paste")
			(net "TPS74801_1V53_STBY_SS")
			(options
				(clearance outline)
				(anchor circle)
			)
			(primitives
				(gr_poly
					(pts
						(arc
							(start 0.3048 -0.2032)
							(mid 0.275042 -0.275042)
							(end 0.2032 -0.3048)
						)
						(arc
							(start -0.2032 -0.3048)
							(mid -0.275042 -0.275042)
							(end -0.3048 -0.2032)
						)
						(arc
							(start -0.3048 0.2032)
							(mid -0.275042 0.275042)
							(end -0.2032 0.3048)
						)
						(arc
							(start 0.2032 0.3048)
							(mid 0.275042 0.275042)
							(end 0.3048 0.2032)
						)
					)
					(width 0)
					(fill yes)
				)
			)
		)
	)
	(footprint ""
		(layer "F.Cu")
		(at 179.33797 -67.183 180)
		(property "Reference" "C289"
			(at 0 0 180)
			(layer "F.SilkS")
			(hide yes)
			(effects
				(font
					(size 1.27 1.27)
				)
			)
		)
		(property "Value" "SCD1U25V2KX-2-GP"
			(at 1.1811 -2.7051 180)
			(unlocked yes)
			(layer "F.Fab")
			(hide yes)
			(effects
				(font
					(size 1.016 1.016)
					(thickness 0.1524)
				)
			)
		)
		(property "Device Type" "C402H22"
			(at 1.1811 -4.2291 180)
			(unlocked yes)
			(layer "F.Fab")
			(hide yes)
			(effects
				(font
					(size 1.016 1.016)
					(thickness 0.1524)
				)
			)
		)
		(duplicate_pad_numbers_are_jumpers no)
		(fp_rect
			(start -0.4318 0.9525)
			(end 0.4318 -0.9525)
			(stroke
				(width 0)
				(type default)
			)
			(fill no)
			(layer "F.CrtYd")
		)
		(fp_rect
			(start -0.4318 0.9525)
			(end 0.4318 -0.9525)
			(stroke
				(width 0)
				(type default)
			)
			(fill no)
			(layer "F.Fab")
		)
		(pad "1" smd custom
			(at 0 -0.4445 180)
			(size 0.1524 0.1524)
			(layers "F.Cu" "F.Mask" "F.Paste")
			(net "GND")
			(options
				(clearance outline)
				(anchor circle)
			)
			(primitives
				(gr_poly
					(pts
						(arc
							(start 0.3048 -0.2032)
							(mid 0.275042 -0.275042)
							(end 0.2032 -0.3048)
						)
						(arc
							(start -0.2032 -0.3048)
							(mid -0.275042 -0.275042)
							(end -0.3048 -0.2032)
						)
						(arc
							(start -0.3048 0.2032)
							(mid -0.275042 0.275042)
							(end -0.2032 0.3048)
						)
						(arc
							(start 0.2032 0.3048)
							(mid 0.275042 0.275042)
							(end 0.3048 0.2032)
						)
					)
					(width 0)
					(fill yes)
				)
			)
		)
		(pad "2" smd custom
			(at 0 0.4445 180)
			(size 0.1524 0.1524)
			(layers "F.Cu" "F.Mask" "F.Paste")
			(net "TP_MSB_B32_CPU_SATA_TX_N")
			(options
				(clearance outline)
				(anchor circle)
			)
			(primitives
				(gr_poly
					(pts
						(arc
							(start 0.3048 -0.2032)
							(mid 0.275042 -0.275042)
							(end 0.2032 -0.3048)
						)
						(arc
							(start -0.2032 -0.3048)
							(mid -0.275042 -0.275042)
							(end -0.3048 -0.2032)
						)
						(arc
							(start -0.3048 0.2032)
							(mid -0.275042 0.275042)
							(end -0.2032 0.3048)
						)
						(arc
							(start 0.2032 0.3048)
							(mid 0.275042 0.275042)
							(end 0.3048 0.2032)
						)
					)
					(width 0)
					(fill yes)
				)
			)
		)
	)
	(footprint ""
		(layer "F.Cu")
		(at 16.333216 -211.00288 90)
		(property "Reference" "SR590"
			(at 0 0 90)
			(layer "F.SilkS")
			(hide yes)
			(effects
				(font
					(size 1.27 1.27)
				)
			)
		)
		(property "Value" "4K7R2F-GP"
			(at 0.064008 -3.993896 90)
			(unlocked yes)
			(layer "F.Fab")
			(hide yes)
			(effects
				(font
					(size 1.016 1.016)
					(thickness 0.1524)
				)
			)
		)
		(property "Device Type" "R402H16"
			(at 0.064008 -5.517896 90)
			(unlocked yes)
			(layer "F.Fab")
			(hide yes)
			(effects
				(font
					(size 1.016 1.016)
					(thickness 0.1524)
				)
			)
		)
		(duplicate_pad_numbers_are_jumpers no)
		(fp_line
			(start 0.508 -0.9398)
			(end -0.508 -0.9398)
			(stroke
				(width 0.1524)
				(type default)
			)
			(layer "F.SilkS")
		)
		(fp_line
			(start -0.508 -0.9398)
			(end -0.508 0.9398)
			(stroke
				(width 0.1524)
				(type default)
			)
			(layer "F.SilkS")
		)
		(fp_rect
			(start -0.508 0.9398)
			(end 0.508 -0.9398)
			(stroke
				(width 0)
				(type default)
			)
			(fill no)
			(layer "F.CrtYd")
		)
		(fp_rect
			(start -0.508 0.9398)
			(end 0.508 -0.9398)
			(stroke
				(width 0)
				(type default)
			)
			(fill no)
			(layer "F.Fab")
		)
		(pad "1" smd custom
			(at 0 -0.4445 90)
			(size 0.1397 0.1397)
			(layers "F.Cu" "F.Mask" "F.Paste")
			(net "BMC_IOEXP_SCL_10")
			(options
				(clearance outline)
				(anchor circle)
			)
			(primitives
				(gr_poly
					(pts
						(arc
							(start -0.1778 -0.2794)
							(mid -0.249642 -0.249642)
							(end -0.2794 -0.1778)
						)
						(arc
							(start -0.2794 0.1778)
							(mid -0.249642 0.249642)
							(end -0.1778 0.2794)
						)
						(arc
							(start 0.1778 0.2794)
							(mid 0.249642 0.249642)
							(end 0.2794 0.1778)
						)
						(arc
							(start 0.2794 -0.1778)
							(mid 0.249642 -0.249642)
							(end 0.1778 -0.2794)
						)
					)
					(width 0)
					(fill yes)
				)
			)
		)
		(pad "2" smd custom
			(at 0 0.4445 90)
			(size 0.1397 0.1397)
			(layers "F.Cu" "F.Mask" "F.Paste")
			(net "P1V8_E")
			(options
				(clearance outline)
				(anchor circle)
			)
			(primitives
				(gr_poly
					(pts
						(arc
							(start -0.1778 -0.2794)
							(mid -0.249642 -0.249642)
							(end -0.2794 -0.1778)
						)
						(arc
							(start -0.2794 0.1778)
							(mid -0.249642 0.249642)
							(end -0.1778 0.2794)
						)
						(arc
							(start 0.1778 0.2794)
							(mid 0.249642 0.249642)
							(end 0.2794 0.1778)
						)
						(arc
							(start 0.2794 -0.1778)
							(mid 0.249642 -0.249642)
							(end 0.1778 -0.2794)
						)
					)
					(width 0)
					(fill yes)
				)
			)
		)
	)
	(footprint ""
		(layer "F.Cu")
		(at 68.961 -228.092 180)
		(property "Reference" "D36"
			(at 0 0 180)
			(layer "F.SilkS")
			(hide yes)
			(effects
				(font
					(size 1.27 1.27)
				)
			)
		)
		(property "Value" "MM3Z15VT1G-GP-U"
			(at 0 -6.7818 180)
			(unlocked yes)
			(layer "F.Fab")
			(hide yes)
			(effects
				(font
					(size 1.016 1.016)
					(thickness 0.1524)
				)
			)
		)
		(property "Device Type" "SOD323AKH44"
			(at 0 -8.6868 180)
			(unlocked yes)
			(layer "F.Fab")
			(hide yes)
			(effects
				(font
					(size 1.016 1.016)
					(thickness 0.1524)
				)
			)
		)
		(duplicate_pad_numbers_are_jumpers no)
		(fp_line
			(start 0.889 2.159)
			(end -0.889 2.159)
			(stroke
				(width 0.1524)
				(type default)
			)
			(layer "F.SilkS")
		)
		(fp_line
			(start 0.889 -1.9304)
			(end 0.889 2.159)
			(stroke
				(width 0.1524)
				(type default)
			)
			(layer "F.SilkS")
		)
		(fp_line
			(start 0.762 2.0574)
			(end -0.762 2.0574)
			(stroke
				(width 0.508)
				(type default)
			)
			(layer "F.SilkS")
		)
		(fp_line
			(start -0.889 2.159)
			(end -0.889 -1.9304)
			(stroke
				(width 0.1524)
				(type default)
			)
			(layer "F.SilkS")
		)
		(fp_line
			(start -0.889 -1.9304)
			(end 0.889 -1.9304)
			(stroke
				(width 0.1524)
				(type default)
			)
			(layer "F.SilkS")
		)
		(fp_rect
			(start -1.016 2.3114)
			(end 1.016 -2.0066)
			(stroke
				(width 0)
				(type default)
			)
			(fill no)
			(layer "F.CrtYd")
		)
		(fp_poly
			(pts
				(xy -1.016 -2.0066) (xy 1.016 -2.0066) (xy 1.016 2.3114) (xy -1.016 2.3114)
			)
			(stroke
				(width 0)
				(type default)
			)
			(fill no)
			(layer "F.Fab")
		)
		(pad "A" smd rect
			(at 0 -1.143 180)
			(size 0.5588 1.016)
			(layers "F.Cu" "F.Mask" "F.Paste")
			(net "MB0_P12V_R")
		)
		(pad "K" smd rect
			(at 0 1.143 180)
			(size 0.5588 1.016)
			(layers "F.Cu" "F.Mask" "F.Paste")
			(net "MB0_CM_GATE_R")
		)
	)
	(footprint ""
		(layer "F.Cu")
		(at 330.484988 -75.946 -90)
		(property "Reference" "U195"
			(at 0 0 270)
			(layer "F.SilkS")
			(hide yes)
			(effects
				(font
					(size 1.27 1.27)
				)
			)
		)
		(property "Value" "W25Q128FVSIG-GP"
			(at 0 -13.1572 270)
			(unlocked yes)
			(layer "F.Fab")
			(hide yes)
			(effects
				(font
					(size 1.016 1.016)
					(thickness 0.1524)
				)
			)
		)
		(property "Device Type" "SOIC8-1H86"
			(at 0 -14.6812 270)
			(unlocked yes)
			(layer "F.Fab")
			(hide yes)
			(effects
				(font
					(size 1.016 1.016)
					(thickness 0.1524)
				)
			)
		)
		(duplicate_pad_numbers_are_jumpers no)
		(fp_line
			(start -3.048 4.572)
			(end -3.048 2.3876)
			(stroke
				(width 0.508)
				(type default)
			)
			(layer "F.SilkS")
		)
		(fp_line
			(start 2.1336 2.3876)
			(end -3.048 2.3876)
			(stroke
				(width 0.1524)
				(type default)
			)
			(layer "F.SilkS")
		)
		(fp_line
			(start -2.3114 0)
			(end -3.2258 0.9144)
			(stroke
				(width 0.1524)
				(type default)
			)
			(layer "F.SilkS")
		)
		(fp_line
			(start -2.3114 0)
			(end -3.2258 -0.9144)
			(stroke
				(width 0.1524)
				(type default)
			)
			(layer "F.SilkS")
		)
		(fp_line
			(start -3.2258 -2.3876)
			(end -3.2258 4.572)
			(stroke
				(width 0.1524)
				(type default)
			)
			(layer "F.SilkS")
		)
		(fp_line
			(start 2.1336 -2.3876)
			(end 2.1336 2.3876)
			(stroke
				(width 0.1524)
				(type default)
			)
			(layer "F.SilkS")
		)
		(fp_line
			(start 2.1336 -2.3876)
			(end -3.2258 -2.3876)
			(stroke
				(width 0.1524)
				(type default)
			)
			(layer "F.SilkS")
		)
		(fp_poly
			(pts
				(xy -2.2352 2.3876) (xy 2.1336 2.3876) (xy 2.1336 -2.3876) (xy -2.2352 -2.3876)
			)
			(stroke
				(width 0)
				(type default)
			)
			(fill yes)
			(layer "F.SilkS")
		)
		(fp_poly
			(pts
				(xy -3.302 4.826) (xy 3.302 4.826) (xy 3.302 -4.826) (xy -3.302 -4.826)
			)
			(stroke
				(width 0)
				(type default)
			)
			(fill no)
			(layer "F.CrtYd")
		)
		(fp_poly
			(pts
				(xy -3.302 -4.826) (xy 3.302 -4.826) (xy 3.302 4.826) (xy -3.302 4.826)
			)
			(stroke
				(width 0)
				(type default)
			)
			(fill no)
			(layer "F.Fab")
		)
		(pad "1" smd rect
			(at -1.905 3.4925 270)
			(size 0.635 1.651)
			(layers "F.Cu" "F.Mask" "F.Paste")
			(net "FLA_CS_1")
		)
		(pad "2" smd rect
			(at -0.635 3.4925 270)
			(size 0.635 1.651)
			(layers "F.Cu" "F.Mask" "F.Paste")
			(net "ROMD2_R_R")
		)
		(pad "3" smd rect
			(at 0.635 3.4925 270)
			(size 0.635 1.651)
			(layers "F.Cu" "F.Mask" "F.Paste")
			(net "FLA_WPN")
		)
		(pad "4" smd rect
			(at 1.905 3.4925 270)
			(size 0.635 1.651)
			(layers "F.Cu" "F.Mask" "F.Paste")
			(net "GND")
		)
		(pad "5" smd rect
			(at 1.905 -3.4925 270)
			(size 0.635 1.651)
			(layers "F.Cu" "F.Mask" "F.Paste")
			(net "ROMD0_R_R")
		)
		(pad "6" smd rect
			(at 0.635 -3.4925 270)
			(size 0.635 1.651)
			(layers "F.Cu" "F.Mask" "F.Paste")
			(net "ROMD1_R_R")
		)
		(pad "7" smd rect
			(at -0.635 -3.4925 270)
			(size 0.635 1.651)
			(layers "F.Cu" "F.Mask" "F.Paste")
			(net "PU_IBMC_BT_HOLD_N")
		)
		(pad "8" smd rect
			(at -1.905 -3.4925 270)
			(size 0.635 1.651)
			(layers "F.Cu" "F.Mask" "F.Paste")
			(net "P3V3_STBY")
		)
	)
	(footprint ""
		(layer "F.Cu")
		(at 202.888596 -110.636812 180)
		(property "Reference" "PR9016"
			(at 0 0 180)
			(layer "F.SilkS")
			(hide yes)
			(effects
				(font
					(size 1.27 1.27)
				)
			)
		)
		(property "Value" "0R2J-2-GP"
			(at 0.064008 -3.993896 180)
			(unlocked yes)
			(layer "F.Fab")
			(hide yes)
			(effects
				(font
					(size 1.016 1.016)
					(thickness 0.1524)
				)
			)
		)
		(property "Device Type" "R402H16"
			(at 0.064008 -5.517896 180)
			(unlocked yes)
			(layer "F.Fab")
			(hide yes)
			(effects
				(font
					(size 1.016 1.016)
					(thickness 0.1524)
				)
			)
		)
		(duplicate_pad_numbers_are_jumpers no)
		(fp_line
			(start 0.508 -0.9398)
			(end -0.508 -0.9398)
			(stroke
				(width 0.1524)
				(type default)
			)
			(layer "F.SilkS")
		)
		(fp_line
			(start -0.508 -0.9398)
			(end -0.508 0.9398)
			(stroke
				(width 0.1524)
				(type default)
			)
			(layer "F.SilkS")
		)
		(fp_rect
			(start -0.508 0.9398)
			(end 0.508 -0.9398)
			(stroke
				(width 0)
				(type default)
			)
			(fill no)
			(layer "F.CrtYd")
		)
		(fp_rect
			(start -0.508 0.9398)
			(end 0.508 -0.9398)
			(stroke
				(width 0)
				(type default)
			)
			(fill no)
			(layer "F.Fab")
		)
		(pad "1" smd custom
			(at 0 -0.4445 180)
			(size 0.1397 0.1397)
			(layers "F.Cu" "F.Mask" "F.Paste")
			(net "P1V5_E_VBST_RR")
			(options
				(clearance outline)
				(anchor circle)
			)
			(primitives
				(gr_poly
					(pts
						(arc
							(start -0.1778 -0.2794)
							(mid -0.249642 -0.249642)
							(end -0.2794 -0.1778)
						)
						(arc
							(start -0.2794 0.1778)
							(mid -0.249642 0.249642)
							(end -0.1778 0.2794)
						)
						(arc
							(start 0.1778 0.2794)
							(mid 0.249642 0.249642)
							(end 0.2794 0.1778)
						)
						(arc
							(start 0.2794 -0.1778)
							(mid 0.249642 -0.249642)
							(end 0.1778 -0.2794)
						)
					)
					(width 0)
					(fill yes)
				)
			)
		)
		(pad "2" smd custom
			(at 0 0.4445 180)
			(size 0.1397 0.1397)
			(layers "F.Cu" "F.Mask" "F.Paste")
			(net "P1V5_E_VBST")
			(options
				(clearance outline)
				(anchor circle)
			)
			(primitives
				(gr_poly
					(pts
						(arc
							(start -0.1778 -0.2794)
							(mid -0.249642 -0.249642)
							(end -0.2794 -0.1778)
						)
						(arc
							(start -0.2794 0.1778)
							(mid -0.249642 0.249642)
							(end -0.1778 0.2794)
						)
						(arc
							(start 0.1778 0.2794)
							(mid 0.249642 0.249642)
							(end 0.2794 0.1778)
						)
						(arc
							(start 0.2794 -0.1778)
							(mid 0.249642 -0.249642)
							(end 0.1778 -0.2794)
						)
					)
					(width 0)
					(fill yes)
				)
			)
		)
	)
	(footprint ""
		(layer "F.Cu")
		(at 349.123 -112.776 180)
		(property "Reference" "PR5"
			(at 0 0 180)
			(layer "F.SilkS")
			(hide yes)
			(effects
				(font
					(size 1.27 1.27)
				)
			)
		)
		(property "Value" "0R6J-3-GP"
			(at -0.0508 -4.8514 180)
			(unlocked yes)
			(layer "F.Fab")
			(hide yes)
			(effects
				(font
					(size 1.016 1.016)
					(thickness 0.1524)
				)
			)
		)
		(property "Device Type" "R1206H28"
			(at 0 -6.3754 180)
			(unlocked yes)
			(layer "F.Fab")
			(hide yes)
			(effects
				(font
					(size 1.016 1.016)
					(thickness 0.1524)
				)
			)
		)
		(duplicate_pad_numbers_are_jumpers no)
		(fp_line
			(start 1.016 2.2352)
			(end -1.016 2.2352)
			(stroke
				(width 0.1524)
				(type default)
			)
			(layer "F.SilkS")
		)
		(fp_line
			(start 1.016 -2.2352)
			(end 1.016 2.2352)
			(stroke
				(width 0.1524)
				(type default)
			)
			(layer "F.SilkS")
		)
		(fp_line
			(start -1.016 2.2352)
			(end -1.016 -2.2352)
			(stroke
				(width 0.1524)
				(type default)
			)
			(layer "F.SilkS")
		)
		(fp_line
			(start -1.016 -2.2352)
			(end 1.016 -2.2352)
			(stroke
				(width 0.1524)
				(type default)
			)
			(layer "F.SilkS")
		)
		(fp_rect
			(start -1.0922 2.3114)
			(end 1.0922 -2.3114)
			(stroke
				(width 0)
				(type default)
			)
			(fill no)
			(layer "F.CrtYd")
		)
		(fp_poly
			(pts
				(xy -1.0922 -2.3114) (xy 1.0922 -2.3114) (xy 1.0922 2.3114) (xy -1.0922 2.3114)
			)
			(stroke
				(width 0)
				(type default)
			)
			(fill no)
			(layer "F.Fab")
		)
		(pad "1" smd rect
			(at 0 -1.397 180)
			(size 1.651 1.27)
			(layers "F.Cu" "F.Mask" "F.Paste")
			(net "P5V_STBY_VIN")
		)
		(pad "2" smd rect
			(at 0 1.397 180)
			(size 1.651 1.27)
			(layers "F.Cu" "F.Mask" "F.Paste")
			(net "P12V")
		)
	)
	(footprint ""
		(layer "F.Cu")
		(at 81.031842 -117.927882 -90)
		(property "Reference" "SR755"
			(at 0 0 270)
			(layer "F.SilkS")
			(hide yes)
			(effects
				(font
					(size 1.27 1.27)
				)
			)
		)
		(property "Value" "4K7R2F-GP"
			(at 0.064008 -3.993896 270)
			(unlocked yes)
			(layer "F.Fab")
			(hide yes)
			(effects
				(font
					(size 1.016 1.016)
					(thickness 0.1524)
				)
			)
		)
		(property "Device Type" "R402H16"
			(at 0.064008 -5.517896 270)
			(unlocked yes)
			(layer "F.Fab")
			(hide yes)
			(effects
				(font
					(size 1.016 1.016)
					(thickness 0.1524)
				)
			)
		)
		(duplicate_pad_numbers_are_jumpers no)
		(fp_line
			(start -0.508 -0.9398)
			(end -0.508 0.9398)
			(stroke
				(width 0.1524)
				(type default)
			)
			(layer "F.SilkS")
		)
		(fp_line
			(start 0.508 -0.9398)
			(end -0.508 -0.9398)
			(stroke
				(width 0.1524)
				(type default)
			)
			(layer "F.SilkS")
		)
		(fp_rect
			(start -0.508 0.9398)
			(end 0.508 -0.9398)
			(stroke
				(width 0)
				(type default)
			)
			(fill no)
			(layer "F.CrtYd")
		)
		(fp_rect
			(start -0.508 0.9398)
			(end 0.508 -0.9398)
			(stroke
				(width 0)
				(type default)
			)
			(fill no)
			(layer "F.Fab")
		)
		(pad "1" smd custom
			(at 0 -0.4445 270)
			(size 0.1397 0.1397)
			(layers "F.Cu" "F.Mask" "F.Paste")
			(net "EXP_IOC_BMC_SDA_14")
			(options
				(clearance outline)
				(anchor circle)
			)
			(primitives
				(gr_poly
					(pts
						(arc
							(start -0.1778 -0.2794)
							(mid -0.249642 -0.249642)
							(end -0.2794 -0.1778)
						)
						(arc
							(start -0.2794 0.1778)
							(mid -0.249642 0.249642)
							(end -0.1778 0.2794)
						)
						(arc
							(start 0.1778 0.2794)
							(mid 0.249642 0.249642)
							(end 0.2794 0.1778)
						)
						(arc
							(start 0.2794 -0.1778)
							(mid 0.249642 -0.249642)
							(end 0.1778 -0.2794)
						)
					)
					(width 0)
					(fill yes)
				)
			)
		)
		(pad "2" smd custom
			(at 0 0.4445 270)
			(size 0.1397 0.1397)
			(layers "F.Cu" "F.Mask" "F.Paste")
			(net "P3V3_STBY")
			(options
				(clearance outline)
				(anchor circle)
			)
			(primitives
				(gr_poly
					(pts
						(arc
							(start -0.1778 -0.2794)
							(mid -0.249642 -0.249642)
							(end -0.2794 -0.1778)
						)
						(arc
							(start -0.2794 0.1778)
							(mid -0.249642 0.249642)
							(end -0.1778 0.2794)
						)
						(arc
							(start 0.1778 0.2794)
							(mid 0.249642 0.249642)
							(end 0.2794 0.1778)
						)
						(arc
							(start 0.2794 -0.1778)
							(mid 0.249642 -0.249642)
							(end 0.1778 -0.2794)
						)
					)
					(width 0)
					(fill yes)
				)
			)
		)
	)
	(footprint ""
		(layer "F.Cu")
		(at 139.500102 -258.59994 180)
		(property "Reference" "GF1"
			(at 0 0 180)
			(layer "F.SilkS")
			(hide yes)
			(effects
				(font
					(size 1.27 1.27)
				)
			)
		)
		(property "Value" "GF-X16-U"
			(at 12.048744 -9.339834 180)
			(unlocked yes)
			(layer "F.Fab")
			(hide yes)
			(effects
				(font
					(size 1.016 1.016)
					(thickness 0.1524)
				)
			)
		)
		(property "Device Type" "GF-X16-U"
			(at 12.048744 -10.863834 180)
			(unlocked yes)
			(layer "F.Fab")
			(hide yes)
			(effects
				(font
					(size 1.016 1.016)
					(thickness 0.1524)
				)
			)
		)
		(duplicate_pad_numbers_are_jumpers no)
		(fp_rect
			(start -13.89126 2.032)
			(end 73.89114 -6.223)
			(stroke
				(width 0)
				(type default)
			)
			(fill no)
			(layer "B.CrtYd")
		)
		(fp_rect
			(start -13.89126 2.032)
			(end 73.89114 -6.223)
			(stroke
				(width 0)
				(type default)
			)
			(fill no)
			(layer "F.CrtYd")
		)
		(fp_rect
			(start -13.89126 2.032)
			(end 73.89114 -6.223)
			(stroke
				(width 0)
				(type default)
			)
			(fill no)
			(layer "B.Fab")
		)
		(fp_rect
			(start -13.89126 2.032)
			(end 73.89114 -6.223)
			(stroke
				(width 0)
				(type default)
			)
			(fill no)
			(layer "F.Fab")
		)
		(pad "A1" smd rect
			(at -11.49985 -2.5908 180)
			(size 0.7112 3.2004)
			(layers "F.Cu" "F.Mask" "F.Paste")
			(net "GND")
		)
		(pad "A2" smd rect
			(at -10.50036 -2.0955 180)
			(size 0.7112 4.191)
			(layers "F.Cu" "F.Mask" "F.Paste")
			(net "SAS_GF_EXP_RX_DP0")
		)
		(pad "A3" smd rect
			(at -9.4996 -2.0955 180)
			(size 0.7112 4.191)
			(layers "F.Cu" "F.Mask" "F.Paste")
			(net "SAS_GF_EXP_RX_DN0")
		)
		(pad "A4" smd rect
			(at -8.50011 -2.0955 180)
			(size 0.7112 4.191)
			(layers "F.Cu" "F.Mask" "F.Paste")
			(net "GND")
		)
		(pad "A5" smd rect
			(at -7.49935 -2.0955 180)
			(size 0.7112 4.191)
			(layers "F.Cu" "F.Mask" "F.Paste")
			(net "GND")
		)
		(pad "A6" smd rect
			(at -6.49986 -2.0955 180)
			(size 0.7112 4.191)
			(layers "F.Cu" "F.Mask" "F.Paste")
			(net "SAS_GF_EXP_RX_DP1")
		)
		(pad "A7" smd rect
			(at -5.50037 -2.0955 180)
			(size 0.7112 4.191)
			(layers "F.Cu" "F.Mask" "F.Paste")
			(net "SAS_GF_EXP_RX_DN1")
		)
		(pad "A8" smd rect
			(at -4.49961 -2.0955 180)
			(size 0.7112 4.191)
			(layers "F.Cu" "F.Mask" "F.Paste")
			(net "GND")
		)
		(pad "A9" smd rect
			(at -3.50012 -2.0955 180)
			(size 0.7112 4.191)
			(layers "F.Cu" "F.Mask" "F.Paste")
			(net "GND")
		)
		(pad "A10" smd rect
			(at -2.49936 -2.0955 180)
			(size 0.7112 4.191)
			(layers "F.Cu" "F.Mask" "F.Paste")
			(net "SAS_GF_EXP_RX_DP2")
		)
		(pad "A11" smd rect
			(at -1.49987 -2.0955 180)
			(size 0.7112 4.191)
			(layers "F.Cu" "F.Mask" "F.Paste")
			(net "SAS_GF_EXP_RX_DN2")
		)
		(pad "A12" smd rect
			(at 1.49987 -2.0955 180)
			(size 0.7112 4.191)
			(layers "F.Cu" "F.Mask" "F.Paste")
			(net "TRAY_ID")
		)
		(pad "A13" smd rect
			(at 2.50063 -2.0955 180)
			(size 0.7112 4.191)
			(layers "F.Cu" "F.Mask" "F.Paste")
			(net "GND")
		)
		(pad "A14" smd rect
			(at 3.50012 -2.0955 180)
			(size 0.7112 4.191)
			(layers "F.Cu" "F.Mask" "F.Paste")
			(net "SAS_GF_EXP_RX_DP3")
		)
		(pad "A15" smd rect
			(at 4.49961 -2.0955 180)
			(size 0.7112 4.191)
			(layers "F.Cu" "F.Mask" "F.Paste")
			(net "SAS_GF_EXP_RX_DN3")
		)
		(pad "A16" smd rect
			(at 5.50037 -2.0955 180)
			(size 0.7112 4.191)
			(layers "F.Cu" "F.Mask" "F.Paste")
			(net "GND")
		)
		(pad "A17" smd rect
			(at 6.49986 -2.0955 180)
			(size 0.7112 4.191)
			(layers "F.Cu" "F.Mask" "F.Paste")
			(net "GND")
		)
		(pad "A18" smd rect
			(at 7.50062 -2.0955 180)
			(size 0.7112 4.191)
			(layers "F.Cu" "F.Mask" "F.Paste")
			(net "SAS_GF_EXP_RX_DP4")
		)
		(pad "A19" smd rect
			(at 8.50011 -2.0955 180)
			(size 0.7112 4.191)
			(layers "F.Cu" "F.Mask" "F.Paste")
			(net "SAS_GF_EXP_RX_DN4")
		)
		(pad "A20" smd rect
			(at 9.4996 -2.0955 180)
			(size 0.7112 4.191)
			(layers "F.Cu" "F.Mask" "F.Paste")
			(net "GND")
		)
		(pad "A21" smd rect
			(at 10.50036 -2.0955 180)
			(size 0.7112 4.191)
			(layers "F.Cu" "F.Mask" "F.Paste")
			(net "GND")
		)
		(pad "A22" smd rect
			(at 11.49985 -2.0955 180)
			(size 0.7112 4.191)
			(layers "F.Cu" "F.Mask" "F.Paste")
			(net "SAS_GF_EXP_RX_DP5")
		)
		(pad "A23" smd rect
			(at 12.50061 -2.0955 180)
			(size 0.7112 4.191)
			(layers "F.Cu" "F.Mask" "F.Paste")
			(net "SAS_GF_EXP_RX_DN5")
		)
		(pad "A24" smd rect
			(at 13.5001 -2.0955 180)
			(size 0.7112 4.191)
			(layers "F.Cu" "F.Mask" "F.Paste")
			(net "GND")
		)
		(pad "A25" smd rect
			(at 14.49959 -2.0955 180)
			(size 0.7112 4.191)
			(layers "F.Cu" "F.Mask" "F.Paste")
			(net "GND")
		)
		(pad "A26" smd rect
			(at 15.50035 -2.0955 180)
			(size 0.7112 4.191)
			(layers "F.Cu" "F.Mask" "F.Paste")
			(net "SAS_GF_EXP_RX_DP6")
		)
		(pad "A27" smd rect
			(at 16.49984 -2.0955 180)
			(size 0.7112 4.191)
			(layers "F.Cu" "F.Mask" "F.Paste")
			(net "SAS_GF_EXP_RX_DN6")
		)
		(pad "A28" smd rect
			(at 17.5006 -2.0955 180)
			(size 0.7112 4.191)
			(layers "F.Cu" "F.Mask" "F.Paste")
			(net "GND")
		)
		(pad "A29" smd rect
			(at 18.50009 -2.0955 180)
			(size 0.7112 4.191)
			(layers "F.Cu" "F.Mask" "F.Paste")
			(net "GND")
		)
		(pad "A30" smd rect
			(at 19.49958 -2.0955 180)
			(size 0.7112 4.191)
			(layers "F.Cu" "F.Mask" "F.Paste")
			(net "SAS_GF_EXP_RX_DP7")
		)
		(pad "A31" smd rect
			(at 20.50034 -2.0955 180)
			(size 0.7112 4.191)
			(layers "F.Cu" "F.Mask" "F.Paste")
			(net "SAS_GF_EXP_RX_DN7")
		)
		(pad "A32" smd rect
			(at 21.49983 -2.0955 180)
			(size 0.7112 4.191)
			(layers "F.Cu" "F.Mask" "F.Paste")
			(net "GND")
		)
		(pad "A33" smd rect
			(at 22.50059 -2.0955 180)
			(size 0.7112 4.191)
			(layers "F.Cu" "F.Mask" "F.Paste")
			(net "GND")
		)
		(pad "A34" smd rect
			(at 23.50008 -2.0955 180)
			(size 0.7112 4.191)
			(layers "F.Cu" "F.Mask" "F.Paste")
			(net "SAS_GF_EXP_RX_DP8")
		)
		(pad "A35" smd rect
			(at 24.49957 -2.0955 180)
			(size 0.7112 4.191)
			(layers "F.Cu" "F.Mask" "F.Paste")
			(net "SAS_GF_EXP_RX_DN8")
		)
		(pad "A36" smd rect
			(at 25.50033 -2.0955 180)
			(size 0.7112 4.191)
			(layers "F.Cu" "F.Mask" "F.Paste")
			(net "GND")
		)
		(pad "A37" smd rect
			(at 26.49982 -2.0955 180)
			(size 0.7112 4.191)
			(layers "F.Cu" "F.Mask" "F.Paste")
			(net "GND")
		)
		(pad "A38" smd rect
			(at 27.50058 -2.0955 180)
			(size 0.7112 4.191)
			(layers "F.Cu" "F.Mask" "F.Paste")
			(net "SAS_GF_EXP_RX_DP9")
		)
		(pad "A39" smd rect
			(at 28.50007 -2.0955 180)
			(size 0.7112 4.191)
			(layers "F.Cu" "F.Mask" "F.Paste")
			(net "SAS_GF_EXP_RX_DN9")
		)
		(pad "A40" smd rect
			(at 29.49956 -2.0955 180)
			(size 0.7112 4.191)
			(layers "F.Cu" "F.Mask" "F.Paste")
			(net "GND")
		)
		(pad "A41" smd rect
			(at 30.50032 -2.0955 180)
			(size 0.7112 4.191)
			(layers "F.Cu" "F.Mask" "F.Paste")
			(net "SHUTDOWN_RELEASE")
		)
		(pad "A42" smd rect
			(at 31.49981 -2.0955 180)
			(size 0.7112 4.191)
			(layers "F.Cu" "F.Mask" "F.Paste")
			(net "SAS_FAULT_LED1")
		)
		(pad "A43" smd rect
			(at 32.50057 -2.0955 180)
			(size 0.7112 4.191)
			(layers "F.Cu" "F.Mask" "F.Paste")
			(net "SAS_FAULT_LED0")
		)
		(pad "A44" smd rect
			(at 33.50006 -2.0955 180)
			(size 0.7112 4.191)
			(layers "F.Cu" "F.Mask" "F.Paste")
			(net "SAS_FAULT_LED2")
		)
		(pad "A45" smd rect
			(at 34.49955 -2.0955 180)
			(size 0.7112 4.191)
			(layers "F.Cu" "F.Mask" "F.Paste")
			(net "SAS_FAULT_LED3")
		)
		(pad "A46" smd rect
			(at 35.50031 -2.0955 180)
			(size 0.7112 4.191)
			(layers "F.Cu" "F.Mask" "F.Paste")
			(net "SAS_FAULT_LED4")
		)
		(pad "A47" smd rect
			(at 36.4998 -2.0955 180)
			(size 0.7112 4.191)
			(layers "F.Cu" "F.Mask" "F.Paste")
			(net "SAS_FAULT_LED5")
		)
		(pad "A48" smd rect
			(at 37.50056 -2.0955 180)
			(size 0.7112 4.191)
			(layers "F.Cu" "F.Mask" "F.Paste")
			(net "SAS_FAULT_LED6")
		)
		(pad "A49" smd rect
			(at 38.50005 -2.0955 180)
			(size 0.7112 4.191)
			(layers "F.Cu" "F.Mask" "F.Paste")
			(net "SAS_FAULT_LED7")
		)
		(pad "A50" smd rect
			(at 39.49954 -2.0955 180)
			(size 0.7112 4.191)
			(layers "F.Cu" "F.Mask" "F.Paste")
			(net "SAS_FAULT_LED8")
		)
		(pad "A51" smd rect
			(at 40.5003 -2.0955 180)
			(size 0.7112 4.191)
			(layers "F.Cu" "F.Mask" "F.Paste")
			(net "GND")
		)
		(pad "A52" smd rect
			(at 41.49979 -2.0955 180)
			(size 0.7112 4.191)
			(layers "F.Cu" "F.Mask" "F.Paste")
			(net "SAS_GF_EXP_RX_DP10")
		)
		(pad "A53" smd rect
			(at 42.50055 -2.0955 180)
			(size 0.7112 4.191)
			(layers "F.Cu" "F.Mask" "F.Paste")
			(net "SAS_GF_EXP_RX_DN10")
		)
		(pad "A54" smd rect
			(at 43.50004 -2.0955 180)
			(size 0.7112 4.191)
			(layers "F.Cu" "F.Mask" "F.Paste")
			(net "GND")
		)
		(pad "A55" smd rect
			(at 44.49953 -2.0955 180)
			(size 0.7112 4.191)
			(layers "F.Cu" "F.Mask" "F.Paste")
			(net "SAS_I2C_C_BUF_SCL_R")
		)
		(pad "A56" smd rect
			(at 45.50029 -2.0955 180)
			(size 0.7112 4.191)
			(layers "F.Cu" "F.Mask" "F.Paste")
			(net "SAS_I2C_C_BUF_SDA_R")
		)
		(pad "A57" smd rect
			(at 46.49978 -2.0955 180)
			(size 0.7112 4.191)
			(layers "F.Cu" "F.Mask" "F.Paste")
			(net "SAS_I2C_D_BUF_SCL_R")
		)
		(pad "A58" smd rect
			(at 47.50054 -2.0955 180)
			(size 0.7112 4.191)
			(layers "F.Cu" "F.Mask" "F.Paste")
			(net "SAS_I2C_D_BUF_SDA_R")
		)
		(pad "A59" smd rect
			(at 48.50003 -2.0955 180)
			(size 0.7112 4.191)
			(layers "F.Cu" "F.Mask" "F.Paste")
			(net "GND")
		)
		(pad "A60" smd rect
			(at 49.49952 -2.0955 180)
			(size 0.7112 4.191)
			(layers "F.Cu" "F.Mask" "F.Paste")
			(net "SAS_GF_EXP_RX_DP11")
		)
		(pad "A61" smd rect
			(at 50.50028 -2.0955 180)
			(size 0.7112 4.191)
			(layers "F.Cu" "F.Mask" "F.Paste")
			(net "SAS_GF_EXP_RX_DN11")
		)
		(pad "A62" smd rect
			(at 51.49977 -2.0955 180)
			(size 0.7112 4.191)
			(layers "F.Cu" "F.Mask" "F.Paste")
			(net "GND")
		)
		(pad "A63" smd rect
			(at 52.50053 -2.0955 180)
			(size 0.7112 4.191)
			(layers "F.Cu" "F.Mask" "F.Paste")
			(net "GND")
		)
		(pad "A64" smd rect
			(at 53.50002 -2.0955 180)
			(size 0.7112 4.191)
			(layers "F.Cu" "F.Mask" "F.Paste")
			(net "SAS_GF_EXP_RX_DP12")
		)
		(pad "A65" smd rect
			(at 54.50078 -2.0955 180)
			(size 0.7112 4.191)
			(layers "F.Cu" "F.Mask" "F.Paste")
			(net "SAS_GF_EXP_RX_DN12")
		)
		(pad "A66" smd rect
			(at 55.50027 -2.0955 180)
			(size 0.7112 4.191)
			(layers "F.Cu" "F.Mask" "F.Paste")
			(net "GND")
		)
		(pad "A67" smd rect
			(at 56.49976 -2.0955 180)
			(size 0.7112 4.191)
			(layers "F.Cu" "F.Mask" "F.Paste")
			(net "GND")
		)
		(pad "A68" smd rect
			(at 57.50052 -2.0955 180)
			(size 0.7112 4.191)
			(layers "F.Cu" "F.Mask" "F.Paste")
			(net "SAS_GF_EXP_RX_DP13")
		)
		(pad "A69" smd rect
			(at 58.50001 -2.0955 180)
			(size 0.7112 4.191)
			(layers "F.Cu" "F.Mask" "F.Paste")
			(net "SAS_GF_EXP_RX_DN13")
		)
		(pad "A70" smd rect
			(at 59.50077 -2.0955 180)
			(size 0.7112 4.191)
			(layers "F.Cu" "F.Mask" "F.Paste")
			(net "GND")
		)
		(pad "A71" smd rect
			(at 60.50026 -2.0955 180)
			(size 0.7112 4.191)
			(layers "F.Cu" "F.Mask" "F.Paste")
			(net "GND")
		)
		(pad "A72" smd rect
			(at 61.49975 -2.0955 180)
			(size 0.7112 4.191)
			(layers "F.Cu" "F.Mask" "F.Paste")
			(net "SAS_GF_EXP_RX_DP14")
		)
		(pad "A73" smd rect
			(at 62.50051 -2.0955 180)
			(size 0.7112 4.191)
			(layers "F.Cu" "F.Mask" "F.Paste")
			(net "SAS_GF_EXP_RX_DN14")
		)
		(pad "A74" smd rect
			(at 63.5 -2.0955 180)
			(size 0.7112 4.191)
			(layers "F.Cu" "F.Mask" "F.Paste")
			(net "GND")
		)
		(pad "A75" smd rect
			(at 64.50076 -2.0955 180)
			(size 0.7112 4.191)
			(layers "F.Cu" "F.Mask" "F.Paste")
			(net "GND")
		)
		(pad "A76" smd rect
			(at 65.50025 -2.0955 180)
			(size 0.7112 4.191)
			(layers "F.Cu" "F.Mask" "F.Paste")
			(net "SAS_GF_EXP_RX_DP15")
		)
		(pad "A77" smd rect
			(at 66.49974 -2.0955 180)
			(size 0.7112 4.191)
			(layers "F.Cu" "F.Mask" "F.Paste")
			(net "SAS_GF_EXP_RX_DN15")
		)
		(pad "A78" smd rect
			(at 67.5005 -2.0955 180)
			(size 0.7112 4.191)
			(layers "F.Cu" "F.Mask" "F.Paste")
			(net "GND")
		)
		(pad "A79" smd rect
			(at 68.49999 -2.0955 180)
			(size 0.7112 4.191)
			(layers "F.Cu" "F.Mask" "F.Paste")
			(net "PEER_1B_2B_HB")
		)
		(pad "A80" smd rect
			(at 69.50075 -2.0955 180)
			(size 0.7112 4.191)
			(layers "F.Cu" "F.Mask" "F.Paste")
			(net "P12V_PCIE")
		)
		(pad "A81" smd rect
			(at 70.50024 -2.0955 180)
			(size 0.7112 4.191)
			(layers "F.Cu" "F.Mask" "F.Paste")
			(net "P12V_PCIE")
		)
		(pad "A82" smd rect
			(at 71.49973 -2.0955 180)
			(size 0.7112 4.191)
			(layers "F.Cu" "F.Mask" "F.Paste")
			(net "P12V_PCIE")
		)
		(pad "B1" smd rect
			(at -11.49985 -2.3495 180)
			(size 0.7112 4.191)
			(drill
				(offset 0 0.254)
			)
			(layers "F.Cu" "F.Mask" "F.Paste")
			(net "SAS_HDD_PRE15")
		)
		(pad "B2" smd rect
			(at -10.50036 -2.3495 180)
			(size 0.7112 4.191)
			(drill
				(offset 0 0.254)
			)
			(layers "F.Cu" "F.Mask" "F.Paste")
			(net "FCB_HW_REVISION")
		)
		(pad "B3" smd rect
			(at -9.4996 -2.3495 180)
			(size 0.7112 4.191)
			(drill
				(offset 0 0.254)
			)
			(layers "F.Cu" "F.Mask" "F.Paste")
			(net "GND")
		)
		(pad "B4" smd rect
			(at -8.50011 -2.3495 180)
			(size 0.7112 4.191)
			(drill
				(offset 0 0.254)
			)
			(layers "F.Cu" "F.Mask" "F.Paste")
			(net "SAS_EXP_GF_TX_DP0")
		)
		(pad "B5" smd rect
			(at -7.49935 -2.3495 180)
			(size 0.7112 4.191)
			(drill
				(offset 0 0.254)
			)
			(layers "F.Cu" "F.Mask" "F.Paste")
			(net "SAS_EXP_GF_TX_DN0")
		)
		(pad "B6" smd rect
			(at -6.49986 -2.3495 180)
			(size 0.7112 4.191)
			(drill
				(offset 0 0.254)
			)
			(layers "F.Cu" "F.Mask" "F.Paste")
			(net "GND")
		)
		(pad "B7" smd rect
			(at -5.50037 -2.3495 180)
			(size 0.7112 4.191)
			(drill
				(offset 0 0.254)
			)
			(layers "F.Cu" "F.Mask" "F.Paste")
			(net "GND")
		)
		(pad "B8" smd rect
			(at -4.49961 -2.3495 180)
			(size 0.7112 4.191)
			(drill
				(offset 0 0.254)
			)
			(layers "F.Cu" "F.Mask" "F.Paste")
			(net "SAS_EXP_GF_TX_DP1")
		)
		(pad "B9" smd rect
			(at -3.50012 -2.3495 180)
			(size 0.7112 4.191)
			(drill
				(offset 0 0.254)
			)
			(layers "F.Cu" "F.Mask" "F.Paste")
			(net "SAS_EXP_GF_TX_DN1")
		)
		(pad "B10" smd rect
			(at -2.49936 -2.3495 180)
			(size 0.7112 4.191)
			(drill
				(offset 0 0.254)
			)
			(layers "F.Cu" "F.Mask" "F.Paste")
			(net "GND")
		)
		(pad "B11" smd rect
			(at -1.49987 -2.3495 180)
			(size 0.7112 4.191)
			(drill
				(offset 0 0.254)
			)
			(layers "F.Cu" "F.Mask" "F.Paste")
			(net "DPB_HW_REVISION")
		)
		(pad "B12" smd rect
			(at 1.49987 -2.3495 180)
			(size 0.7112 4.191)
			(drill
				(offset 0 0.254)
			)
			(layers "F.Cu" "F.Mask" "F.Paste")
			(net "SAS_EXP_GF_TX_DP2")
		)
		(pad "B13" smd rect
			(at 2.50063 -2.3495 180)
			(size 0.7112 4.191)
			(drill
				(offset 0 0.254)
			)
			(layers "F.Cu" "F.Mask" "F.Paste")
			(net "SAS_EXP_GF_TX_DN2")
		)
		(pad "B14" smd rect
			(at 3.50012 -2.3495 180)
			(size 0.7112 4.191)
			(drill
				(offset 0 0.254)
			)
			(layers "F.Cu" "F.Mask" "F.Paste")
			(net "GND")
		)
		(pad "B15" smd rect
			(at 4.49961 -2.3495 180)
			(size 0.7112 4.191)
			(drill
				(offset 0 0.254)
			)
			(layers "F.Cu" "F.Mask" "F.Paste")
			(net "GND")
		)
		(pad "B16" smd rect
			(at 5.50037 -2.3495 180)
			(size 0.7112 4.191)
			(drill
				(offset 0 0.254)
			)
			(layers "F.Cu" "F.Mask" "F.Paste")
			(net "SAS_EXP_GF_TX_DP3")
		)
		(pad "B17" smd rect
			(at 6.49986 -2.3495 180)
			(size 0.7112 4.191)
			(drill
				(offset 0 0.254)
			)
			(layers "F.Cu" "F.Mask" "F.Paste")
			(net "SAS_EXP_GF_TX_DN3")
		)
		(pad "B18" smd rect
			(at 7.50062 -2.3495 180)
			(size 0.7112 4.191)
			(drill
				(offset 0 0.254)
			)
			(layers "F.Cu" "F.Mask" "F.Paste")
			(net "GND")
		)
		(pad "B19" smd rect
			(at 8.50011 -2.3495 180)
			(size 0.7112 4.191)
			(drill
				(offset 0 0.254)
			)
			(layers "F.Cu" "F.Mask" "F.Paste")
			(net "GND")
		)
		(pad "B20" smd rect
			(at 9.4996 -2.3495 180)
			(size 0.7112 4.191)
			(drill
				(offset 0 0.254)
			)
			(layers "F.Cu" "F.Mask" "F.Paste")
			(net "SAS_EXP_GF_TX_DP4")
		)
		(pad "B21" smd rect
			(at 10.50036 -2.3495 180)
			(size 0.7112 4.191)
			(drill
				(offset 0 0.254)
			)
			(layers "F.Cu" "F.Mask" "F.Paste")
			(net "SAS_EXP_GF_TX_DN4")
		)
		(pad "B22" smd rect
			(at 11.49985 -2.3495 180)
			(size 0.7112 4.191)
			(drill
				(offset 0 0.254)
			)
			(layers "F.Cu" "F.Mask" "F.Paste")
			(net "GND")
		)
		(pad "B23" smd rect
			(at 12.50061 -2.3495 180)
			(size 0.7112 4.191)
			(drill
				(offset 0 0.254)
			)
			(layers "F.Cu" "F.Mask" "F.Paste")
			(net "GND")
		)
		(pad "B24" smd rect
			(at 13.5001 -2.3495 180)
			(size 0.7112 4.191)
			(drill
				(offset 0 0.254)
			)
			(layers "F.Cu" "F.Mask" "F.Paste")
			(net "SAS_EXP_GF_TX_DP5")
		)
		(pad "B25" smd rect
			(at 14.49959 -2.3495 180)
			(size 0.7112 4.191)
			(drill
				(offset 0 0.254)
			)
			(layers "F.Cu" "F.Mask" "F.Paste")
			(net "SAS_EXP_GF_TX_DN5")
		)
		(pad "B26" smd rect
			(at 15.50035 -2.3495 180)
			(size 0.7112 4.191)
			(drill
				(offset 0 0.254)
			)
			(layers "F.Cu" "F.Mask" "F.Paste")
			(net "GND")
		)
		(pad "B27" smd rect
			(at 16.49984 -2.3495 180)
			(size 0.7112 4.191)
			(drill
				(offset 0 0.254)
			)
			(layers "F.Cu" "F.Mask" "F.Paste")
			(net "GND")
		)
		(pad "B28" smd rect
			(at 17.5006 -2.3495 180)
			(size 0.7112 4.191)
			(drill
				(offset 0 0.254)
			)
			(layers "F.Cu" "F.Mask" "F.Paste")
			(net "SAS_EXP_GF_TX_DP6")
		)
		(pad "B29" smd rect
			(at 18.50009 -2.3495 180)
			(size 0.7112 4.191)
			(drill
				(offset 0 0.254)
			)
			(layers "F.Cu" "F.Mask" "F.Paste")
			(net "SAS_EXP_GF_TX_DN6")
		)
		(pad "B30" smd rect
			(at 19.49958 -2.3495 180)
			(size 0.7112 4.191)
			(drill
				(offset 0 0.254)
			)
			(layers "F.Cu" "F.Mask" "F.Paste")
			(net "GND")
		)
		(pad "B31" smd rect
			(at 20.50034 -2.3495 180)
			(size 0.7112 4.191)
			(drill
				(offset 0 0.254)
			)
			(layers "F.Cu" "F.Mask" "F.Paste")
			(net "GND")
		)
		(pad "B32" smd rect
			(at 21.49983 -2.3495 180)
			(size 0.7112 4.191)
			(drill
				(offset 0 0.254)
			)
			(layers "F.Cu" "F.Mask" "F.Paste")
			(net "SAS_HDD_CONN_TX7_P")
		)
		(pad "B33" smd rect
			(at 22.50059 -2.3495 180)
			(size 0.7112 4.191)
			(drill
				(offset 0 0.254)
			)
			(layers "F.Cu" "F.Mask" "F.Paste")
			(net "SAS_HDD_CONN_TX7_N")
		)
		(pad "B34" smd rect
			(at 23.50008 -2.3495 180)
			(size 0.7112 4.191)
			(drill
				(offset 0 0.254)
			)
			(layers "F.Cu" "F.Mask" "F.Paste")
			(net "GND")
		)
		(pad "B35" smd rect
			(at 24.49957 -2.3495 180)
			(size 0.7112 4.191)
			(drill
				(offset 0 0.254)
			)
			(layers "F.Cu" "F.Mask" "F.Paste")
			(net "GND")
		)
		(pad "B36" smd rect
			(at 25.50033 -2.3495 180)
			(size 0.7112 4.191)
			(drill
				(offset 0 0.254)
			)
			(layers "F.Cu" "F.Mask" "F.Paste")
			(net "SAS_HDD_CONN_TX8_P")
		)
		(pad "B37" smd rect
			(at 26.49982 -2.3495 180)
			(size 0.7112 4.191)
			(drill
				(offset 0 0.254)
			)
			(layers "F.Cu" "F.Mask" "F.Paste")
			(net "SAS_HDD_CONN_TX8_N")
		)
		(pad "B38" smd rect
			(at 27.50058 -2.3495 180)
			(size 0.7112 4.191)
			(drill
				(offset 0 0.254)
			)
			(layers "F.Cu" "F.Mask" "F.Paste")
			(net "GND")
		)
		(pad "B39" smd rect
			(at 28.50007 -2.3495 180)
			(size 0.7112 4.191)
			(drill
				(offset 0 0.254)
			)
			(layers "F.Cu" "F.Mask" "F.Paste")
			(net "GND")
		)
		(pad "B40" smd rect
			(at 29.49956 -2.3495 180)
			(size 0.7112 4.191)
			(drill
				(offset 0 0.254)
			)
			(layers "F.Cu" "F.Mask" "F.Paste")
			(net "SAS_EXP_GF_TX_DP9")
		)
		(pad "B41" smd rect
			(at 30.50032 -2.3495 180)
			(size 0.7112 4.191)
			(drill
				(offset 0 0.254)
			)
			(layers "F.Cu" "F.Mask" "F.Paste")
			(net "SAS_EXP_GF_TX_DN9")
		)
		(pad "B42" smd rect
			(at 31.49981 -2.3495 180)
			(size 0.7112 4.191)
			(drill
				(offset 0 0.254)
			)
			(layers "F.Cu" "F.Mask" "F.Paste")
			(net "GND")
		)
		(pad "B43" smd rect
			(at 32.50057 -2.3495 180)
			(size 0.7112 4.191)
			(drill
				(offset 0 0.254)
			)
			(layers "F.Cu" "F.Mask" "F.Paste")
			(net "SAS_FAULT_LED9")
		)
		(pad "B44" smd rect
			(at 33.50006 -2.3495 180)
			(size 0.7112 4.191)
			(drill
				(offset 0 0.254)
			)
			(layers "F.Cu" "F.Mask" "F.Paste")
			(net "SAS_FAULT_LED10")
		)
		(pad "B45" smd rect
			(at 34.49955 -2.3495 180)
			(size 0.7112 4.191)
			(drill
				(offset 0 0.254)
			)
			(layers "F.Cu" "F.Mask" "F.Paste")
			(net "SAS_FAULT_LED11")
		)
		(pad "B46" smd rect
			(at 35.50031 -2.3495 180)
			(size 0.7112 4.191)
			(drill
				(offset 0 0.254)
			)
			(layers "F.Cu" "F.Mask" "F.Paste")
			(net "SAS_FAULT_LED12")
		)
		(pad "B47" smd rect
			(at 36.4998 -2.3495 180)
			(size 0.7112 4.191)
			(drill
				(offset 0 0.254)
			)
			(layers "F.Cu" "F.Mask" "F.Paste")
			(net "SAS_FAULT_LED13")
		)
		(pad "B48" smd rect
			(at 37.50056 -2.3495 180)
			(size 0.7112 4.191)
			(drill
				(offset 0 0.254)
			)
			(layers "F.Cu" "F.Mask" "F.Paste")
			(net "GND")
		)
		(pad "B49" smd rect
			(at 38.50005 -2.3495 180)
			(size 0.7112 4.191)
			(drill
				(offset 0 0.254)
			)
			(layers "F.Cu" "F.Mask" "F.Paste")
			(net "SAS_EXP_GF_TX_DP10")
		)
		(pad "B50" smd rect
			(at 39.49954 -2.3495 180)
			(size 0.7112 4.191)
			(drill
				(offset 0 0.254)
			)
			(layers "F.Cu" "F.Mask" "F.Paste")
			(net "SAS_EXP_GF_TX_DN10")
		)
		(pad "B51" smd rect
			(at 40.5003 -2.3495 180)
			(size 0.7112 4.191)
			(drill
				(offset 0 0.254)
			)
			(layers "F.Cu" "F.Mask" "F.Paste")
			(net "GND")
		)
		(pad "B52" smd rect
			(at 41.49979 -2.3495 180)
			(size 0.7112 4.191)
			(drill
				(offset 0 0.254)
			)
			(layers "F.Cu" "F.Mask" "F.Paste")
			(net "SAS_FAULT_LED14")
		)
		(pad "B53" smd rect
			(at 42.50055 -2.3495 180)
			(size 0.7112 4.191)
			(drill
				(offset 0 0.254)
			)
			(layers "F.Cu" "F.Mask" "F.Paste")
			(net "SAS_FAULT_LED15")
		)
		(pad "B54" smd rect
			(at 43.50004 -2.3495 180)
			(size 0.7112 4.191)
			(drill
				(offset 0 0.254)
			)
			(layers "F.Cu" "F.Mask" "F.Paste")
			(net "HB_OUT")
		)
		(pad "B55" smd rect
			(at 44.49953 -2.3495 180)
			(size 0.7112 4.191)
			(drill
				(offset 0 0.254)
			)
			(layers "F.Cu" "F.Mask" "F.Paste")
			(net "HB_INPUT")
		)
		(pad "B56" smd rect
			(at 45.50029 -2.3495 180)
			(size 0.7112 4.191)
			(drill
				(offset 0 0.254)
			)
			(layers "F.Cu" "F.Mask" "F.Paste")
			(net "SAS_I2C_B_BUF_SCL_R")
		)
		(pad "B57" smd rect
			(at 46.49978 -2.3495 180)
			(size 0.7112 4.191)
			(drill
				(offset 0 0.254)
			)
			(layers "F.Cu" "F.Mask" "F.Paste")
			(net "SAS_I2C_B_BUF_SDA_R")
		)
		(pad "B58" smd rect
			(at 47.50054 -2.3495 180)
			(size 0.7112 4.191)
			(drill
				(offset 0 0.254)
			)
			(layers "F.Cu" "F.Mask" "F.Paste")
			(net "ID_I2C_ADD")
		)
		(pad "B59" smd rect
			(at 48.50003 -2.3495 180)
			(size 0.7112 4.191)
			(drill
				(offset 0 0.254)
			)
			(layers "F.Cu" "F.Mask" "F.Paste")
			(net "FAN_PWM_PCIE")
		)
		(pad "B60" smd rect
			(at 49.49952 -2.3495 180)
			(size 0.7112 4.191)
			(drill
				(offset 0 0.254)
			)
			(layers "F.Cu" "F.Mask" "F.Paste")
			(net "PEER_1A_2A_HB")
		)
		(pad "B61" smd rect
			(at 50.50028 -2.3495 180)
			(size 0.7112 4.191)
			(drill
				(offset 0 0.254)
			)
			(layers "F.Cu" "F.Mask" "F.Paste")
			(net "GND")
		)
		(pad "B62" smd rect
			(at 51.49977 -2.3495 180)
			(size 0.7112 4.191)
			(drill
				(offset 0 0.254)
			)
			(layers "F.Cu" "F.Mask" "F.Paste")
			(net "SAS_EXP_GF_TX_DP11")
		)
		(pad "B63" smd rect
			(at 52.50053 -2.3495 180)
			(size 0.7112 4.191)
			(drill
				(offset 0 0.254)
			)
			(layers "F.Cu" "F.Mask" "F.Paste")
			(net "SAS_EXP_GF_TX_DN11")
		)
		(pad "B64" smd rect
			(at 53.50002 -2.3495 180)
			(size 0.7112 4.191)
			(drill
				(offset 0 0.254)
			)
			(layers "F.Cu" "F.Mask" "F.Paste")
			(net "GND")
		)
		(pad "B65" smd rect
			(at 54.50078 -2.3495 180)
			(size 0.7112 4.191)
			(drill
				(offset 0 0.254)
			)
			(layers "F.Cu" "F.Mask" "F.Paste")
			(net "GND")
		)
		(pad "B66" smd rect
			(at 55.50027 -2.3495 180)
			(size 0.7112 4.191)
			(drill
				(offset 0 0.254)
			)
			(layers "F.Cu" "F.Mask" "F.Paste")
			(net "SAS_EXP_GF_TX_DP12")
		)
		(pad "B67" smd rect
			(at 56.49976 -2.3495 180)
			(size 0.7112 4.191)
			(drill
				(offset 0 0.254)
			)
			(layers "F.Cu" "F.Mask" "F.Paste")
			(net "SAS_EXP_GF_TX_DN12")
		)
		(pad "B68" smd rect
			(at 57.50052 -2.3495 180)
			(size 0.7112 4.191)
			(drill
				(offset 0 0.254)
			)
			(layers "F.Cu" "F.Mask" "F.Paste")
			(net "GND")
		)
		(pad "B69" smd rect
			(at 58.50001 -2.3495 180)
			(size 0.7112 4.191)
			(drill
				(offset 0 0.254)
			)
			(layers "F.Cu" "F.Mask" "F.Paste")
			(net "GND")
		)
		(pad "B70" smd rect
			(at 59.50077 -2.3495 180)
			(size 0.7112 4.191)
			(drill
				(offset 0 0.254)
			)
			(layers "F.Cu" "F.Mask" "F.Paste")
			(net "SAS_EXP_GF_TX_DP13")
		)
		(pad "B71" smd rect
			(at 60.50026 -2.3495 180)
			(size 0.7112 4.191)
			(drill
				(offset 0 0.254)
			)
			(layers "F.Cu" "F.Mask" "F.Paste")
			(net "SAS_EXP_GF_TX_DN13")
		)
		(pad "B72" smd rect
			(at 61.49975 -2.3495 180)
			(size 0.7112 4.191)
			(drill
				(offset 0 0.254)
			)
			(layers "F.Cu" "F.Mask" "F.Paste")
			(net "GND")
		)
		(pad "B73" smd rect
			(at 62.50051 -2.3495 180)
			(size 0.7112 4.191)
			(drill
				(offset 0 0.254)
			)
			(layers "F.Cu" "F.Mask" "F.Paste")
			(net "GND")
		)
		(pad "B74" smd rect
			(at 63.5 -2.3495 180)
			(size 0.7112 4.191)
			(drill
				(offset 0 0.254)
			)
			(layers "F.Cu" "F.Mask" "F.Paste")
			(net "SAS_EXP_GF_TX_DP14")
		)
		(pad "B75" smd rect
			(at 64.50076 -2.3495 180)
			(size 0.7112 4.191)
			(drill
				(offset 0 0.254)
			)
			(layers "F.Cu" "F.Mask" "F.Paste")
			(net "SAS_EXP_GF_TX_DN14")
		)
		(pad "B76" smd rect
			(at 65.50025 -2.3495 180)
			(size 0.7112 4.191)
			(drill
				(offset 0 0.254)
			)
			(layers "F.Cu" "F.Mask" "F.Paste")
			(net "GND")
		)
		(pad "B77" smd rect
			(at 66.49974 -2.3495 180)
			(size 0.7112 4.191)
			(drill
				(offset 0 0.254)
			)
			(layers "F.Cu" "F.Mask" "F.Paste")
			(net "GND")
		)
		(pad "B78" smd rect
			(at 67.5005 -2.3495 180)
			(size 0.7112 4.191)
			(drill
				(offset 0 0.254)
			)
			(layers "F.Cu" "F.Mask" "F.Paste")
			(net "SAS_EXP_GF_TX_DP15")
		)
		(pad "B79" smd rect
			(at 68.49999 -2.3495 180)
			(size 0.7112 4.191)
			(drill
				(offset 0 0.254)
			)
			(layers "F.Cu" "F.Mask" "F.Paste")
			(net "SAS_EXP_GF_TX_DN15")
		)
		(pad "B80" smd rect
			(at 69.50075 -2.3495 180)
			(size 0.7112 4.191)
			(drill
				(offset 0 0.254)
			)
			(layers "F.Cu" "F.Mask" "F.Paste")
			(net "GND")
		)
		(pad "B81" smd rect
			(at 70.50024 -2.5908 180)
			(size 0.7112 3.2004)
			(layers "F.Cu" "F.Mask" "F.Paste")
			(net "GND")
		)
		(pad "B82" smd rect
			(at 71.49973 -2.3495 180)
			(size 0.7112 4.191)
			(drill
				(offset 0 0.254)
			)
			(layers "F.Cu" "F.Mask" "F.Paste")
			(net "GND")
		)
		(zone
			(layer "F.Cu")
			(hatch none 0.5)
			(connect_pads
				(clearance 0)
			)
			(min_thickness 0.25)
			(keepout
				(tracks not_allowed)
				(vias allowed)
				(pads allowed)
				(copperpour not_allowed)
				(footprints allowed)
			)
			(placement
				(enabled no)
				(sheetname "")
			)
			(fill
				(thermal_gap 0.5)
				(thermal_bridge_width 0.5)
				(island_removal_mode 0)
			)
			(polygon
				(pts
					(xy 152.375362 -259.61594) (xy 66.624962 -259.61594) (xy 66.624962 -258.59994) (xy 152.375362 -258.59994)
				)
			)
		)
		(zone
			(layer "F.Cu")
			(hatch none 0.5)
			(connect_pads
				(clearance 0)
			)
			(min_thickness 0.25)
			(keepout
				(tracks allowed)
				(vias not_allowed)
				(pads allowed)
				(copperpour not_allowed)
				(footprints allowed)
			)
			(placement
				(enabled no)
				(sheetname "")
			)
			(fill
				(thermal_gap 0.5)
				(thermal_bridge_width 0.5)
				(island_removal_mode 0)
			)
			(polygon
				(pts
					(xy 152.375362 -259.61594) (xy 66.624962 -259.61594) (xy 66.624962 -253.39294) (xy 152.375362 -253.39294)
				)
			)
		)
		(zone
			(layer "B.Cu")
			(hatch none 0.5)
			(connect_pads
				(clearance 0)
			)
			(min_thickness 0.25)
			(keepout
				(tracks not_allowed)
				(vias allowed)
				(pads allowed)
				(copperpour not_allowed)
				(footprints allowed)
			)
			(placement
				(enabled no)
				(sheetname "")
			)
			(fill
				(thermal_gap 0.5)
				(thermal_bridge_width 0.5)
				(island_removal_mode 0)
			)
			(polygon
				(pts
					(xy 152.375362 -259.61594) (xy 66.624962 -259.61594) (xy 66.624962 -258.59994) (xy 152.375362 -258.59994)
				)
			)
		)
		(zone
			(layer "B.Cu")
			(hatch none 0.5)
			(connect_pads
				(clearance 0)
			)
			(min_thickness 0.25)
			(keepout
				(tracks allowed)
				(vias not_allowed)
				(pads allowed)
				(copperpour not_allowed)
				(footprints allowed)
			)
			(placement
				(enabled no)
				(sheetname "")
			)
			(fill
				(thermal_gap 0.5)
				(thermal_bridge_width 0.5)
				(island_removal_mode 0)
			)
			(polygon
				(pts
					(xy 152.375362 -259.61594) (xy 66.624962 -259.61594) (xy 66.624962 -253.39294) (xy 152.375362 -253.39294)
				)
			)
		)
	)
	(footprint ""
		(layer "F.Cu")
		(at 209.931 -103.124 180)
		(property "Reference" "PC141"
			(at 0 0 180)
			(layer "F.SilkS")
			(hide yes)
			(effects
				(font
					(size 1.27 1.27)
				)
			)
		)
		(property "Value" "SC1KP50V2KX-1GP"
			(at 1.1811 -2.7051 180)
			(unlocked yes)
			(layer "F.Fab")
			(hide yes)
			(effects
				(font
					(size 1.016 1.016)
					(thickness 0.1524)
				)
			)
		)
		(property "Device Type" "C402H22"
			(at 1.1811 -4.2291 180)
			(unlocked yes)
			(layer "F.Fab")
			(hide yes)
			(effects
				(font
					(size 1.016 1.016)
					(thickness 0.1524)
				)
			)
		)
		(duplicate_pad_numbers_are_jumpers no)
		(fp_rect
			(start -0.4318 0.9525)
			(end 0.4318 -0.9525)
			(stroke
				(width 0)
				(type default)
			)
			(fill no)
			(layer "F.CrtYd")
		)
		(fp_rect
			(start -0.4318 0.9525)
			(end 0.4318 -0.9525)
			(stroke
				(width 0)
				(type default)
			)
			(fill no)
			(layer "F.Fab")
		)
		(pad "1" smd custom
			(at 0 -0.4445 180)
			(size 0.1524 0.1524)
			(layers "F.Cu" "F.Mask" "F.Paste")
			(net "P1V5_C")
			(options
				(clearance outline)
				(anchor circle)
			)
			(primitives
				(gr_poly
					(pts
						(arc
							(start 0.3048 -0.2032)
							(mid 0.275042 -0.275042)
							(end 0.2032 -0.3048)
						)
						(arc
							(start -0.2032 -0.3048)
							(mid -0.275042 -0.275042)
							(end -0.3048 -0.2032)
						)
						(arc
							(start -0.3048 0.2032)
							(mid -0.275042 0.275042)
							(end -0.2032 0.3048)
						)
						(arc
							(start 0.2032 0.3048)
							(mid 0.275042 0.275042)
							(end 0.3048 0.2032)
						)
					)
					(width 0)
					(fill yes)
				)
			)
		)
		(pad "2" smd custom
			(at 0 0.4445 180)
			(size 0.1524 0.1524)
			(layers "F.Cu" "F.Mask" "F.Paste")
			(net "TPS74801_1V5_C_FB")
			(options
				(clearance outline)
				(anchor circle)
			)
			(primitives
				(gr_poly
					(pts
						(arc
							(start 0.3048 -0.2032)
							(mid 0.275042 -0.275042)
							(end 0.2032 -0.3048)
						)
						(arc
							(start -0.2032 -0.3048)
							(mid -0.275042 -0.275042)
							(end -0.3048 -0.2032)
						)
						(arc
							(start -0.3048 0.2032)
							(mid -0.275042 0.275042)
							(end -0.2032 0.3048)
						)
						(arc
							(start 0.2032 0.3048)
							(mid 0.275042 0.275042)
							(end 0.3048 0.2032)
						)
					)
					(width 0)
					(fill yes)
				)
			)
		)
	)
	(footprint ""
		(layer "F.Cu")
		(at 220.345 -118.745 -90)
		(property "Reference" "R604"
			(at 0 0 270)
			(layer "F.SilkS")
			(hide yes)
			(effects
				(font
					(size 1.27 1.27)
				)
			)
		)
		(property "Value" "1KR2J-1-GP"
			(at 0.064008 -3.993896 270)
			(unlocked yes)
			(layer "F.Fab")
			(hide yes)
			(effects
				(font
					(size 1.016 1.016)
					(thickness 0.1524)
				)
			)
		)
		(property "Device Type" "R402H16"
			(at 0.064008 -5.517896 270)
			(unlocked yes)
			(layer "F.Fab")
			(hide yes)
			(effects
				(font
					(size 1.016 1.016)
					(thickness 0.1524)
				)
			)
		)
		(duplicate_pad_numbers_are_jumpers no)
		(fp_line
			(start -0.508 -0.9398)
			(end -0.508 0.9398)
			(stroke
				(width 0.1524)
				(type default)
			)
			(layer "F.SilkS")
		)
		(fp_line
			(start 0.508 -0.9398)
			(end -0.508 -0.9398)
			(stroke
				(width 0.1524)
				(type default)
			)
			(layer "F.SilkS")
		)
		(fp_rect
			(start -0.508 0.9398)
			(end 0.508 -0.9398)
			(stroke
				(width 0)
				(type default)
			)
			(fill no)
			(layer "F.CrtYd")
		)
		(fp_rect
			(start -0.508 0.9398)
			(end 0.508 -0.9398)
			(stroke
				(width 0)
				(type default)
			)
			(fill no)
			(layer "F.Fab")
		)
		(pad "1" smd custom
			(at 0 -0.4445 270)
			(size 0.1397 0.1397)
			(layers "F.Cu" "F.Mask" "F.Paste")
			(net "P3V3_STBY_R3")
			(options
				(clearance outline)
				(anchor circle)
			)
			(primitives
				(gr_poly
					(pts
						(arc
							(start -0.1778 -0.2794)
							(mid -0.249642 -0.249642)
							(end -0.2794 -0.1778)
						)
						(arc
							(start -0.2794 0.1778)
							(mid -0.249642 0.249642)
							(end -0.1778 0.2794)
						)
						(arc
							(start 0.1778 0.2794)
							(mid 0.249642 0.249642)
							(end 0.2794 0.1778)
						)
						(arc
							(start 0.2794 -0.1778)
							(mid 0.249642 -0.249642)
							(end 0.1778 -0.2794)
						)
					)
					(width 0)
					(fill yes)
				)
			)
		)
		(pad "2" smd custom
			(at 0 0.4445 270)
			(size 0.1397 0.1397)
			(layers "F.Cu" "F.Mask" "F.Paste")
			(net "P3V3_STBY")
			(options
				(clearance outline)
				(anchor circle)
			)
			(primitives
				(gr_poly
					(pts
						(arc
							(start -0.1778 -0.2794)
							(mid -0.249642 -0.249642)
							(end -0.2794 -0.1778)
						)
						(arc
							(start -0.2794 0.1778)
							(mid -0.249642 0.249642)
							(end -0.1778 0.2794)
						)
						(arc
							(start 0.1778 0.2794)
							(mid 0.249642 0.249642)
							(end 0.2794 0.1778)
						)
						(arc
							(start 0.2794 -0.1778)
							(mid 0.249642 -0.249642)
							(end 0.1778 -0.2794)
						)
					)
					(width 0)
					(fill yes)
				)
			)
		)
	)
	(footprint ""
		(layer "F.Cu")
		(at 200.348596 -121.177812)
		(property "Reference" "PR9010"
			(at 0 0 0)
			(layer "F.SilkS")
			(hide yes)
			(effects
				(font
					(size 1.27 1.27)
				)
			)
		)
		(property "Value" "10KR2F-2-GP"
			(at 0.064008 -3.993896 0)
			(unlocked yes)
			(layer "F.Fab")
			(hide yes)
			(effects
				(font
					(size 1.016 1.016)
					(thickness 0.1524)
				)
			)
		)
		(property "Device Type" "R402H16"
			(at 0.064008 -5.517896 0)
			(unlocked yes)
			(layer "F.Fab")
			(hide yes)
			(effects
				(font
					(size 1.016 1.016)
					(thickness 0.1524)
				)
			)
		)
		(duplicate_pad_numbers_are_jumpers no)
		(fp_line
			(start -0.508 -0.9398)
			(end -0.508 0.9398)
			(stroke
				(width 0.1524)
				(type default)
			)
			(layer "F.SilkS")
		)
		(fp_line
			(start 0.508 -0.9398)
			(end -0.508 -0.9398)
			(stroke
				(width 0.1524)
				(type default)
			)
			(layer "F.SilkS")
		)
		(fp_rect
			(start -0.508 0.9398)
			(end 0.508 -0.9398)
			(stroke
				(width 0)
				(type default)
			)
			(fill no)
			(layer "F.CrtYd")
		)
		(fp_rect
			(start -0.508 0.9398)
			(end 0.508 -0.9398)
			(stroke
				(width 0)
				(type default)
			)
			(fill no)
			(layer "F.Fab")
		)
		(pad "1" smd custom
			(at 0 -0.4445)
			(size 0.1397 0.1397)
			(layers "F.Cu" "F.Mask" "F.Paste")
			(net "AGND_P1V5_E")
			(options
				(clearance outline)
				(anchor circle)
			)
			(primitives
				(gr_poly
					(pts
						(arc
							(start -0.1778 -0.2794)
							(mid -0.249642 -0.249642)
							(end -0.2794 -0.1778)
						)
						(arc
							(start -0.2794 0.1778)
							(mid -0.249642 0.249642)
							(end -0.1778 0.2794)
						)
						(arc
							(start 0.1778 0.2794)
							(mid 0.249642 0.249642)
							(end 0.2794 0.1778)
						)
						(arc
							(start 0.2794 -0.1778)
							(mid 0.249642 -0.249642)
							(end 0.1778 -0.2794)
						)
					)
					(width 0)
					(fill yes)
				)
			)
		)
		(pad "2" smd custom
			(at 0 0.4445)
			(size 0.1397 0.1397)
			(layers "F.Cu" "F.Mask" "F.Paste")
			(net "P1V5_E_VFB")
			(options
				(clearance outline)
				(anchor circle)
			)
			(primitives
				(gr_poly
					(pts
						(arc
							(start -0.1778 -0.2794)
							(mid -0.249642 -0.249642)
							(end -0.2794 -0.1778)
						)
						(arc
							(start -0.2794 0.1778)
							(mid -0.249642 0.249642)
							(end -0.1778 0.2794)
						)
						(arc
							(start 0.1778 0.2794)
							(mid 0.249642 0.249642)
							(end 0.2794 0.1778)
						)
						(arc
							(start 0.2794 -0.1778)
							(mid 0.249642 -0.249642)
							(end 0.1778 -0.2794)
						)
					)
					(width 0)
					(fill yes)
				)
			)
		)
	)
	(footprint ""
		(layer "F.Cu")
		(at 256.159 -136.779 180)
		(property "Reference" "SC1303"
			(at 0 0 180)
			(layer "F.SilkS")
			(hide yes)
			(effects
				(font
					(size 1.27 1.27)
				)
			)
		)
		(property "Value" "SCD1U16V2KX-3GP"
			(at 1.1811 -2.7051 180)
			(unlocked yes)
			(layer "F.Fab")
			(hide yes)
			(effects
				(font
					(size 1.016 1.016)
					(thickness 0.1524)
				)
			)
		)
		(property "Device Type" "C402H22"
			(at 1.1811 -4.2291 180)
			(unlocked yes)
			(layer "F.Fab")
			(hide yes)
			(effects
				(font
					(size 1.016 1.016)
					(thickness 0.1524)
				)
			)
		)
		(duplicate_pad_numbers_are_jumpers no)
		(fp_rect
			(start -0.4318 0.9525)
			(end 0.4318 -0.9525)
			(stroke
				(width 0)
				(type default)
			)
			(fill no)
			(layer "F.CrtYd")
		)
		(fp_rect
			(start -0.4318 0.9525)
			(end 0.4318 -0.9525)
			(stroke
				(width 0)
				(type default)
			)
			(fill no)
			(layer "F.Fab")
		)
		(pad "1" smd custom
			(at 0 -0.4445 180)
			(size 0.1524 0.1524)
			(layers "F.Cu" "F.Mask" "F.Paste")
			(net "P3V3_STBY")
			(options
				(clearance outline)
				(anchor circle)
			)
			(primitives
				(gr_poly
					(pts
						(arc
							(start 0.3048 -0.2032)
							(mid 0.275042 -0.275042)
							(end 0.2032 -0.3048)
						)
						(arc
							(start -0.2032 -0.3048)
							(mid -0.275042 -0.275042)
							(end -0.3048 -0.2032)
						)
						(arc
							(start -0.3048 0.2032)
							(mid -0.275042 0.275042)
							(end -0.2032 0.3048)
						)
						(arc
							(start 0.2032 0.3048)
							(mid 0.275042 0.275042)
							(end 0.3048 0.2032)
						)
					)
					(width 0)
					(fill yes)
				)
			)
		)
		(pad "2" smd custom
			(at 0 0.4445 180)
			(size 0.1524 0.1524)
			(layers "F.Cu" "F.Mask" "F.Paste")
			(net "GND")
			(options
				(clearance outline)
				(anchor circle)
			)
			(primitives
				(gr_poly
					(pts
						(arc
							(start 0.3048 -0.2032)
							(mid 0.275042 -0.275042)
							(end 0.2032 -0.3048)
						)
						(arc
							(start -0.2032 -0.3048)
							(mid -0.275042 -0.275042)
							(end -0.3048 -0.2032)
						)
						(arc
							(start -0.3048 0.2032)
							(mid -0.275042 0.275042)
							(end -0.2032 0.3048)
						)
						(arc
							(start 0.2032 0.3048)
							(mid 0.275042 0.275042)
							(end 0.3048 0.2032)
						)
					)
					(width 0)
					(fill yes)
				)
			)
		)
	)
	(footprint ""
		(layer "F.Cu")
		(at 191.516 -145.034 -90)
		(property "Reference" "SR737"
			(at 0 0 270)
			(layer "F.SilkS")
			(hide yes)
			(effects
				(font
					(size 1.27 1.27)
				)
			)
		)
		(property "Value" "2K2R2F-GP"
			(at 0.064008 -3.993896 270)
			(unlocked yes)
			(layer "F.Fab")
			(hide yes)
			(effects
				(font
					(size 1.016 1.016)
					(thickness 0.1524)
				)
			)
		)
		(property "Device Type" "R402H16"
			(at 0.064008 -5.517896 270)
			(unlocked yes)
			(layer "F.Fab")
			(hide yes)
			(effects
				(font
					(size 1.016 1.016)
					(thickness 0.1524)
				)
			)
		)
		(duplicate_pad_numbers_are_jumpers no)
		(fp_line
			(start -0.508 -0.9398)
			(end -0.508 0.9398)
			(stroke
				(width 0.1524)
				(type default)
			)
			(layer "F.SilkS")
		)
		(fp_line
			(start 0.508 -0.9398)
			(end -0.508 -0.9398)
			(stroke
				(width 0.1524)
				(type default)
			)
			(layer "F.SilkS")
		)
		(fp_rect
			(start -0.508 0.9398)
			(end 0.508 -0.9398)
			(stroke
				(width 0)
				(type default)
			)
			(fill no)
			(layer "F.CrtYd")
		)
		(fp_rect
			(start -0.508 0.9398)
			(end 0.508 -0.9398)
			(stroke
				(width 0)
				(type default)
			)
			(fill no)
			(layer "F.Fab")
		)
		(pad "1" smd custom
			(at 0 -0.4445 270)
			(size 0.1397 0.1397)
			(layers "F.Cu" "F.Mask" "F.Paste")
			(net "EXP_I2C_SDA_3")
			(options
				(clearance outline)
				(anchor circle)
			)
			(primitives
				(gr_poly
					(pts
						(arc
							(start -0.1778 -0.2794)
							(mid -0.249642 -0.249642)
							(end -0.2794 -0.1778)
						)
						(arc
							(start -0.2794 0.1778)
							(mid -0.249642 0.249642)
							(end -0.1778 0.2794)
						)
						(arc
							(start 0.1778 0.2794)
							(mid 0.249642 0.249642)
							(end 0.2794 0.1778)
						)
						(arc
							(start 0.2794 -0.1778)
							(mid 0.249642 -0.249642)
							(end 0.1778 -0.2794)
						)
					)
					(width 0)
					(fill yes)
				)
			)
		)
		(pad "2" smd custom
			(at 0 0.4445 270)
			(size 0.1397 0.1397)
			(layers "F.Cu" "F.Mask" "F.Paste")
			(net "P1V8_E")
			(options
				(clearance outline)
				(anchor circle)
			)
			(primitives
				(gr_poly
					(pts
						(arc
							(start -0.1778 -0.2794)
							(mid -0.249642 -0.249642)
							(end -0.2794 -0.1778)
						)
						(arc
							(start -0.2794 0.1778)
							(mid -0.249642 0.249642)
							(end -0.1778 0.2794)
						)
						(arc
							(start 0.1778 0.2794)
							(mid 0.249642 0.249642)
							(end 0.2794 0.1778)
						)
						(arc
							(start 0.2794 -0.1778)
							(mid 0.249642 -0.249642)
							(end 0.1778 -0.2794)
						)
					)
					(width 0)
					(fill yes)
				)
			)
		)
	)
	(footprint ""
		(layer "F.Cu")
		(at 82.94497 -111.76 180)
		(property "Reference" "SC1206"
			(at 0 0 180)
			(layer "F.SilkS")
			(hide yes)
			(effects
				(font
					(size 1.27 1.27)
				)
			)
		)
		(property "Value" "SC10U6D3V5KX-4GP"
			(at -0.0762 -6.1214 180)
			(unlocked yes)
			(layer "F.Fab")
			(hide yes)
			(effects
				(font
					(size 1.016 1.016)
					(thickness 0.1524)
				)
			)
		)
		(property "Device Type" "C805H58"
			(at -0.0762 -8.1534 180)
			(unlocked yes)
			(layer "F.Fab")
			(hide yes)
			(effects
				(font
					(size 1.016 1.016)
					(thickness 0.1524)
				)
			)
		)
		(duplicate_pad_numbers_are_jumpers no)
		(fp_line
			(start 0.635 0)
			(end -0.635 0)
			(stroke
				(width 0.508)
				(type default)
			)
			(layer "F.SilkS")
		)
		(fp_rect
			(start -0.9652 1.778)
			(end 0.9652 -1.778)
			(stroke
				(width 0)
				(type default)
			)
			(fill no)
			(layer "F.CrtYd")
		)
		(fp_poly
			(pts
				(xy -0.9652 -1.778) (xy 0.9652 -1.778) (xy 0.9652 1.778) (xy -0.9652 1.778)
			)
			(stroke
				(width 0)
				(type default)
			)
			(fill no)
			(layer "F.Fab")
		)
		(pad "1" smd rect
			(at 0 -0.9652 180)
			(size 1.397 1.143)
			(layers "F.Cu" "F.Mask" "F.Paste")
			(net "P1V8_E")
		)
		(pad "2" smd rect
			(at 0 0.9652 180)
			(size 1.397 1.143)
			(layers "F.Cu" "F.Mask" "F.Paste")
			(net "GND")
		)
	)
	(footprint ""
		(layer "F.Cu")
		(at 174.107348 -125.847856 90)
		(property "Reference" "PC171"
			(at 0 0 90)
			(layer "F.SilkS")
			(hide yes)
			(effects
				(font
					(size 1.27 1.27)
				)
			)
		)
		(property "Value" "SC22U25V5MX-GP"
			(at -0.0762 -6.1214 90)
			(unlocked yes)
			(layer "F.Fab")
			(hide yes)
			(effects
				(font
					(size 1.016 1.016)
					(thickness 0.1524)
				)
			)
		)
		(property "Device Type" "C805H58"
			(at -0.0762 -8.1534 90)
			(unlocked yes)
			(layer "F.Fab")
			(hide yes)
			(effects
				(font
					(size 1.016 1.016)
					(thickness 0.1524)
				)
			)
		)
		(duplicate_pad_numbers_are_jumpers no)
		(fp_line
			(start 0.635 0)
			(end -0.635 0)
			(stroke
				(width 0.508)
				(type default)
			)
			(layer "F.SilkS")
		)
		(fp_rect
			(start -0.9652 1.778)
			(end 0.9652 -1.778)
			(stroke
				(width 0)
				(type default)
			)
			(fill no)
			(layer "F.CrtYd")
		)
		(fp_poly
			(pts
				(xy -0.9652 -1.778) (xy 0.9652 -1.778) (xy 0.9652 1.778) (xy -0.9652 1.778)
			)
			(stroke
				(width 0)
				(type default)
			)
			(fill no)
			(layer "F.Fab")
		)
		(pad "1" smd rect
			(at 0 -0.9652 90)
			(size 1.397 1.143)
			(layers "F.Cu" "F.Mask" "F.Paste")
			(net "P0V9_E_VIN")
		)
		(pad "2" smd rect
			(at 0 0.9652 90)
			(size 1.397 1.143)
			(layers "F.Cu" "F.Mask" "F.Paste")
			(net "GND")
		)
	)
	(footprint ""
		(layer "F.Cu")
		(at 291.211 -158.496)
		(property "Reference" "R615"
			(at 0 0 0)
			(layer "F.SilkS")
			(hide yes)
			(effects
				(font
					(size 1.27 1.27)
				)
			)
		)
		(property "Value" "2K2R2J-2-GP"
			(at 0.064008 -3.993896 0)
			(unlocked yes)
			(layer "F.Fab")
			(hide yes)
			(effects
				(font
					(size 1.016 1.016)
					(thickness 0.1524)
				)
			)
		)
		(property "Device Type" "R402H16"
			(at 0.064008 -5.517896 0)
			(unlocked yes)
			(layer "F.Fab")
			(hide yes)
			(effects
				(font
					(size 1.016 1.016)
					(thickness 0.1524)
				)
			)
		)
		(duplicate_pad_numbers_are_jumpers no)
		(fp_line
			(start -0.508 -0.9398)
			(end -0.508 0.9398)
			(stroke
				(width 0.1524)
				(type default)
			)
			(layer "F.SilkS")
		)
		(fp_line
			(start 0.508 -0.9398)
			(end -0.508 -0.9398)
			(stroke
				(width 0.1524)
				(type default)
			)
			(layer "F.SilkS")
		)
		(fp_rect
			(start -0.508 0.9398)
			(end 0.508 -0.9398)
			(stroke
				(width 0)
				(type default)
			)
			(fill no)
			(layer "F.CrtYd")
		)
		(fp_rect
			(start -0.508 0.9398)
			(end 0.508 -0.9398)
			(stroke
				(width 0)
				(type default)
			)
			(fill no)
			(layer "F.Fab")
		)
		(pad "1" smd custom
			(at 0 -0.4445)
			(size 0.1397 0.1397)
			(layers "F.Cu" "F.Mask" "F.Paste")
			(net "CPU_BMC_UART_RX")
			(options
				(clearance outline)
				(anchor circle)
			)
			(primitives
				(gr_poly
					(pts
						(arc
							(start -0.1778 -0.2794)
							(mid -0.249642 -0.249642)
							(end -0.2794 -0.1778)
						)
						(arc
							(start -0.2794 0.1778)
							(mid -0.249642 0.249642)
							(end -0.1778 0.2794)
						)
						(arc
							(start 0.1778 0.2794)
							(mid 0.249642 0.249642)
							(end 0.2794 0.1778)
						)
						(arc
							(start 0.2794 -0.1778)
							(mid 0.249642 -0.249642)
							(end 0.1778 -0.2794)
						)
					)
					(width 0)
					(fill yes)
				)
			)
		)
		(pad "2" smd custom
			(at 0 0.4445)
			(size 0.1397 0.1397)
			(layers "F.Cu" "F.Mask" "F.Paste")
			(net "GND")
			(options
				(clearance outline)
				(anchor circle)
			)
			(primitives
				(gr_poly
					(pts
						(arc
							(start -0.1778 -0.2794)
							(mid -0.249642 -0.249642)
							(end -0.2794 -0.1778)
						)
						(arc
							(start -0.2794 0.1778)
							(mid -0.249642 0.249642)
							(end -0.1778 0.2794)
						)
						(arc
							(start 0.1778 0.2794)
							(mid 0.249642 0.249642)
							(end 0.2794 0.1778)
						)
						(arc
							(start 0.2794 -0.1778)
							(mid 0.249642 -0.249642)
							(end 0.1778 -0.2794)
						)
					)
					(width 0)
					(fill yes)
				)
			)
		)
	)
	(footprint ""
		(layer "F.Cu")
		(at 103.867966 -65.8876 90)
		(property "Reference" "SC916"
			(at 0 0 90)
			(layer "F.SilkS")
			(hide yes)
			(effects
				(font
					(size 1.27 1.27)
				)
			)
		)
		(property "Value" "SC10U6D3V5KX-4GP"
			(at -0.0762 -6.1214 90)
			(unlocked yes)
			(layer "F.Fab")
			(hide yes)
			(effects
				(font
					(size 1.016 1.016)
					(thickness 0.1524)
				)
			)
		)
		(property "Device Type" "C805H58"
			(at -0.0762 -8.1534 90)
			(unlocked yes)
			(layer "F.Fab")
			(hide yes)
			(effects
				(font
					(size 1.016 1.016)
					(thickness 0.1524)
				)
			)
		)
		(duplicate_pad_numbers_are_jumpers no)
		(fp_line
			(start 0.635 0)
			(end -0.635 0)
			(stroke
				(width 0.508)
				(type default)
			)
			(layer "F.SilkS")
		)
		(fp_rect
			(start -0.9652 1.778)
			(end 0.9652 -1.778)
			(stroke
				(width 0)
				(type default)
			)
			(fill no)
			(layer "F.CrtYd")
		)
		(fp_poly
			(pts
				(xy -0.9652 -1.778) (xy 0.9652 -1.778) (xy 0.9652 1.778) (xy -0.9652 1.778)
			)
			(stroke
				(width 0)
				(type default)
			)
			(fill no)
			(layer "F.Fab")
		)
		(pad "1" smd rect
			(at 0 -0.9652 90)
			(size 1.397 1.143)
			(layers "F.Cu" "F.Mask" "F.Paste")
			(net "HM40ADC_VDDA")
		)
		(pad "2" smd rect
			(at 0 0.9652 90)
			(size 1.397 1.143)
			(layers "F.Cu" "F.Mask" "F.Paste")
			(net "GND")
		)
	)
	(footprint ""
		(layer "F.Cu")
		(at 93.072966 -60.452)
		(property "Reference" "STP35"
			(at 0 0 0)
			(layer "F.SilkS")
			(hide yes)
			(effects
				(font
					(size 1.27 1.27)
				)
			)
		)
		(property "Value" "TPAD28"
			(at 0.0127 -1.8034 0)
			(unlocked yes)
			(layer "F.Fab")
			(hide yes)
			(effects
				(font
					(size 1.016 1.016)
					(thickness 0.1524)
				)
			)
		)
		(property "Device Type" "TPAD28"
			(at 0.0127 -3.3274 0)
			(unlocked yes)
			(layer "F.Fab")
			(hide yes)
			(effects
				(font
					(size 1.016 1.016)
					(thickness 0.1524)
				)
			)
		)
		(duplicate_pad_numbers_are_jumpers no)
		(fp_poly
			(pts
				(arc
					(start 0.3556 0)
					(mid -0.3556 0)
					(end 0.3556 0)
				)
			)
			(stroke
				(width 0)
				(type default)
			)
			(fill no)
			(layer "F.CrtYd")
		)
		(fp_poly
			(pts
				(arc
					(start 0.6096 0)
					(mid -0.6096 0)
					(end 0.6096 0)
				)
			)
			(stroke
				(width 0)
				(type default)
			)
			(fill no)
			(layer "F.Fab")
		)
		(pad "1" smd circle
			(at 0 0)
			(size 0.7112 0.7112)
			(layers "F.Cu" "F.Mask" "F.Paste")
			(net "ICE1_TCK")
		)
	)
	(footprint ""
		(layer "F.Cu")
		(at 106.788966 -65.8876 180)
		(property "Reference" "SR866"
			(at 0 0 180)
			(layer "F.SilkS")
			(hide yes)
			(effects
				(font
					(size 1.27 1.27)
				)
			)
		)
		(property "Value" "0R2J-2-GP"
			(at 0.064008 -3.993896 180)
			(unlocked yes)
			(layer "F.Fab")
			(hide yes)
			(effects
				(font
					(size 1.016 1.016)
					(thickness 0.1524)
				)
			)
		)
		(property "Device Type" "R402H16"
			(at 0.064008 -5.517896 180)
			(unlocked yes)
			(layer "F.Fab")
			(hide yes)
			(effects
				(font
					(size 1.016 1.016)
					(thickness 0.1524)
				)
			)
		)
		(duplicate_pad_numbers_are_jumpers no)
		(fp_line
			(start 0.508 -0.9398)
			(end -0.508 -0.9398)
			(stroke
				(width 0.1524)
				(type default)
			)
			(layer "F.SilkS")
		)
		(fp_line
			(start -0.508 -0.9398)
			(end -0.508 0.9398)
			(stroke
				(width 0.1524)
				(type default)
			)
			(layer "F.SilkS")
		)
		(fp_rect
			(start -0.508 0.9398)
			(end 0.508 -0.9398)
			(stroke
				(width 0)
				(type default)
			)
			(fill no)
			(layer "F.CrtYd")
		)
		(fp_rect
			(start -0.508 0.9398)
			(end 0.508 -0.9398)
			(stroke
				(width 0)
				(type default)
			)
			(fill no)
			(layer "F.Fab")
		)
		(pad "1" smd custom
			(at 0 -0.4445 180)
			(size 0.1397 0.1397)
			(layers "F.Cu" "F.Mask" "F.Paste")
			(net "IOC_TRST_N")
			(options
				(clearance outline)
				(anchor circle)
			)
			(primitives
				(gr_poly
					(pts
						(arc
							(start -0.1778 -0.2794)
							(mid -0.249642 -0.249642)
							(end -0.2794 -0.1778)
						)
						(arc
							(start -0.2794 0.1778)
							(mid -0.249642 0.249642)
							(end -0.1778 0.2794)
						)
						(arc
							(start 0.1778 0.2794)
							(mid 0.249642 0.249642)
							(end 0.2794 0.1778)
						)
						(arc
							(start 0.2794 -0.1778)
							(mid 0.249642 -0.249642)
							(end 0.1778 -0.2794)
						)
					)
					(width 0)
					(fill yes)
				)
			)
		)
		(pad "2" smd custom
			(at 0 0.4445 180)
			(size 0.1397 0.1397)
			(layers "F.Cu" "F.Mask" "F.Paste")
			(net "JTAG_EXP_IOC_RST")
			(options
				(clearance outline)
				(anchor circle)
			)
			(primitives
				(gr_poly
					(pts
						(arc
							(start -0.1778 -0.2794)
							(mid -0.249642 -0.249642)
							(end -0.2794 -0.1778)
						)
						(arc
							(start -0.2794 0.1778)
							(mid -0.249642 0.249642)
							(end -0.1778 0.2794)
						)
						(arc
							(start 0.1778 0.2794)
							(mid 0.249642 0.249642)
							(end 0.2794 0.1778)
						)
						(arc
							(start 0.2794 -0.1778)
							(mid 0.249642 -0.249642)
							(end 0.1778 -0.2794)
						)
					)
					(width 0)
					(fill yes)
				)
			)
		)
	)
	(footprint ""
		(layer "F.Cu")
		(at 200.856596 -110.255812 90)
		(property "Reference" "PC229"
			(at 0 0 90)
			(layer "F.SilkS")
			(hide yes)
			(effects
				(font
					(size 1.27 1.27)
				)
			)
		)
		(property "Value" "SCD1U50V3KX-GP"
			(at 0 -2.8194 90)
			(unlocked yes)
			(layer "F.Fab")
			(hide yes)
			(effects
				(font
					(size 1.016 1.016)
					(thickness 0.1524)
				)
			)
		)
		(property "Device Type" "C603H36"
			(at 0 -4.3434 90)
			(unlocked yes)
			(layer "F.Fab")
			(hide yes)
			(effects
				(font
					(size 1.016 1.016)
					(thickness 0.1524)
				)
			)
		)
		(duplicate_pad_numbers_are_jumpers no)
		(fp_line
			(start 0.508 0)
			(end -0.508 0)
			(stroke
				(width 0.2032)
				(type default)
			)
			(layer "F.SilkS")
		)
		(fp_rect
			(start -0.5842 1.3335)
			(end 0.5842 -1.3335)
			(stroke
				(width 0)
				(type default)
			)
			(fill no)
			(layer "F.CrtYd")
		)
		(fp_rect
			(start -0.5842 1.3335)
			(end 0.5842 -1.3335)
			(stroke
				(width 0)
				(type default)
			)
			(fill no)
			(layer "F.Fab")
		)
		(pad "1" smd custom
			(at 0 -0.762 90)
			(size 0.2159 0.2159)
			(layers "F.Cu" "F.Mask" "F.Paste")
			(net "P1V5_E_SW")
			(options
				(clearance outline)
				(anchor circle)
			)
			(primitives
				(gr_poly
					(pts
						(arc
							(start -0.3302 -0.4318)
							(mid -0.402042 -0.402042)
							(end -0.4318 -0.3302)
						)
						(arc
							(start -0.4318 0.3302)
							(mid -0.402042 0.402042)
							(end -0.3302 0.4318)
						)
						(arc
							(start 0.3302 0.4318)
							(mid 0.402042 0.402042)
							(end 0.4318 0.3302)
						)
						(arc
							(start 0.4318 -0.3302)
							(mid 0.402042 -0.402042)
							(end 0.3302 -0.4318)
						)
					)
					(width 0)
					(fill yes)
				)
			)
		)
		(pad "2" smd custom
			(at 0 0.762 90)
			(size 0.2159 0.2159)
			(layers "F.Cu" "F.Mask" "F.Paste")
			(net "P1V5_E_VBST_RR")
			(options
				(clearance outline)
				(anchor circle)
			)
			(primitives
				(gr_poly
					(pts
						(arc
							(start -0.3302 -0.4318)
							(mid -0.402042 -0.402042)
							(end -0.4318 -0.3302)
						)
						(arc
							(start -0.4318 0.3302)
							(mid -0.402042 0.402042)
							(end -0.3302 0.4318)
						)
						(arc
							(start 0.3302 0.4318)
							(mid 0.402042 0.402042)
							(end 0.4318 0.3302)
						)
						(arc
							(start 0.4318 -0.3302)
							(mid 0.402042 -0.402042)
							(end 0.3302 -0.4318)
						)
					)
					(width 0)
					(fill yes)
				)
			)
		)
	)
	(footprint ""
		(layer "F.Cu")
		(at 320.9544 -212.1154 -90)
		(property "Reference" "R563"
			(at 0 0 270)
			(layer "F.SilkS")
			(hide yes)
			(effects
				(font
					(size 1.27 1.27)
				)
			)
		)
		(property "Value" "10KR2F-2-GP"
			(at 0.064008 -3.993896 270)
			(unlocked yes)
			(layer "F.Fab")
			(hide yes)
			(effects
				(font
					(size 1.016 1.016)
					(thickness 0.1524)
				)
			)
		)
		(property "Device Type" "R402H16"
			(at 0.064008 -5.517896 270)
			(unlocked yes)
			(layer "F.Fab")
			(hide yes)
			(effects
				(font
					(size 1.016 1.016)
					(thickness 0.1524)
				)
			)
		)
		(duplicate_pad_numbers_are_jumpers no)
		(fp_line
			(start -0.508 -0.9398)
			(end -0.508 0.9398)
			(stroke
				(width 0.1524)
				(type default)
			)
			(layer "F.SilkS")
		)
		(fp_line
			(start 0.508 -0.9398)
			(end -0.508 -0.9398)
			(stroke
				(width 0.1524)
				(type default)
			)
			(layer "F.SilkS")
		)
		(fp_rect
			(start -0.508 0.9398)
			(end 0.508 -0.9398)
			(stroke
				(width 0)
				(type default)
			)
			(fill no)
			(layer "F.CrtYd")
		)
		(fp_rect
			(start -0.508 0.9398)
			(end 0.508 -0.9398)
			(stroke
				(width 0)
				(type default)
			)
			(fill no)
			(layer "F.Fab")
		)
		(pad "1" smd custom
			(at 0 -0.4445 270)
			(size 0.1397 0.1397)
			(layers "F.Cu" "F.Mask" "F.Paste")
			(net "P3V3_STBY")
			(options
				(clearance outline)
				(anchor circle)
			)
			(primitives
				(gr_poly
					(pts
						(arc
							(start -0.1778 -0.2794)
							(mid -0.249642 -0.249642)
							(end -0.2794 -0.1778)
						)
						(arc
							(start -0.2794 0.1778)
							(mid -0.249642 0.249642)
							(end -0.1778 0.2794)
						)
						(arc
							(start 0.1778 0.2794)
							(mid 0.249642 0.249642)
							(end 0.2794 0.1778)
						)
						(arc
							(start 0.2794 -0.1778)
							(mid 0.249642 -0.249642)
							(end 0.1778 -0.2794)
						)
					)
					(width 0)
					(fill yes)
				)
			)
		)
		(pad "2" smd custom
			(at 0 0.4445 270)
			(size 0.1397 0.1397)
			(layers "F.Cu" "F.Mask" "F.Paste")
			(net "BMC_JTAG_L_EN")
			(options
				(clearance outline)
				(anchor circle)
			)
			(primitives
				(gr_poly
					(pts
						(arc
							(start -0.1778 -0.2794)
							(mid -0.249642 -0.249642)
							(end -0.2794 -0.1778)
						)
						(arc
							(start -0.2794 0.1778)
							(mid -0.249642 0.249642)
							(end -0.1778 0.2794)
						)
						(arc
							(start 0.1778 0.2794)
							(mid 0.249642 0.249642)
							(end 0.2794 0.1778)
						)
						(arc
							(start 0.2794 -0.1778)
							(mid 0.249642 -0.249642)
							(end 0.1778 -0.2794)
						)
					)
					(width 0)
					(fill yes)
				)
			)
		)
	)
	(footprint ""
		(layer "F.Cu")
		(at 257.429 -230.378 90)
		(property "Reference" "PR88"
			(at 0 0 90)
			(layer "F.SilkS")
			(hide yes)
			(effects
				(font
					(size 1.27 1.27)
				)
			)
		)
		(property "Value" "0R2J-2-GP"
			(at 0.064008 -3.993896 90)
			(unlocked yes)
			(layer "F.Fab")
			(hide yes)
			(effects
				(font
					(size 1.016 1.016)
					(thickness 0.1524)
				)
			)
		)
		(property "Device Type" "R402H16"
			(at 0.064008 -5.517896 90)
			(unlocked yes)
			(layer "F.Fab")
			(hide yes)
			(effects
				(font
					(size 1.016 1.016)
					(thickness 0.1524)
				)
			)
		)
		(duplicate_pad_numbers_are_jumpers no)
		(fp_line
			(start 0.508 -0.9398)
			(end -0.508 -0.9398)
			(stroke
				(width 0.1524)
				(type default)
			)
			(layer "F.SilkS")
		)
		(fp_line
			(start -0.508 -0.9398)
			(end -0.508 0.9398)
			(stroke
				(width 0.1524)
				(type default)
			)
			(layer "F.SilkS")
		)
		(fp_rect
			(start -0.508 0.9398)
			(end 0.508 -0.9398)
			(stroke
				(width 0)
				(type default)
			)
			(fill no)
			(layer "F.CrtYd")
		)
		(fp_rect
			(start -0.508 0.9398)
			(end 0.508 -0.9398)
			(stroke
				(width 0)
				(type default)
			)
			(fill no)
			(layer "F.Fab")
		)
		(pad "1" smd custom
			(at 0 -0.4445 90)
			(size 0.1397 0.1397)
			(layers "F.Cu" "F.Mask" "F.Paste")
			(net "P1V53_STBY_PG")
			(options
				(clearance outline)
				(anchor circle)
			)
			(primitives
				(gr_poly
					(pts
						(arc
							(start -0.1778 -0.2794)
							(mid -0.249642 -0.249642)
							(end -0.2794 -0.1778)
						)
						(arc
							(start -0.2794 0.1778)
							(mid -0.249642 0.249642)
							(end -0.1778 0.2794)
						)
						(arc
							(start 0.1778 0.2794)
							(mid 0.249642 0.249642)
							(end 0.2794 0.1778)
						)
						(arc
							(start 0.2794 -0.1778)
							(mid 0.249642 -0.249642)
							(end 0.1778 -0.2794)
						)
					)
					(width 0)
					(fill yes)
				)
			)
		)
		(pad "2" smd custom
			(at 0 0.4445 90)
			(size 0.1397 0.1397)
			(layers "F.Cu" "F.Mask" "F.Paste")
			(net "TPS74801_1V26_STBY_EN")
			(options
				(clearance outline)
				(anchor circle)
			)
			(primitives
				(gr_poly
					(pts
						(arc
							(start -0.1778 -0.2794)
							(mid -0.249642 -0.249642)
							(end -0.2794 -0.1778)
						)
						(arc
							(start -0.2794 0.1778)
							(mid -0.249642 0.249642)
							(end -0.1778 0.2794)
						)
						(arc
							(start 0.1778 0.2794)
							(mid 0.249642 0.249642)
							(end 0.2794 0.1778)
						)
						(arc
							(start 0.2794 -0.1778)
							(mid 0.249642 -0.249642)
							(end 0.1778 -0.2794)
						)
					)
					(width 0)
					(fill yes)
				)
			)
		)
	)
	(footprint ""
		(layer "F.Cu")
		(at 278.13 -191.77 180)
		(property "Reference" "C201"
			(at 0 0 180)
			(layer "F.SilkS")
			(hide yes)
			(effects
				(font
					(size 1.27 1.27)
				)
			)
		)
		(property "Value" "SC1U6D3V3KX-2GP"
			(at 0 -2.8194 180)
			(unlocked yes)
			(layer "F.Fab")
			(hide yes)
			(effects
				(font
					(size 1.016 1.016)
					(thickness 0.1524)
				)
			)
		)
		(property "Device Type" "C603H36"
			(at 0 -4.3434 180)
			(unlocked yes)
			(layer "F.Fab")
			(hide yes)
			(effects
				(font
					(size 1.016 1.016)
					(thickness 0.1524)
				)
			)
		)
		(duplicate_pad_numbers_are_jumpers no)
		(fp_line
			(start 0.508 0)
			(end -0.508 0)
			(stroke
				(width 0.2032)
				(type default)
			)
			(layer "F.SilkS")
		)
		(fp_rect
			(start -0.5842 1.3335)
			(end 0.5842 -1.3335)
			(stroke
				(width 0)
				(type default)
			)
			(fill no)
			(layer "F.CrtYd")
		)
		(fp_rect
			(start -0.5842 1.3335)
			(end 0.5842 -1.3335)
			(stroke
				(width 0)
				(type default)
			)
			(fill no)
			(layer "F.Fab")
		)
		(pad "1" smd custom
			(at 0 -0.762 180)
			(size 0.2159 0.2159)
			(layers "F.Cu" "F.Mask" "F.Paste")
			(net "V1PLLAV12")
			(options
				(clearance outline)
				(anchor circle)
			)
			(primitives
				(gr_poly
					(pts
						(arc
							(start -0.3302 -0.4318)
							(mid -0.402042 -0.402042)
							(end -0.4318 -0.3302)
						)
						(arc
							(start -0.4318 0.3302)
							(mid -0.402042 0.402042)
							(end -0.3302 0.4318)
						)
						(arc
							(start 0.3302 0.4318)
							(mid 0.402042 0.402042)
							(end 0.4318 0.3302)
						)
						(arc
							(start 0.4318 -0.3302)
							(mid 0.402042 -0.402042)
							(end 0.3302 -0.4318)
						)
					)
					(width 0)
					(fill yes)
				)
			)
		)
		(pad "2" smd custom
			(at 0 0.762 180)
			(size 0.2159 0.2159)
			(layers "F.Cu" "F.Mask" "F.Paste")
			(net "GND")
			(options
				(clearance outline)
				(anchor circle)
			)
			(primitives
				(gr_poly
					(pts
						(arc
							(start -0.3302 -0.4318)
							(mid -0.402042 -0.402042)
							(end -0.4318 -0.3302)
						)
						(arc
							(start -0.4318 0.3302)
							(mid -0.402042 0.402042)
							(end -0.3302 0.4318)
						)
						(arc
							(start 0.3302 0.4318)
							(mid 0.402042 0.402042)
							(end 0.4318 0.3302)
						)
						(arc
							(start 0.4318 -0.3302)
							(mid 0.402042 -0.402042)
							(end 0.3302 -0.4318)
						)
					)
					(width 0)
					(fill yes)
				)
			)
		)
	)
	(footprint ""
		(layer "F.Cu")
		(at 260.785864 -220.209872 -90)
		(property "Reference" "PR87"
			(at 0 0 270)
			(layer "F.SilkS")
			(hide yes)
			(effects
				(font
					(size 1.27 1.27)
				)
			)
		)
		(property "Value" "4K75R2F-1-GP"
			(at 0.064008 -3.993896 270)
			(unlocked yes)
			(layer "F.Fab")
			(hide yes)
			(effects
				(font
					(size 1.016 1.016)
					(thickness 0.1524)
				)
			)
		)
		(property "Device Type" "R402H16"
			(at 0.064008 -5.517896 270)
			(unlocked yes)
			(layer "F.Fab")
			(hide yes)
			(effects
				(font
					(size 1.016 1.016)
					(thickness 0.1524)
				)
			)
		)
		(duplicate_pad_numbers_are_jumpers no)
		(fp_line
			(start -0.508 -0.9398)
			(end -0.508 0.9398)
			(stroke
				(width 0.1524)
				(type default)
			)
			(layer "F.SilkS")
		)
		(fp_line
			(start 0.508 -0.9398)
			(end -0.508 -0.9398)
			(stroke
				(width 0.1524)
				(type default)
			)
			(layer "F.SilkS")
		)
		(fp_rect
			(start -0.508 0.9398)
			(end 0.508 -0.9398)
			(stroke
				(width 0)
				(type default)
			)
			(fill no)
			(layer "F.CrtYd")
		)
		(fp_rect
			(start -0.508 0.9398)
			(end 0.508 -0.9398)
			(stroke
				(width 0)
				(type default)
			)
			(fill no)
			(layer "F.Fab")
		)
		(pad "1" smd custom
			(at 0 -0.4445 270)
			(size 0.1397 0.1397)
			(layers "F.Cu" "F.Mask" "F.Paste")
			(net "TPS74801_1V26_STBY_FB")
			(options
				(clearance outline)
				(anchor circle)
			)
			(primitives
				(gr_poly
					(pts
						(arc
							(start -0.1778 -0.2794)
							(mid -0.249642 -0.249642)
							(end -0.2794 -0.1778)
						)
						(arc
							(start -0.2794 0.1778)
							(mid -0.249642 0.249642)
							(end -0.1778 0.2794)
						)
						(arc
							(start 0.1778 0.2794)
							(mid 0.249642 0.249642)
							(end 0.2794 0.1778)
						)
						(arc
							(start 0.2794 -0.1778)
							(mid 0.249642 -0.249642)
							(end 0.1778 -0.2794)
						)
					)
					(width 0)
					(fill yes)
				)
			)
		)
		(pad "2" smd custom
			(at 0 0.4445 270)
			(size 0.1397 0.1397)
			(layers "F.Cu" "F.Mask" "F.Paste")
			(net "GND")
			(options
				(clearance outline)
				(anchor circle)
			)
			(primitives
				(gr_poly
					(pts
						(arc
							(start -0.1778 -0.2794)
							(mid -0.249642 -0.249642)
							(end -0.2794 -0.1778)
						)
						(arc
							(start -0.2794 0.1778)
							(mid -0.249642 0.249642)
							(end -0.1778 0.2794)
						)
						(arc
							(start 0.1778 0.2794)
							(mid 0.249642 0.249642)
							(end 0.2794 0.1778)
						)
						(arc
							(start 0.2794 -0.1778)
							(mid 0.249642 -0.249642)
							(end 0.1778 -0.2794)
						)
					)
					(width 0)
					(fill yes)
				)
			)
		)
	)
	(footprint ""
		(layer "F.Cu")
		(at 303.320958 -62.865 -90)
		(property "Reference" "R215"
			(at 0 0 270)
			(layer "F.SilkS")
			(hide yes)
			(effects
				(font
					(size 1.27 1.27)
				)
			)
		)
		(property "Value" "0R2J-2-GP"
			(at 0.064008 -3.993896 270)
			(unlocked yes)
			(layer "F.Fab")
			(hide yes)
			(effects
				(font
					(size 1.016 1.016)
					(thickness 0.1524)
				)
			)
		)
		(property "Device Type" "R402H16"
			(at 0.064008 -5.517896 270)
			(unlocked yes)
			(layer "F.Fab")
			(hide yes)
			(effects
				(font
					(size 1.016 1.016)
					(thickness 0.1524)
				)
			)
		)
		(duplicate_pad_numbers_are_jumpers no)
		(fp_line
			(start -0.508 -0.9398)
			(end -0.508 0.9398)
			(stroke
				(width 0.1524)
				(type default)
			)
			(layer "F.SilkS")
		)
		(fp_line
			(start 0.508 -0.9398)
			(end -0.508 -0.9398)
			(stroke
				(width 0.1524)
				(type default)
			)
			(layer "F.SilkS")
		)
		(fp_rect
			(start -0.508 0.9398)
			(end 0.508 -0.9398)
			(stroke
				(width 0)
				(type default)
			)
			(fill no)
			(layer "F.CrtYd")
		)
		(fp_rect
			(start -0.508 0.9398)
			(end 0.508 -0.9398)
			(stroke
				(width 0)
				(type default)
			)
			(fill no)
			(layer "F.Fab")
		)
		(pad "1" smd custom
			(at 0 -0.4445 270)
			(size 0.1397 0.1397)
			(layers "F.Cu" "F.Mask" "F.Paste")
			(net "NCSI_10G_RX_ER_R")
			(options
				(clearance outline)
				(anchor circle)
			)
			(primitives
				(gr_poly
					(pts
						(arc
							(start -0.1778 -0.2794)
							(mid -0.249642 -0.249642)
							(end -0.2794 -0.1778)
						)
						(arc
							(start -0.2794 0.1778)
							(mid -0.249642 0.249642)
							(end -0.1778 0.2794)
						)
						(arc
							(start 0.1778 0.2794)
							(mid 0.249642 0.249642)
							(end 0.2794 0.1778)
						)
						(arc
							(start 0.2794 -0.1778)
							(mid 0.249642 -0.249642)
							(end 0.1778 -0.2794)
						)
					)
					(width 0)
					(fill yes)
				)
			)
		)
		(pad "2" smd custom
			(at 0 0.4445 270)
			(size 0.1397 0.1397)
			(layers "F.Cu" "F.Mask" "F.Paste")
			(net "NCSI_10G_RX_ER")
			(options
				(clearance outline)
				(anchor circle)
			)
			(primitives
				(gr_poly
					(pts
						(arc
							(start -0.1778 -0.2794)
							(mid -0.249642 -0.249642)
							(end -0.2794 -0.1778)
						)
						(arc
							(start -0.2794 0.1778)
							(mid -0.249642 0.249642)
							(end -0.1778 0.2794)
						)
						(arc
							(start 0.1778 0.2794)
							(mid 0.249642 0.249642)
							(end 0.2794 0.1778)
						)
						(arc
							(start 0.2794 -0.1778)
							(mid 0.249642 -0.249642)
							(end 0.1778 -0.2794)
						)
					)
					(width 0)
					(fill yes)
				)
			)
		)
	)
	(footprint ""
		(layer "F.Cu")
		(at 250.259596 -51.962812 -90)
		(property "Reference" "SR718"
			(at 0 0 270)
			(layer "F.SilkS")
			(hide yes)
			(effects
				(font
					(size 1.27 1.27)
				)
			)
		)
		(property "Value" "0R2J-2-GP"
			(at 0.064008 -3.993896 270)
			(unlocked yes)
			(layer "F.Fab")
			(hide yes)
			(effects
				(font
					(size 1.016 1.016)
					(thickness 0.1524)
				)
			)
		)
		(property "Device Type" "R402H16"
			(at 0.064008 -5.517896 270)
			(unlocked yes)
			(layer "F.Fab")
			(hide yes)
			(effects
				(font
					(size 1.016 1.016)
					(thickness 0.1524)
				)
			)
		)
		(duplicate_pad_numbers_are_jumpers no)
		(fp_line
			(start -0.508 -0.9398)
			(end -0.508 0.9398)
			(stroke
				(width 0.1524)
				(type default)
			)
			(layer "F.SilkS")
		)
		(fp_line
			(start 0.508 -0.9398)
			(end -0.508 -0.9398)
			(stroke
				(width 0.1524)
				(type default)
			)
			(layer "F.SilkS")
		)
		(fp_rect
			(start -0.508 0.9398)
			(end 0.508 -0.9398)
			(stroke
				(width 0)
				(type default)
			)
			(fill no)
			(layer "F.CrtYd")
		)
		(fp_rect
			(start -0.508 0.9398)
			(end 0.508 -0.9398)
			(stroke
				(width 0)
				(type default)
			)
			(fill no)
			(layer "F.Fab")
		)
		(pad "1" smd custom
			(at 0 -0.4445 270)
			(size 0.1397 0.1397)
			(layers "F.Cu" "F.Mask" "F.Paste")
			(net "IOC_EEPROM_WP")
			(options
				(clearance outline)
				(anchor circle)
			)
			(primitives
				(gr_poly
					(pts
						(arc
							(start -0.1778 -0.2794)
							(mid -0.249642 -0.249642)
							(end -0.2794 -0.1778)
						)
						(arc
							(start -0.2794 0.1778)
							(mid -0.249642 0.249642)
							(end -0.1778 0.2794)
						)
						(arc
							(start 0.1778 0.2794)
							(mid 0.249642 0.249642)
							(end 0.2794 0.1778)
						)
						(arc
							(start 0.2794 -0.1778)
							(mid 0.249642 -0.249642)
							(end 0.1778 -0.2794)
						)
					)
					(width 0)
					(fill yes)
				)
			)
		)
		(pad "2" smd custom
			(at 0 0.4445 270)
			(size 0.1397 0.1397)
			(layers "F.Cu" "F.Mask" "F.Paste")
			(net "GND")
			(options
				(clearance outline)
				(anchor circle)
			)
			(primitives
				(gr_poly
					(pts
						(arc
							(start -0.1778 -0.2794)
							(mid -0.249642 -0.249642)
							(end -0.2794 -0.1778)
						)
						(arc
							(start -0.2794 0.1778)
							(mid -0.249642 0.249642)
							(end -0.1778 0.2794)
						)
						(arc
							(start 0.1778 0.2794)
							(mid 0.249642 0.249642)
							(end 0.2794 0.1778)
						)
						(arc
							(start 0.2794 -0.1778)
							(mid 0.249642 -0.249642)
							(end 0.1778 -0.2794)
						)
					)
					(width 0)
					(fill yes)
				)
			)
		)
	)
	(footprint ""
		(layer "F.Cu")
		(at 44.2722 -116.2812 -90)
		(property "Reference" "SR937"
			(at 0 0 270)
			(layer "F.SilkS")
			(hide yes)
			(effects
				(font
					(size 1.27 1.27)
				)
			)
		)
		(property "Value" "0R2J-2-GP"
			(at 0.064008 -3.993896 270)
			(unlocked yes)
			(layer "F.Fab")
			(hide yes)
			(effects
				(font
					(size 1.016 1.016)
					(thickness 0.1524)
				)
			)
		)
		(property "Device Type" "R402H16"
			(at 0.064008 -5.517896 270)
			(unlocked yes)
			(layer "F.Fab")
			(hide yes)
			(effects
				(font
					(size 1.016 1.016)
					(thickness 0.1524)
				)
			)
		)
		(duplicate_pad_numbers_are_jumpers no)
		(fp_line
			(start -0.508 -0.9398)
			(end -0.508 0.9398)
			(stroke
				(width 0.1524)
				(type default)
			)
			(layer "F.SilkS")
		)
		(fp_line
			(start 0.508 -0.9398)
			(end -0.508 -0.9398)
			(stroke
				(width 0.1524)
				(type default)
			)
			(layer "F.SilkS")
		)
		(fp_rect
			(start -0.508 0.9398)
			(end 0.508 -0.9398)
			(stroke
				(width 0)
				(type default)
			)
			(fill no)
			(layer "F.CrtYd")
		)
		(fp_rect
			(start -0.508 0.9398)
			(end 0.508 -0.9398)
			(stroke
				(width 0)
				(type default)
			)
			(fill no)
			(layer "F.Fab")
		)
		(pad "1" smd custom
			(at 0 -0.4445 270)
			(size 0.1397 0.1397)
			(layers "F.Cu" "F.Mask" "F.Paste")
			(net "SAS_SDBRX")
			(options
				(clearance outline)
				(anchor circle)
			)
			(primitives
				(gr_poly
					(pts
						(arc
							(start -0.1778 -0.2794)
							(mid -0.249642 -0.249642)
							(end -0.2794 -0.1778)
						)
						(arc
							(start -0.2794 0.1778)
							(mid -0.249642 0.249642)
							(end -0.1778 0.2794)
						)
						(arc
							(start 0.1778 0.2794)
							(mid 0.249642 0.249642)
							(end 0.2794 0.1778)
						)
						(arc
							(start 0.2794 -0.1778)
							(mid 0.249642 -0.249642)
							(end 0.1778 -0.2794)
						)
					)
					(width 0)
					(fill yes)
				)
			)
		)
		(pad "2" smd custom
			(at 0 0.4445 270)
			(size 0.1397 0.1397)
			(layers "F.Cu" "F.Mask" "F.Paste")
			(net "SAS_R_SDBRX")
			(options
				(clearance outline)
				(anchor circle)
			)
			(primitives
				(gr_poly
					(pts
						(arc
							(start -0.1778 -0.2794)
							(mid -0.249642 -0.249642)
							(end -0.2794 -0.1778)
						)
						(arc
							(start -0.2794 0.1778)
							(mid -0.249642 0.249642)
							(end -0.1778 0.2794)
						)
						(arc
							(start 0.1778 0.2794)
							(mid 0.249642 0.249642)
							(end 0.2794 0.1778)
						)
						(arc
							(start 0.2794 -0.1778)
							(mid 0.249642 -0.249642)
							(end 0.1778 -0.2794)
						)
					)
					(width 0)
					(fill yes)
				)
			)
		)
	)
	(footprint ""
		(layer "F.Cu")
		(at 296.028872 -223.592136 180)
		(property "Reference" "PC85"
			(at 0 0 180)
			(layer "F.SilkS")
			(hide yes)
			(effects
				(font
					(size 1.27 1.27)
				)
			)
		)
		(property "Value" "SC10U6D3V5KX-1GP"
			(at -0.0762 -6.1214 180)
			(unlocked yes)
			(layer "F.Fab")
			(hide yes)
			(effects
				(font
					(size 1.016 1.016)
					(thickness 0.1524)
				)
			)
		)
		(property "Device Type" "C805H54"
			(at -0.0762 -8.1534 180)
			(unlocked yes)
			(layer "F.Fab")
			(hide yes)
			(effects
				(font
					(size 1.016 1.016)
					(thickness 0.1524)
				)
			)
		)
		(duplicate_pad_numbers_are_jumpers no)
		(fp_line
			(start 0.635 0)
			(end -0.635 0)
			(stroke
				(width 0.508)
				(type default)
			)
			(layer "F.SilkS")
		)
		(fp_rect
			(start -0.9652 1.778)
			(end 0.9652 -1.778)
			(stroke
				(width 0)
				(type default)
			)
			(fill no)
			(layer "F.CrtYd")
		)
		(fp_poly
			(pts
				(xy -0.9652 -1.778) (xy 0.9652 -1.778) (xy 0.9652 1.778) (xy -0.9652 1.778)
			)
			(stroke
				(width 0)
				(type default)
			)
			(fill no)
			(layer "F.Fab")
		)
		(pad "1" smd rect
			(at 0 -0.9652 180)
			(size 1.397 1.143)
			(layers "F.Cu" "F.Mask" "F.Paste")
			(net "TPS74801_1V53_STBY_OUT")
		)
		(pad "2" smd rect
			(at 0 0.9652 180)
			(size 1.397 1.143)
			(layers "F.Cu" "F.Mask" "F.Paste")
			(net "GND")
		)
	)
	(footprint ""
		(layer "F.Cu")
		(at 289.687 -65.659 90)
		(property "Reference" "PR9002"
			(at 0 0 90)
			(layer "F.SilkS")
			(hide yes)
			(effects
				(font
					(size 1.27 1.27)
				)
			)
		)
		(property "Value" "0R2J-2-GP"
			(at 0.064008 -3.993896 90)
			(unlocked yes)
			(layer "F.Fab")
			(hide yes)
			(effects
				(font
					(size 1.016 1.016)
					(thickness 0.1524)
				)
			)
		)
		(property "Device Type" "R402H16"
			(at 0.064008 -5.517896 90)
			(unlocked yes)
			(layer "F.Fab")
			(hide yes)
			(effects
				(font
					(size 1.016 1.016)
					(thickness 0.1524)
				)
			)
		)
		(duplicate_pad_numbers_are_jumpers no)
		(fp_line
			(start 0.508 -0.9398)
			(end -0.508 -0.9398)
			(stroke
				(width 0.1524)
				(type default)
			)
			(layer "F.SilkS")
		)
		(fp_line
			(start -0.508 -0.9398)
			(end -0.508 0.9398)
			(stroke
				(width 0.1524)
				(type default)
			)
			(layer "F.SilkS")
		)
		(fp_rect
			(start -0.508 0.9398)
			(end 0.508 -0.9398)
			(stroke
				(width 0)
				(type default)
			)
			(fill no)
			(layer "F.CrtYd")
		)
		(fp_rect
			(start -0.508 0.9398)
			(end 0.508 -0.9398)
			(stroke
				(width 0)
				(type default)
			)
			(fill no)
			(layer "F.Fab")
		)
		(pad "1" smd custom
			(at 0 -0.4445 90)
			(size 0.1397 0.1397)
			(layers "F.Cu" "F.Mask" "F.Paste")
			(net "HSW_SCL1")
			(options
				(clearance outline)
				(anchor circle)
			)
			(primitives
				(gr_poly
					(pts
						(arc
							(start -0.1778 -0.2794)
							(mid -0.249642 -0.249642)
							(end -0.2794 -0.1778)
						)
						(arc
							(start -0.2794 0.1778)
							(mid -0.249642 0.249642)
							(end -0.1778 0.2794)
						)
						(arc
							(start 0.1778 0.2794)
							(mid 0.249642 0.249642)
							(end 0.2794 0.1778)
						)
						(arc
							(start 0.2794 -0.1778)
							(mid 0.249642 -0.249642)
							(end 0.1778 -0.2794)
						)
					)
					(width 0)
					(fill yes)
				)
			)
		)
		(pad "2" smd custom
			(at 0 0.4445 90)
			(size 0.1397 0.1397)
			(layers "F.Cu" "F.Mask" "F.Paste")
			(net "BMC_I2C_SCL_10")
			(options
				(clearance outline)
				(anchor circle)
			)
			(primitives
				(gr_poly
					(pts
						(arc
							(start -0.1778 -0.2794)
							(mid -0.249642 -0.249642)
							(end -0.2794 -0.1778)
						)
						(arc
							(start -0.2794 0.1778)
							(mid -0.249642 0.249642)
							(end -0.1778 0.2794)
						)
						(arc
							(start 0.1778 0.2794)
							(mid 0.249642 0.249642)
							(end 0.2794 0.1778)
						)
						(arc
							(start 0.2794 -0.1778)
							(mid 0.249642 -0.249642)
							(end 0.1778 -0.2794)
						)
					)
					(width 0)
					(fill yes)
				)
			)
		)
	)
	(footprint ""
		(layer "F.Cu")
		(at 30.011116 -81.522062 -90)
		(property "Reference" "R675"
			(at 0 0 270)
			(layer "F.SilkS")
			(hide yes)
			(effects
				(font
					(size 1.27 1.27)
				)
			)
		)
		(property "Value" "1KR2F-3-GP"
			(at 0.064008 -3.993896 270)
			(unlocked yes)
			(layer "F.Fab")
			(hide yes)
			(effects
				(font
					(size 1.016 1.016)
					(thickness 0.1524)
				)
			)
		)
		(property "Device Type" "R402H16"
			(at 0.064008 -5.517896 270)
			(unlocked yes)
			(layer "F.Fab")
			(hide yes)
			(effects
				(font
					(size 1.016 1.016)
					(thickness 0.1524)
				)
			)
		)
		(duplicate_pad_numbers_are_jumpers no)
		(fp_line
			(start -0.508 -0.9398)
			(end -0.508 0.9398)
			(stroke
				(width 0.1524)
				(type default)
			)
			(layer "F.SilkS")
		)
		(fp_line
			(start 0.508 -0.9398)
			(end -0.508 -0.9398)
			(stroke
				(width 0.1524)
				(type default)
			)
			(layer "F.SilkS")
		)
		(fp_rect
			(start -0.508 0.9398)
			(end 0.508 -0.9398)
			(stroke
				(width 0)
				(type default)
			)
			(fill no)
			(layer "F.CrtYd")
		)
		(fp_rect
			(start -0.508 0.9398)
			(end 0.508 -0.9398)
			(stroke
				(width 0)
				(type default)
			)
			(fill no)
			(layer "F.Fab")
		)
		(pad "1" smd custom
			(at 0 -0.4445 270)
			(size 0.1397 0.1397)
			(layers "F.Cu" "F.Mask" "F.Paste")
			(net "INTA_LED_RED_B")
			(options
				(clearance outline)
				(anchor circle)
			)
			(primitives
				(gr_poly
					(pts
						(arc
							(start -0.1778 -0.2794)
							(mid -0.249642 -0.249642)
							(end -0.2794 -0.1778)
						)
						(arc
							(start -0.2794 0.1778)
							(mid -0.249642 0.249642)
							(end -0.1778 0.2794)
						)
						(arc
							(start 0.1778 0.2794)
							(mid 0.249642 0.249642)
							(end 0.2794 0.1778)
						)
						(arc
							(start 0.2794 -0.1778)
							(mid 0.249642 -0.249642)
							(end 0.1778 -0.2794)
						)
					)
					(width 0)
					(fill yes)
				)
			)
		)
		(pad "2" smd custom
			(at 0 0.4445 270)
			(size 0.1397 0.1397)
			(layers "F.Cu" "F.Mask" "F.Paste")
			(net "SAS_ACTIVITY_LED16")
			(options
				(clearance outline)
				(anchor circle)
			)
			(primitives
				(gr_poly
					(pts
						(arc
							(start -0.1778 -0.2794)
							(mid -0.249642 -0.249642)
							(end -0.2794 -0.1778)
						)
						(arc
							(start -0.2794 0.1778)
							(mid -0.249642 0.249642)
							(end -0.1778 0.2794)
						)
						(arc
							(start 0.1778 0.2794)
							(mid 0.249642 0.249642)
							(end 0.2794 0.1778)
						)
						(arc
							(start 0.2794 -0.1778)
							(mid 0.249642 -0.249642)
							(end 0.1778 -0.2794)
						)
					)
					(width 0)
					(fill yes)
				)
			)
		)
	)
	(footprint ""
		(layer "F.Cu")
		(at 92.21597 -96.647 -90)
		(property "Reference" "SR780"
			(at 0 0 270)
			(layer "F.SilkS")
			(hide yes)
			(effects
				(font
					(size 1.27 1.27)
				)
			)
		)
		(property "Value" "4K7R2F-GP"
			(at 0.064008 -3.993896 270)
			(unlocked yes)
			(layer "F.Fab")
			(hide yes)
			(effects
				(font
					(size 1.016 1.016)
					(thickness 0.1524)
				)
			)
		)
		(property "Device Type" "R402H16"
			(at 0.064008 -5.517896 270)
			(unlocked yes)
			(layer "F.Fab")
			(hide yes)
			(effects
				(font
					(size 1.016 1.016)
					(thickness 0.1524)
				)
			)
		)
		(duplicate_pad_numbers_are_jumpers no)
		(fp_line
			(start -0.508 -0.9398)
			(end -0.508 0.9398)
			(stroke
				(width 0.1524)
				(type default)
			)
			(layer "F.SilkS")
		)
		(fp_line
			(start 0.508 -0.9398)
			(end -0.508 -0.9398)
			(stroke
				(width 0.1524)
				(type default)
			)
			(layer "F.SilkS")
		)
		(fp_rect
			(start -0.508 0.9398)
			(end 0.508 -0.9398)
			(stroke
				(width 0)
				(type default)
			)
			(fill no)
			(layer "F.CrtYd")
		)
		(fp_rect
			(start -0.508 0.9398)
			(end 0.508 -0.9398)
			(stroke
				(width 0)
				(type default)
			)
			(fill no)
			(layer "F.Fab")
		)
		(pad "1" smd custom
			(at 0 -0.4445 270)
			(size 0.1397 0.1397)
			(layers "F.Cu" "F.Mask" "F.Paste")
			(net "EXP_XM_ADDR_19")
			(options
				(clearance outline)
				(anchor circle)
			)
			(primitives
				(gr_poly
					(pts
						(arc
							(start -0.1778 -0.2794)
							(mid -0.249642 -0.249642)
							(end -0.2794 -0.1778)
						)
						(arc
							(start -0.2794 0.1778)
							(mid -0.249642 0.249642)
							(end -0.1778 0.2794)
						)
						(arc
							(start 0.1778 0.2794)
							(mid 0.249642 0.249642)
							(end 0.2794 0.1778)
						)
						(arc
							(start 0.2794 -0.1778)
							(mid 0.249642 -0.249642)
							(end 0.1778 -0.2794)
						)
					)
					(width 0)
					(fill yes)
				)
			)
		)
		(pad "2" smd custom
			(at 0 0.4445 270)
			(size 0.1397 0.1397)
			(layers "F.Cu" "F.Mask" "F.Paste")
			(net "GND")
			(options
				(clearance outline)
				(anchor circle)
			)
			(primitives
				(gr_poly
					(pts
						(arc
							(start -0.1778 -0.2794)
							(mid -0.249642 -0.249642)
							(end -0.2794 -0.1778)
						)
						(arc
							(start -0.2794 0.1778)
							(mid -0.249642 0.249642)
							(end -0.1778 0.2794)
						)
						(arc
							(start 0.1778 0.2794)
							(mid 0.249642 0.249642)
							(end 0.2794 0.1778)
						)
						(arc
							(start 0.2794 -0.1778)
							(mid 0.249642 -0.249642)
							(end 0.1778 -0.2794)
						)
					)
					(width 0)
					(fill yes)
				)
			)
		)
	)
	(footprint ""
		(layer "F.Cu")
		(at 203.708 -185.42 180)
		(property "Reference" "R484"
			(at 0 0 180)
			(layer "F.SilkS")
			(hide yes)
			(effects
				(font
					(size 1.27 1.27)
				)
			)
		)
		(property "Value" "1KR2F-3-GP"
			(at 0.064008 -3.993896 180)
			(unlocked yes)
			(layer "F.Fab")
			(hide yes)
			(effects
				(font
					(size 1.016 1.016)
					(thickness 0.1524)
				)
			)
		)
		(property "Device Type" "R402H16"
			(at 0.064008 -5.517896 180)
			(unlocked yes)
			(layer "F.Fab")
			(hide yes)
			(effects
				(font
					(size 1.016 1.016)
					(thickness 0.1524)
				)
			)
		)
		(duplicate_pad_numbers_are_jumpers no)
		(fp_line
			(start 0.508 -0.9398)
			(end -0.508 -0.9398)
			(stroke
				(width 0.1524)
				(type default)
			)
			(layer "F.SilkS")
		)
		(fp_line
			(start -0.508 -0.9398)
			(end -0.508 0.9398)
			(stroke
				(width 0.1524)
				(type default)
			)
			(layer "F.SilkS")
		)
		(fp_rect
			(start -0.508 0.9398)
			(end 0.508 -0.9398)
			(stroke
				(width 0)
				(type default)
			)
			(fill no)
			(layer "F.CrtYd")
		)
		(fp_rect
			(start -0.508 0.9398)
			(end 0.508 -0.9398)
			(stroke
				(width 0)
				(type default)
			)
			(fill no)
			(layer "F.Fab")
		)
		(pad "1" smd custom
			(at 0 -0.4445 180)
			(size 0.1397 0.1397)
			(layers "F.Cu" "F.Mask" "F.Paste")
			(net "P3V3_STBY")
			(options
				(clearance outline)
				(anchor circle)
			)
			(primitives
				(gr_poly
					(pts
						(arc
							(start -0.1778 -0.2794)
							(mid -0.249642 -0.249642)
							(end -0.2794 -0.1778)
						)
						(arc
							(start -0.2794 0.1778)
							(mid -0.249642 0.249642)
							(end -0.1778 0.2794)
						)
						(arc
							(start 0.1778 0.2794)
							(mid 0.249642 0.249642)
							(end 0.2794 0.1778)
						)
						(arc
							(start 0.2794 -0.1778)
							(mid 0.249642 -0.249642)
							(end 0.1778 -0.2794)
						)
					)
					(width 0)
					(fill yes)
				)
			)
		)
		(pad "2" smd custom
			(at 0 0.4445 180)
			(size 0.1397 0.1397)
			(layers "F.Cu" "F.Mask" "F.Paste")
			(net "DIVIDER 1_IN")
			(options
				(clearance outline)
				(anchor circle)
			)
			(primitives
				(gr_poly
					(pts
						(arc
							(start -0.1778 -0.2794)
							(mid -0.249642 -0.249642)
							(end -0.2794 -0.1778)
						)
						(arc
							(start -0.2794 0.1778)
							(mid -0.249642 0.249642)
							(end -0.1778 0.2794)
						)
						(arc
							(start 0.1778 0.2794)
							(mid 0.249642 0.249642)
							(end 0.2794 0.1778)
						)
						(arc
							(start 0.2794 -0.1778)
							(mid 0.249642 -0.249642)
							(end 0.1778 -0.2794)
						)
					)
					(width 0)
					(fill yes)
				)
			)
		)
	)
	(footprint ""
		(layer "F.Cu")
		(at 43.561 -230.759)
		(property "Reference" "C303"
			(at 0 0 0)
			(layer "F.SilkS")
			(hide yes)
			(effects
				(font
					(size 1.27 1.27)
				)
			)
		)
		(property "Value" "SCD1U25V2KX-2-GP"
			(at 1.1811 -2.7051 0)
			(unlocked yes)
			(layer "F.Fab")
			(hide yes)
			(effects
				(font
					(size 1.016 1.016)
					(thickness 0.1524)
				)
			)
		)
		(property "Device Type" "C402H22"
			(at 1.1811 -4.2291 0)
			(unlocked yes)
			(layer "F.Fab")
			(hide yes)
			(effects
				(font
					(size 1.016 1.016)
					(thickness 0.1524)
				)
			)
		)
		(duplicate_pad_numbers_are_jumpers no)
		(fp_rect
			(start -0.4318 0.9525)
			(end 0.4318 -0.9525)
			(stroke
				(width 0)
				(type default)
			)
			(fill no)
			(layer "F.CrtYd")
		)
		(fp_rect
			(start -0.4318 0.9525)
			(end 0.4318 -0.9525)
			(stroke
				(width 0)
				(type default)
			)
			(fill no)
			(layer "F.Fab")
		)
		(pad "1" smd custom
			(at 0 -0.4445)
			(size 0.1524 0.1524)
			(layers "F.Cu" "F.Mask" "F.Paste")
			(net "P12V_PCIE")
			(options
				(clearance outline)
				(anchor circle)
			)
			(primitives
				(gr_poly
					(pts
						(arc
							(start 0.3048 -0.2032)
							(mid 0.275042 -0.275042)
							(end 0.2032 -0.3048)
						)
						(arc
							(start -0.2032 -0.3048)
							(mid -0.275042 -0.275042)
							(end -0.3048 -0.2032)
						)
						(arc
							(start -0.3048 0.2032)
							(mid -0.275042 0.275042)
							(end -0.2032 0.3048)
						)
						(arc
							(start 0.2032 0.3048)
							(mid 0.275042 0.275042)
							(end 0.3048 0.2032)
						)
					)
					(width 0)
					(fill yes)
				)
			)
		)
		(pad "2" smd custom
			(at 0 0.4445)
			(size 0.1524 0.1524)
			(layers "F.Cu" "F.Mask" "F.Paste")
			(net "GND")
			(options
				(clearance outline)
				(anchor circle)
			)
			(primitives
				(gr_poly
					(pts
						(arc
							(start 0.3048 -0.2032)
							(mid 0.275042 -0.275042)
							(end 0.2032 -0.3048)
						)
						(arc
							(start -0.2032 -0.3048)
							(mid -0.275042 -0.275042)
							(end -0.3048 -0.2032)
						)
						(arc
							(start -0.3048 0.2032)
							(mid -0.275042 0.275042)
							(end -0.2032 0.3048)
						)
						(arc
							(start 0.2032 0.3048)
							(mid 0.275042 0.275042)
							(end 0.3048 0.2032)
						)
					)
					(width 0)
					(fill yes)
				)
			)
		)
	)
	(footprint ""
		(layer "F.Cu")
		(at 21.159216 -213.79688 180)
		(property "Reference" "SR306"
			(at 0 0 180)
			(layer "F.SilkS")
			(hide yes)
			(effects
				(font
					(size 1.27 1.27)
				)
			)
		)
		(property "Value" "0R2J-2-GP"
			(at 0.064008 -3.993896 180)
			(unlocked yes)
			(layer "F.Fab")
			(hide yes)
			(effects
				(font
					(size 1.016 1.016)
					(thickness 0.1524)
				)
			)
		)
		(property "Device Type" "R402H16"
			(at 0.064008 -5.517896 180)
			(unlocked yes)
			(layer "F.Fab")
			(hide yes)
			(effects
				(font
					(size 1.016 1.016)
					(thickness 0.1524)
				)
			)
		)
		(duplicate_pad_numbers_are_jumpers no)
		(fp_line
			(start 0.508 -0.9398)
			(end -0.508 -0.9398)
			(stroke
				(width 0.1524)
				(type default)
			)
			(layer "F.SilkS")
		)
		(fp_line
			(start -0.508 -0.9398)
			(end -0.508 0.9398)
			(stroke
				(width 0.1524)
				(type default)
			)
			(layer "F.SilkS")
		)
		(fp_rect
			(start -0.508 0.9398)
			(end 0.508 -0.9398)
			(stroke
				(width 0)
				(type default)
			)
			(fill no)
			(layer "F.CrtYd")
		)
		(fp_rect
			(start -0.508 0.9398)
			(end 0.508 -0.9398)
			(stroke
				(width 0)
				(type default)
			)
			(fill no)
			(layer "F.Fab")
		)
		(pad "1" smd custom
			(at 0 -0.4445 180)
			(size 0.1397 0.1397)
			(layers "F.Cu" "F.Mask" "F.Paste")
			(net "HDD_PWR_RESET_N")
			(options
				(clearance outline)
				(anchor circle)
			)
			(primitives
				(gr_poly
					(pts
						(arc
							(start -0.1778 -0.2794)
							(mid -0.249642 -0.249642)
							(end -0.2794 -0.1778)
						)
						(arc
							(start -0.2794 0.1778)
							(mid -0.249642 0.249642)
							(end -0.1778 0.2794)
						)
						(arc
							(start 0.1778 0.2794)
							(mid 0.249642 0.249642)
							(end 0.2794 0.1778)
						)
						(arc
							(start 0.2794 -0.1778)
							(mid 0.249642 -0.249642)
							(end 0.1778 -0.2794)
						)
					)
					(width 0)
					(fill yes)
				)
			)
		)
		(pad "2" smd custom
			(at 0 0.4445 180)
			(size 0.1397 0.1397)
			(layers "F.Cu" "F.Mask" "F.Paste")
			(net "I2C_IO_EXP_RESET#_PWR")
			(options
				(clearance outline)
				(anchor circle)
			)
			(primitives
				(gr_poly
					(pts
						(arc
							(start -0.1778 -0.2794)
							(mid -0.249642 -0.249642)
							(end -0.2794 -0.1778)
						)
						(arc
							(start -0.2794 0.1778)
							(mid -0.249642 0.249642)
							(end -0.1778 0.2794)
						)
						(arc
							(start 0.1778 0.2794)
							(mid 0.249642 0.249642)
							(end 0.2794 0.1778)
						)
						(arc
							(start 0.2794 -0.1778)
							(mid 0.249642 -0.249642)
							(end 0.1778 -0.2794)
						)
					)
					(width 0)
					(fill yes)
				)
			)
		)
	)
	(footprint ""
		(layer "F.Cu")
		(at 62.357 -219.329 -90)
		(property "Reference" "R1227"
			(at 0 0 270)
			(layer "F.SilkS")
			(hide yes)
			(effects
				(font
					(size 1.27 1.27)
				)
			)
		)
		(property "Value" "100KR2F-L1-GP"
			(at 0.064008 -3.993896 270)
			(unlocked yes)
			(layer "F.Fab")
			(hide yes)
			(effects
				(font
					(size 1.016 1.016)
					(thickness 0.1524)
				)
			)
		)
		(property "Device Type" "R402H16"
			(at 0.064008 -5.517896 270)
			(unlocked yes)
			(layer "F.Fab")
			(hide yes)
			(effects
				(font
					(size 1.016 1.016)
					(thickness 0.1524)
				)
			)
		)
		(duplicate_pad_numbers_are_jumpers no)
		(fp_line
			(start -0.508 -0.9398)
			(end -0.508 0.9398)
			(stroke
				(width 0.1524)
				(type default)
			)
			(layer "F.SilkS")
		)
		(fp_line
			(start 0.508 -0.9398)
			(end -0.508 -0.9398)
			(stroke
				(width 0.1524)
				(type default)
			)
			(layer "F.SilkS")
		)
		(fp_rect
			(start -0.508 0.9398)
			(end 0.508 -0.9398)
			(stroke
				(width 0)
				(type default)
			)
			(fill no)
			(layer "F.CrtYd")
		)
		(fp_rect
			(start -0.508 0.9398)
			(end 0.508 -0.9398)
			(stroke
				(width 0)
				(type default)
			)
			(fill no)
			(layer "F.Fab")
		)
		(pad "1" smd custom
			(at 0 -0.4445 270)
			(size 0.1397 0.1397)
			(layers "F.Cu" "F.Mask" "F.Paste")
			(net "P12V")
			(options
				(clearance outline)
				(anchor circle)
			)
			(primitives
				(gr_poly
					(pts
						(arc
							(start -0.1778 -0.2794)
							(mid -0.249642 -0.249642)
							(end -0.2794 -0.1778)
						)
						(arc
							(start -0.2794 0.1778)
							(mid -0.249642 0.249642)
							(end -0.1778 0.2794)
						)
						(arc
							(start 0.1778 0.2794)
							(mid 0.249642 0.249642)
							(end 0.2794 0.1778)
						)
						(arc
							(start 0.2794 -0.1778)
							(mid 0.249642 -0.249642)
							(end 0.1778 -0.2794)
						)
					)
					(width 0)
					(fill yes)
				)
			)
		)
		(pad "2" smd custom
			(at 0 0.4445 270)
			(size 0.1397 0.1397)
			(layers "F.Cu" "F.Mask" "F.Paste")
			(net "MB0_P12V_PWGIN_R")
			(options
				(clearance outline)
				(anchor circle)
			)
			(primitives
				(gr_poly
					(pts
						(arc
							(start -0.1778 -0.2794)
							(mid -0.249642 -0.249642)
							(end -0.2794 -0.1778)
						)
						(arc
							(start -0.2794 0.1778)
							(mid -0.249642 0.249642)
							(end -0.1778 0.2794)
						)
						(arc
							(start 0.1778 0.2794)
							(mid 0.249642 0.249642)
							(end 0.2794 0.1778)
						)
						(arc
							(start 0.2794 -0.1778)
							(mid 0.249642 -0.249642)
							(end 0.1778 -0.2794)
						)
					)
					(width 0)
					(fill yes)
				)
			)
		)
	)
	(footprint ""
		(layer "F.Cu")
		(at 86.49716 -45.212 -90)
		(property "Reference" "SC902"
			(at 0 0 270)
			(layer "F.SilkS")
			(hide yes)
			(effects
				(font
					(size 1.27 1.27)
				)
			)
		)
		(property "Value" "SCD01U10V1KX-GP"
			(at -2.8321 -1.7399 270)
			(unlocked yes)
			(layer "F.Fab")
			(hide yes)
			(effects
				(font
					(size 1.016 1.016)
					(thickness 0.1524)
				)
			)
		)
		(property "Device Type" "C0201H13"
			(at -2.8321 -3.2639 270)
			(unlocked yes)
			(layer "F.Fab")
			(hide yes)
			(effects
				(font
					(size 1.016 1.016)
					(thickness 0.1524)
				)
			)
		)
		(duplicate_pad_numbers_are_jumpers no)
		(fp_rect
			(start -0.2794 0.6477)
			(end 0.2794 -0.6477)
			(stroke
				(width 0)
				(type default)
			)
			(fill no)
			(layer "F.CrtYd")
		)
		(fp_rect
			(start -0.2794 0.6477)
			(end 0.2794 -0.6477)
			(stroke
				(width 0)
				(type default)
			)
			(fill no)
			(layer "F.Fab")
		)
		(pad "1" smd custom
			(at 0 -0.2794 270)
			(size 0.0762 0.0762)
			(layers "F.Cu" "F.Mask" "F.Paste")
			(net "SAS3008_RAID_TX_C_P4")
			(options
				(clearance outline)
				(anchor circle)
			)
			(primitives
				(gr_poly
					(pts
						(arc
							(start 0.1524 -0.127)
							(mid 0.137521 -0.162921)
							(end 0.1016 -0.1778)
						)
						(arc
							(start -0.1016 -0.1778)
							(mid -0.137521 -0.162921)
							(end -0.1524 -0.127)
						)
						(arc
							(start -0.1524 0.127)
							(mid -0.137521 0.162921)
							(end -0.1016 0.1778)
						)
						(arc
							(start 0.1016 0.1778)
							(mid 0.137521 0.162921)
							(end 0.1524 0.127)
						)
					)
					(width 0)
					(fill yes)
				)
			)
		)
		(pad "2" smd custom
			(at 0 0.2794 270)
			(size 0.0762 0.0762)
			(layers "F.Cu" "F.Mask" "F.Paste")
			(net "IOC_RAID_TX_P4")
			(options
				(clearance outline)
				(anchor circle)
			)
			(primitives
				(gr_poly
					(pts
						(arc
							(start 0.1524 -0.127)
							(mid 0.137521 -0.162921)
							(end 0.1016 -0.1778)
						)
						(arc
							(start -0.1016 -0.1778)
							(mid -0.137521 -0.162921)
							(end -0.1524 -0.127)
						)
						(arc
							(start -0.1524 0.127)
							(mid -0.137521 0.162921)
							(end -0.1016 0.1778)
						)
						(arc
							(start 0.1016 0.1778)
							(mid 0.137521 0.162921)
							(end 0.1524 0.127)
						)
					)
					(width 0)
					(fill yes)
				)
			)
		)
	)
	(footprint ""
		(layer "F.Cu")
		(at 289.687 -68.707 90)
		(property "Reference" "PR9001"
			(at 0 0 90)
			(layer "F.SilkS")
			(hide yes)
			(effects
				(font
					(size 1.27 1.27)
				)
			)
		)
		(property "Value" "0R2J-2-GP"
			(at 0.064008 -3.993896 90)
			(unlocked yes)
			(layer "F.Fab")
			(hide yes)
			(effects
				(font
					(size 1.016 1.016)
					(thickness 0.1524)
				)
			)
		)
		(property "Device Type" "R402H16"
			(at 0.064008 -5.517896 90)
			(unlocked yes)
			(layer "F.Fab")
			(hide yes)
			(effects
				(font
					(size 1.016 1.016)
					(thickness 0.1524)
				)
			)
		)
		(duplicate_pad_numbers_are_jumpers no)
		(fp_line
			(start 0.508 -0.9398)
			(end -0.508 -0.9398)
			(stroke
				(width 0.1524)
				(type default)
			)
			(layer "F.SilkS")
		)
		(fp_line
			(start -0.508 -0.9398)
			(end -0.508 0.9398)
			(stroke
				(width 0.1524)
				(type default)
			)
			(layer "F.SilkS")
		)
		(fp_rect
			(start -0.508 0.9398)
			(end 0.508 -0.9398)
			(stroke
				(width 0)
				(type default)
			)
			(fill no)
			(layer "F.CrtYd")
		)
		(fp_rect
			(start -0.508 0.9398)
			(end 0.508 -0.9398)
			(stroke
				(width 0)
				(type default)
			)
			(fill no)
			(layer "F.Fab")
		)
		(pad "1" smd custom
			(at 0 -0.4445 90)
			(size 0.1397 0.1397)
			(layers "F.Cu" "F.Mask" "F.Paste")
			(net "HSW_SDA1")
			(options
				(clearance outline)
				(anchor circle)
			)
			(primitives
				(gr_poly
					(pts
						(arc
							(start -0.1778 -0.2794)
							(mid -0.249642 -0.249642)
							(end -0.2794 -0.1778)
						)
						(arc
							(start -0.2794 0.1778)
							(mid -0.249642 0.249642)
							(end -0.1778 0.2794)
						)
						(arc
							(start 0.1778 0.2794)
							(mid 0.249642 0.249642)
							(end 0.2794 0.1778)
						)
						(arc
							(start 0.2794 -0.1778)
							(mid 0.249642 -0.249642)
							(end 0.1778 -0.2794)
						)
					)
					(width 0)
					(fill yes)
				)
			)
		)
		(pad "2" smd custom
			(at 0 0.4445 90)
			(size 0.1397 0.1397)
			(layers "F.Cu" "F.Mask" "F.Paste")
			(net "BMC_I2C_A_SDA")
			(options
				(clearance outline)
				(anchor circle)
			)
			(primitives
				(gr_poly
					(pts
						(arc
							(start -0.1778 -0.2794)
							(mid -0.249642 -0.249642)
							(end -0.2794 -0.1778)
						)
						(arc
							(start -0.2794 0.1778)
							(mid -0.249642 0.249642)
							(end -0.1778 0.2794)
						)
						(arc
							(start 0.1778 0.2794)
							(mid 0.249642 0.249642)
							(end 0.2794 0.1778)
						)
						(arc
							(start 0.2794 -0.1778)
							(mid 0.249642 -0.249642)
							(end 0.1778 -0.2794)
						)
					)
					(width 0)
					(fill yes)
				)
			)
		)
	)
	(footprint ""
		(layer "F.Cu")
		(at 79.4766 -13.1318 90)
		(property "Reference" "PC211"
			(at 0 0 90)
			(layer "F.SilkS")
			(hide yes)
			(effects
				(font
					(size 1.27 1.27)
				)
			)
		)
		(property "Value" "SCD01U50V3KX-4GP"
			(at 0 -2.8194 90)
			(unlocked yes)
			(layer "F.Fab")
			(hide yes)
			(effects
				(font
					(size 1.016 1.016)
					(thickness 0.1524)
				)
			)
		)
		(property "Device Type" "C603H36"
			(at 0 -4.3434 90)
			(unlocked yes)
			(layer "F.Fab")
			(hide yes)
			(effects
				(font
					(size 1.016 1.016)
					(thickness 0.1524)
				)
			)
		)
		(duplicate_pad_numbers_are_jumpers no)
		(fp_line
			(start 0.508 0)
			(end -0.508 0)
			(stroke
				(width 0.2032)
				(type default)
			)
			(layer "F.SilkS")
		)
		(fp_rect
			(start -0.5842 1.3335)
			(end 0.5842 -1.3335)
			(stroke
				(width 0)
				(type default)
			)
			(fill no)
			(layer "F.CrtYd")
		)
		(fp_rect
			(start -0.5842 1.3335)
			(end 0.5842 -1.3335)
			(stroke
				(width 0)
				(type default)
			)
			(fill no)
			(layer "F.Fab")
		)
		(pad "1" smd custom
			(at 0 -0.762 90)
			(size 0.2159 0.2159)
			(layers "F.Cu" "F.Mask" "F.Paste")
			(net "VT235_VDDH")
			(options
				(clearance outline)
				(anchor circle)
			)
			(primitives
				(gr_poly
					(pts
						(arc
							(start -0.3302 -0.4318)
							(mid -0.402042 -0.402042)
							(end -0.4318 -0.3302)
						)
						(arc
							(start -0.4318 0.3302)
							(mid -0.402042 0.402042)
							(end -0.3302 0.4318)
						)
						(arc
							(start 0.3302 0.4318)
							(mid 0.402042 0.402042)
							(end 0.4318 0.3302)
						)
						(arc
							(start 0.4318 -0.3302)
							(mid 0.402042 -0.402042)
							(end 0.3302 -0.4318)
						)
					)
					(width 0)
					(fill yes)
				)
			)
		)
		(pad "2" smd custom
			(at 0 0.762 90)
			(size 0.2159 0.2159)
			(layers "F.Cu" "F.Mask" "F.Paste")
			(net "GND")
			(options
				(clearance outline)
				(anchor circle)
			)
			(primitives
				(gr_poly
					(pts
						(arc
							(start -0.3302 -0.4318)
							(mid -0.402042 -0.402042)
							(end -0.4318 -0.3302)
						)
						(arc
							(start -0.4318 0.3302)
							(mid -0.402042 0.402042)
							(end -0.3302 0.4318)
						)
						(arc
							(start 0.3302 0.4318)
							(mid 0.402042 0.402042)
							(end 0.4318 0.3302)
						)
						(arc
							(start 0.4318 -0.3302)
							(mid 0.402042 -0.402042)
							(end 0.3302 -0.4318)
						)
					)
					(width 0)
					(fill yes)
				)
			)
		)
	)
	(footprint ""
		(layer "F.Cu")
		(at 133.736842 -84.526882 90)
		(property "Reference" "SC1096"
			(at 0 0 90)
			(layer "F.SilkS")
			(hide yes)
			(effects
				(font
					(size 1.27 1.27)
				)
			)
		)
		(property "Value" "SCD01U10V1KX-GP"
			(at -2.8321 -1.7399 90)
			(unlocked yes)
			(layer "F.Fab")
			(hide yes)
			(effects
				(font
					(size 1.016 1.016)
					(thickness 0.1524)
				)
			)
		)
		(property "Device Type" "C0201H13"
			(at -2.8321 -3.2639 90)
			(unlocked yes)
			(layer "F.Fab")
			(hide yes)
			(effects
				(font
					(size 1.016 1.016)
					(thickness 0.1524)
				)
			)
		)
		(duplicate_pad_numbers_are_jumpers no)
		(fp_rect
			(start -0.2794 0.6477)
			(end 0.2794 -0.6477)
			(stroke
				(width 0)
				(type default)
			)
			(fill no)
			(layer "F.CrtYd")
		)
		(fp_rect
			(start -0.2794 0.6477)
			(end 0.2794 -0.6477)
			(stroke
				(width 0)
				(type default)
			)
			(fill no)
			(layer "F.Fab")
		)
		(pad "1" smd custom
			(at 0 -0.2794 90)
			(size 0.0762 0.0762)
			(layers "F.Cu" "F.Mask" "F.Paste")
			(net "SAS_HDD_TX14_P")
			(options
				(clearance outline)
				(anchor circle)
			)
			(primitives
				(gr_poly
					(pts
						(arc
							(start 0.1524 -0.127)
							(mid 0.137521 -0.162921)
							(end 0.1016 -0.1778)
						)
						(arc
							(start -0.1016 -0.1778)
							(mid -0.137521 -0.162921)
							(end -0.1524 -0.127)
						)
						(arc
							(start -0.1524 0.127)
							(mid -0.137521 0.162921)
							(end -0.1016 0.1778)
						)
						(arc
							(start 0.1016 0.1778)
							(mid 0.137521 0.162921)
							(end 0.1524 0.127)
						)
					)
					(width 0)
					(fill yes)
				)
			)
		)
		(pad "2" smd custom
			(at 0 0.2794 90)
			(size 0.0762 0.0762)
			(layers "F.Cu" "F.Mask" "F.Paste")
			(net "3008_SAS_RX_P2")
			(options
				(clearance outline)
				(anchor circle)
			)
			(primitives
				(gr_poly
					(pts
						(arc
							(start 0.1524 -0.127)
							(mid 0.137521 -0.162921)
							(end 0.1016 -0.1778)
						)
						(arc
							(start -0.1016 -0.1778)
							(mid -0.137521 -0.162921)
							(end -0.1524 -0.127)
						)
						(arc
							(start -0.1524 0.127)
							(mid -0.137521 0.162921)
							(end -0.1016 0.1778)
						)
						(arc
							(start 0.1016 0.1778)
							(mid 0.137521 0.162921)
							(end 0.1524 0.127)
						)
					)
					(width 0)
					(fill yes)
				)
			)
		)
	)
	(footprint ""
		(layer "F.Cu")
		(at 333.066136 -206.002128)
		(property "Reference" "U16"
			(at 0 0 0)
			(layer "F.SilkS")
			(hide yes)
			(effects
				(font
					(size 1.27 1.27)
				)
			)
		)
		(property "Value" "24LC64-I-SN-GP"
			(at -3.707384 -1.5367 0)
			(unlocked yes)
			(layer "F.Fab")
			(hide yes)
			(effects
				(font
					(size 1.016 1.016)
					(thickness 0.1524)
				)
			)
		)
		(property "Device Type" "SOIC8H69"
			(at -3.707384 -3.0607 0)
			(unlocked yes)
			(layer "F.Fab")
			(hide yes)
			(effects
				(font
					(size 1.016 1.016)
					(thickness 0.1524)
				)
			)
		)
		(duplicate_pad_numbers_are_jumpers no)
		(fp_line
			(start -2.7432 -1.4224)
			(end -2.7432 1.4224)
			(stroke
				(width 0.1524)
				(type default)
			)
			(layer "F.SilkS")
		)
		(fp_line
			(start -2.7432 1.4224)
			(end -2.6416 1.4224)
			(stroke
				(width 0.1524)
				(type default)
			)
			(layer "F.SilkS")
		)
		(fp_line
			(start -2.7432 1.4224)
			(end 2.1336 1.4224)
			(stroke
				(width 0.1524)
				(type default)
			)
			(layer "F.SilkS")
		)
		(fp_line
			(start -2.7178 -0.508)
			(end -2.1844 -0.0508)
			(stroke
				(width 0.1524)
				(type default)
			)
			(layer "F.SilkS")
		)
		(fp_line
			(start -2.6289 3.4417)
			(end -2.6289 1.4732)
			(stroke
				(width 0.381)
				(type default)
			)
			(layer "F.SilkS")
		)
		(fp_line
			(start -2.1844 -0.0508)
			(end -2.7178 0.508)
			(stroke
				(width 0.1524)
				(type default)
			)
			(layer "F.SilkS")
		)
		(fp_line
			(start 2.1336 -1.4224)
			(end -2.7432 -1.4224)
			(stroke
				(width 0.1524)
				(type default)
			)
			(layer "F.SilkS")
		)
		(fp_line
			(start 2.1336 1.4224)
			(end 2.1336 -1.4224)
			(stroke
				(width 0.1524)
				(type default)
			)
			(layer "F.SilkS")
		)
		(fp_poly
			(pts
				(xy -2.2098 -1.4224) (xy -2.2098 1.4224) (xy 2.2098 1.4224) (xy 2.2098 -1.4224)
			)
			(stroke
				(width 0)
				(type default)
			)
			(fill yes)
			(layer "F.SilkS")
		)
		(fp_rect
			(start -2.450084 2.999994)
			(end 2.450084 -2.999994)
			(stroke
				(width 0)
				(type default)
			)
			(fill no)
			(layer "F.CrtYd")
		)
		(fp_poly
			(pts
				(xy -2.8194 3.6322) (xy -2.8194 -3.6322) (xy 2.8194 -3.6322) (xy 2.8194 1.18364) (xy 2.450084 1.18364)
				(xy 2.450084 -2.999994) (xy -2.450084 -2.999994) (xy -2.450084 2.999994) (xy 2.450084 2.999994)
				(xy 2.450084 1.18618) (xy 2.8194 1.18618) (xy 2.8194 3.6322)
			)
			(stroke
				(width 0)
				(type default)
			)
			(fill no)
			(layer "F.CrtYd")
		)
		(fp_rect
			(start -2.8194 3.6322)
			(end 2.8194 -3.6322)
			(stroke
				(width 0)
				(type default)
			)
			(fill no)
			(layer "F.Fab")
		)
		(pad "1" smd rect
			(at -1.905 2.54)
			(size 0.635 1.651)
			(layers "F.Cu" "F.Mask" "F.Paste")
			(net "EEPROM_A0_R")
		)
		(pad "2" smd rect
			(at -0.635 2.54)
			(size 0.635 1.651)
			(layers "F.Cu" "F.Mask" "F.Paste")
			(net "EEPROM_A1_R")
		)
		(pad "3" smd rect
			(at 0.635 2.54)
			(size 0.635 1.651)
			(layers "F.Cu" "F.Mask" "F.Paste")
			(net "EEPROM_A2_R")
		)
		(pad "4" smd rect
			(at 1.905 2.54)
			(size 0.635 1.651)
			(layers "F.Cu" "F.Mask" "F.Paste")
			(net "GND")
		)
		(pad "5" smd rect
			(at 1.905 -2.54)
			(size 0.635 1.651)
			(layers "F.Cu" "F.Mask" "F.Paste")
			(net "EEPROM_SDA")
		)
		(pad "6" smd rect
			(at 0.635 -2.54)
			(size 0.635 1.651)
			(layers "F.Cu" "F.Mask" "F.Paste")
			(net "EEPROM_SCL")
		)
		(pad "7" smd rect
			(at -0.635 -2.54)
			(size 0.635 1.651)
			(layers "F.Cu" "F.Mask" "F.Paste")
			(net "EEPROM_WP")
		)
		(pad "8" smd rect
			(at -1.905 -2.54)
			(size 0.635 1.651)
			(layers "F.Cu" "F.Mask" "F.Paste")
			(net "P3V3_STBY")
		)
	)
	(footprint ""
		(layer "F.Cu")
		(at 117.74297 -114.3 180)
		(property "Reference" "SC1072"
			(at 0 0 180)
			(layer "F.SilkS")
			(hide yes)
			(effects
				(font
					(size 1.27 1.27)
				)
			)
		)
		(property "Value" "SCD01U10V1KX-GP"
			(at -2.8321 -1.7399 180)
			(unlocked yes)
			(layer "F.Fab")
			(hide yes)
			(effects
				(font
					(size 1.016 1.016)
					(thickness 0.1524)
				)
			)
		)
		(property "Device Type" "C0201H13"
			(at -2.8321 -3.2639 180)
			(unlocked yes)
			(layer "F.Fab")
			(hide yes)
			(effects
				(font
					(size 1.016 1.016)
					(thickness 0.1524)
				)
			)
		)
		(duplicate_pad_numbers_are_jumpers no)
		(fp_rect
			(start -0.2794 0.6477)
			(end 0.2794 -0.6477)
			(stroke
				(width 0)
				(type default)
			)
			(fill no)
			(layer "F.CrtYd")
		)
		(fp_rect
			(start -0.2794 0.6477)
			(end 0.2794 -0.6477)
			(stroke
				(width 0)
				(type default)
			)
			(fill no)
			(layer "F.Fab")
		)
		(pad "1" smd custom
			(at 0 -0.2794 180)
			(size 0.0762 0.0762)
			(layers "F.Cu" "F.Mask" "F.Paste")
			(net "SAS_HDD_TX2_N")
			(options
				(clearance outline)
				(anchor circle)
			)
			(primitives
				(gr_poly
					(pts
						(arc
							(start 0.1524 -0.127)
							(mid 0.137521 -0.162921)
							(end 0.1016 -0.1778)
						)
						(arc
							(start -0.1016 -0.1778)
							(mid -0.137521 -0.162921)
							(end -0.1524 -0.127)
						)
						(arc
							(start -0.1524 0.127)
							(mid -0.137521 0.162921)
							(end -0.1016 0.1778)
						)
						(arc
							(start 0.1016 0.1778)
							(mid 0.137521 0.162921)
							(end 0.1524 0.127)
						)
					)
					(width 0)
					(fill yes)
				)
			)
		)
		(pad "2" smd custom
			(at 0 0.2794 180)
			(size 0.0762 0.0762)
			(layers "F.Cu" "F.Mask" "F.Paste")
			(net "SAS_EXP_GF_TX_DN6")
			(options
				(clearance outline)
				(anchor circle)
			)
			(primitives
				(gr_poly
					(pts
						(arc
							(start 0.1524 -0.127)
							(mid 0.137521 -0.162921)
							(end 0.1016 -0.1778)
						)
						(arc
							(start -0.1016 -0.1778)
							(mid -0.137521 -0.162921)
							(end -0.1524 -0.127)
						)
						(arc
							(start -0.1524 0.127)
							(mid -0.137521 0.162921)
							(end -0.1016 0.1778)
						)
						(arc
							(start 0.1016 0.1778)
							(mid 0.137521 0.162921)
							(end 0.1524 0.127)
						)
					)
					(width 0)
					(fill yes)
				)
			)
		)
	)
	(footprint ""
		(layer "F.Cu")
		(at 83.439 -24.384 180)
		(property "Reference" "PC221"
			(at 0 0 180)
			(layer "F.SilkS")
			(hide yes)
			(effects
				(font
					(size 1.27 1.27)
				)
			)
		)
		(property "Value" "SC1KP50V2KX-1GP"
			(at 1.1811 -2.7051 180)
			(unlocked yes)
			(layer "F.Fab")
			(hide yes)
			(effects
				(font
					(size 1.016 1.016)
					(thickness 0.1524)
				)
			)
		)
		(property "Device Type" "C402H22"
			(at 1.1811 -4.2291 180)
			(unlocked yes)
			(layer "F.Fab")
			(hide yes)
			(effects
				(font
					(size 1.016 1.016)
					(thickness 0.1524)
				)
			)
		)
		(duplicate_pad_numbers_are_jumpers no)
		(fp_rect
			(start -0.4318 0.9525)
			(end 0.4318 -0.9525)
			(stroke
				(width 0)
				(type default)
			)
			(fill no)
			(layer "F.CrtYd")
		)
		(fp_rect
			(start -0.4318 0.9525)
			(end 0.4318 -0.9525)
			(stroke
				(width 0)
				(type default)
			)
			(fill no)
			(layer "F.Fab")
		)
		(pad "1" smd custom
			(at 0 -0.4445 180)
			(size 0.1524 0.1524)
			(layers "F.Cu" "F.Mask" "F.Paste")
			(net "VT235_VREF")
			(options
				(clearance outline)
				(anchor circle)
			)
			(primitives
				(gr_poly
					(pts
						(arc
							(start 0.3048 -0.2032)
							(mid 0.275042 -0.275042)
							(end 0.2032 -0.3048)
						)
						(arc
							(start -0.2032 -0.3048)
							(mid -0.275042 -0.275042)
							(end -0.3048 -0.2032)
						)
						(arc
							(start -0.3048 0.2032)
							(mid -0.275042 0.275042)
							(end -0.2032 0.3048)
						)
						(arc
							(start 0.2032 0.3048)
							(mid 0.275042 0.275042)
							(end 0.3048 0.2032)
						)
					)
					(width 0)
					(fill yes)
				)
			)
		)
		(pad "2" smd custom
			(at 0 0.4445 180)
			(size 0.1524 0.1524)
			(layers "F.Cu" "F.Mask" "F.Paste")
			(net "VT235_VDES_RCC")
			(options
				(clearance outline)
				(anchor circle)
			)
			(primitives
				(gr_poly
					(pts
						(arc
							(start 0.3048 -0.2032)
							(mid 0.275042 -0.275042)
							(end 0.2032 -0.3048)
						)
						(arc
							(start -0.2032 -0.3048)
							(mid -0.275042 -0.275042)
							(end -0.3048 -0.2032)
						)
						(arc
							(start -0.3048 0.2032)
							(mid -0.275042 0.275042)
							(end -0.2032 0.3048)
						)
						(arc
							(start 0.2032 0.3048)
							(mid 0.275042 0.275042)
							(end 0.3048 0.2032)
						)
					)
					(width 0)
					(fill yes)
				)
			)
		)
	)
	(footprint ""
		(layer "F.Cu")
		(at 182.934864 -22.551136 180)
		(property "Reference" "R384"
			(at 0 0 180)
			(layer "F.SilkS")
			(hide yes)
			(effects
				(font
					(size 1.27 1.27)
				)
			)
		)
		(property "Value" "4K75R2F-1-GP"
			(at 0.064008 -3.993896 180)
			(unlocked yes)
			(layer "F.Fab")
			(hide yes)
			(effects
				(font
					(size 1.016 1.016)
					(thickness 0.1524)
				)
			)
		)
		(property "Device Type" "R402H16"
			(at 0.064008 -5.517896 180)
			(unlocked yes)
			(layer "F.Fab")
			(hide yes)
			(effects
				(font
					(size 1.016 1.016)
					(thickness 0.1524)
				)
			)
		)
		(duplicate_pad_numbers_are_jumpers no)
		(fp_line
			(start 0.508 -0.9398)
			(end -0.508 -0.9398)
			(stroke
				(width 0.1524)
				(type default)
			)
			(layer "F.SilkS")
		)
		(fp_line
			(start -0.508 -0.9398)
			(end -0.508 0.9398)
			(stroke
				(width 0.1524)
				(type default)
			)
			(layer "F.SilkS")
		)
		(fp_rect
			(start -0.508 0.9398)
			(end 0.508 -0.9398)
			(stroke
				(width 0)
				(type default)
			)
			(fill no)
			(layer "F.CrtYd")
		)
		(fp_rect
			(start -0.508 0.9398)
			(end 0.508 -0.9398)
			(stroke
				(width 0)
				(type default)
			)
			(fill no)
			(layer "F.Fab")
		)
		(pad "1" smd custom
			(at 0 -0.4445 180)
			(size 0.1397 0.1397)
			(layers "F.Cu" "F.Mask" "F.Paste")
			(net "P3V3_STBY")
			(options
				(clearance outline)
				(anchor circle)
			)
			(primitives
				(gr_poly
					(pts
						(arc
							(start -0.1778 -0.2794)
							(mid -0.249642 -0.249642)
							(end -0.2794 -0.1778)
						)
						(arc
							(start -0.2794 0.1778)
							(mid -0.249642 0.249642)
							(end -0.1778 0.2794)
						)
						(arc
							(start 0.1778 0.2794)
							(mid 0.249642 0.249642)
							(end 0.2794 0.1778)
						)
						(arc
							(start 0.2794 -0.1778)
							(mid 0.249642 -0.249642)
							(end 0.1778 -0.2794)
						)
					)
					(width 0)
					(fill yes)
				)
			)
		)
		(pad "2" smd custom
			(at 0 0.4445 180)
			(size 0.1397 0.1397)
			(layers "F.Cu" "F.Mask" "F.Paste")
			(net "PHY_FDX")
			(options
				(clearance outline)
				(anchor circle)
			)
			(primitives
				(gr_poly
					(pts
						(arc
							(start -0.1778 -0.2794)
							(mid -0.249642 -0.249642)
							(end -0.2794 -0.1778)
						)
						(arc
							(start -0.2794 0.1778)
							(mid -0.249642 0.249642)
							(end -0.1778 0.2794)
						)
						(arc
							(start 0.1778 0.2794)
							(mid 0.249642 0.249642)
							(end 0.2794 0.1778)
						)
						(arc
							(start 0.2794 -0.1778)
							(mid 0.249642 -0.249642)
							(end 0.1778 -0.2794)
						)
					)
					(width 0)
					(fill yes)
				)
			)
		)
	)
	(footprint ""
		(layer "F.Cu")
		(at 318.893952 -59.69 90)
		(property "Reference" "R214"
			(at 0 0 90)
			(layer "F.SilkS")
			(hide yes)
			(effects
				(font
					(size 1.27 1.27)
				)
			)
		)
		(property "Value" "0R2J-2-GP"
			(at 0.064008 -3.993896 90)
			(unlocked yes)
			(layer "F.Fab")
			(hide yes)
			(effects
				(font
					(size 1.016 1.016)
					(thickness 0.1524)
				)
			)
		)
		(property "Device Type" "R402H16"
			(at 0.064008 -5.517896 90)
			(unlocked yes)
			(layer "F.Fab")
			(hide yes)
			(effects
				(font
					(size 1.016 1.016)
					(thickness 0.1524)
				)
			)
		)
		(duplicate_pad_numbers_are_jumpers no)
		(fp_line
			(start 0.508 -0.9398)
			(end -0.508 -0.9398)
			(stroke
				(width 0.1524)
				(type default)
			)
			(layer "F.SilkS")
		)
		(fp_line
			(start -0.508 -0.9398)
			(end -0.508 0.9398)
			(stroke
				(width 0.1524)
				(type default)
			)
			(layer "F.SilkS")
		)
		(fp_rect
			(start -0.508 0.9398)
			(end 0.508 -0.9398)
			(stroke
				(width 0)
				(type default)
			)
			(fill no)
			(layer "F.CrtYd")
		)
		(fp_rect
			(start -0.508 0.9398)
			(end 0.508 -0.9398)
			(stroke
				(width 0)
				(type default)
			)
			(fill no)
			(layer "F.Fab")
		)
		(pad "1" smd custom
			(at 0 -0.4445 90)
			(size 0.1397 0.1397)
			(layers "F.Cu" "F.Mask" "F.Paste")
			(net "PMU_PLTRST_N_10G")
			(options
				(clearance outline)
				(anchor circle)
			)
			(primitives
				(gr_poly
					(pts
						(arc
							(start -0.1778 -0.2794)
							(mid -0.249642 -0.249642)
							(end -0.2794 -0.1778)
						)
						(arc
							(start -0.2794 0.1778)
							(mid -0.249642 0.249642)
							(end -0.1778 0.2794)
						)
						(arc
							(start 0.1778 0.2794)
							(mid 0.249642 0.249642)
							(end 0.2794 0.1778)
						)
						(arc
							(start 0.2794 -0.1778)
							(mid 0.249642 -0.249642)
							(end 0.1778 -0.2794)
						)
					)
					(width 0)
					(fill yes)
				)
			)
		)
		(pad "2" smd custom
			(at 0 0.4445 90)
			(size 0.1397 0.1397)
			(layers "F.Cu" "F.Mask" "F.Paste")
			(net "PMU_PLTRST_N")
			(options
				(clearance outline)
				(anchor circle)
			)
			(primitives
				(gr_poly
					(pts
						(arc
							(start -0.1778 -0.2794)
							(mid -0.249642 -0.249642)
							(end -0.2794 -0.1778)
						)
						(arc
							(start -0.2794 0.1778)
							(mid -0.249642 0.249642)
							(end -0.1778 0.2794)
						)
						(arc
							(start 0.1778 0.2794)
							(mid 0.249642 0.249642)
							(end 0.2794 0.1778)
						)
						(arc
							(start 0.2794 -0.1778)
							(mid 0.249642 -0.249642)
							(end 0.1778 -0.2794)
						)
					)
					(width 0)
					(fill yes)
				)
			)
		)
	)
	(footprint ""
		(layer "F.Cu")
		(at 323.596 -143.383 -90)
		(property "Reference" "C306"
			(at 0 0 270)
			(layer "F.SilkS")
			(hide yes)
			(effects
				(font
					(size 1.27 1.27)
				)
			)
		)
		(property "Value" "SC15P50V2JN-2-GP"
			(at 1.1811 -2.7051 270)
			(unlocked yes)
			(layer "F.Fab")
			(hide yes)
			(effects
				(font
					(size 1.016 1.016)
					(thickness 0.1524)
				)
			)
		)
		(property "Device Type" "C402H22"
			(at 1.1811 -4.2291 270)
			(unlocked yes)
			(layer "F.Fab")
			(hide yes)
			(effects
				(font
					(size 1.016 1.016)
					(thickness 0.1524)
				)
			)
		)
		(duplicate_pad_numbers_are_jumpers no)
		(fp_rect
			(start -0.4318 0.9525)
			(end 0.4318 -0.9525)
			(stroke
				(width 0)
				(type default)
			)
			(fill no)
			(layer "F.CrtYd")
		)
		(fp_rect
			(start -0.4318 0.9525)
			(end 0.4318 -0.9525)
			(stroke
				(width 0)
				(type default)
			)
			(fill no)
			(layer "F.Fab")
		)
		(pad "1" smd custom
			(at 0 -0.4445 270)
			(size 0.1524 0.1524)
			(layers "F.Cu" "F.Mask" "F.Paste")
			(net "RTC_OSCI")
			(options
				(clearance outline)
				(anchor circle)
			)
			(primitives
				(gr_poly
					(pts
						(arc
							(start 0.3048 -0.2032)
							(mid 0.275042 -0.275042)
							(end 0.2032 -0.3048)
						)
						(arc
							(start -0.2032 -0.3048)
							(mid -0.275042 -0.275042)
							(end -0.3048 -0.2032)
						)
						(arc
							(start -0.3048 0.2032)
							(mid -0.275042 0.275042)
							(end -0.2032 0.3048)
						)
						(arc
							(start 0.2032 0.3048)
							(mid 0.275042 0.275042)
							(end 0.3048 0.2032)
						)
					)
					(width 0)
					(fill yes)
				)
			)
		)
		(pad "2" smd custom
			(at 0 0.4445 270)
			(size 0.1524 0.1524)
			(layers "F.Cu" "F.Mask" "F.Paste")
			(net "GND")
			(options
				(clearance outline)
				(anchor circle)
			)
			(primitives
				(gr_poly
					(pts
						(arc
							(start 0.3048 -0.2032)
							(mid 0.275042 -0.275042)
							(end 0.2032 -0.3048)
						)
						(arc
							(start -0.2032 -0.3048)
							(mid -0.275042 -0.275042)
							(end -0.3048 -0.2032)
						)
						(arc
							(start -0.3048 0.2032)
							(mid -0.275042 0.275042)
							(end -0.2032 0.3048)
						)
						(arc
							(start 0.2032 0.3048)
							(mid 0.275042 0.275042)
							(end 0.3048 0.2032)
						)
					)
					(width 0)
					(fill yes)
				)
			)
		)
	)
	(footprint ""
		(layer "F.Cu")
		(at 114.18697 -114.3 180)
		(property "Reference" "SC1076"
			(at 0 0 180)
			(layer "F.SilkS")
			(hide yes)
			(effects
				(font
					(size 1.27 1.27)
				)
			)
		)
		(property "Value" "SCD01U10V1KX-GP"
			(at -2.8321 -1.7399 180)
			(unlocked yes)
			(layer "F.Fab")
			(hide yes)
			(effects
				(font
					(size 1.016 1.016)
					(thickness 0.1524)
				)
			)
		)
		(property "Device Type" "C0201H13"
			(at -2.8321 -3.2639 180)
			(unlocked yes)
			(layer "F.Fab")
			(hide yes)
			(effects
				(font
					(size 1.016 1.016)
					(thickness 0.1524)
				)
			)
		)
		(duplicate_pad_numbers_are_jumpers no)
		(fp_rect
			(start -0.2794 0.6477)
			(end 0.2794 -0.6477)
			(stroke
				(width 0)
				(type default)
			)
			(fill no)
			(layer "F.CrtYd")
		)
		(fp_rect
			(start -0.2794 0.6477)
			(end 0.2794 -0.6477)
			(stroke
				(width 0)
				(type default)
			)
			(fill no)
			(layer "F.Fab")
		)
		(pad "1" smd custom
			(at 0 -0.2794 180)
			(size 0.0762 0.0762)
			(layers "F.Cu" "F.Mask" "F.Paste")
			(net "SAS_HDD_TX4_N")
			(options
				(clearance outline)
				(anchor circle)
			)
			(primitives
				(gr_poly
					(pts
						(arc
							(start 0.1524 -0.127)
							(mid 0.137521 -0.162921)
							(end 0.1016 -0.1778)
						)
						(arc
							(start -0.1016 -0.1778)
							(mid -0.137521 -0.162921)
							(end -0.1524 -0.127)
						)
						(arc
							(start -0.1524 0.127)
							(mid -0.137521 0.162921)
							(end -0.1016 0.1778)
						)
						(arc
							(start 0.1016 0.1778)
							(mid 0.137521 0.162921)
							(end 0.1524 0.127)
						)
					)
					(width 0)
					(fill yes)
				)
			)
		)
		(pad "2" smd custom
			(at 0 0.2794 180)
			(size 0.0762 0.0762)
			(layers "F.Cu" "F.Mask" "F.Paste")
			(net "SAS_HDD_REDV_TX8_N")
			(options
				(clearance outline)
				(anchor circle)
			)
			(primitives
				(gr_poly
					(pts
						(arc
							(start 0.1524 -0.127)
							(mid 0.137521 -0.162921)
							(end 0.1016 -0.1778)
						)
						(arc
							(start -0.1016 -0.1778)
							(mid -0.137521 -0.162921)
							(end -0.1524 -0.127)
						)
						(arc
							(start -0.1524 0.127)
							(mid -0.137521 0.162921)
							(end -0.1016 0.1778)
						)
						(arc
							(start 0.1016 0.1778)
							(mid 0.137521 0.162921)
							(end 0.1524 0.127)
						)
					)
					(width 0)
					(fill yes)
				)
			)
		)
	)
	(footprint ""
		(layer "F.Cu")
		(at 64.77 -218.313 90)
		(property "Reference" "P2121"
			(at 0 0 90)
			(layer "F.SilkS")
			(hide yes)
			(effects
				(font
					(size 1.27 1.27)
				)
			)
		)
		(property "Value" "0R0603-PAD-2-GP-U"
			(at -0.0254 -2.2987 90)
			(unlocked yes)
			(layer "F.Fab")
			(hide yes)
			(effects
				(font
					(size 1.016 1.016)
					(thickness 0.1524)
				)
			)
		)
		(property "Device Type" "0R0603-PAD-1-U"
			(at -0.0254 -3.8227 90)
			(unlocked yes)
			(layer "F.Fab")
			(hide yes)
			(effects
				(font
					(size 1.016 1.016)
					(thickness 0.1524)
				)
			)
		)
		(duplicate_pad_numbers_are_jumpers no)
		(fp_rect
			(start -0.5842 1.3335)
			(end 0.5842 -1.3335)
			(stroke
				(width 0)
				(type default)
			)
			(fill no)
			(layer "F.CrtYd")
		)
		(fp_rect
			(start -0.5842 1.3335)
			(end 0.5842 -1.3335)
			(stroke
				(width 0)
				(type default)
			)
			(fill no)
			(layer "F.Fab")
		)
		(pad "1" smd custom
			(at 0 -0.762 90)
			(size 0.2159 0.2159)
			(layers "F.Cu" "F.Mask" "F.Paste")
			(net "AGND_CURRENT_MON")
			(options
				(clearance outline)
				(anchor circle)
			)
			(primitives
				(gr_poly
					(pts
						(arc
							(start -0.3302 -0.5842)
							(mid -0.402042 -0.554442)
							(end -0.4318 -0.4826)
						)
						(arc
							(start -0.4318 0.4826)
							(mid -0.402042 0.554442)
							(end -0.3302 0.5842)
						)
						(arc
							(start 0.3302 0.5842)
							(mid 0.402042 0.554442)
							(end 0.4318 0.4826)
						)
						(arc
							(start 0.4318 -0.4826)
							(mid 0.402042 -0.554442)
							(end 0.3302 -0.5842)
						)
					)
					(width 0)
					(fill yes)
				)
			)
		)
		(pad "2" smd custom
			(at 0 0.762 90)
			(size 0.2159 0.2159)
			(layers "F.Cu" "F.Mask" "F.Paste")
			(net "GND")
			(options
				(clearance outline)
				(anchor circle)
			)
			(primitives
				(gr_poly
					(pts
						(arc
							(start -0.4318 0.4826)
							(mid -0.402042 0.554442)
							(end -0.3302 0.5842)
						)
						(arc
							(start 0.3302 0.5842)
							(mid 0.402042 0.554442)
							(end 0.4318 0.4826)
						)
						(arc
							(start 0.4318 -0.4826)
							(mid 0.402042 -0.554442)
							(end 0.3302 -0.5842)
						)
						(arc
							(start -0.3302 -0.5842)
							(mid -0.402042 -0.554442)
							(end -0.4318 -0.4826)
						)
					)
					(width 0)
					(fill yes)
				)
			)
		)
	)
	(footprint ""
		(layer "F.Cu")
		(at 221.869 -172.212 180)
		(property "Reference" "R496"
			(at 0 0 180)
			(layer "F.SilkS")
			(hide yes)
			(effects
				(font
					(size 1.27 1.27)
				)
			)
		)
		(property "Value" "10KR2F-2-GP"
			(at 0.064008 -3.993896 180)
			(unlocked yes)
			(layer "F.Fab")
			(hide yes)
			(effects
				(font
					(size 1.016 1.016)
					(thickness 0.1524)
				)
			)
		)
		(property "Device Type" "R402H16"
			(at 0.064008 -5.517896 180)
			(unlocked yes)
			(layer "F.Fab")
			(hide yes)
			(effects
				(font
					(size 1.016 1.016)
					(thickness 0.1524)
				)
			)
		)
		(duplicate_pad_numbers_are_jumpers no)
		(fp_line
			(start 0.508 -0.9398)
			(end -0.508 -0.9398)
			(stroke
				(width 0.1524)
				(type default)
			)
			(layer "F.SilkS")
		)
		(fp_line
			(start -0.508 -0.9398)
			(end -0.508 0.9398)
			(stroke
				(width 0.1524)
				(type default)
			)
			(layer "F.SilkS")
		)
		(fp_rect
			(start -0.508 0.9398)
			(end 0.508 -0.9398)
			(stroke
				(width 0)
				(type default)
			)
			(fill no)
			(layer "F.CrtYd")
		)
		(fp_rect
			(start -0.508 0.9398)
			(end 0.508 -0.9398)
			(stroke
				(width 0)
				(type default)
			)
			(fill no)
			(layer "F.Fab")
		)
		(pad "1" smd custom
			(at 0 -0.4445 180)
			(size 0.1397 0.1397)
			(layers "F.Cu" "F.Mask" "F.Paste")
			(net "P3V3_STBY")
			(options
				(clearance outline)
				(anchor circle)
			)
			(primitives
				(gr_poly
					(pts
						(arc
							(start -0.1778 -0.2794)
							(mid -0.249642 -0.249642)
							(end -0.2794 -0.1778)
						)
						(arc
							(start -0.2794 0.1778)
							(mid -0.249642 0.249642)
							(end -0.1778 0.2794)
						)
						(arc
							(start 0.1778 0.2794)
							(mid 0.249642 0.249642)
							(end 0.2794 0.1778)
						)
						(arc
							(start 0.2794 -0.1778)
							(mid 0.249642 -0.249642)
							(end 0.1778 -0.2794)
						)
					)
					(width 0)
					(fill yes)
				)
			)
		)
		(pad "2" smd custom
			(at 0 0.4445 180)
			(size 0.1397 0.1397)
			(layers "F.Cu" "F.Mask" "F.Paste")
			(net "INVERTER_G2_EXP")
			(options
				(clearance outline)
				(anchor circle)
			)
			(primitives
				(gr_poly
					(pts
						(arc
							(start -0.1778 -0.2794)
							(mid -0.249642 -0.249642)
							(end -0.2794 -0.1778)
						)
						(arc
							(start -0.2794 0.1778)
							(mid -0.249642 0.249642)
							(end -0.1778 0.2794)
						)
						(arc
							(start 0.1778 0.2794)
							(mid 0.249642 0.249642)
							(end 0.2794 0.1778)
						)
						(arc
							(start 0.2794 -0.1778)
							(mid 0.249642 -0.249642)
							(end 0.1778 -0.2794)
						)
					)
					(width 0)
					(fill yes)
				)
			)
		)
	)
	(footprint ""
		(layer "F.Cu")
		(at 8.713216 -226.62388 180)
		(property "Reference" "R155"
			(at 0 0 180)
			(layer "F.SilkS")
			(hide yes)
			(effects
				(font
					(size 1.27 1.27)
				)
			)
		)
		(property "Value" "0R2J-2-GP"
			(at 0.064008 -3.993896 180)
			(unlocked yes)
			(layer "F.Fab")
			(hide yes)
			(effects
				(font
					(size 1.016 1.016)
					(thickness 0.1524)
				)
			)
		)
		(property "Device Type" "R402H16"
			(at 0.064008 -5.517896 180)
			(unlocked yes)
			(layer "F.Fab")
			(hide yes)
			(effects
				(font
					(size 1.016 1.016)
					(thickness 0.1524)
				)
			)
		)
		(duplicate_pad_numbers_are_jumpers no)
		(fp_line
			(start 0.508 -0.9398)
			(end -0.508 -0.9398)
			(stroke
				(width 0.1524)
				(type default)
			)
			(layer "F.SilkS")
		)
		(fp_line
			(start -0.508 -0.9398)
			(end -0.508 0.9398)
			(stroke
				(width 0.1524)
				(type default)
			)
			(layer "F.SilkS")
		)
		(fp_rect
			(start -0.508 0.9398)
			(end 0.508 -0.9398)
			(stroke
				(width 0)
				(type default)
			)
			(fill no)
			(layer "F.CrtYd")
		)
		(fp_rect
			(start -0.508 0.9398)
			(end 0.508 -0.9398)
			(stroke
				(width 0)
				(type default)
			)
			(fill no)
			(layer "F.Fab")
		)
		(pad "1" smd custom
			(at 0 -0.4445 180)
			(size 0.1397 0.1397)
			(layers "F.Cu" "F.Mask" "F.Paste")
			(net "BMC_SELF_TRAY")
			(options
				(clearance outline)
				(anchor circle)
			)
			(primitives
				(gr_poly
					(pts
						(arc
							(start -0.1778 -0.2794)
							(mid -0.249642 -0.249642)
							(end -0.2794 -0.1778)
						)
						(arc
							(start -0.2794 0.1778)
							(mid -0.249642 0.249642)
							(end -0.1778 0.2794)
						)
						(arc
							(start 0.1778 0.2794)
							(mid 0.249642 0.249642)
							(end 0.2794 0.1778)
						)
						(arc
							(start 0.2794 -0.1778)
							(mid 0.249642 -0.249642)
							(end 0.1778 -0.2794)
						)
					)
					(width 0)
					(fill yes)
				)
			)
		)
		(pad "2" smd custom
			(at 0 0.4445 180)
			(size 0.1397 0.1397)
			(layers "F.Cu" "F.Mask" "F.Paste")
			(net "SELF_TRAY")
			(options
				(clearance outline)
				(anchor circle)
			)
			(primitives
				(gr_poly
					(pts
						(arc
							(start -0.1778 -0.2794)
							(mid -0.249642 -0.249642)
							(end -0.2794 -0.1778)
						)
						(arc
							(start -0.2794 0.1778)
							(mid -0.249642 0.249642)
							(end -0.1778 0.2794)
						)
						(arc
							(start 0.1778 0.2794)
							(mid 0.249642 0.249642)
							(end 0.2794 0.1778)
						)
						(arc
							(start 0.2794 -0.1778)
							(mid 0.249642 -0.249642)
							(end 0.1778 -0.2794)
						)
					)
					(width 0)
					(fill yes)
				)
			)
		)
	)
	(footprint ""
		(layer "F.Cu")
		(at 188.595 -15.24 -90)
		(property "Reference" "U15"
			(at 0 0 270)
			(layer "F.SilkS")
			(hide yes)
			(effects
				(font
					(size 1.27 1.27)
				)
			)
		)
		(property "Value" "TMP421AIDCNRG4-GP"
			(at -5.08 -8.5852 270)
			(unlocked yes)
			(layer "F.Fab")
			(hide yes)
			(effects
				(font
					(size 1.016 1.016)
					(thickness 0.1524)
				)
			)
		)
		(property "Device Type" "SOT23-8PH58"
			(at -5.08 -10.1092 270)
			(unlocked yes)
			(layer "F.Fab")
			(hide yes)
			(effects
				(font
					(size 1.016 1.016)
					(thickness 0.1524)
				)
			)
		)
		(duplicate_pad_numbers_are_jumpers no)
		(fp_line
			(start -1.8796 0.5588)
			(end -1.8796 -0.5588)
			(stroke
				(width 0.1524)
				(type default)
			)
			(layer "F.SilkS")
		)
		(fp_line
			(start -1.7018 0.5588)
			(end -1.7018 2.1082)
			(stroke
				(width 0.508)
				(type default)
			)
			(layer "F.SilkS")
		)
		(fp_line
			(start 1.8796 0.5588)
			(end -1.8796 0.5588)
			(stroke
				(width 0.1524)
				(type default)
			)
			(layer "F.SilkS")
		)
		(fp_line
			(start -1.6256 0)
			(end -1.8796 0.254)
			(stroke
				(width 0.1524)
				(type default)
			)
			(layer "F.SilkS")
		)
		(fp_line
			(start -1.8796 -0.254)
			(end -1.6256 0)
			(stroke
				(width 0.1524)
				(type default)
			)
			(layer "F.SilkS")
		)
		(fp_line
			(start -1.8796 -0.5588)
			(end 1.8796 -0.5588)
			(stroke
				(width 0.1524)
				(type default)
			)
			(layer "F.SilkS")
		)
		(fp_line
			(start 1.8796 -0.5588)
			(end 1.8796 0.5588)
			(stroke
				(width 0.1524)
				(type default)
			)
			(layer "F.SilkS")
		)
		(fp_poly
			(pts
				(xy -1.15316 0.5588) (xy 1.8796 0.5588) (xy 1.8796 -0.5588) (xy -1.15316 -0.5588)
			)
			(stroke
				(width 0)
				(type default)
			)
			(fill yes)
			(layer "F.SilkS")
		)
		(fp_rect
			(start -1.9558 2.3622)
			(end 1.9558 -2.3622)
			(stroke
				(width 0)
				(type default)
			)
			(fill no)
			(layer "F.CrtYd")
		)
		(fp_poly
			(pts
				(xy -1.9558 -2.3622) (xy 1.9558 -2.3622) (xy 1.9558 2.3622) (xy -1.9558 2.3622)
			)
			(stroke
				(width 0)
				(type default)
			)
			(fill no)
			(layer "F.Fab")
		)
		(pad "1" smd rect
			(at -0.97536 1.3462 270)
			(size 0.3556 1.016)
			(layers "F.Cu" "F.Mask" "F.Paste")
			(net "TEMP_SENSOR_DXP")
		)
		(pad "2" smd rect
			(at -0.32512 1.3462 270)
			(size 0.3556 1.016)
			(layers "F.Cu" "F.Mask" "F.Paste")
			(net "TEMP_SENSOR_DXN")
		)
		(pad "3" smd rect
			(at 0.32512 1.3462 270)
			(size 0.3556 1.016)
			(layers "F.Cu" "F.Mask" "F.Paste")
			(net "TEMP_1_A1")
		)
		(pad "4" smd rect
			(at 0.97409 1.3462 270)
			(size 0.3556 1.016)
			(layers "F.Cu" "F.Mask" "F.Paste")
			(net "TEMP_1_A0")
		)
		(pad "5" smd rect
			(at 0.97409 -1.3462 270)
			(size 0.3556 1.016)
			(layers "F.Cu" "F.Mask" "F.Paste")
			(net "GND")
		)
		(pad "6" smd rect
			(at 0.32512 -1.3462 270)
			(size 0.3556 1.016)
			(layers "F.Cu" "F.Mask" "F.Paste")
			(net "TEMP_1_SDA")
		)
		(pad "7" smd rect
			(at -0.32512 -1.3462 270)
			(size 0.3556 1.016)
			(layers "F.Cu" "F.Mask" "F.Paste")
			(net "TEMP_1_SCL")
		)
		(pad "8" smd rect
			(at -0.97536 -1.3462 270)
			(size 0.3556 1.016)
			(layers "F.Cu" "F.Mask" "F.Paste")
			(net "P3V3_STBY")
		)
	)
	(footprint ""
		(layer "F.Cu")
		(at 86.49716 -33.655 -90)
		(property "Reference" "SC878"
			(at 0 0 270)
			(layer "F.SilkS")
			(hide yes)
			(effects
				(font
					(size 1.27 1.27)
				)
			)
		)
		(property "Value" "SCD01U10V1KX-GP"
			(at -2.8321 -1.7399 270)
			(unlocked yes)
			(layer "F.Fab")
			(hide yes)
			(effects
				(font
					(size 1.016 1.016)
					(thickness 0.1524)
				)
			)
		)
		(property "Device Type" "C0201H13"
			(at -2.8321 -3.2639 270)
			(unlocked yes)
			(layer "F.Fab")
			(hide yes)
			(effects
				(font
					(size 1.016 1.016)
					(thickness 0.1524)
				)
			)
		)
		(duplicate_pad_numbers_are_jumpers no)
		(fp_rect
			(start -0.2794 0.6477)
			(end 0.2794 -0.6477)
			(stroke
				(width 0)
				(type default)
			)
			(fill no)
			(layer "F.CrtYd")
		)
		(fp_rect
			(start -0.2794 0.6477)
			(end 0.2794 -0.6477)
			(stroke
				(width 0)
				(type default)
			)
			(fill no)
			(layer "F.Fab")
		)
		(pad "1" smd custom
			(at 0 -0.2794 270)
			(size 0.0762 0.0762)
			(layers "F.Cu" "F.Mask" "F.Paste")
			(net "SAS3008_RAID_TX_C_P0")
			(options
				(clearance outline)
				(anchor circle)
			)
			(primitives
				(gr_poly
					(pts
						(arc
							(start 0.1524 -0.127)
							(mid 0.137521 -0.162921)
							(end 0.1016 -0.1778)
						)
						(arc
							(start -0.1016 -0.1778)
							(mid -0.137521 -0.162921)
							(end -0.1524 -0.127)
						)
						(arc
							(start -0.1524 0.127)
							(mid -0.137521 0.162921)
							(end -0.1016 0.1778)
						)
						(arc
							(start 0.1016 0.1778)
							(mid 0.137521 0.162921)
							(end 0.1524 0.127)
						)
					)
					(width 0)
					(fill yes)
				)
			)
		)
		(pad "2" smd custom
			(at 0 0.2794 270)
			(size 0.0762 0.0762)
			(layers "F.Cu" "F.Mask" "F.Paste")
			(net "SAS3008_RAID_TX_P0")
			(options
				(clearance outline)
				(anchor circle)
			)
			(primitives
				(gr_poly
					(pts
						(arc
							(start 0.1524 -0.127)
							(mid 0.137521 -0.162921)
							(end 0.1016 -0.1778)
						)
						(arc
							(start -0.1016 -0.1778)
							(mid -0.137521 -0.162921)
							(end -0.1524 -0.127)
						)
						(arc
							(start -0.1524 0.127)
							(mid -0.137521 0.162921)
							(end -0.1016 0.1778)
						)
						(arc
							(start 0.1016 0.1778)
							(mid 0.137521 0.162921)
							(end 0.1524 0.127)
						)
					)
					(width 0)
					(fill yes)
				)
			)
		)
	)
	(footprint ""
		(layer "F.Cu")
		(at 276.479 -192.405)
		(property "Reference" "L6"
			(at 0 0 0)
			(layer "F.SilkS")
			(hide yes)
			(effects
				(font
					(size 1.27 1.27)
				)
			)
		)
		(property "Value" "MMZ2012S601ATA1N-GP"
			(at 0 -4.2418 0)
			(unlocked yes)
			(layer "F.Fab")
			(hide yes)
			(effects
				(font
					(size 1.016 1.016)
					(thickness 0.1524)
				)
			)
		)
		(property "Device Type" "L805H42"
			(at 0 -5.7912 0)
			(unlocked yes)
			(layer "F.Fab")
			(hide yes)
			(effects
				(font
					(size 1.016 1.016)
					(thickness 0.1524)
				)
			)
		)
		(duplicate_pad_numbers_are_jumpers no)
		(fp_line
			(start -0.889 -1.7018)
			(end 0.889 -1.7018)
			(stroke
				(width 0.1524)
				(type default)
			)
			(layer "F.SilkS")
		)
		(fp_line
			(start -0.889 1.7018)
			(end -0.889 -1.7018)
			(stroke
				(width 0.1524)
				(type default)
			)
			(layer "F.SilkS")
		)
		(fp_line
			(start 0.889 -1.7018)
			(end 0.889 1.7018)
			(stroke
				(width 0.1524)
				(type default)
			)
			(layer "F.SilkS")
		)
		(fp_line
			(start 0.889 1.7018)
			(end -0.889 1.7018)
			(stroke
				(width 0.1524)
				(type default)
			)
			(layer "F.SilkS")
		)
		(fp_rect
			(start -0.9652 1.778)
			(end 0.9652 -1.778)
			(stroke
				(width 0)
				(type default)
			)
			(fill no)
			(layer "F.CrtYd")
		)
		(fp_rect
			(start -0.9652 1.778)
			(end 0.9652 -1.778)
			(stroke
				(width 0)
				(type default)
			)
			(fill no)
			(layer "F.Fab")
		)
		(pad "1" smd rect
			(at 0 -0.9652)
			(size 1.397 1.143)
			(layers "F.Cu" "F.Mask" "F.Paste")
			(net "P1V26_STBY")
		)
		(pad "2" smd rect
			(at 0 0.9652)
			(size 1.397 1.143)
			(layers "F.Cu" "F.Mask" "F.Paste")
			(net "V1PLLAV12")
		)
	)
	(footprint ""
		(layer "F.Cu")
		(at 268.478 -16.383 180)
		(property "Reference" "TC11"
			(at 0 0 180)
			(layer "F.SilkS")
			(hide yes)
			(effects
				(font
					(size 1.27 1.27)
				)
			)
		)
		(property "Value" "SC47U16V0MX-GP"
			(at -0.00254 -4.78536 180)
			(unlocked yes)
			(layer "F.Fab")
			(hide yes)
			(effects
				(font
					(size 1.016 1.016)
					(thickness 0.1524)
				)
			)
		)
		(property "Device Type" "C1210H107"
			(at -0.00254 -6.38048 180)
			(unlocked yes)
			(layer "F.Fab")
			(hide yes)
			(effects
				(font
					(size 1.016 1.016)
					(thickness 0.1524)
				)
			)
		)
		(duplicate_pad_numbers_are_jumpers no)
		(fp_line
			(start 1.5748 2.3368)
			(end 1.5748 0.762)
			(stroke
				(width 0.1524)
				(type default)
			)
			(layer "F.SilkS")
		)
		(fp_line
			(start 1.5748 -0.762)
			(end 1.5748 -2.3368)
			(stroke
				(width 0.1524)
				(type default)
			)
			(layer "F.SilkS")
		)
		(fp_line
			(start 1.5748 -2.3368)
			(end -1.5748 -2.3368)
			(stroke
				(width 0.1524)
				(type default)
			)
			(layer "F.SilkS")
		)
		(fp_line
			(start -1.5748 2.3368)
			(end 1.5748 2.3368)
			(stroke
				(width 0.1524)
				(type default)
			)
			(layer "F.SilkS")
		)
		(fp_line
			(start -1.5748 0.762)
			(end -1.5748 2.3368)
			(stroke
				(width 0.1524)
				(type default)
			)
			(layer "F.SilkS")
		)
		(fp_line
			(start -1.5748 -2.3368)
			(end -1.5748 -0.762)
			(stroke
				(width 0.1524)
				(type default)
			)
			(layer "F.SilkS")
		)
		(fp_rect
			(start -1.651 2.413)
			(end 1.651 -2.413)
			(stroke
				(width 0)
				(type default)
			)
			(fill no)
			(layer "F.CrtYd")
		)
		(fp_poly
			(pts
				(xy 1.651 2.413) (xy 1.651 -2.413) (xy -1.651 -2.413) (xy -1.651 2.413)
			)
			(stroke
				(width 0)
				(type default)
			)
			(fill no)
			(layer "F.Fab")
		)
		(pad "1" smd rect
			(at 0 -1.4732 180)
			(size 2.794 1.397)
			(layers "F.Cu" "F.Mask" "F.Paste")
			(net "P5V_USB")
		)
		(pad "2" smd rect
			(at 0 1.4732 180)
			(size 2.794 1.397)
			(layers "F.Cu" "F.Mask" "F.Paste")
			(net "GND")
		)
	)
	(footprint ""
		(layer "F.Cu")
		(at 194.563492 -180.226716)
		(property "Reference" "R483"
			(at 0 0 0)
			(layer "F.SilkS")
			(hide yes)
			(effects
				(font
					(size 1.27 1.27)
				)
			)
		)
		(property "Value" "0R2J-2-GP"
			(at 0.064008 -3.993896 0)
			(unlocked yes)
			(layer "F.Fab")
			(hide yes)
			(effects
				(font
					(size 1.016 1.016)
					(thickness 0.1524)
				)
			)
		)
		(property "Device Type" "R402H16"
			(at 0.064008 -5.517896 0)
			(unlocked yes)
			(layer "F.Fab")
			(hide yes)
			(effects
				(font
					(size 1.016 1.016)
					(thickness 0.1524)
				)
			)
		)
		(duplicate_pad_numbers_are_jumpers no)
		(fp_line
			(start -0.508 -0.9398)
			(end -0.508 0.9398)
			(stroke
				(width 0.1524)
				(type default)
			)
			(layer "F.SilkS")
		)
		(fp_line
			(start 0.508 -0.9398)
			(end -0.508 -0.9398)
			(stroke
				(width 0.1524)
				(type default)
			)
			(layer "F.SilkS")
		)
		(fp_rect
			(start -0.508 0.9398)
			(end 0.508 -0.9398)
			(stroke
				(width 0)
				(type default)
			)
			(fill no)
			(layer "F.CrtYd")
		)
		(fp_rect
			(start -0.508 0.9398)
			(end 0.508 -0.9398)
			(stroke
				(width 0)
				(type default)
			)
			(fill no)
			(layer "F.Fab")
		)
		(pad "1" smd custom
			(at 0 -0.4445)
			(size 0.1397 0.1397)
			(layers "F.Cu" "F.Mask" "F.Paste")
			(net "HB_A_OUT")
			(options
				(clearance outline)
				(anchor circle)
			)
			(primitives
				(gr_poly
					(pts
						(arc
							(start -0.1778 -0.2794)
							(mid -0.249642 -0.249642)
							(end -0.2794 -0.1778)
						)
						(arc
							(start -0.2794 0.1778)
							(mid -0.249642 0.249642)
							(end -0.1778 0.2794)
						)
						(arc
							(start 0.1778 0.2794)
							(mid 0.249642 0.249642)
							(end 0.2794 0.1778)
						)
						(arc
							(start 0.2794 -0.1778)
							(mid 0.249642 -0.249642)
							(end 0.1778 -0.2794)
						)
					)
					(width 0)
					(fill yes)
				)
			)
		)
		(pad "2" smd custom
			(at 0 0.4445)
			(size 0.1397 0.1397)
			(layers "F.Cu" "F.Mask" "F.Paste")
			(net "HB_OUT")
			(options
				(clearance outline)
				(anchor circle)
			)
			(primitives
				(gr_poly
					(pts
						(arc
							(start -0.1778 -0.2794)
							(mid -0.249642 -0.249642)
							(end -0.2794 -0.1778)
						)
						(arc
							(start -0.2794 0.1778)
							(mid -0.249642 0.249642)
							(end -0.1778 0.2794)
						)
						(arc
							(start 0.1778 0.2794)
							(mid 0.249642 0.249642)
							(end 0.2794 0.1778)
						)
						(arc
							(start 0.2794 -0.1778)
							(mid 0.249642 -0.249642)
							(end 0.1778 -0.2794)
						)
					)
					(width 0)
					(fill yes)
				)
			)
		)
	)
	(footprint ""
		(layer "F.Cu")
		(at 332.105 -94.234 90)
		(property "Reference" "PC37"
			(at 0 0 90)
			(layer "F.SilkS")
			(hide yes)
			(effects
				(font
					(size 1.27 1.27)
				)
			)
		)
		(property "Value" "SC100U6D3V6MX-GP"
			(at -0.0762 -5.1308 90)
			(unlocked yes)
			(layer "F.Fab")
			(hide yes)
			(effects
				(font
					(size 1.016 1.016)
					(thickness 0.1524)
				)
			)
		)
		(property "Device Type" "C1206H71"
			(at -0.127 -6.6548 90)
			(unlocked yes)
			(layer "F.Fab")
			(hide yes)
			(effects
				(font
					(size 1.016 1.016)
					(thickness 0.1524)
				)
			)
		)
		(duplicate_pad_numbers_are_jumpers no)
		(fp_line
			(start 1.016 -2.2352)
			(end 1.016 -0.8382)
			(stroke
				(width 0.1524)
				(type default)
			)
			(layer "F.SilkS")
		)
		(fp_line
			(start -1.016 -2.2352)
			(end 1.016 -2.2352)
			(stroke
				(width 0.1524)
				(type default)
			)
			(layer "F.SilkS")
		)
		(fp_line
			(start -1.016 -0.8382)
			(end -1.016 -2.2352)
			(stroke
				(width 0.1524)
				(type default)
			)
			(layer "F.SilkS")
		)
		(fp_line
			(start 1.016 0.8382)
			(end 1.016 2.2352)
			(stroke
				(width 0.1524)
				(type default)
			)
			(layer "F.SilkS")
		)
		(fp_line
			(start 1.016 2.2352)
			(end -1.016 2.2352)
			(stroke
				(width 0.1524)
				(type default)
			)
			(layer "F.SilkS")
		)
		(fp_line
			(start -1.016 2.2352)
			(end -1.016 0.8382)
			(stroke
				(width 0.1524)
				(type default)
			)
			(layer "F.SilkS")
		)
		(fp_rect
			(start -1.0922 2.3114)
			(end 1.0922 -2.3114)
			(stroke
				(width 0)
				(type default)
			)
			(fill no)
			(layer "F.CrtYd")
		)
		(fp_poly
			(pts
				(xy 1.0922 -2.3114) (xy 1.0922 2.3114) (xy -1.0922 2.3114) (xy -1.0922 -2.3114)
			)
			(stroke
				(width 0)
				(type default)
			)
			(fill no)
			(layer "F.Fab")
		)
		(pad "1" smd rect
			(at 0 -1.397 90)
			(size 1.651 1.27)
			(layers "F.Cu" "F.Mask" "F.Paste")
			(net "P3V3_STBY")
		)
		(pad "2" smd rect
			(at 0 1.397 90)
			(size 1.651 1.27)
			(layers "F.Cu" "F.Mask" "F.Paste")
			(net "GND")
		)
	)
	(footprint ""
		(layer "F.Cu")
		(at 35.56 -72.009 -90)
		(property "Reference" "R290"
			(at 0 0 270)
			(layer "F.SilkS")
			(hide yes)
			(effects
				(font
					(size 1.27 1.27)
				)
			)
		)
		(property "Value" "49D9R2F-GP"
			(at 0.064008 -3.993896 270)
			(unlocked yes)
			(layer "F.Fab")
			(hide yes)
			(effects
				(font
					(size 1.016 1.016)
					(thickness 0.1524)
				)
			)
		)
		(property "Device Type" "R402H16"
			(at 0.064008 -5.517896 270)
			(unlocked yes)
			(layer "F.Fab")
			(hide yes)
			(effects
				(font
					(size 1.016 1.016)
					(thickness 0.1524)
				)
			)
		)
		(duplicate_pad_numbers_are_jumpers no)
		(fp_line
			(start -0.508 -0.9398)
			(end -0.508 0.9398)
			(stroke
				(width 0.1524)
				(type default)
			)
			(layer "F.SilkS")
		)
		(fp_line
			(start 0.508 -0.9398)
			(end -0.508 -0.9398)
			(stroke
				(width 0.1524)
				(type default)
			)
			(layer "F.SilkS")
		)
		(fp_rect
			(start -0.508 0.9398)
			(end 0.508 -0.9398)
			(stroke
				(width 0)
				(type default)
			)
			(fill no)
			(layer "F.CrtYd")
		)
		(fp_rect
			(start -0.508 0.9398)
			(end 0.508 -0.9398)
			(stroke
				(width 0)
				(type default)
			)
			(fill no)
			(layer "F.Fab")
		)
		(pad "1" smd custom
			(at 0 -0.4445 270)
			(size 0.1397 0.1397)
			(layers "F.Cu" "F.Mask" "F.Paste")
			(net "P3V3")
			(options
				(clearance outline)
				(anchor circle)
			)
			(primitives
				(gr_poly
					(pts
						(arc
							(start -0.1778 -0.2794)
							(mid -0.249642 -0.249642)
							(end -0.2794 -0.1778)
						)
						(arc
							(start -0.2794 0.1778)
							(mid -0.249642 0.249642)
							(end -0.1778 0.2794)
						)
						(arc
							(start 0.1778 0.2794)
							(mid 0.249642 0.249642)
							(end 0.2794 0.1778)
						)
						(arc
							(start 0.2794 -0.1778)
							(mid 0.249642 -0.249642)
							(end 0.1778 -0.2794)
						)
					)
					(width 0)
					(fill yes)
				)
			)
		)
		(pad "2" smd custom
			(at 0 0.4445 270)
			(size 0.1397 0.1397)
			(layers "F.Cu" "F.Mask" "F.Paste")
			(net "INTA_LED_BLUE_C")
			(options
				(clearance outline)
				(anchor circle)
			)
			(primitives
				(gr_poly
					(pts
						(arc
							(start -0.1778 -0.2794)
							(mid -0.249642 -0.249642)
							(end -0.2794 -0.1778)
						)
						(arc
							(start -0.2794 0.1778)
							(mid -0.249642 0.249642)
							(end -0.1778 0.2794)
						)
						(arc
							(start 0.1778 0.2794)
							(mid 0.249642 0.249642)
							(end 0.2794 0.1778)
						)
						(arc
							(start 0.2794 -0.1778)
							(mid 0.249642 -0.249642)
							(end 0.1778 -0.2794)
						)
					)
					(width 0)
					(fill yes)
				)
			)
		)
	)
	(footprint ""
		(layer "F.Cu")
		(at 221.361 -104.013 90)
		(property "Reference" "PC148"
			(at 0 0 90)
			(layer "F.SilkS")
			(hide yes)
			(effects
				(font
					(size 1.27 1.27)
				)
			)
		)
		(property "Value" "SCD1U16V2KX-3GP"
			(at 1.1811 -2.7051 90)
			(unlocked yes)
			(layer "F.Fab")
			(hide yes)
			(effects
				(font
					(size 1.016 1.016)
					(thickness 0.1524)
				)
			)
		)
		(property "Device Type" "C402H22"
			(at 1.1811 -4.2291 90)
			(unlocked yes)
			(layer "F.Fab")
			(hide yes)
			(effects
				(font
					(size 1.016 1.016)
					(thickness 0.1524)
				)
			)
		)
		(duplicate_pad_numbers_are_jumpers no)
		(fp_rect
			(start -0.4318 0.9525)
			(end 0.4318 -0.9525)
			(stroke
				(width 0)
				(type default)
			)
			(fill no)
			(layer "F.CrtYd")
		)
		(fp_rect
			(start -0.4318 0.9525)
			(end 0.4318 -0.9525)
			(stroke
				(width 0)
				(type default)
			)
			(fill no)
			(layer "F.Fab")
		)
		(pad "1" smd custom
			(at 0 -0.4445 90)
			(size 0.1524 0.1524)
			(layers "F.Cu" "F.Mask" "F.Paste")
			(net "TPS74801_1V5_C_BIAS")
			(options
				(clearance outline)
				(anchor circle)
			)
			(primitives
				(gr_poly
					(pts
						(arc
							(start 0.3048 -0.2032)
							(mid 0.275042 -0.275042)
							(end 0.2032 -0.3048)
						)
						(arc
							(start -0.2032 -0.3048)
							(mid -0.275042 -0.275042)
							(end -0.3048 -0.2032)
						)
						(arc
							(start -0.3048 0.2032)
							(mid -0.275042 0.275042)
							(end -0.2032 0.3048)
						)
						(arc
							(start 0.2032 0.3048)
							(mid 0.275042 0.275042)
							(end 0.3048 0.2032)
						)
					)
					(width 0)
					(fill yes)
				)
			)
		)
		(pad "2" smd custom
			(at 0 0.4445 90)
			(size 0.1524 0.1524)
			(layers "F.Cu" "F.Mask" "F.Paste")
			(net "GND")
			(options
				(clearance outline)
				(anchor circle)
			)
			(primitives
				(gr_poly
					(pts
						(arc
							(start 0.3048 -0.2032)
							(mid 0.275042 -0.275042)
							(end 0.2032 -0.3048)
						)
						(arc
							(start -0.2032 -0.3048)
							(mid -0.275042 -0.275042)
							(end -0.3048 -0.2032)
						)
						(arc
							(start -0.3048 0.2032)
							(mid -0.275042 0.275042)
							(end -0.2032 0.3048)
						)
						(arc
							(start 0.2032 0.3048)
							(mid 0.275042 0.275042)
							(end 0.3048 0.2032)
						)
					)
					(width 0)
					(fill yes)
				)
			)
		)
	)
	(footprint ""
		(layer "F.Cu")
		(at 119.196612 -204.978)
		(property "Reference" "SR873"
			(at 0 0 0)
			(layer "F.SilkS")
			(hide yes)
			(effects
				(font
					(size 1.27 1.27)
				)
			)
		)
		(property "Value" "0R2J-2-GP"
			(at 0.064008 -3.993896 0)
			(unlocked yes)
			(layer "F.Fab")
			(hide yes)
			(effects
				(font
					(size 1.016 1.016)
					(thickness 0.1524)
				)
			)
		)
		(property "Device Type" "R402H16"
			(at 0.064008 -5.517896 0)
			(unlocked yes)
			(layer "F.Fab")
			(hide yes)
			(effects
				(font
					(size 1.016 1.016)
					(thickness 0.1524)
				)
			)
		)
		(duplicate_pad_numbers_are_jumpers no)
		(fp_line
			(start -0.508 -0.9398)
			(end -0.508 0.9398)
			(stroke
				(width 0.1524)
				(type default)
			)
			(layer "F.SilkS")
		)
		(fp_line
			(start 0.508 -0.9398)
			(end -0.508 -0.9398)
			(stroke
				(width 0.1524)
				(type default)
			)
			(layer "F.SilkS")
		)
		(fp_rect
			(start -0.508 0.9398)
			(end 0.508 -0.9398)
			(stroke
				(width 0)
				(type default)
			)
			(fill no)
			(layer "F.CrtYd")
		)
		(fp_rect
			(start -0.508 0.9398)
			(end 0.508 -0.9398)
			(stroke
				(width 0)
				(type default)
			)
			(fill no)
			(layer "F.Fab")
		)
		(pad "1" smd custom
			(at 0 -0.4445)
			(size 0.1397 0.1397)
			(layers "F.Cu" "F.Mask" "F.Paste")
			(net "SAS_HDD_REDV_TX7_N")
			(options
				(clearance outline)
				(anchor circle)
			)
			(primitives
				(gr_poly
					(pts
						(arc
							(start -0.1778 -0.2794)
							(mid -0.249642 -0.249642)
							(end -0.2794 -0.1778)
						)
						(arc
							(start -0.2794 0.1778)
							(mid -0.249642 0.249642)
							(end -0.1778 0.2794)
						)
						(arc
							(start 0.1778 0.2794)
							(mid 0.249642 0.249642)
							(end 0.2794 0.1778)
						)
						(arc
							(start 0.2794 -0.1778)
							(mid 0.249642 -0.249642)
							(end 0.1778 -0.2794)
						)
					)
					(width 0)
					(fill yes)
				)
			)
		)
		(pad "2" smd custom
			(at 0 0.4445)
			(size 0.1397 0.1397)
			(layers "F.Cu" "F.Mask" "F.Paste")
			(net "SAS_HDD_REDV_SER_TX7_N")
			(options
				(clearance outline)
				(anchor circle)
			)
			(primitives
				(gr_poly
					(pts
						(arc
							(start -0.1778 -0.2794)
							(mid -0.249642 -0.249642)
							(end -0.2794 -0.1778)
						)
						(arc
							(start -0.2794 0.1778)
							(mid -0.249642 0.249642)
							(end -0.1778 0.2794)
						)
						(arc
							(start 0.1778 0.2794)
							(mid 0.249642 0.249642)
							(end 0.2794 0.1778)
						)
						(arc
							(start 0.2794 -0.1778)
							(mid 0.249642 -0.249642)
							(end 0.1778 -0.2794)
						)
					)
					(width 0)
					(fill yes)
				)
			)
		)
	)
	(footprint ""
		(layer "F.Cu")
		(at 270.684752 -190.907416 180)
		(property "Reference" "R324"
			(at 0 0 180)
			(layer "F.SilkS")
			(hide yes)
			(effects
				(font
					(size 1.27 1.27)
				)
			)
		)
		(property "Value" "10KR2F-2-GP"
			(at 0.064008 -3.993896 180)
			(unlocked yes)
			(layer "F.Fab")
			(hide yes)
			(effects
				(font
					(size 1.016 1.016)
					(thickness 0.1524)
				)
			)
		)
		(property "Device Type" "R402H16"
			(at 0.064008 -5.517896 180)
			(unlocked yes)
			(layer "F.Fab")
			(hide yes)
			(effects
				(font
					(size 1.016 1.016)
					(thickness 0.1524)
				)
			)
		)
		(duplicate_pad_numbers_are_jumpers no)
		(fp_line
			(start 0.508 -0.9398)
			(end -0.508 -0.9398)
			(stroke
				(width 0.1524)
				(type default)
			)
			(layer "F.SilkS")
		)
		(fp_line
			(start -0.508 -0.9398)
			(end -0.508 0.9398)
			(stroke
				(width 0.1524)
				(type default)
			)
			(layer "F.SilkS")
		)
		(fp_rect
			(start -0.508 0.9398)
			(end 0.508 -0.9398)
			(stroke
				(width 0)
				(type default)
			)
			(fill no)
			(layer "F.CrtYd")
		)
		(fp_rect
			(start -0.508 0.9398)
			(end 0.508 -0.9398)
			(stroke
				(width 0)
				(type default)
			)
			(fill no)
			(layer "F.Fab")
		)
		(pad "1" smd custom
			(at 0 -0.4445 180)
			(size 0.1397 0.1397)
			(layers "F.Cu" "F.Mask" "F.Paste")
			(net "PECI0_R")
			(options
				(clearance outline)
				(anchor circle)
			)
			(primitives
				(gr_poly
					(pts
						(arc
							(start -0.1778 -0.2794)
							(mid -0.249642 -0.249642)
							(end -0.2794 -0.1778)
						)
						(arc
							(start -0.2794 0.1778)
							(mid -0.249642 0.249642)
							(end -0.1778 0.2794)
						)
						(arc
							(start 0.1778 0.2794)
							(mid 0.249642 0.249642)
							(end 0.2794 0.1778)
						)
						(arc
							(start 0.2794 -0.1778)
							(mid 0.249642 -0.249642)
							(end 0.1778 -0.2794)
						)
					)
					(width 0)
					(fill yes)
				)
			)
		)
		(pad "2" smd custom
			(at 0 0.4445 180)
			(size 0.1397 0.1397)
			(layers "F.Cu" "F.Mask" "F.Paste")
			(net "GND")
			(options
				(clearance outline)
				(anchor circle)
			)
			(primitives
				(gr_poly
					(pts
						(arc
							(start -0.1778 -0.2794)
							(mid -0.249642 -0.249642)
							(end -0.2794 -0.1778)
						)
						(arc
							(start -0.2794 0.1778)
							(mid -0.249642 0.249642)
							(end -0.1778 0.2794)
						)
						(arc
							(start 0.1778 0.2794)
							(mid 0.249642 0.249642)
							(end 0.2794 0.1778)
						)
						(arc
							(start 0.2794 -0.1778)
							(mid 0.249642 -0.249642)
							(end 0.1778 -0.2794)
						)
					)
					(width 0)
					(fill yes)
				)
			)
		)
	)
	(footprint ""
		(layer "F.Cu")
		(at 85.23097 -112.014 180)
		(property "Reference" "SC1229"
			(at 0 0 180)
			(layer "F.SilkS")
			(hide yes)
			(effects
				(font
					(size 1.27 1.27)
				)
			)
		)
		(property "Value" "SCD1U6D3V1KX-GP"
			(at -2.8321 -1.7399 180)
			(unlocked yes)
			(layer "F.Fab")
			(hide yes)
			(effects
				(font
					(size 1.016 1.016)
					(thickness 0.1524)
				)
			)
		)
		(property "Device Type" "C0201H13"
			(at -2.8321 -3.2639 180)
			(unlocked yes)
			(layer "F.Fab")
			(hide yes)
			(effects
				(font
					(size 1.016 1.016)
					(thickness 0.1524)
				)
			)
		)
		(duplicate_pad_numbers_are_jumpers no)
		(fp_rect
			(start -0.2794 0.6477)
			(end 0.2794 -0.6477)
			(stroke
				(width 0)
				(type default)
			)
			(fill no)
			(layer "F.CrtYd")
		)
		(fp_rect
			(start -0.2794 0.6477)
			(end 0.2794 -0.6477)
			(stroke
				(width 0)
				(type default)
			)
			(fill no)
			(layer "F.Fab")
		)
		(pad "1" smd custom
			(at 0 -0.2794 180)
			(size 0.0762 0.0762)
			(layers "F.Cu" "F.Mask" "F.Paste")
			(net "P1V8_E")
			(options
				(clearance outline)
				(anchor circle)
			)
			(primitives
				(gr_poly
					(pts
						(arc
							(start 0.1524 -0.127)
							(mid 0.137521 -0.162921)
							(end 0.1016 -0.1778)
						)
						(arc
							(start -0.1016 -0.1778)
							(mid -0.137521 -0.162921)
							(end -0.1524 -0.127)
						)
						(arc
							(start -0.1524 0.127)
							(mid -0.137521 0.162921)
							(end -0.1016 0.1778)
						)
						(arc
							(start 0.1016 0.1778)
							(mid 0.137521 0.162921)
							(end 0.1524 0.127)
						)
					)
					(width 0)
					(fill yes)
				)
			)
		)
		(pad "2" smd custom
			(at 0 0.2794 180)
			(size 0.0762 0.0762)
			(layers "F.Cu" "F.Mask" "F.Paste")
			(net "GND")
			(options
				(clearance outline)
				(anchor circle)
			)
			(primitives
				(gr_poly
					(pts
						(arc
							(start 0.1524 -0.127)
							(mid 0.137521 -0.162921)
							(end 0.1016 -0.1778)
						)
						(arc
							(start -0.1016 -0.1778)
							(mid -0.137521 -0.162921)
							(end -0.1524 -0.127)
						)
						(arc
							(start -0.1524 0.127)
							(mid -0.137521 0.162921)
							(end -0.1016 0.1778)
						)
						(arc
							(start 0.1016 0.1778)
							(mid 0.137521 0.162921)
							(end 0.1524 0.127)
						)
					)
					(width 0)
					(fill yes)
				)
			)
		)
	)
	(footprint ""
		(layer "F.Cu")
		(at 300.228 -163.322)
		(property "Reference" "TP94"
			(at 0 0 0)
			(layer "F.SilkS")
			(hide yes)
			(effects
				(font
					(size 1.27 1.27)
				)
			)
		)
		(property "Value" "TPAD28"
			(at 0.0127 -1.8034 0)
			(unlocked yes)
			(layer "F.Fab")
			(hide yes)
			(effects
				(font
					(size 1.016 1.016)
					(thickness 0.1524)
				)
			)
		)
		(property "Device Type" "TPAD28"
			(at 0.0127 -3.3274 0)
			(unlocked yes)
			(layer "F.Fab")
			(hide yes)
			(effects
				(font
					(size 1.016 1.016)
					(thickness 0.1524)
				)
			)
		)
		(duplicate_pad_numbers_are_jumpers no)
		(fp_poly
			(pts
				(arc
					(start 0.3556 0)
					(mid -0.3556 0)
					(end 0.3556 0)
				)
			)
			(stroke
				(width 0)
				(type default)
			)
			(fill no)
			(layer "F.CrtYd")
		)
		(fp_poly
			(pts
				(arc
					(start 0.6096 0)
					(mid -0.6096 0)
					(end 0.6096 0)
				)
			)
			(stroke
				(width 0)
				(type default)
			)
			(fill no)
			(layer "F.Fab")
		)
		(pad "1" smd circle
			(at 0 0)
			(size 0.7112 0.7112)
			(layers "F.Cu" "F.Mask" "F.Paste")
			(net "TP_GPIOH5")
		)
	)
	(footprint ""
		(layer "F.Cu")
		(at 67.437 -228.473 180)
		(property "Reference" "R2111"
			(at 0 0 180)
			(layer "F.SilkS")
			(hide yes)
			(effects
				(font
					(size 1.27 1.27)
				)
			)
		)
		(property "Value" "10R2J-2-GP"
			(at 0.064008 -3.993896 180)
			(unlocked yes)
			(layer "F.Fab")
			(hide yes)
			(effects
				(font
					(size 1.016 1.016)
					(thickness 0.1524)
				)
			)
		)
		(property "Device Type" "R402H14"
			(at 0.064008 -5.517896 180)
			(unlocked yes)
			(layer "F.Fab")
			(hide yes)
			(effects
				(font
					(size 1.016 1.016)
					(thickness 0.1524)
				)
			)
		)
		(duplicate_pad_numbers_are_jumpers no)
		(fp_line
			(start 0.508 -0.9398)
			(end -0.508 -0.9398)
			(stroke
				(width 0.1524)
				(type default)
			)
			(layer "F.SilkS")
		)
		(fp_line
			(start -0.508 -0.9398)
			(end -0.508 0.9398)
			(stroke
				(width 0.1524)
				(type default)
			)
			(layer "F.SilkS")
		)
		(fp_rect
			(start -0.508 0.9398)
			(end 0.508 -0.9398)
			(stroke
				(width 0)
				(type default)
			)
			(fill no)
			(layer "F.CrtYd")
		)
		(fp_rect
			(start -0.508 0.9398)
			(end 0.508 -0.9398)
			(stroke
				(width 0)
				(type default)
			)
			(fill no)
			(layer "F.Fab")
		)
		(pad "1" smd custom
			(at 0 -0.4445 180)
			(size 0.1397 0.1397)
			(layers "F.Cu" "F.Mask" "F.Paste")
			(net "MB0_12V_CTRL_GATE1")
			(options
				(clearance outline)
				(anchor circle)
			)
			(primitives
				(gr_poly
					(pts
						(arc
							(start -0.1778 -0.2794)
							(mid -0.249642 -0.249642)
							(end -0.2794 -0.1778)
						)
						(arc
							(start -0.2794 0.1778)
							(mid -0.249642 0.249642)
							(end -0.1778 0.2794)
						)
						(arc
							(start 0.1778 0.2794)
							(mid 0.249642 0.249642)
							(end 0.2794 0.1778)
						)
						(arc
							(start 0.2794 -0.1778)
							(mid 0.249642 -0.249642)
							(end 0.1778 -0.2794)
						)
					)
					(width 0)
					(fill yes)
				)
			)
		)
		(pad "2" smd custom
			(at 0 0.4445 180)
			(size 0.1397 0.1397)
			(layers "F.Cu" "F.Mask" "F.Paste")
			(net "MB0_CM_GATE_R")
			(options
				(clearance outline)
				(anchor circle)
			)
			(primitives
				(gr_poly
					(pts
						(arc
							(start -0.1778 -0.2794)
							(mid -0.249642 -0.249642)
							(end -0.2794 -0.1778)
						)
						(arc
							(start -0.2794 0.1778)
							(mid -0.249642 0.249642)
							(end -0.1778 0.2794)
						)
						(arc
							(start 0.1778 0.2794)
							(mid 0.249642 0.249642)
							(end 0.2794 0.1778)
						)
						(arc
							(start 0.2794 -0.1778)
							(mid 0.249642 -0.249642)
							(end 0.1778 -0.2794)
						)
					)
					(width 0)
					(fill yes)
				)
			)
		)
	)
	(footprint ""
		(layer "F.Cu")
		(at 278.003 -15.494 90)
		(property "Reference" "R545"
			(at 0 0 90)
			(layer "F.SilkS")
			(hide yes)
			(effects
				(font
					(size 1.27 1.27)
				)
			)
		)
		(property "Value" "0R3J-0-U-GP"
			(at -0.0254 -2.5146 90)
			(unlocked yes)
			(layer "F.Fab")
			(hide yes)
			(effects
				(font
					(size 1.016 1.016)
					(thickness 0.1524)
				)
			)
		)
		(property "Device Type" "R603H22"
			(at -0.0254 -4.0386 90)
			(unlocked yes)
			(layer "F.Fab")
			(hide yes)
			(effects
				(font
					(size 1.016 1.016)
					(thickness 0.1524)
				)
			)
		)
		(duplicate_pad_numbers_are_jumpers no)
		(fp_line
			(start 0.2032 0)
			(end 0.4826 0)
			(stroke
				(width 0.2032)
				(type default)
			)
			(layer "F.SilkS")
		)
		(fp_line
			(start -0.4826 0)
			(end -0.2032 0)
			(stroke
				(width 0.2032)
				(type default)
			)
			(layer "F.SilkS")
		)
		(fp_rect
			(start -0.5842 1.3335)
			(end 0.5842 -1.3335)
			(stroke
				(width 0)
				(type default)
			)
			(fill no)
			(layer "F.CrtYd")
		)
		(fp_rect
			(start -0.5842 1.3335)
			(end 0.5842 -1.3335)
			(stroke
				(width 0)
				(type default)
			)
			(fill no)
			(layer "F.Fab")
		)
		(pad "1" smd custom
			(at 0 -0.762 90)
			(size 0.2159 0.2159)
			(layers "F.Cu" "F.Mask" "F.Paste")
			(net "AGND_USB")
			(options
				(clearance outline)
				(anchor circle)
			)
			(primitives
				(gr_poly
					(pts
						(arc
							(start -0.3302 -0.4318)
							(mid -0.402042 -0.402042)
							(end -0.4318 -0.3302)
						)
						(arc
							(start -0.4318 0.3302)
							(mid -0.402042 0.402042)
							(end -0.3302 0.4318)
						)
						(arc
							(start 0.3302 0.4318)
							(mid 0.402042 0.402042)
							(end 0.4318 0.3302)
						)
						(arc
							(start 0.4318 -0.3302)
							(mid 0.402042 -0.402042)
							(end 0.3302 -0.4318)
						)
					)
					(width 0)
					(fill yes)
				)
			)
		)
		(pad "2" smd custom
			(at 0 0.762 90)
			(size 0.2159 0.2159)
			(layers "F.Cu" "F.Mask" "F.Paste")
			(net "GND")
			(options
				(clearance outline)
				(anchor circle)
			)
			(primitives
				(gr_poly
					(pts
						(arc
							(start -0.3302 -0.4318)
							(mid -0.402042 -0.402042)
							(end -0.4318 -0.3302)
						)
						(arc
							(start -0.4318 0.3302)
							(mid -0.402042 0.402042)
							(end -0.3302 0.4318)
						)
						(arc
							(start 0.3302 0.4318)
							(mid 0.402042 0.402042)
							(end 0.4318 0.3302)
						)
						(arc
							(start 0.4318 -0.3302)
							(mid 0.402042 -0.402042)
							(end 0.3302 -0.4318)
						)
					)
					(width 0)
					(fill yes)
				)
			)
		)
	)
	(footprint ""
		(layer "F.Cu")
		(at 94.215966 -63.119)
		(property "Reference" "SR677"
			(at 0 0 0)
			(layer "F.SilkS")
			(hide yes)
			(effects
				(font
					(size 1.27 1.27)
				)
			)
		)
		(property "Value" "4K7R2F-GP"
			(at 0.064008 -3.993896 0)
			(unlocked yes)
			(layer "F.Fab")
			(hide yes)
			(effects
				(font
					(size 1.016 1.016)
					(thickness 0.1524)
				)
			)
		)
		(property "Device Type" "R402H16"
			(at 0.064008 -5.517896 0)
			(unlocked yes)
			(layer "F.Fab")
			(hide yes)
			(effects
				(font
					(size 1.016 1.016)
					(thickness 0.1524)
				)
			)
		)
		(duplicate_pad_numbers_are_jumpers no)
		(fp_line
			(start -0.508 -0.9398)
			(end -0.508 0.9398)
			(stroke
				(width 0.1524)
				(type default)
			)
			(layer "F.SilkS")
		)
		(fp_line
			(start 0.508 -0.9398)
			(end -0.508 -0.9398)
			(stroke
				(width 0.1524)
				(type default)
			)
			(layer "F.SilkS")
		)
		(fp_rect
			(start -0.508 0.9398)
			(end 0.508 -0.9398)
			(stroke
				(width 0)
				(type default)
			)
			(fill no)
			(layer "F.CrtYd")
		)
		(fp_rect
			(start -0.508 0.9398)
			(end 0.508 -0.9398)
			(stroke
				(width 0)
				(type default)
			)
			(fill no)
			(layer "F.Fab")
		)
		(pad "1" smd custom
			(at 0 -0.4445)
			(size 0.1397 0.1397)
			(layers "F.Cu" "F.Mask" "F.Paste")
			(net "P1V8_C")
			(options
				(clearance outline)
				(anchor circle)
			)
			(primitives
				(gr_poly
					(pts
						(arc
							(start -0.1778 -0.2794)
							(mid -0.249642 -0.249642)
							(end -0.2794 -0.1778)
						)
						(arc
							(start -0.2794 0.1778)
							(mid -0.249642 0.249642)
							(end -0.1778 0.2794)
						)
						(arc
							(start 0.1778 0.2794)
							(mid 0.249642 0.249642)
							(end 0.2794 0.1778)
						)
						(arc
							(start 0.2794 -0.1778)
							(mid 0.249642 -0.249642)
							(end 0.1778 -0.2794)
						)
					)
					(width 0)
					(fill yes)
				)
			)
		)
		(pad "2" smd custom
			(at 0 0.4445)
			(size 0.1397 0.1397)
			(layers "F.Cu" "F.Mask" "F.Paste")
			(net "ICE0_TDI")
			(options
				(clearance outline)
				(anchor circle)
			)
			(primitives
				(gr_poly
					(pts
						(arc
							(start -0.1778 -0.2794)
							(mid -0.249642 -0.249642)
							(end -0.2794 -0.1778)
						)
						(arc
							(start -0.2794 0.1778)
							(mid -0.249642 0.249642)
							(end -0.1778 0.2794)
						)
						(arc
							(start 0.1778 0.2794)
							(mid 0.249642 0.249642)
							(end 0.2794 0.1778)
						)
						(arc
							(start 0.2794 -0.1778)
							(mid 0.249642 -0.249642)
							(end 0.1778 -0.2794)
						)
					)
					(width 0)
					(fill yes)
				)
			)
		)
	)
	(footprint ""
		(layer "F.Cu")
		(at 141.49197 -83.566 180)
		(property "Reference" "R611"
			(at 0 0 180)
			(layer "F.SilkS")
			(hide yes)
			(effects
				(font
					(size 1.27 1.27)
				)
			)
		)
		(property "Value" "4K7R2F-GP"
			(at 0.064008 -3.993896 180)
			(unlocked yes)
			(layer "F.Fab")
			(hide yes)
			(effects
				(font
					(size 1.016 1.016)
					(thickness 0.1524)
				)
			)
		)
		(property "Device Type" "R402H16"
			(at 0.064008 -5.517896 180)
			(unlocked yes)
			(layer "F.Fab")
			(hide yes)
			(effects
				(font
					(size 1.016 1.016)
					(thickness 0.1524)
				)
			)
		)
		(duplicate_pad_numbers_are_jumpers no)
		(fp_line
			(start 0.508 -0.9398)
			(end -0.508 -0.9398)
			(stroke
				(width 0.1524)
				(type default)
			)
			(layer "F.SilkS")
		)
		(fp_line
			(start -0.508 -0.9398)
			(end -0.508 0.9398)
			(stroke
				(width 0.1524)
				(type default)
			)
			(layer "F.SilkS")
		)
		(fp_rect
			(start -0.508 0.9398)
			(end 0.508 -0.9398)
			(stroke
				(width 0)
				(type default)
			)
			(fill no)
			(layer "F.CrtYd")
		)
		(fp_rect
			(start -0.508 0.9398)
			(end 0.508 -0.9398)
			(stroke
				(width 0)
				(type default)
			)
			(fill no)
			(layer "F.Fab")
		)
		(pad "1" smd custom
			(at 0 -0.4445 180)
			(size 0.1397 0.1397)
			(layers "F.Cu" "F.Mask" "F.Paste")
			(net "P3V3_STBY")
			(options
				(clearance outline)
				(anchor circle)
			)
			(primitives
				(gr_poly
					(pts
						(arc
							(start -0.1778 -0.2794)
							(mid -0.249642 -0.249642)
							(end -0.2794 -0.1778)
						)
						(arc
							(start -0.2794 0.1778)
							(mid -0.249642 0.249642)
							(end -0.1778 0.2794)
						)
						(arc
							(start 0.1778 0.2794)
							(mid 0.249642 0.249642)
							(end 0.2794 0.1778)
						)
						(arc
							(start 0.2794 -0.1778)
							(mid 0.249642 -0.249642)
							(end 0.1778 -0.2794)
						)
					)
					(width 0)
					(fill yes)
				)
			)
		)
		(pad "2" smd custom
			(at 0 0.4445 180)
			(size 0.1397 0.1397)
			(layers "F.Cu" "F.Mask" "F.Paste")
			(net "TEMP_3_A0")
			(options
				(clearance outline)
				(anchor circle)
			)
			(primitives
				(gr_poly
					(pts
						(arc
							(start -0.1778 -0.2794)
							(mid -0.249642 -0.249642)
							(end -0.2794 -0.1778)
						)
						(arc
							(start -0.2794 0.1778)
							(mid -0.249642 0.249642)
							(end -0.1778 0.2794)
						)
						(arc
							(start 0.1778 0.2794)
							(mid 0.249642 0.249642)
							(end 0.2794 0.1778)
						)
						(arc
							(start 0.2794 -0.1778)
							(mid 0.249642 -0.249642)
							(end 0.1778 -0.2794)
						)
					)
					(width 0)
					(fill yes)
				)
			)
		)
	)
	(footprint ""
		(layer "F.Cu")
		(at 77.8256 -18.3896 180)
		(property "Reference" "PC207"
			(at 0 0 180)
			(layer "F.SilkS")
			(hide yes)
			(effects
				(font
					(size 1.27 1.27)
				)
			)
		)
		(property "Value" "SC1U25V3KX-GP"
			(at 0 -2.8194 180)
			(unlocked yes)
			(layer "F.Fab")
			(hide yes)
			(effects
				(font
					(size 1.016 1.016)
					(thickness 0.1524)
				)
			)
		)
		(property "Device Type" "C603H36"
			(at 0 -4.3434 180)
			(unlocked yes)
			(layer "F.Fab")
			(hide yes)
			(effects
				(font
					(size 1.016 1.016)
					(thickness 0.1524)
				)
			)
		)
		(duplicate_pad_numbers_are_jumpers no)
		(fp_line
			(start 0.508 0)
			(end -0.508 0)
			(stroke
				(width 0.2032)
				(type default)
			)
			(layer "F.SilkS")
		)
		(fp_rect
			(start -0.5842 1.3335)
			(end 0.5842 -1.3335)
			(stroke
				(width 0)
				(type default)
			)
			(fill no)
			(layer "F.CrtYd")
		)
		(fp_rect
			(start -0.5842 1.3335)
			(end 0.5842 -1.3335)
			(stroke
				(width 0)
				(type default)
			)
			(fill no)
			(layer "F.Fab")
		)
		(pad "1" smd custom
			(at 0 -0.762 180)
			(size 0.2159 0.2159)
			(layers "F.Cu" "F.Mask" "F.Paste")
			(net "VT235_VDDH")
			(options
				(clearance outline)
				(anchor circle)
			)
			(primitives
				(gr_poly
					(pts
						(arc
							(start -0.3302 -0.4318)
							(mid -0.402042 -0.402042)
							(end -0.4318 -0.3302)
						)
						(arc
							(start -0.4318 0.3302)
							(mid -0.402042 0.402042)
							(end -0.3302 0.4318)
						)
						(arc
							(start 0.3302 0.4318)
							(mid 0.402042 0.402042)
							(end 0.4318 0.3302)
						)
						(arc
							(start 0.4318 -0.3302)
							(mid 0.402042 -0.402042)
							(end 0.3302 -0.4318)
						)
					)
					(width 0)
					(fill yes)
				)
			)
		)
		(pad "2" smd custom
			(at 0 0.762 180)
			(size 0.2159 0.2159)
			(layers "F.Cu" "F.Mask" "F.Paste")
			(net "GND")
			(options
				(clearance outline)
				(anchor circle)
			)
			(primitives
				(gr_poly
					(pts
						(arc
							(start -0.3302 -0.4318)
							(mid -0.402042 -0.402042)
							(end -0.4318 -0.3302)
						)
						(arc
							(start -0.4318 0.3302)
							(mid -0.402042 0.402042)
							(end -0.3302 0.4318)
						)
						(arc
							(start 0.3302 0.4318)
							(mid 0.402042 0.402042)
							(end 0.4318 0.3302)
						)
						(arc
							(start 0.4318 -0.3302)
							(mid 0.402042 -0.402042)
							(end 0.3302 -0.4318)
						)
					)
					(width 0)
					(fill yes)
				)
			)
		)
	)
	(footprint ""
		(layer "F.Cu")
		(at 152.247092 -109.503464 -90)
		(property "Reference" "SR833"
			(at 0 0 270)
			(layer "F.SilkS")
			(hide yes)
			(effects
				(font
					(size 1.27 1.27)
				)
			)
		)
		(property "Value" "D51R3F-2-GP"
			(at -0.0254 -2.5146 270)
			(unlocked yes)
			(layer "F.Fab")
			(hide yes)
			(effects
				(font
					(size 1.016 1.016)
					(thickness 0.1524)
				)
			)
		)
		(property "Device Type" "R603H22"
			(at -0.0254 -4.0386 270)
			(unlocked yes)
			(layer "F.Fab")
			(hide yes)
			(effects
				(font
					(size 1.016 1.016)
					(thickness 0.1524)
				)
			)
		)
		(duplicate_pad_numbers_are_jumpers no)
		(fp_line
			(start -0.4826 0)
			(end -0.2032 0)
			(stroke
				(width 0.2032)
				(type default)
			)
			(layer "F.SilkS")
		)
		(fp_line
			(start 0.2032 0)
			(end 0.4826 0)
			(stroke
				(width 0.2032)
				(type default)
			)
			(layer "F.SilkS")
		)
		(fp_rect
			(start -0.5842 1.3335)
			(end 0.5842 -1.3335)
			(stroke
				(width 0)
				(type default)
			)
			(fill no)
			(layer "F.CrtYd")
		)
		(fp_rect
			(start -0.5842 1.3335)
			(end 0.5842 -1.3335)
			(stroke
				(width 0)
				(type default)
			)
			(fill no)
			(layer "F.Fab")
		)
		(pad "1" smd custom
			(at 0 -0.762 270)
			(size 0.2159 0.2159)
			(layers "F.Cu" "F.Mask" "F.Paste")
			(net "P0V9_E")
			(options
				(clearance outline)
				(anchor circle)
			)
			(primitives
				(gr_poly
					(pts
						(arc
							(start -0.3302 -0.4318)
							(mid -0.402042 -0.402042)
							(end -0.4318 -0.3302)
						)
						(arc
							(start -0.4318 0.3302)
							(mid -0.402042 0.402042)
							(end -0.3302 0.4318)
						)
						(arc
							(start 0.3302 0.4318)
							(mid 0.402042 0.402042)
							(end 0.4318 0.3302)
						)
						(arc
							(start 0.4318 -0.3302)
							(mid 0.402042 -0.402042)
							(end 0.3302 -0.4318)
						)
					)
					(width 0)
					(fill yes)
				)
			)
		)
		(pad "2" smd custom
			(at 0 0.762 270)
			(size 0.2159 0.2159)
			(layers "F.Cu" "F.Mask" "F.Paste")
			(net "GB_VDDA")
			(options
				(clearance outline)
				(anchor circle)
			)
			(primitives
				(gr_poly
					(pts
						(arc
							(start -0.3302 -0.4318)
							(mid -0.402042 -0.402042)
							(end -0.4318 -0.3302)
						)
						(arc
							(start -0.4318 0.3302)
							(mid -0.402042 0.402042)
							(end -0.3302 0.4318)
						)
						(arc
							(start 0.3302 0.4318)
							(mid 0.402042 0.402042)
							(end 0.4318 0.3302)
						)
						(arc
							(start 0.4318 -0.3302)
							(mid 0.402042 -0.402042)
							(end 0.3302 -0.4318)
						)
					)
					(width 0)
					(fill yes)
				)
			)
		)
	)
	(footprint ""
		(layer "F.Cu")
		(at 118.364 -33.02)
		(property "Reference" "STP45"
			(at 0 0 0)
			(layer "F.SilkS")
			(hide yes)
			(effects
				(font
					(size 1.27 1.27)
				)
			)
		)
		(property "Value" "TPAD28"
			(at 0.0127 -1.8034 0)
			(unlocked yes)
			(layer "F.Fab")
			(hide yes)
			(effects
				(font
					(size 1.016 1.016)
					(thickness 0.1524)
				)
			)
		)
		(property "Device Type" "TPAD28"
			(at 0.0127 -3.3274 0)
			(unlocked yes)
			(layer "F.Fab")
			(hide yes)
			(effects
				(font
					(size 1.016 1.016)
					(thickness 0.1524)
				)
			)
		)
		(duplicate_pad_numbers_are_jumpers no)
		(fp_poly
			(pts
				(arc
					(start 0.3556 0)
					(mid -0.3556 0)
					(end 0.3556 0)
				)
			)
			(stroke
				(width 0)
				(type default)
			)
			(fill no)
			(layer "F.CrtYd")
		)
		(fp_poly
			(pts
				(arc
					(start 0.6096 0)
					(mid -0.6096 0)
					(end 0.6096 0)
				)
			)
			(stroke
				(width 0)
				(type default)
			)
			(fill no)
			(layer "F.Fab")
		)
		(pad "1" smd circle
			(at 0 0)
			(size 0.7112 0.7112)
			(layers "F.Cu" "F.Mask" "F.Paste")
			(net "IOC_GPIO_11")
		)
	)
	(footprint ""
		(layer "F.Cu")
		(at 278.765 -200.914)
		(property "Reference" "C187"
			(at 0 0 0)
			(layer "F.SilkS")
			(hide yes)
			(effects
				(font
					(size 1.27 1.27)
				)
			)
		)
		(property "Value" "SCD1U16V2KX-3GP"
			(at 1.1811 -2.7051 0)
			(unlocked yes)
			(layer "F.Fab")
			(hide yes)
			(effects
				(font
					(size 1.016 1.016)
					(thickness 0.1524)
				)
			)
		)
		(property "Device Type" "C402H22"
			(at 1.1811 -4.2291 0)
			(unlocked yes)
			(layer "F.Fab")
			(hide yes)
			(effects
				(font
					(size 1.016 1.016)
					(thickness 0.1524)
				)
			)
		)
		(duplicate_pad_numbers_are_jumpers no)
		(fp_rect
			(start -0.4318 0.9525)
			(end 0.4318 -0.9525)
			(stroke
				(width 0)
				(type default)
			)
			(fill no)
			(layer "F.CrtYd")
		)
		(fp_rect
			(start -0.4318 0.9525)
			(end 0.4318 -0.9525)
			(stroke
				(width 0)
				(type default)
			)
			(fill no)
			(layer "F.Fab")
		)
		(pad "1" smd custom
			(at 0 -0.4445)
			(size 0.1524 0.1524)
			(layers "F.Cu" "F.Mask" "F.Paste")
			(net "P3V3_STBY")
			(options
				(clearance outline)
				(anchor circle)
			)
			(primitives
				(gr_poly
					(pts
						(arc
							(start 0.3048 -0.2032)
							(mid 0.275042 -0.275042)
							(end 0.2032 -0.3048)
						)
						(arc
							(start -0.2032 -0.3048)
							(mid -0.275042 -0.275042)
							(end -0.3048 -0.2032)
						)
						(arc
							(start -0.3048 0.2032)
							(mid -0.275042 0.275042)
							(end -0.2032 0.3048)
						)
						(arc
							(start 0.2032 0.3048)
							(mid 0.275042 0.275042)
							(end 0.3048 0.2032)
						)
					)
					(width 0)
					(fill yes)
				)
			)
		)
		(pad "2" smd custom
			(at 0 0.4445)
			(size 0.1524 0.1524)
			(layers "F.Cu" "F.Mask" "F.Paste")
			(net "GND")
			(options
				(clearance outline)
				(anchor circle)
			)
			(primitives
				(gr_poly
					(pts
						(arc
							(start 0.3048 -0.2032)
							(mid 0.275042 -0.275042)
							(end 0.2032 -0.3048)
						)
						(arc
							(start -0.2032 -0.3048)
							(mid -0.275042 -0.275042)
							(end -0.3048 -0.2032)
						)
						(arc
							(start -0.3048 0.2032)
							(mid -0.275042 0.275042)
							(end -0.2032 0.3048)
						)
						(arc
							(start 0.2032 0.3048)
							(mid 0.275042 0.275042)
							(end 0.3048 0.2032)
						)
					)
					(width 0)
					(fill yes)
				)
			)
		)
	)
	(footprint ""
		(layer "F.Cu")
		(at 310.515 -110.236 180)
		(property "Reference" "PR36"
			(at 0 0 180)
			(layer "F.SilkS")
			(hide yes)
			(effects
				(font
					(size 1.27 1.27)
				)
			)
		)
		(property "Value" "0R2J-2-GP"
			(at 0.064008 -3.993896 180)
			(unlocked yes)
			(layer "F.Fab")
			(hide yes)
			(effects
				(font
					(size 1.016 1.016)
					(thickness 0.1524)
				)
			)
		)
		(property "Device Type" "R402H16"
			(at 0.064008 -5.517896 180)
			(unlocked yes)
			(layer "F.Fab")
			(hide yes)
			(effects
				(font
					(size 1.016 1.016)
					(thickness 0.1524)
				)
			)
		)
		(duplicate_pad_numbers_are_jumpers no)
		(fp_line
			(start 0.508 -0.9398)
			(end -0.508 -0.9398)
			(stroke
				(width 0.1524)
				(type default)
			)
			(layer "F.SilkS")
		)
		(fp_line
			(start -0.508 -0.9398)
			(end -0.508 0.9398)
			(stroke
				(width 0.1524)
				(type default)
			)
			(layer "F.SilkS")
		)
		(fp_rect
			(start -0.508 0.9398)
			(end 0.508 -0.9398)
			(stroke
				(width 0)
				(type default)
			)
			(fill no)
			(layer "F.CrtYd")
		)
		(fp_rect
			(start -0.508 0.9398)
			(end 0.508 -0.9398)
			(stroke
				(width 0)
				(type default)
			)
			(fill no)
			(layer "F.Fab")
		)
		(pad "1" smd custom
			(at 0 -0.4445 180)
			(size 0.1397 0.1397)
			(layers "F.Cu" "F.Mask" "F.Paste")
			(net "P3V3_STBY_ROVP")
			(options
				(clearance outline)
				(anchor circle)
			)
			(primitives
				(gr_poly
					(pts
						(arc
							(start -0.1778 -0.2794)
							(mid -0.249642 -0.249642)
							(end -0.2794 -0.1778)
						)
						(arc
							(start -0.2794 0.1778)
							(mid -0.249642 0.249642)
							(end -0.1778 0.2794)
						)
						(arc
							(start 0.1778 0.2794)
							(mid 0.249642 0.249642)
							(end 0.2794 0.1778)
						)
						(arc
							(start 0.2794 -0.1778)
							(mid 0.249642 -0.249642)
							(end 0.1778 -0.2794)
						)
					)
					(width 0)
					(fill yes)
				)
			)
		)
		(pad "2" smd custom
			(at 0 0.4445 180)
			(size 0.1397 0.1397)
			(layers "F.Cu" "F.Mask" "F.Paste")
			(net "AGND_P3V3_STBY")
			(options
				(clearance outline)
				(anchor circle)
			)
			(primitives
				(gr_poly
					(pts
						(arc
							(start -0.1778 -0.2794)
							(mid -0.249642 -0.249642)
							(end -0.2794 -0.1778)
						)
						(arc
							(start -0.2794 0.1778)
							(mid -0.249642 0.249642)
							(end -0.1778 0.2794)
						)
						(arc
							(start 0.1778 0.2794)
							(mid 0.249642 0.249642)
							(end 0.2794 0.1778)
						)
						(arc
							(start 0.2794 -0.1778)
							(mid 0.249642 -0.249642)
							(end 0.1778 -0.2794)
						)
					)
					(width 0)
					(fill yes)
				)
			)
		)
	)
	(footprint ""
		(layer "F.Cu")
		(at 86.49716 -34.671 -90)
		(property "Reference" "SC880"
			(at 0 0 270)
			(layer "F.SilkS")
			(hide yes)
			(effects
				(font
					(size 1.27 1.27)
				)
			)
		)
		(property "Value" "SCD01U10V1KX-GP"
			(at -2.8321 -1.7399 270)
			(unlocked yes)
			(layer "F.Fab")
			(hide yes)
			(effects
				(font
					(size 1.016 1.016)
					(thickness 0.1524)
				)
			)
		)
		(property "Device Type" "C0201H13"
			(at -2.8321 -3.2639 270)
			(unlocked yes)
			(layer "F.Fab")
			(hide yes)
			(effects
				(font
					(size 1.016 1.016)
					(thickness 0.1524)
				)
			)
		)
		(duplicate_pad_numbers_are_jumpers no)
		(fp_rect
			(start -0.2794 0.6477)
			(end 0.2794 -0.6477)
			(stroke
				(width 0)
				(type default)
			)
			(fill no)
			(layer "F.CrtYd")
		)
		(fp_rect
			(start -0.2794 0.6477)
			(end 0.2794 -0.6477)
			(stroke
				(width 0)
				(type default)
			)
			(fill no)
			(layer "F.Fab")
		)
		(pad "1" smd custom
			(at 0 -0.2794 270)
			(size 0.0762 0.0762)
			(layers "F.Cu" "F.Mask" "F.Paste")
			(net "SAS3008_RAID_TX_C_N1")
			(options
				(clearance outline)
				(anchor circle)
			)
			(primitives
				(gr_poly
					(pts
						(arc
							(start 0.1524 -0.127)
							(mid 0.137521 -0.162921)
							(end 0.1016 -0.1778)
						)
						(arc
							(start -0.1016 -0.1778)
							(mid -0.137521 -0.162921)
							(end -0.1524 -0.127)
						)
						(arc
							(start -0.1524 0.127)
							(mid -0.137521 0.162921)
							(end -0.1016 0.1778)
						)
						(arc
							(start 0.1016 0.1778)
							(mid 0.137521 0.162921)
							(end 0.1524 0.127)
						)
					)
					(width 0)
					(fill yes)
				)
			)
		)
		(pad "2" smd custom
			(at 0 0.2794 270)
			(size 0.0762 0.0762)
			(layers "F.Cu" "F.Mask" "F.Paste")
			(net "SAS3008_RAID_TX_N1")
			(options
				(clearance outline)
				(anchor circle)
			)
			(primitives
				(gr_poly
					(pts
						(arc
							(start 0.1524 -0.127)
							(mid 0.137521 -0.162921)
							(end 0.1016 -0.1778)
						)
						(arc
							(start -0.1016 -0.1778)
							(mid -0.137521 -0.162921)
							(end -0.1524 -0.127)
						)
						(arc
							(start -0.1524 0.127)
							(mid -0.137521 0.162921)
							(end -0.1016 0.1778)
						)
						(arc
							(start 0.1016 0.1778)
							(mid 0.137521 0.162921)
							(end 0.1524 0.127)
						)
					)
					(width 0)
					(fill yes)
				)
			)
		)
	)
	(footprint ""
		(layer "F.Cu")
		(at 274.193 -172.593 90)
		(property "Reference" "R365"
			(at 0 0 90)
			(layer "F.SilkS")
			(hide yes)
			(effects
				(font
					(size 1.27 1.27)
				)
			)
		)
		(property "Value" "3K3R2F-2-GP"
			(at 0.064008 -3.993896 90)
			(unlocked yes)
			(layer "F.Fab")
			(hide yes)
			(effects
				(font
					(size 1.016 1.016)
					(thickness 0.1524)
				)
			)
		)
		(property "Device Type" "R402H16"
			(at 0.064008 -5.517896 90)
			(unlocked yes)
			(layer "F.Fab")
			(hide yes)
			(effects
				(font
					(size 1.016 1.016)
					(thickness 0.1524)
				)
			)
		)
		(duplicate_pad_numbers_are_jumpers no)
		(fp_line
			(start 0.508 -0.9398)
			(end -0.508 -0.9398)
			(stroke
				(width 0.1524)
				(type default)
			)
			(layer "F.SilkS")
		)
		(fp_line
			(start -0.508 -0.9398)
			(end -0.508 0.9398)
			(stroke
				(width 0.1524)
				(type default)
			)
			(layer "F.SilkS")
		)
		(fp_rect
			(start -0.508 0.9398)
			(end 0.508 -0.9398)
			(stroke
				(width 0)
				(type default)
			)
			(fill no)
			(layer "F.CrtYd")
		)
		(fp_rect
			(start -0.508 0.9398)
			(end 0.508 -0.9398)
			(stroke
				(width 0)
				(type default)
			)
			(fill no)
			(layer "F.Fab")
		)
		(pad "1" smd custom
			(at 0 -0.4445 90)
			(size 0.1397 0.1397)
			(layers "F.Cu" "F.Mask" "F.Paste")
			(net "P3V3_STBY")
			(options
				(clearance outline)
				(anchor circle)
			)
			(primitives
				(gr_poly
					(pts
						(arc
							(start -0.1778 -0.2794)
							(mid -0.249642 -0.249642)
							(end -0.2794 -0.1778)
						)
						(arc
							(start -0.2794 0.1778)
							(mid -0.249642 0.249642)
							(end -0.1778 0.2794)
						)
						(arc
							(start 0.1778 0.2794)
							(mid 0.249642 0.249642)
							(end 0.2794 0.1778)
						)
						(arc
							(start 0.2794 -0.1778)
							(mid 0.249642 -0.249642)
							(end 0.1778 -0.2794)
						)
					)
					(width 0)
					(fill yes)
				)
			)
		)
		(pad "2" smd custom
			(at 0 0.4445 90)
			(size 0.1397 0.1397)
			(layers "F.Cu" "F.Mask" "F.Paste")
			(net "ROMA22")
			(options
				(clearance outline)
				(anchor circle)
			)
			(primitives
				(gr_poly
					(pts
						(arc
							(start -0.1778 -0.2794)
							(mid -0.249642 -0.249642)
							(end -0.2794 -0.1778)
						)
						(arc
							(start -0.2794 0.1778)
							(mid -0.249642 0.249642)
							(end -0.1778 0.2794)
						)
						(arc
							(start 0.1778 0.2794)
							(mid 0.249642 0.249642)
							(end 0.2794 0.1778)
						)
						(arc
							(start 0.2794 -0.1778)
							(mid 0.249642 -0.249642)
							(end 0.1778 -0.2794)
						)
					)
					(width 0)
					(fill yes)
				)
			)
		)
	)
	(footprint ""
		(layer "F.Cu")
		(at 292.165532 -191.819276)
		(property "Reference" "C175"
			(at 0 0 0)
			(layer "F.SilkS")
			(hide yes)
			(effects
				(font
					(size 1.27 1.27)
				)
			)
		)
		(property "Value" "SCD1U16V2KX-3GP"
			(at 1.1811 -2.7051 0)
			(unlocked yes)
			(layer "F.Fab")
			(hide yes)
			(effects
				(font
					(size 1.016 1.016)
					(thickness 0.1524)
				)
			)
		)
		(property "Device Type" "C402H22"
			(at 1.1811 -4.2291 0)
			(unlocked yes)
			(layer "F.Fab")
			(hide yes)
			(effects
				(font
					(size 1.016 1.016)
					(thickness 0.1524)
				)
			)
		)
		(duplicate_pad_numbers_are_jumpers no)
		(fp_rect
			(start -0.4318 0.9525)
			(end 0.4318 -0.9525)
			(stroke
				(width 0)
				(type default)
			)
			(fill no)
			(layer "F.CrtYd")
		)
		(fp_rect
			(start -0.4318 0.9525)
			(end 0.4318 -0.9525)
			(stroke
				(width 0)
				(type default)
			)
			(fill no)
			(layer "F.Fab")
		)
		(pad "1" smd custom
			(at 0 -0.4445)
			(size 0.1524 0.1524)
			(layers "F.Cu" "F.Mask" "F.Paste")
			(net "P1V53_STBY")
			(options
				(clearance outline)
				(anchor circle)
			)
			(primitives
				(gr_poly
					(pts
						(arc
							(start 0.3048 -0.2032)
							(mid 0.275042 -0.275042)
							(end 0.2032 -0.3048)
						)
						(arc
							(start -0.2032 -0.3048)
							(mid -0.275042 -0.275042)
							(end -0.3048 -0.2032)
						)
						(arc
							(start -0.3048 0.2032)
							(mid -0.275042 0.275042)
							(end -0.2032 0.3048)
						)
						(arc
							(start 0.2032 0.3048)
							(mid 0.275042 0.275042)
							(end 0.3048 0.2032)
						)
					)
					(width 0)
					(fill yes)
				)
			)
		)
		(pad "2" smd custom
			(at 0 0.4445)
			(size 0.1524 0.1524)
			(layers "F.Cu" "F.Mask" "F.Paste")
			(net "GND")
			(options
				(clearance outline)
				(anchor circle)
			)
			(primitives
				(gr_poly
					(pts
						(arc
							(start 0.3048 -0.2032)
							(mid 0.275042 -0.275042)
							(end 0.2032 -0.3048)
						)
						(arc
							(start -0.2032 -0.3048)
							(mid -0.275042 -0.275042)
							(end -0.3048 -0.2032)
						)
						(arc
							(start -0.3048 0.2032)
							(mid -0.275042 0.275042)
							(end -0.2032 0.3048)
						)
						(arc
							(start 0.2032 0.3048)
							(mid 0.275042 0.275042)
							(end 0.3048 0.2032)
						)
					)
					(width 0)
					(fill yes)
				)
			)
		)
	)
	(footprint ""
		(layer "F.Cu")
		(at 119.52097 -114.3 180)
		(property "Reference" "SC1070"
			(at 0 0 180)
			(layer "F.SilkS")
			(hide yes)
			(effects
				(font
					(size 1.27 1.27)
				)
			)
		)
		(property "Value" "SCD01U10V1KX-GP"
			(at -2.8321 -1.7399 180)
			(unlocked yes)
			(layer "F.Fab")
			(hide yes)
			(effects
				(font
					(size 1.016 1.016)
					(thickness 0.1524)
				)
			)
		)
		(property "Device Type" "C0201H13"
			(at -2.8321 -3.2639 180)
			(unlocked yes)
			(layer "F.Fab")
			(hide yes)
			(effects
				(font
					(size 1.016 1.016)
					(thickness 0.1524)
				)
			)
		)
		(duplicate_pad_numbers_are_jumpers no)
		(fp_rect
			(start -0.2794 0.6477)
			(end 0.2794 -0.6477)
			(stroke
				(width 0)
				(type default)
			)
			(fill no)
			(layer "F.CrtYd")
		)
		(fp_rect
			(start -0.2794 0.6477)
			(end 0.2794 -0.6477)
			(stroke
				(width 0)
				(type default)
			)
			(fill no)
			(layer "F.Fab")
		)
		(pad "1" smd custom
			(at 0 -0.2794 180)
			(size 0.0762 0.0762)
			(layers "F.Cu" "F.Mask" "F.Paste")
			(net "SAS_HDD_TX1_N")
			(options
				(clearance outline)
				(anchor circle)
			)
			(primitives
				(gr_poly
					(pts
						(arc
							(start 0.1524 -0.127)
							(mid 0.137521 -0.162921)
							(end 0.1016 -0.1778)
						)
						(arc
							(start -0.1016 -0.1778)
							(mid -0.137521 -0.162921)
							(end -0.1524 -0.127)
						)
						(arc
							(start -0.1524 0.127)
							(mid -0.137521 0.162921)
							(end -0.1016 0.1778)
						)
						(arc
							(start 0.1016 0.1778)
							(mid 0.137521 0.162921)
							(end 0.1524 0.127)
						)
					)
					(width 0)
					(fill yes)
				)
			)
		)
		(pad "2" smd custom
			(at 0 0.2794 180)
			(size 0.0762 0.0762)
			(layers "F.Cu" "F.Mask" "F.Paste")
			(net "SAS_EXP_GF_TX_DN5")
			(options
				(clearance outline)
				(anchor circle)
			)
			(primitives
				(gr_poly
					(pts
						(arc
							(start 0.1524 -0.127)
							(mid 0.137521 -0.162921)
							(end 0.1016 -0.1778)
						)
						(arc
							(start -0.1016 -0.1778)
							(mid -0.137521 -0.162921)
							(end -0.1524 -0.127)
						)
						(arc
							(start -0.1524 0.127)
							(mid -0.137521 0.162921)
							(end -0.1016 0.1778)
						)
						(arc
							(start 0.1016 0.1778)
							(mid 0.137521 0.162921)
							(end 0.1524 0.127)
						)
					)
					(width 0)
					(fill yes)
				)
			)
		)
	)
	(footprint ""
		(layer "F.Cu")
		(at 251.11964 -50.039778)
		(property "Reference" "SC1065"
			(at 0 0 0)
			(layer "F.SilkS")
			(hide yes)
			(effects
				(font
					(size 1.27 1.27)
				)
			)
		)
		(property "Value" "SCD01U50V2KX-1GP"
			(at 1.1811 -2.7051 0)
			(unlocked yes)
			(layer "F.Fab")
			(hide yes)
			(effects
				(font
					(size 1.016 1.016)
					(thickness 0.1524)
				)
			)
		)
		(property "Device Type" "C402H22"
			(at 1.1811 -4.2291 0)
			(unlocked yes)
			(layer "F.Fab")
			(hide yes)
			(effects
				(font
					(size 1.016 1.016)
					(thickness 0.1524)
				)
			)
		)
		(duplicate_pad_numbers_are_jumpers no)
		(fp_rect
			(start -0.4318 0.9525)
			(end 0.4318 -0.9525)
			(stroke
				(width 0)
				(type default)
			)
			(fill no)
			(layer "F.CrtYd")
		)
		(fp_rect
			(start -0.4318 0.9525)
			(end 0.4318 -0.9525)
			(stroke
				(width 0)
				(type default)
			)
			(fill no)
			(layer "F.Fab")
		)
		(pad "1" smd custom
			(at 0 -0.4445)
			(size 0.1524 0.1524)
			(layers "F.Cu" "F.Mask" "F.Paste")
			(net "P1V8_C")
			(options
				(clearance outline)
				(anchor circle)
			)
			(primitives
				(gr_poly
					(pts
						(arc
							(start 0.3048 -0.2032)
							(mid 0.275042 -0.275042)
							(end 0.2032 -0.3048)
						)
						(arc
							(start -0.2032 -0.3048)
							(mid -0.275042 -0.275042)
							(end -0.3048 -0.2032)
						)
						(arc
							(start -0.3048 0.2032)
							(mid -0.275042 0.275042)
							(end -0.2032 0.3048)
						)
						(arc
							(start 0.2032 0.3048)
							(mid 0.275042 0.275042)
							(end 0.3048 0.2032)
						)
					)
					(width 0)
					(fill yes)
				)
			)
		)
		(pad "2" smd custom
			(at 0 0.4445)
			(size 0.1524 0.1524)
			(layers "F.Cu" "F.Mask" "F.Paste")
			(net "GND")
			(options
				(clearance outline)
				(anchor circle)
			)
			(primitives
				(gr_poly
					(pts
						(arc
							(start 0.3048 -0.2032)
							(mid 0.275042 -0.275042)
							(end 0.2032 -0.3048)
						)
						(arc
							(start -0.2032 -0.3048)
							(mid -0.275042 -0.275042)
							(end -0.3048 -0.2032)
						)
						(arc
							(start -0.3048 0.2032)
							(mid -0.275042 0.275042)
							(end -0.2032 0.3048)
						)
						(arc
							(start 0.2032 0.3048)
							(mid 0.275042 0.275042)
							(end 0.3048 0.2032)
						)
					)
					(width 0)
					(fill yes)
				)
			)
		)
	)
	(footprint ""
		(layer "F.Cu")
		(at 222.123 -25.781 -90)
		(property "Reference" "R7889"
			(at 0 0 270)
			(layer "F.SilkS")
			(hide yes)
			(effects
				(font
					(size 1.27 1.27)
				)
			)
		)
		(property "Value" "0R2J-2-GP"
			(at 0.064008 -3.993896 270)
			(unlocked yes)
			(layer "F.Fab")
			(hide yes)
			(effects
				(font
					(size 1.016 1.016)
					(thickness 0.1524)
				)
			)
		)
		(property "Device Type" "R402H16"
			(at 0.064008 -5.517896 270)
			(unlocked yes)
			(layer "F.Fab")
			(hide yes)
			(effects
				(font
					(size 1.016 1.016)
					(thickness 0.1524)
				)
			)
		)
		(duplicate_pad_numbers_are_jumpers no)
		(fp_line
			(start -0.508 -0.9398)
			(end -0.508 0.9398)
			(stroke
				(width 0.1524)
				(type default)
			)
			(layer "F.SilkS")
		)
		(fp_line
			(start 0.508 -0.9398)
			(end -0.508 -0.9398)
			(stroke
				(width 0.1524)
				(type default)
			)
			(layer "F.SilkS")
		)
		(fp_rect
			(start -0.508 0.9398)
			(end 0.508 -0.9398)
			(stroke
				(width 0)
				(type default)
			)
			(fill no)
			(layer "F.CrtYd")
		)
		(fp_rect
			(start -0.508 0.9398)
			(end 0.508 -0.9398)
			(stroke
				(width 0)
				(type default)
			)
			(fill no)
			(layer "F.Fab")
		)
		(pad "1" smd custom
			(at 0 -0.4445 270)
			(size 0.1397 0.1397)
			(layers "F.Cu" "F.Mask" "F.Paste")
			(net "BMC_ID_LED")
			(options
				(clearance outline)
				(anchor circle)
			)
			(primitives
				(gr_poly
					(pts
						(arc
							(start -0.1778 -0.2794)
							(mid -0.249642 -0.249642)
							(end -0.2794 -0.1778)
						)
						(arc
							(start -0.2794 0.1778)
							(mid -0.249642 0.249642)
							(end -0.1778 0.2794)
						)
						(arc
							(start 0.1778 0.2794)
							(mid 0.249642 0.249642)
							(end 0.2794 0.1778)
						)
						(arc
							(start 0.2794 -0.1778)
							(mid 0.249642 -0.249642)
							(end 0.1778 -0.2794)
						)
					)
					(width 0)
					(fill yes)
				)
			)
		)
		(pad "2" smd custom
			(at 0 0.4445 270)
			(size 0.1397 0.1397)
			(layers "F.Cu" "F.Mask" "F.Paste")
			(net "BMC_ID_LED_R")
			(options
				(clearance outline)
				(anchor circle)
			)
			(primitives
				(gr_poly
					(pts
						(arc
							(start -0.1778 -0.2794)
							(mid -0.249642 -0.249642)
							(end -0.2794 -0.1778)
						)
						(arc
							(start -0.2794 0.1778)
							(mid -0.249642 0.249642)
							(end -0.1778 0.2794)
						)
						(arc
							(start 0.1778 0.2794)
							(mid 0.249642 0.249642)
							(end 0.2794 0.1778)
						)
						(arc
							(start 0.2794 -0.1778)
							(mid 0.249642 -0.249642)
							(end 0.1778 -0.2794)
						)
					)
					(width 0)
					(fill yes)
				)
			)
		)
	)
	(footprint ""
		(layer "F.Cu")
		(at 193.167 -122.682 180)
		(property "Reference" "R602"
			(at 0 0 180)
			(layer "F.SilkS")
			(hide yes)
			(effects
				(font
					(size 1.27 1.27)
				)
			)
		)
		(property "Value" "4K7R2F-GP"
			(at 0.064008 -3.993896 180)
			(unlocked yes)
			(layer "F.Fab")
			(hide yes)
			(effects
				(font
					(size 1.016 1.016)
					(thickness 0.1524)
				)
			)
		)
		(property "Device Type" "R402H16"
			(at 0.064008 -5.517896 180)
			(unlocked yes)
			(layer "F.Fab")
			(hide yes)
			(effects
				(font
					(size 1.016 1.016)
					(thickness 0.1524)
				)
			)
		)
		(duplicate_pad_numbers_are_jumpers no)
		(fp_line
			(start 0.508 -0.9398)
			(end -0.508 -0.9398)
			(stroke
				(width 0.1524)
				(type default)
			)
			(layer "F.SilkS")
		)
		(fp_line
			(start -0.508 -0.9398)
			(end -0.508 0.9398)
			(stroke
				(width 0.1524)
				(type default)
			)
			(layer "F.SilkS")
		)
		(fp_rect
			(start -0.508 0.9398)
			(end 0.508 -0.9398)
			(stroke
				(width 0)
				(type default)
			)
			(fill no)
			(layer "F.CrtYd")
		)
		(fp_rect
			(start -0.508 0.9398)
			(end 0.508 -0.9398)
			(stroke
				(width 0)
				(type default)
			)
			(fill no)
			(layer "F.Fab")
		)
		(pad "1" smd custom
			(at 0 -0.4445 180)
			(size 0.1397 0.1397)
			(layers "F.Cu" "F.Mask" "F.Paste")
			(net "P1V8_E_B")
			(options
				(clearance outline)
				(anchor circle)
			)
			(primitives
				(gr_poly
					(pts
						(arc
							(start -0.1778 -0.2794)
							(mid -0.249642 -0.249642)
							(end -0.2794 -0.1778)
						)
						(arc
							(start -0.2794 0.1778)
							(mid -0.249642 0.249642)
							(end -0.1778 0.2794)
						)
						(arc
							(start 0.1778 0.2794)
							(mid 0.249642 0.249642)
							(end 0.2794 0.1778)
						)
						(arc
							(start 0.2794 -0.1778)
							(mid 0.249642 -0.249642)
							(end 0.1778 -0.2794)
						)
					)
					(width 0)
					(fill yes)
				)
			)
		)
		(pad "2" smd custom
			(at 0 0.4445 180)
			(size 0.1397 0.1397)
			(layers "F.Cu" "F.Mask" "F.Paste")
			(net "P1V8_E")
			(options
				(clearance outline)
				(anchor circle)
			)
			(primitives
				(gr_poly
					(pts
						(arc
							(start -0.1778 -0.2794)
							(mid -0.249642 -0.249642)
							(end -0.2794 -0.1778)
						)
						(arc
							(start -0.2794 0.1778)
							(mid -0.249642 0.249642)
							(end -0.1778 0.2794)
						)
						(arc
							(start 0.1778 0.2794)
							(mid 0.249642 0.249642)
							(end 0.2794 0.1778)
						)
						(arc
							(start 0.2794 -0.1778)
							(mid 0.249642 -0.249642)
							(end 0.1778 -0.2794)
						)
					)
					(width 0)
					(fill yes)
				)
			)
		)
	)
	(footprint ""
		(layer "F.Cu")
		(at 16.714216 -213.79688 180)
		(property "Reference" "R630"
			(at 0 0 180)
			(layer "F.SilkS")
			(hide yes)
			(effects
				(font
					(size 1.27 1.27)
				)
			)
		)
		(property "Value" "4K7R2F-GP"
			(at 0.064008 -3.993896 180)
			(unlocked yes)
			(layer "F.Fab")
			(hide yes)
			(effects
				(font
					(size 1.016 1.016)
					(thickness 0.1524)
				)
			)
		)
		(property "Device Type" "R402H16"
			(at 0.064008 -5.517896 180)
			(unlocked yes)
			(layer "F.Fab")
			(hide yes)
			(effects
				(font
					(size 1.016 1.016)
					(thickness 0.1524)
				)
			)
		)
		(duplicate_pad_numbers_are_jumpers no)
		(fp_line
			(start 0.508 -0.9398)
			(end -0.508 -0.9398)
			(stroke
				(width 0.1524)
				(type default)
			)
			(layer "F.SilkS")
		)
		(fp_line
			(start -0.508 -0.9398)
			(end -0.508 0.9398)
			(stroke
				(width 0.1524)
				(type default)
			)
			(layer "F.SilkS")
		)
		(fp_rect
			(start -0.508 0.9398)
			(end 0.508 -0.9398)
			(stroke
				(width 0)
				(type default)
			)
			(fill no)
			(layer "F.CrtYd")
		)
		(fp_rect
			(start -0.508 0.9398)
			(end 0.508 -0.9398)
			(stroke
				(width 0)
				(type default)
			)
			(fill no)
			(layer "F.Fab")
		)
		(pad "1" smd custom
			(at 0 -0.4445 180)
			(size 0.1397 0.1397)
			(layers "F.Cu" "F.Mask" "F.Paste")
			(net "P3V3_STBY")
			(options
				(clearance outline)
				(anchor circle)
			)
			(primitives
				(gr_poly
					(pts
						(arc
							(start -0.1778 -0.2794)
							(mid -0.249642 -0.249642)
							(end -0.2794 -0.1778)
						)
						(arc
							(start -0.2794 0.1778)
							(mid -0.249642 0.249642)
							(end -0.1778 0.2794)
						)
						(arc
							(start 0.1778 0.2794)
							(mid 0.249642 0.249642)
							(end 0.2794 0.1778)
						)
						(arc
							(start 0.2794 -0.1778)
							(mid 0.249642 -0.249642)
							(end 0.1778 -0.2794)
						)
					)
					(width 0)
					(fill yes)
				)
			)
		)
		(pad "2" smd custom
			(at 0 0.4445 180)
			(size 0.1397 0.1397)
			(layers "F.Cu" "F.Mask" "F.Paste")
			(net "IO_EXP_HDD_PWR_A0")
			(options
				(clearance outline)
				(anchor circle)
			)
			(primitives
				(gr_poly
					(pts
						(arc
							(start -0.1778 -0.2794)
							(mid -0.249642 -0.249642)
							(end -0.2794 -0.1778)
						)
						(arc
							(start -0.2794 0.1778)
							(mid -0.249642 0.249642)
							(end -0.1778 0.2794)
						)
						(arc
							(start 0.1778 0.2794)
							(mid 0.249642 0.249642)
							(end 0.2794 0.1778)
						)
						(arc
							(start 0.2794 -0.1778)
							(mid 0.249642 -0.249642)
							(end 0.1778 -0.2794)
						)
					)
					(width 0)
					(fill yes)
				)
			)
		)
	)
	(footprint ""
		(layer "F.Cu")
		(at 181.791864 -22.551136)
		(property "Reference" "R396"
			(at 0 0 0)
			(layer "F.SilkS")
			(hide yes)
			(effects
				(font
					(size 1.27 1.27)
				)
			)
		)
		(property "Value" "150R2F-1-GP"
			(at 0.064008 -3.993896 0)
			(unlocked yes)
			(layer "F.Fab")
			(hide yes)
			(effects
				(font
					(size 1.016 1.016)
					(thickness 0.1524)
				)
			)
		)
		(property "Device Type" "R402H16"
			(at 0.064008 -5.517896 0)
			(unlocked yes)
			(layer "F.Fab")
			(hide yes)
			(effects
				(font
					(size 1.016 1.016)
					(thickness 0.1524)
				)
			)
		)
		(duplicate_pad_numbers_are_jumpers no)
		(fp_line
			(start -0.508 -0.9398)
			(end -0.508 0.9398)
			(stroke
				(width 0.1524)
				(type default)
			)
			(layer "F.SilkS")
		)
		(fp_line
			(start 0.508 -0.9398)
			(end -0.508 -0.9398)
			(stroke
				(width 0.1524)
				(type default)
			)
			(layer "F.SilkS")
		)
		(fp_rect
			(start -0.508 0.9398)
			(end 0.508 -0.9398)
			(stroke
				(width 0)
				(type default)
			)
			(fill no)
			(layer "F.CrtYd")
		)
		(fp_rect
			(start -0.508 0.9398)
			(end 0.508 -0.9398)
			(stroke
				(width 0)
				(type default)
			)
			(fill no)
			(layer "F.Fab")
		)
		(pad "1" smd custom
			(at 0 -0.4445)
			(size 0.1397 0.1397)
			(layers "F.Cu" "F.Mask" "F.Paste")
			(net "PHY_ANEN")
			(options
				(clearance outline)
				(anchor circle)
			)
			(primitives
				(gr_poly
					(pts
						(arc
							(start -0.1778 -0.2794)
							(mid -0.249642 -0.249642)
							(end -0.2794 -0.1778)
						)
						(arc
							(start -0.2794 0.1778)
							(mid -0.249642 0.249642)
							(end -0.1778 0.2794)
						)
						(arc
							(start 0.1778 0.2794)
							(mid 0.249642 0.249642)
							(end 0.2794 0.1778)
						)
						(arc
							(start 0.2794 -0.1778)
							(mid 0.249642 -0.249642)
							(end 0.1778 -0.2794)
						)
					)
					(width 0)
					(fill yes)
				)
			)
		)
		(pad "2" smd custom
			(at 0 0.4445)
			(size 0.1397 0.1397)
			(layers "F.Cu" "F.Mask" "F.Paste")
			(net "GND")
			(options
				(clearance outline)
				(anchor circle)
			)
			(primitives
				(gr_poly
					(pts
						(arc
							(start -0.1778 -0.2794)
							(mid -0.249642 -0.249642)
							(end -0.2794 -0.1778)
						)
						(arc
							(start -0.2794 0.1778)
							(mid -0.249642 0.249642)
							(end -0.1778 0.2794)
						)
						(arc
							(start 0.1778 0.2794)
							(mid 0.249642 0.249642)
							(end 0.2794 0.1778)
						)
						(arc
							(start 0.2794 -0.1778)
							(mid 0.249642 -0.249642)
							(end 0.1778 -0.2794)
						)
					)
					(width 0)
					(fill yes)
				)
			)
		)
	)
	(footprint ""
		(layer "F.Cu")
		(at 183.569864 -38.172136 180)
		(property "Reference" "R390"
			(at 0 0 180)
			(layer "F.SilkS")
			(hide yes)
			(effects
				(font
					(size 1.27 1.27)
				)
			)
		)
		(property "Value" "4K75R2F-1-GP"
			(at 0.064008 -3.993896 180)
			(unlocked yes)
			(layer "F.Fab")
			(hide yes)
			(effects
				(font
					(size 1.016 1.016)
					(thickness 0.1524)
				)
			)
		)
		(property "Device Type" "R402H16"
			(at 0.064008 -5.517896 180)
			(unlocked yes)
			(layer "F.Fab")
			(hide yes)
			(effects
				(font
					(size 1.016 1.016)
					(thickness 0.1524)
				)
			)
		)
		(duplicate_pad_numbers_are_jumpers no)
		(fp_line
			(start 0.508 -0.9398)
			(end -0.508 -0.9398)
			(stroke
				(width 0.1524)
				(type default)
			)
			(layer "F.SilkS")
		)
		(fp_line
			(start -0.508 -0.9398)
			(end -0.508 0.9398)
			(stroke
				(width 0.1524)
				(type default)
			)
			(layer "F.SilkS")
		)
		(fp_rect
			(start -0.508 0.9398)
			(end 0.508 -0.9398)
			(stroke
				(width 0)
				(type default)
			)
			(fill no)
			(layer "F.CrtYd")
		)
		(fp_rect
			(start -0.508 0.9398)
			(end 0.508 -0.9398)
			(stroke
				(width 0)
				(type default)
			)
			(fill no)
			(layer "F.Fab")
		)
		(pad "1" smd custom
			(at 0 -0.4445 180)
			(size 0.1397 0.1397)
			(layers "F.Cu" "F.Mask" "F.Paste")
			(net "PHY_AD0")
			(options
				(clearance outline)
				(anchor circle)
			)
			(primitives
				(gr_poly
					(pts
						(arc
							(start -0.1778 -0.2794)
							(mid -0.249642 -0.249642)
							(end -0.2794 -0.1778)
						)
						(arc
							(start -0.2794 0.1778)
							(mid -0.249642 0.249642)
							(end -0.1778 0.2794)
						)
						(arc
							(start 0.1778 0.2794)
							(mid 0.249642 0.249642)
							(end 0.2794 0.1778)
						)
						(arc
							(start 0.2794 -0.1778)
							(mid 0.249642 -0.249642)
							(end 0.1778 -0.2794)
						)
					)
					(width 0)
					(fill yes)
				)
			)
		)
		(pad "2" smd custom
			(at 0 0.4445 180)
			(size 0.1397 0.1397)
			(layers "F.Cu" "F.Mask" "F.Paste")
			(net "GND")
			(options
				(clearance outline)
				(anchor circle)
			)
			(primitives
				(gr_poly
					(pts
						(arc
							(start -0.1778 -0.2794)
							(mid -0.249642 -0.249642)
							(end -0.2794 -0.1778)
						)
						(arc
							(start -0.2794 0.1778)
							(mid -0.249642 0.249642)
							(end -0.1778 0.2794)
						)
						(arc
							(start 0.1778 0.2794)
							(mid 0.249642 0.249642)
							(end 0.2794 0.1778)
						)
						(arc
							(start 0.2794 -0.1778)
							(mid 0.249642 -0.249642)
							(end 0.1778 -0.2794)
						)
					)
					(width 0)
					(fill yes)
				)
			)
		)
	)
	(footprint ""
		(layer "F.Cu")
		(at 166.614856 -112.404652 180)
		(property "Reference" "PR157"
			(at 0 0 180)
			(layer "F.SilkS")
			(hide yes)
			(effects
				(font
					(size 1.27 1.27)
				)
			)
		)
		(property "Value" "51KR2F-L-GP"
			(at 0.064008 -3.993896 180)
			(unlocked yes)
			(layer "F.Fab")
			(hide yes)
			(effects
				(font
					(size 1.016 1.016)
					(thickness 0.1524)
				)
			)
		)
		(property "Device Type" "R402H16"
			(at 0.064008 -5.517896 180)
			(unlocked yes)
			(layer "F.Fab")
			(hide yes)
			(effects
				(font
					(size 1.016 1.016)
					(thickness 0.1524)
				)
			)
		)
		(duplicate_pad_numbers_are_jumpers no)
		(fp_line
			(start 0.508 -0.9398)
			(end -0.508 -0.9398)
			(stroke
				(width 0.1524)
				(type default)
			)
			(layer "F.SilkS")
		)
		(fp_line
			(start -0.508 -0.9398)
			(end -0.508 0.9398)
			(stroke
				(width 0.1524)
				(type default)
			)
			(layer "F.SilkS")
		)
		(fp_rect
			(start -0.508 0.9398)
			(end 0.508 -0.9398)
			(stroke
				(width 0)
				(type default)
			)
			(fill no)
			(layer "F.CrtYd")
		)
		(fp_rect
			(start -0.508 0.9398)
			(end 0.508 -0.9398)
			(stroke
				(width 0)
				(type default)
			)
			(fill no)
			(layer "F.Fab")
		)
		(pad "1" smd custom
			(at 0 -0.4445 180)
			(size 0.1397 0.1397)
			(layers "F.Cu" "F.Mask" "F.Paste")
			(net "P0V9_E_EN")
			(options
				(clearance outline)
				(anchor circle)
			)
			(primitives
				(gr_poly
					(pts
						(arc
							(start -0.1778 -0.2794)
							(mid -0.249642 -0.249642)
							(end -0.2794 -0.1778)
						)
						(arc
							(start -0.2794 0.1778)
							(mid -0.249642 0.249642)
							(end -0.1778 0.2794)
						)
						(arc
							(start 0.1778 0.2794)
							(mid 0.249642 0.249642)
							(end 0.2794 0.1778)
						)
						(arc
							(start 0.2794 -0.1778)
							(mid 0.249642 -0.249642)
							(end 0.1778 -0.2794)
						)
					)
					(width 0)
					(fill yes)
				)
			)
		)
		(pad "2" smd custom
			(at 0 0.4445 180)
			(size 0.1397 0.1397)
			(layers "F.Cu" "F.Mask" "F.Paste")
			(net "GND")
			(options
				(clearance outline)
				(anchor circle)
			)
			(primitives
				(gr_poly
					(pts
						(arc
							(start -0.1778 -0.2794)
							(mid -0.249642 -0.249642)
							(end -0.2794 -0.1778)
						)
						(arc
							(start -0.2794 0.1778)
							(mid -0.249642 0.249642)
							(end -0.1778 0.2794)
						)
						(arc
							(start 0.1778 0.2794)
							(mid 0.249642 0.249642)
							(end 0.2794 0.1778)
						)
						(arc
							(start 0.2794 -0.1778)
							(mid 0.249642 -0.249642)
							(end 0.1778 -0.2794)
						)
					)
					(width 0)
					(fill yes)
				)
			)
		)
	)
	(footprint ""
		(layer "F.Cu")
		(at 198.119492 -171.463716 180)
		(property "Reference" "R480"
			(at 0 0 180)
			(layer "F.SilkS")
			(hide yes)
			(effects
				(font
					(size 1.27 1.27)
				)
			)
		)
		(property "Value" "10KR2F-2-GP"
			(at 0.064008 -3.993896 180)
			(unlocked yes)
			(layer "F.Fab")
			(hide yes)
			(effects
				(font
					(size 1.016 1.016)
					(thickness 0.1524)
				)
			)
		)
		(property "Device Type" "R402H16"
			(at 0.064008 -5.517896 180)
			(unlocked yes)
			(layer "F.Fab")
			(hide yes)
			(effects
				(font
					(size 1.016 1.016)
					(thickness 0.1524)
				)
			)
		)
		(duplicate_pad_numbers_are_jumpers no)
		(fp_line
			(start 0.508 -0.9398)
			(end -0.508 -0.9398)
			(stroke
				(width 0.1524)
				(type default)
			)
			(layer "F.SilkS")
		)
		(fp_line
			(start -0.508 -0.9398)
			(end -0.508 0.9398)
			(stroke
				(width 0.1524)
				(type default)
			)
			(layer "F.SilkS")
		)
		(fp_rect
			(start -0.508 0.9398)
			(end 0.508 -0.9398)
			(stroke
				(width 0)
				(type default)
			)
			(fill no)
			(layer "F.CrtYd")
		)
		(fp_rect
			(start -0.508 0.9398)
			(end 0.508 -0.9398)
			(stroke
				(width 0)
				(type default)
			)
			(fill no)
			(layer "F.Fab")
		)
		(pad "1" smd custom
			(at 0 -0.4445 180)
			(size 0.1397 0.1397)
			(layers "F.Cu" "F.Mask" "F.Paste")
			(net "P3V3_STBY")
			(options
				(clearance outline)
				(anchor circle)
			)
			(primitives
				(gr_poly
					(pts
						(arc
							(start -0.1778 -0.2794)
							(mid -0.249642 -0.249642)
							(end -0.2794 -0.1778)
						)
						(arc
							(start -0.2794 0.1778)
							(mid -0.249642 0.249642)
							(end -0.1778 0.2794)
						)
						(arc
							(start 0.1778 0.2794)
							(mid 0.249642 0.249642)
							(end 0.2794 0.1778)
						)
						(arc
							(start 0.2794 -0.1778)
							(mid 0.249642 -0.249642)
							(end 0.1778 -0.2794)
						)
					)
					(width 0)
					(fill yes)
				)
			)
		)
		(pad "2" smd custom
			(at 0 0.4445 180)
			(size 0.1397 0.1397)
			(layers "F.Cu" "F.Mask" "F.Paste")
			(net "INVERTER_G2")
			(options
				(clearance outline)
				(anchor circle)
			)
			(primitives
				(gr_poly
					(pts
						(arc
							(start -0.1778 -0.2794)
							(mid -0.249642 -0.249642)
							(end -0.2794 -0.1778)
						)
						(arc
							(start -0.2794 0.1778)
							(mid -0.249642 0.249642)
							(end -0.1778 0.2794)
						)
						(arc
							(start 0.1778 0.2794)
							(mid 0.249642 0.249642)
							(end 0.2794 0.1778)
						)
						(arc
							(start 0.2794 -0.1778)
							(mid 0.249642 -0.249642)
							(end 0.1778 -0.2794)
						)
					)
					(width 0)
					(fill yes)
				)
			)
		)
	)
	(footprint ""
		(layer "F.Cu")
		(at 84.21497 -112.014 180)
		(property "Reference" "SC1228"
			(at 0 0 180)
			(layer "F.SilkS")
			(hide yes)
			(effects
				(font
					(size 1.27 1.27)
				)
			)
		)
		(property "Value" "SCD1U6D3V1KX-GP"
			(at -2.8321 -1.7399 180)
			(unlocked yes)
			(layer "F.Fab")
			(hide yes)
			(effects
				(font
					(size 1.016 1.016)
					(thickness 0.1524)
				)
			)
		)
		(property "Device Type" "C0201H13"
			(at -2.8321 -3.2639 180)
			(unlocked yes)
			(layer "F.Fab")
			(hide yes)
			(effects
				(font
					(size 1.016 1.016)
					(thickness 0.1524)
				)
			)
		)
		(duplicate_pad_numbers_are_jumpers no)
		(fp_rect
			(start -0.2794 0.6477)
			(end 0.2794 -0.6477)
			(stroke
				(width 0)
				(type default)
			)
			(fill no)
			(layer "F.CrtYd")
		)
		(fp_rect
			(start -0.2794 0.6477)
			(end 0.2794 -0.6477)
			(stroke
				(width 0)
				(type default)
			)
			(fill no)
			(layer "F.Fab")
		)
		(pad "1" smd custom
			(at 0 -0.2794 180)
			(size 0.0762 0.0762)
			(layers "F.Cu" "F.Mask" "F.Paste")
			(net "P1V8_E")
			(options
				(clearance outline)
				(anchor circle)
			)
			(primitives
				(gr_poly
					(pts
						(arc
							(start 0.1524 -0.127)
							(mid 0.137521 -0.162921)
							(end 0.1016 -0.1778)
						)
						(arc
							(start -0.1016 -0.1778)
							(mid -0.137521 -0.162921)
							(end -0.1524 -0.127)
						)
						(arc
							(start -0.1524 0.127)
							(mid -0.137521 0.162921)
							(end -0.1016 0.1778)
						)
						(arc
							(start 0.1016 0.1778)
							(mid 0.137521 0.162921)
							(end 0.1524 0.127)
						)
					)
					(width 0)
					(fill yes)
				)
			)
		)
		(pad "2" smd custom
			(at 0 0.2794 180)
			(size 0.0762 0.0762)
			(layers "F.Cu" "F.Mask" "F.Paste")
			(net "GND")
			(options
				(clearance outline)
				(anchor circle)
			)
			(primitives
				(gr_poly
					(pts
						(arc
							(start 0.1524 -0.127)
							(mid 0.137521 -0.162921)
							(end 0.1016 -0.1778)
						)
						(arc
							(start -0.1016 -0.1778)
							(mid -0.137521 -0.162921)
							(end -0.1524 -0.127)
						)
						(arc
							(start -0.1524 0.127)
							(mid -0.137521 0.162921)
							(end -0.1016 0.1778)
						)
						(arc
							(start 0.1016 0.1778)
							(mid 0.137521 0.162921)
							(end 0.1524 0.127)
						)
					)
					(width 0)
					(fill yes)
				)
			)
		)
	)
	(footprint ""
		(layer "F.Cu")
		(at 97.54997 -80.518)
		(property "Reference" "STP102"
			(at 0 0 0)
			(layer "F.SilkS")
			(hide yes)
			(effects
				(font
					(size 1.27 1.27)
				)
			)
		)
		(property "Value" "TPAD28"
			(at 0.0127 -1.8034 0)
			(unlocked yes)
			(layer "F.Fab")
			(hide yes)
			(effects
				(font
					(size 1.016 1.016)
					(thickness 0.1524)
				)
			)
		)
		(property "Device Type" "TPAD28"
			(at 0.0127 -3.3274 0)
			(unlocked yes)
			(layer "F.Fab")
			(hide yes)
			(effects
				(font
					(size 1.016 1.016)
					(thickness 0.1524)
				)
			)
		)
		(duplicate_pad_numbers_are_jumpers no)
		(fp_poly
			(pts
				(arc
					(start 0.3556 0)
					(mid -0.3556 0)
					(end 0.3556 0)
				)
			)
			(stroke
				(width 0)
				(type default)
			)
			(fill no)
			(layer "F.CrtYd")
		)
		(fp_poly
			(pts
				(arc
					(start 0.6096 0)
					(mid -0.6096 0)
					(end 0.6096 0)
				)
			)
			(stroke
				(width 0)
				(type default)
			)
			(fill no)
			(layer "F.Fab")
		)
		(pad "1" smd circle
			(at 0 0)
			(size 0.7112 0.7112)
			(layers "F.Cu" "F.Mask" "F.Paste")
			(net "TMUX_EN")
		)
	)
	(footprint ""
		(layer "F.Cu")
		(at 79.38897 -112.014)
		(property "Reference" "PR171"
			(at 0 0 0)
			(layer "F.SilkS")
			(hide yes)
			(effects
				(font
					(size 1.27 1.27)
				)
			)
		)
		(property "Value" "1KR2J-1-GP"
			(at 0.064008 -3.993896 0)
			(unlocked yes)
			(layer "F.Fab")
			(hide yes)
			(effects
				(font
					(size 1.016 1.016)
					(thickness 0.1524)
				)
			)
		)
		(property "Device Type" "R402H16"
			(at 0.064008 -5.517896 0)
			(unlocked yes)
			(layer "F.Fab")
			(hide yes)
			(effects
				(font
					(size 1.016 1.016)
					(thickness 0.1524)
				)
			)
		)
		(duplicate_pad_numbers_are_jumpers no)
		(fp_line
			(start -0.508 -0.9398)
			(end -0.508 0.9398)
			(stroke
				(width 0.1524)
				(type default)
			)
			(layer "F.SilkS")
		)
		(fp_line
			(start 0.508 -0.9398)
			(end -0.508 -0.9398)
			(stroke
				(width 0.1524)
				(type default)
			)
			(layer "F.SilkS")
		)
		(fp_rect
			(start -0.508 0.9398)
			(end 0.508 -0.9398)
			(stroke
				(width 0)
				(type default)
			)
			(fill no)
			(layer "F.CrtYd")
		)
		(fp_rect
			(start -0.508 0.9398)
			(end 0.508 -0.9398)
			(stroke
				(width 0)
				(type default)
			)
			(fill no)
			(layer "F.Fab")
		)
		(pad "1" smd custom
			(at 0 -0.4445)
			(size 0.1397 0.1397)
			(layers "F.Cu" "F.Mask" "F.Paste")
			(net "GND")
			(options
				(clearance outline)
				(anchor circle)
			)
			(primitives
				(gr_poly
					(pts
						(arc
							(start -0.1778 -0.2794)
							(mid -0.249642 -0.249642)
							(end -0.2794 -0.1778)
						)
						(arc
							(start -0.2794 0.1778)
							(mid -0.249642 0.249642)
							(end -0.1778 0.2794)
						)
						(arc
							(start 0.1778 0.2794)
							(mid 0.249642 0.249642)
							(end 0.2794 0.1778)
						)
						(arc
							(start 0.2794 -0.1778)
							(mid 0.249642 -0.249642)
							(end 0.1778 -0.2794)
						)
					)
					(width 0)
					(fill yes)
				)
			)
		)
		(pad "2" smd custom
			(at 0 0.4445)
			(size 0.1397 0.1397)
			(layers "F.Cu" "F.Mask" "F.Paste")
			(net "P1V8_E")
			(options
				(clearance outline)
				(anchor circle)
			)
			(primitives
				(gr_poly
					(pts
						(arc
							(start -0.1778 -0.2794)
							(mid -0.249642 -0.249642)
							(end -0.2794 -0.1778)
						)
						(arc
							(start -0.2794 0.1778)
							(mid -0.249642 0.249642)
							(end -0.1778 0.2794)
						)
						(arc
							(start 0.1778 0.2794)
							(mid 0.249642 0.249642)
							(end 0.2794 0.1778)
						)
						(arc
							(start 0.2794 -0.1778)
							(mid 0.249642 -0.249642)
							(end 0.1778 -0.2794)
						)
					)
					(width 0)
					(fill yes)
				)
			)
		)
	)
	(footprint ""
		(layer "F.Cu")
		(at 14.99108 -231.568752)
		(property "Reference" "SU15"
			(at 0 0 0)
			(layer "F.SilkS")
			(hide yes)
			(effects
				(font
					(size 1.27 1.27)
				)
			)
		)
		(property "Value" "PI3C3861-AQE-GP"
			(at 0 -13.1572 0)
			(unlocked yes)
			(layer "F.Fab")
			(hide yes)
			(effects
				(font
					(size 1.016 1.016)
					(thickness 0.1524)
				)
			)
		)
		(property "Device Type" "QSOIC24H69"
			(at 0 -15.1892 0)
			(unlocked yes)
			(layer "F.Fab")
			(hide yes)
			(effects
				(font
					(size 1.016 1.016)
					(thickness 0.1524)
				)
			)
		)
		(duplicate_pad_numbers_are_jumpers no)
		(fp_line
			(start -4.4958 -1.5748)
			(end 3.5814 -1.5748)
			(stroke
				(width 0.1524)
				(type default)
			)
			(layer "F.SilkS")
		)
		(fp_line
			(start -4.4958 -0.4318)
			(end -4.4958 -1.5748)
			(stroke
				(width 0.1524)
				(type default)
			)
			(layer "F.SilkS")
		)
		(fp_line
			(start -4.4958 -0.4318)
			(end -4.064 0)
			(stroke
				(width 0.1524)
				(type default)
			)
			(layer "F.SilkS")
		)
		(fp_line
			(start -4.4958 0.4318)
			(end -4.4958 -0.4318)
			(stroke
				(width 0.1524)
				(type default)
			)
			(layer "F.SilkS")
		)
		(fp_line
			(start -4.4958 0.4318)
			(end -4.4958 1.5748)
			(stroke
				(width 0.1524)
				(type default)
			)
			(layer "F.SilkS")
		)
		(fp_line
			(start -4.318 1.5748)
			(end -4.318 3.556)
			(stroke
				(width 0.508)
				(type default)
			)
			(layer "F.SilkS")
		)
		(fp_line
			(start -4.064 0)
			(end -4.4958 0.4318)
			(stroke
				(width 0.1524)
				(type default)
			)
			(layer "F.SilkS")
		)
		(fp_line
			(start 3.5814 -1.5748)
			(end 3.5814 1.5748)
			(stroke
				(width 0.1524)
				(type default)
			)
			(layer "F.SilkS")
		)
		(fp_line
			(start 3.5814 1.5748)
			(end -4.4958 1.5748)
			(stroke
				(width 0.1524)
				(type default)
			)
			(layer "F.SilkS")
		)
		(fp_line
			(start 3.5814 1.5748)
			(end 3.5814 -1.5748)
			(stroke
				(width 0.1524)
				(type default)
			)
			(layer "F.SilkS")
		)
		(fp_poly
			(pts
				(xy -3.683 -1.5748) (xy 3.5814 -1.5748) (xy 3.5814 1.5748) (xy -3.683 1.5748)
			)
			(stroke
				(width 0)
				(type default)
			)
			(fill yes)
			(layer "F.SilkS")
		)
		(fp_rect
			(start -4.572 3.81)
			(end 4.572 -3.81)
			(stroke
				(width 0)
				(type default)
			)
			(fill no)
			(layer "F.CrtYd")
		)
		(fp_poly
			(pts
				(xy -4.572 -3.81) (xy 4.572 -3.81) (xy 4.572 3.81) (xy -4.572 3.81)
			)
			(stroke
				(width 0)
				(type default)
			)
			(fill no)
			(layer "F.Fab")
		)
		(pad "1" smd rect
			(at -3.4925 2.6162)
			(size 0.3556 1.524)
			(layers "F.Cu" "F.Mask" "F.Paste")
			(net "Net_1511")
		)
		(pad "2" smd rect
			(at -2.8575 2.6162)
			(size 0.3556 1.524)
			(layers "F.Cu" "F.Mask" "F.Paste")
			(net "SAS_HDD_PWR10")
		)
		(pad "3" smd rect
			(at -2.2225 2.6162)
			(size 0.3556 1.524)
			(layers "F.Cu" "F.Mask" "F.Paste")
			(net "SAS_HDD_PWR11")
		)
		(pad "4" smd rect
			(at -1.5875 2.6162)
			(size 0.3556 1.524)
			(layers "F.Cu" "F.Mask" "F.Paste")
			(net "SAS_HDD_PWR12")
		)
		(pad "5" smd rect
			(at -0.9525 2.6162)
			(size 0.3556 1.524)
			(layers "F.Cu" "F.Mask" "F.Paste")
			(net "SAS_HDD_PWR13")
		)
		(pad "6" smd rect
			(at -0.3175 2.6162)
			(size 0.3556 1.524)
			(layers "F.Cu" "F.Mask" "F.Paste")
			(net "SAS_HDD_PWR14")
		)
		(pad "7" smd rect
			(at 0.3175 2.6162)
			(size 0.3556 1.524)
			(layers "F.Cu" "F.Mask" "F.Paste")
			(net "SAS_HDD_PWR15")
		)
		(pad "8" smd rect
			(at 0.9525 2.6162)
			(size 0.3556 1.524)
			(layers "F.Cu" "F.Mask" "F.Paste")
			(net "Net_1509")
		)
		(pad "9" smd rect
			(at 1.5875 2.6162)
			(size 0.3556 1.524)
			(layers "F.Cu" "F.Mask" "F.Paste")
			(net "Net_1510")
		)
		(pad "10" smd rect
			(at 2.2225 2.6162)
			(size 0.3556 1.524)
			(layers "F.Cu" "F.Mask" "F.Paste")
			(net "Net_1506")
		)
		(pad "11" smd rect
			(at 2.8575 2.6162)
			(size 0.3556 1.524)
			(layers "F.Cu" "F.Mask" "F.Paste")
			(net "Net_1507")
		)
		(pad "12" smd rect
			(at 3.4925 2.6162)
			(size 0.3556 1.524)
			(layers "F.Cu" "F.Mask" "F.Paste")
			(net "GND")
		)
		(pad "13" smd rect
			(at 3.4925 -2.6162)
			(size 0.3556 1.524)
			(layers "F.Cu" "F.Mask" "F.Paste")
			(net "Net_1503")
		)
		(pad "14" smd rect
			(at 2.8575 -2.6162)
			(size 0.3556 1.524)
			(layers "F.Cu" "F.Mask" "F.Paste")
			(net "Net_1504")
		)
		(pad "15" smd rect
			(at 2.2225 -2.6162)
			(size 0.3556 1.524)
			(layers "F.Cu" "F.Mask" "F.Paste")
			(net "Net_1505")
		)
		(pad "16" smd rect
			(at 1.5875 -2.6162)
			(size 0.3556 1.524)
			(layers "F.Cu" "F.Mask" "F.Paste")
			(net "Net_1508")
		)
		(pad "17" smd rect
			(at 0.9525 -2.6162)
			(size 0.3556 1.524)
			(layers "F.Cu" "F.Mask" "F.Paste")
			(net "SAS_HDD_PWR15_PCIE")
		)
		(pad "18" smd rect
			(at 0.3175 -2.6162)
			(size 0.3556 1.524)
			(layers "F.Cu" "F.Mask" "F.Paste")
			(net "SAS_HDD_PWR14_PCIE")
		)
		(pad "19" smd rect
			(at -0.3175 -2.6162)
			(size 0.3556 1.524)
			(layers "F.Cu" "F.Mask" "F.Paste")
			(net "SAS_HDD_PWR13_PCIE")
		)
		(pad "20" smd rect
			(at -0.9525 -2.6162)
			(size 0.3556 1.524)
			(layers "F.Cu" "F.Mask" "F.Paste")
			(net "SAS_HDD_PWR12_PCIE")
		)
		(pad "21" smd rect
			(at -1.5875 -2.6162)
			(size 0.3556 1.524)
			(layers "F.Cu" "F.Mask" "F.Paste")
			(net "SAS_HDD_PWR11_PCIE")
		)
		(pad "22" smd rect
			(at -2.2225 -2.6162)
			(size 0.3556 1.524)
			(layers "F.Cu" "F.Mask" "F.Paste")
			(net "SAS_HDD_PWR10_PCIE")
		)
		(pad "23" smd rect
			(at -2.8575 -2.6162)
			(size 0.3556 1.524)
			(layers "F.Cu" "F.Mask" "F.Paste")
			(net "PCIE_MATED#_AB")
		)
		(pad "24" smd rect
			(at -3.4925 -2.6162)
			(size 0.3556 1.524)
			(layers "F.Cu" "F.Mask" "F.Paste")
			(net "P3V3_STBY")
		)
	)
	(footprint ""
		(layer "F.Cu")
		(at 139.07897 -92.583 180)
		(property "Reference" "TP170"
			(at 0 0 180)
			(layer "F.SilkS")
			(hide yes)
			(effects
				(font
					(size 1.27 1.27)
				)
			)
		)
		(property "Value" "TPAD32-GP"
			(at 0 -3.166364 180)
			(unlocked yes)
			(layer "F.Fab")
			(hide yes)
			(effects
				(font
					(size 1.016 1.016)
					(thickness 0.1524)
				)
			)
		)
		(property "Device Type" "TPAD32"
			(at 0 -4.690618 180)
			(unlocked yes)
			(layer "F.Fab")
			(hide yes)
			(effects
				(font
					(size 1.016 1.016)
					(thickness 0.1524)
				)
			)
		)
		(duplicate_pad_numbers_are_jumpers no)
		(fp_poly
			(pts
				(arc
					(start -0.4064 0)
					(mid 0.4064 0)
					(end -0.4064 0)
				)
			)
			(stroke
				(width 0)
				(type default)
			)
			(fill no)
			(layer "F.CrtYd")
		)
		(fp_poly
			(pts
				(arc
					(start -0.7112 0)
					(mid 0.7112 0)
					(end -0.7112 0)
				)
			)
			(stroke
				(width 0)
				(type default)
			)
			(fill no)
			(layer "F.Fab")
		)
		(pad "1" smd circle
			(at 0 0 180)
			(size 0.8128 0.8128)
			(layers "F.Cu" "F.Mask" "F.Paste")
			(net "TEMP_3_ALERT")
		)
	)
	(footprint ""
		(layer "F.Cu")
		(at 329.302872 -172.030136 -90)
		(property "Reference" "U27"
			(at 0 0 270)
			(layer "F.SilkS")
			(hide yes)
			(effects
				(font
					(size 1.27 1.27)
				)
			)
		)
		(property "Value" "TS5A23157DGSR-GP"
			(at 0 -11.1252 270)
			(unlocked yes)
			(layer "F.Fab")
			(hide yes)
			(effects
				(font
					(size 1.016 1.016)
					(thickness 0.1524)
				)
			)
		)
		(property "Device Type" "MSOP10H44"
			(at 0 -12.6492 270)
			(unlocked yes)
			(layer "F.Fab")
			(hide yes)
			(effects
				(font
					(size 1.016 1.016)
					(thickness 0.1524)
				)
			)
		)
		(duplicate_pad_numbers_are_jumpers no)
		(fp_line
			(start -2.0066 1.016)
			(end -2.0066 -1.016)
			(stroke
				(width 0.1524)
				(type default)
			)
			(layer "F.SilkS")
		)
		(fp_line
			(start -1.8288 1.016)
			(end -1.8288 3.048)
			(stroke
				(width 0.508)
				(type default)
			)
			(layer "F.SilkS")
		)
		(fp_line
			(start 1.143 1.016)
			(end -2.0066 1.016)
			(stroke
				(width 0.1524)
				(type default)
			)
			(layer "F.SilkS")
		)
		(fp_line
			(start -1.5748 0)
			(end -1.9558 0.381)
			(stroke
				(width 0.1524)
				(type default)
			)
			(layer "F.SilkS")
		)
		(fp_line
			(start -1.5748 0)
			(end -1.9558 -0.381)
			(stroke
				(width 0.1524)
				(type default)
			)
			(layer "F.SilkS")
		)
		(fp_line
			(start -2.0066 -1.016)
			(end 1.143 -1.016)
			(stroke
				(width 0.1524)
				(type default)
			)
			(layer "F.SilkS")
		)
		(fp_line
			(start 1.143 -1.016)
			(end 1.143 1.016)
			(stroke
				(width 0.1524)
				(type default)
			)
			(layer "F.SilkS")
		)
		(fp_poly
			(pts
				(xy -2.0828 3.3401) (xy 2.0828 3.3401) (xy 2.0828 -3.3401) (xy -2.0828 -3.3401)
			)
			(stroke
				(width 0)
				(type default)
			)
			(fill no)
			(layer "F.CrtYd")
		)
		(fp_poly
			(pts
				(xy -2.0828 3.3401) (xy 2.0828 3.3401) (xy 2.0828 -3.3401) (xy -2.0828 -3.3401)
			)
			(stroke
				(width 0)
				(type default)
			)
			(fill no)
			(layer "F.Fab")
		)
		(pad "1" smd rect
			(at -0.99949 2.0701 270)
			(size 0.3048 1.524)
			(layers "F.Cu" "F.Mask" "F.Paste")
			(net "BMC_UART_SWITCH_1R")
		)
		(pad "2" smd rect
			(at -0.50038 2.0701 270)
			(size 0.3048 1.524)
			(layers "F.Cu" "F.Mask" "F.Paste")
			(net "EXP_UART_TX_R")
		)
		(pad "3" smd rect
			(at 0 2.0701 270)
			(size 0.3048 1.524)
			(layers "F.Cu" "F.Mask" "F.Paste")
			(net "GND")
		)
		(pad "4" smd rect
			(at 0.50038 2.0701 270)
			(size 0.3048 1.524)
			(layers "F.Cu" "F.Mask" "F.Paste")
			(net "EXP_UART_RX_R")
		)
		(pad "5" smd rect
			(at 0.99949 2.0701 270)
			(size 0.3048 1.524)
			(layers "F.Cu" "F.Mask" "F.Paste")
			(net "BMC_UART_SWITCH_1R")
		)
		(pad "6" smd rect
			(at 0.99949 -2.0701 270)
			(size 0.3048 1.524)
			(layers "F.Cu" "F.Mask" "F.Paste")
			(net "UART2_RX")
		)
		(pad "7" smd rect
			(at 0.50038 -2.0701 270)
			(size 0.3048 1.524)
			(layers "F.Cu" "F.Mask" "F.Paste")
			(net "BMC_RXD5")
		)
		(pad "8" smd rect
			(at 0 -2.0701 270)
			(size 0.3048 1.524)
			(layers "F.Cu" "F.Mask" "F.Paste")
			(net "P3V3_STBY")
		)
		(pad "9" smd rect
			(at -0.50038 -2.0701 270)
			(size 0.3048 1.524)
			(layers "F.Cu" "F.Mask" "F.Paste")
			(net "BMC_TXD5")
		)
		(pad "10" smd rect
			(at -0.99949 -2.0701 270)
			(size 0.3048 1.524)
			(layers "F.Cu" "F.Mask" "F.Paste")
			(net "UART2_TX")
		)
	)
	(footprint ""
		(layer "F.Cu")
		(at 277.994872 -221.433136 90)
		(property "Reference" "PR82"
			(at 0 0 90)
			(layer "F.SilkS")
			(hide yes)
			(effects
				(font
					(size 1.27 1.27)
				)
			)
		)
		(property "Value" "2K7R2J-GP"
			(at 0.064008 -3.993896 90)
			(unlocked yes)
			(layer "F.Fab")
			(hide yes)
			(effects
				(font
					(size 1.016 1.016)
					(thickness 0.1524)
				)
			)
		)
		(property "Device Type" "R402H16"
			(at 0.064008 -5.517896 90)
			(unlocked yes)
			(layer "F.Fab")
			(hide yes)
			(effects
				(font
					(size 1.016 1.016)
					(thickness 0.1524)
				)
			)
		)
		(duplicate_pad_numbers_are_jumpers no)
		(fp_line
			(start 0.508 -0.9398)
			(end -0.508 -0.9398)
			(stroke
				(width 0.1524)
				(type default)
			)
			(layer "F.SilkS")
		)
		(fp_line
			(start -0.508 -0.9398)
			(end -0.508 0.9398)
			(stroke
				(width 0.1524)
				(type default)
			)
			(layer "F.SilkS")
		)
		(fp_rect
			(start -0.508 0.9398)
			(end 0.508 -0.9398)
			(stroke
				(width 0)
				(type default)
			)
			(fill no)
			(layer "F.CrtYd")
		)
		(fp_rect
			(start -0.508 0.9398)
			(end 0.508 -0.9398)
			(stroke
				(width 0)
				(type default)
			)
			(fill no)
			(layer "F.Fab")
		)
		(pad "1" smd custom
			(at 0 -0.4445 90)
			(size 0.1397 0.1397)
			(layers "F.Cu" "F.Mask" "F.Paste")
			(net "P3V3_STBY")
			(options
				(clearance outline)
				(anchor circle)
			)
			(primitives
				(gr_poly
					(pts
						(arc
							(start -0.1778 -0.2794)
							(mid -0.249642 -0.249642)
							(end -0.2794 -0.1778)
						)
						(arc
							(start -0.2794 0.1778)
							(mid -0.249642 0.249642)
							(end -0.1778 0.2794)
						)
						(arc
							(start 0.1778 0.2794)
							(mid 0.249642 0.249642)
							(end 0.2794 0.1778)
						)
						(arc
							(start 0.2794 -0.1778)
							(mid 0.249642 -0.249642)
							(end 0.1778 -0.2794)
						)
					)
					(width 0)
					(fill yes)
				)
			)
		)
		(pad "2" smd custom
			(at 0 0.4445 90)
			(size 0.1397 0.1397)
			(layers "F.Cu" "F.Mask" "F.Paste")
			(net "P1V53_STBY_PG")
			(options
				(clearance outline)
				(anchor circle)
			)
			(primitives
				(gr_poly
					(pts
						(arc
							(start -0.1778 -0.2794)
							(mid -0.249642 -0.249642)
							(end -0.2794 -0.1778)
						)
						(arc
							(start -0.2794 0.1778)
							(mid -0.249642 0.249642)
							(end -0.1778 0.2794)
						)
						(arc
							(start 0.1778 0.2794)
							(mid 0.249642 0.249642)
							(end 0.2794 0.1778)
						)
						(arc
							(start 0.2794 -0.1778)
							(mid 0.249642 -0.249642)
							(end 0.1778 -0.2794)
						)
					)
					(width 0)
					(fill yes)
				)
			)
		)
	)
	(footprint ""
		(layer "F.Cu")
		(at 87.992966 -80.137)
		(property "Reference" "SC1197"
			(at 0 0 0)
			(layer "F.SilkS")
			(hide yes)
			(effects
				(font
					(size 1.27 1.27)
				)
			)
		)
		(property "Value" "SCD1U6D3V1KX-GP"
			(at -2.8321 -1.7399 0)
			(unlocked yes)
			(layer "F.Fab")
			(hide yes)
			(effects
				(font
					(size 1.016 1.016)
					(thickness 0.1524)
				)
			)
		)
		(property "Device Type" "C0201H13"
			(at -2.8321 -3.2639 0)
			(unlocked yes)
			(layer "F.Fab")
			(hide yes)
			(effects
				(font
					(size 1.016 1.016)
					(thickness 0.1524)
				)
			)
		)
		(duplicate_pad_numbers_are_jumpers no)
		(fp_rect
			(start -0.2794 0.6477)
			(end 0.2794 -0.6477)
			(stroke
				(width 0)
				(type default)
			)
			(fill no)
			(layer "F.CrtYd")
		)
		(fp_rect
			(start -0.2794 0.6477)
			(end 0.2794 -0.6477)
			(stroke
				(width 0)
				(type default)
			)
			(fill no)
			(layer "F.Fab")
		)
		(pad "1" smd custom
			(at 0 -0.2794)
			(size 0.0762 0.0762)
			(layers "F.Cu" "F.Mask" "F.Paste")
			(net "XTAL_VDDA09")
			(options
				(clearance outline)
				(anchor circle)
			)
			(primitives
				(gr_poly
					(pts
						(arc
							(start 0.1524 -0.127)
							(mid 0.137521 -0.162921)
							(end 0.1016 -0.1778)
						)
						(arc
							(start -0.1016 -0.1778)
							(mid -0.137521 -0.162921)
							(end -0.1524 -0.127)
						)
						(arc
							(start -0.1524 0.127)
							(mid -0.137521 0.162921)
							(end -0.1016 0.1778)
						)
						(arc
							(start 0.1016 0.1778)
							(mid 0.137521 0.162921)
							(end 0.1524 0.127)
						)
					)
					(width 0)
					(fill yes)
				)
			)
		)
		(pad "2" smd custom
			(at 0 0.2794)
			(size 0.0762 0.0762)
			(layers "F.Cu" "F.Mask" "F.Paste")
			(net "GND")
			(options
				(clearance outline)
				(anchor circle)
			)
			(primitives
				(gr_poly
					(pts
						(arc
							(start 0.1524 -0.127)
							(mid 0.137521 -0.162921)
							(end 0.1016 -0.1778)
						)
						(arc
							(start -0.1016 -0.1778)
							(mid -0.137521 -0.162921)
							(end -0.1524 -0.127)
						)
						(arc
							(start -0.1524 0.127)
							(mid -0.137521 0.162921)
							(end -0.1016 0.1778)
						)
						(arc
							(start 0.1016 0.1778)
							(mid 0.137521 0.162921)
							(end 0.1524 0.127)
						)
					)
					(width 0)
					(fill yes)
				)
			)
		)
	)
	(footprint ""
		(layer "F.Cu")
		(at 174.117 -129.921 90)
		(property "Reference" "PC173"
			(at 0 0 90)
			(layer "F.SilkS")
			(hide yes)
			(effects
				(font
					(size 1.27 1.27)
				)
			)
		)
		(property "Value" "SC22U25V5MX-GP"
			(at -0.0762 -6.1214 90)
			(unlocked yes)
			(layer "F.Fab")
			(hide yes)
			(effects
				(font
					(size 1.016 1.016)
					(thickness 0.1524)
				)
			)
		)
		(property "Device Type" "C805H58"
			(at -0.0762 -8.1534 90)
			(unlocked yes)
			(layer "F.Fab")
			(hide yes)
			(effects
				(font
					(size 1.016 1.016)
					(thickness 0.1524)
				)
			)
		)
		(duplicate_pad_numbers_are_jumpers no)
		(fp_line
			(start 0.635 0)
			(end -0.635 0)
			(stroke
				(width 0.508)
				(type default)
			)
			(layer "F.SilkS")
		)
		(fp_rect
			(start -0.9652 1.778)
			(end 0.9652 -1.778)
			(stroke
				(width 0)
				(type default)
			)
			(fill no)
			(layer "F.CrtYd")
		)
		(fp_poly
			(pts
				(xy -0.9652 -1.778) (xy 0.9652 -1.778) (xy 0.9652 1.778) (xy -0.9652 1.778)
			)
			(stroke
				(width 0)
				(type default)
			)
			(fill no)
			(layer "F.Fab")
		)
		(pad "1" smd rect
			(at 0 -0.9652 90)
			(size 1.397 1.143)
			(layers "F.Cu" "F.Mask" "F.Paste")
			(net "P0V9_E_VIN")
		)
		(pad "2" smd rect
			(at 0 0.9652 90)
			(size 1.397 1.143)
			(layers "F.Cu" "F.Mask" "F.Paste")
			(net "GND")
		)
	)
	(footprint ""
		(layer "F.Cu")
		(at 331.851 -217.17 -90)
		(property "Reference" "C146"
			(at 0 0 270)
			(layer "F.SilkS")
			(hide yes)
			(effects
				(font
					(size 1.27 1.27)
				)
			)
		)
		(property "Value" "SCD1U16V2KX-3GP"
			(at 1.1811 -2.7051 270)
			(unlocked yes)
			(layer "F.Fab")
			(hide yes)
			(effects
				(font
					(size 1.016 1.016)
					(thickness 0.1524)
				)
			)
		)
		(property "Device Type" "C402H22"
			(at 1.1811 -4.2291 270)
			(unlocked yes)
			(layer "F.Fab")
			(hide yes)
			(effects
				(font
					(size 1.016 1.016)
					(thickness 0.1524)
				)
			)
		)
		(duplicate_pad_numbers_are_jumpers no)
		(fp_rect
			(start -0.4318 0.9525)
			(end 0.4318 -0.9525)
			(stroke
				(width 0)
				(type default)
			)
			(fill no)
			(layer "F.CrtYd")
		)
		(fp_rect
			(start -0.4318 0.9525)
			(end 0.4318 -0.9525)
			(stroke
				(width 0)
				(type default)
			)
			(fill no)
			(layer "F.Fab")
		)
		(pad "1" smd custom
			(at 0 -0.4445 270)
			(size 0.1524 0.1524)
			(layers "F.Cu" "F.Mask" "F.Paste")
			(net "P3V3_STBY")
			(options
				(clearance outline)
				(anchor circle)
			)
			(primitives
				(gr_poly
					(pts
						(arc
							(start 0.3048 -0.2032)
							(mid 0.275042 -0.275042)
							(end 0.2032 -0.3048)
						)
						(arc
							(start -0.2032 -0.3048)
							(mid -0.275042 -0.275042)
							(end -0.3048 -0.2032)
						)
						(arc
							(start -0.3048 0.2032)
							(mid -0.275042 0.275042)
							(end -0.2032 0.3048)
						)
						(arc
							(start 0.2032 0.3048)
							(mid 0.275042 0.275042)
							(end 0.3048 0.2032)
						)
					)
					(width 0)
					(fill yes)
				)
			)
		)
		(pad "2" smd custom
			(at 0 0.4445 270)
			(size 0.1524 0.1524)
			(layers "F.Cu" "F.Mask" "F.Paste")
			(net "GND")
			(options
				(clearance outline)
				(anchor circle)
			)
			(primitives
				(gr_poly
					(pts
						(arc
							(start 0.3048 -0.2032)
							(mid 0.275042 -0.275042)
							(end 0.2032 -0.3048)
						)
						(arc
							(start -0.2032 -0.3048)
							(mid -0.275042 -0.275042)
							(end -0.3048 -0.2032)
						)
						(arc
							(start -0.3048 0.2032)
							(mid -0.275042 0.275042)
							(end -0.2032 0.3048)
						)
						(arc
							(start 0.2032 0.3048)
							(mid 0.275042 0.275042)
							(end 0.3048 0.2032)
						)
					)
					(width 0)
					(fill yes)
				)
			)
		)
	)
	(footprint ""
		(layer "F.Cu")
		(at 166.624 -155.8036 90)
		(property "Reference" "SR728"
			(at 0 0 90)
			(layer "F.SilkS")
			(hide yes)
			(effects
				(font
					(size 1.27 1.27)
				)
			)
		)
		(property "Value" "0R2J-2-GP"
			(at 0.064008 -3.993896 90)
			(unlocked yes)
			(layer "F.Fab")
			(hide yes)
			(effects
				(font
					(size 1.016 1.016)
					(thickness 0.1524)
				)
			)
		)
		(property "Device Type" "R402H16"
			(at 0.064008 -5.517896 90)
			(unlocked yes)
			(layer "F.Fab")
			(hide yes)
			(effects
				(font
					(size 1.016 1.016)
					(thickness 0.1524)
				)
			)
		)
		(duplicate_pad_numbers_are_jumpers no)
		(fp_line
			(start 0.508 -0.9398)
			(end -0.508 -0.9398)
			(stroke
				(width 0.1524)
				(type default)
			)
			(layer "F.SilkS")
		)
		(fp_line
			(start -0.508 -0.9398)
			(end -0.508 0.9398)
			(stroke
				(width 0.1524)
				(type default)
			)
			(layer "F.SilkS")
		)
		(fp_rect
			(start -0.508 0.9398)
			(end 0.508 -0.9398)
			(stroke
				(width 0)
				(type default)
			)
			(fill no)
			(layer "F.CrtYd")
		)
		(fp_rect
			(start -0.508 0.9398)
			(end 0.508 -0.9398)
			(stroke
				(width 0)
				(type default)
			)
			(fill no)
			(layer "F.Fab")
		)
		(pad "1" smd custom
			(at 0 -0.4445 90)
			(size 0.1397 0.1397)
			(layers "F.Cu" "F.Mask" "F.Paste")
			(net "EXP_IOC_BMC_R_SCL_14")
			(options
				(clearance outline)
				(anchor circle)
			)
			(primitives
				(gr_poly
					(pts
						(arc
							(start -0.1778 -0.2794)
							(mid -0.249642 -0.249642)
							(end -0.2794 -0.1778)
						)
						(arc
							(start -0.2794 0.1778)
							(mid -0.249642 0.249642)
							(end -0.1778 0.2794)
						)
						(arc
							(start 0.1778 0.2794)
							(mid 0.249642 0.249642)
							(end 0.2794 0.1778)
						)
						(arc
							(start 0.2794 -0.1778)
							(mid 0.249642 -0.249642)
							(end 0.1778 -0.2794)
						)
					)
					(width 0)
					(fill yes)
				)
			)
		)
		(pad "2" smd custom
			(at 0 0.4445 90)
			(size 0.1397 0.1397)
			(layers "F.Cu" "F.Mask" "F.Paste")
			(net "EXP_IOC_BMC_SCL_14")
			(options
				(clearance outline)
				(anchor circle)
			)
			(primitives
				(gr_poly
					(pts
						(arc
							(start -0.1778 -0.2794)
							(mid -0.249642 -0.249642)
							(end -0.2794 -0.1778)
						)
						(arc
							(start -0.2794 0.1778)
							(mid -0.249642 0.249642)
							(end -0.1778 0.2794)
						)
						(arc
							(start 0.1778 0.2794)
							(mid 0.249642 0.249642)
							(end 0.2794 0.1778)
						)
						(arc
							(start 0.2794 -0.1778)
							(mid 0.249642 -0.249642)
							(end 0.1778 -0.2794)
						)
					)
					(width 0)
					(fill yes)
				)
			)
		)
	)
	(footprint ""
		(layer "F.Cu")
		(at 184.785 -118.826788)
		(property "Reference" "U32"
			(at 0 0 0)
			(layer "F.SilkS")
			(hide yes)
			(effects
				(font
					(size 1.27 1.27)
				)
			)
		)
		(property "Value" "SN74LVC1G07DCKRG4-2-GP"
			(at -2.3368 -8.6868 0)
			(unlocked yes)
			(layer "F.Fab")
			(hide yes)
			(effects
				(font
					(size 1.016 1.016)
					(thickness 0.1524)
				)
			)
		)
		(property "Device Type" "SC70-5H44"
			(at -2.3114 -10.414 0)
			(unlocked yes)
			(layer "F.Fab")
			(hide yes)
			(effects
				(font
					(size 1.016 1.016)
					(thickness 0.1524)
				)
			)
		)
		(duplicate_pad_numbers_are_jumpers no)
		(fp_line
			(start -1.27 -1.7018)
			(end 1.27 -1.7018)
			(stroke
				(width 0.1524)
				(type default)
			)
			(layer "F.SilkS")
		)
		(fp_line
			(start -1.27 1.7018)
			(end -1.27 -1.7018)
			(stroke
				(width 0.1524)
				(type default)
			)
			(layer "F.SilkS")
		)
		(fp_line
			(start 0.6604 -1.8034)
			(end 1.3843 -1.8034)
			(stroke
				(width 0.3302)
				(type default)
			)
			(layer "F.SilkS")
		)
		(fp_line
			(start 1.27 -1.7018)
			(end 1.27 1.7018)
			(stroke
				(width 0.1524)
				(type default)
			)
			(layer "F.SilkS")
		)
		(fp_line
			(start 1.27 1.7018)
			(end -1.27 1.7018)
			(stroke
				(width 0.1524)
				(type default)
			)
			(layer "F.SilkS")
		)
		(fp_line
			(start 1.3843 -1.8034)
			(end 1.3843 -1.1176)
			(stroke
				(width 0.3302)
				(type default)
			)
			(layer "F.SilkS")
		)
		(fp_rect
			(start -1.524 1.9558)
			(end 1.524 -1.9558)
			(stroke
				(width 0)
				(type default)
			)
			(fill no)
			(layer "F.CrtYd")
		)
		(fp_poly
			(pts
				(xy -1.524 -1.9558) (xy 1.524 -1.9558) (xy 1.524 1.9558) (xy -1.524 1.9558)
			)
			(stroke
				(width 0)
				(type default)
			)
			(fill no)
			(layer "F.Fab")
		)
		(pad "1" smd rect
			(at 0.65024 -0.8255)
			(size 0.4064 1.2192)
			(layers "F.Cu" "F.Mask" "F.Paste")
			(net "Net_215")
		)
		(pad "2" smd rect
			(at 0 -0.8255)
			(size 0.4064 1.2192)
			(layers "F.Cu" "F.Mask" "F.Paste")
			(net "PMU_PLTRST#")
		)
		(pad "3" smd rect
			(at -0.65024 -0.8255)
			(size 0.4064 1.2192)
			(layers "F.Cu" "F.Mask" "F.Paste")
			(net "GND")
		)
		(pad "4" smd rect
			(at -0.65024 0.8255)
			(size 0.4064 1.2192)
			(layers "F.Cu" "F.Mask" "F.Paste")
			(net "PMU_PLTRST_N")
		)
		(pad "5" smd rect
			(at 0.65024 0.8255)
			(size 0.4064 1.2192)
			(layers "F.Cu" "F.Mask" "F.Paste")
			(net "P3V3_STBY")
		)
	)
	(footprint ""
		(layer "F.Cu")
		(at 91.929966 -63.119)
		(property "Reference" "SR674"
			(at 0 0 0)
			(layer "F.SilkS")
			(hide yes)
			(effects
				(font
					(size 1.27 1.27)
				)
			)
		)
		(property "Value" "4K7R2F-GP"
			(at 0.064008 -3.993896 0)
			(unlocked yes)
			(layer "F.Fab")
			(hide yes)
			(effects
				(font
					(size 1.016 1.016)
					(thickness 0.1524)
				)
			)
		)
		(property "Device Type" "R402H16"
			(at 0.064008 -5.517896 0)
			(unlocked yes)
			(layer "F.Fab")
			(hide yes)
			(effects
				(font
					(size 1.016 1.016)
					(thickness 0.1524)
				)
			)
		)
		(duplicate_pad_numbers_are_jumpers no)
		(fp_line
			(start -0.508 -0.9398)
			(end -0.508 0.9398)
			(stroke
				(width 0.1524)
				(type default)
			)
			(layer "F.SilkS")
		)
		(fp_line
			(start 0.508 -0.9398)
			(end -0.508 -0.9398)
			(stroke
				(width 0.1524)
				(type default)
			)
			(layer "F.SilkS")
		)
		(fp_rect
			(start -0.508 0.9398)
			(end 0.508 -0.9398)
			(stroke
				(width 0)
				(type default)
			)
			(fill no)
			(layer "F.CrtYd")
		)
		(fp_rect
			(start -0.508 0.9398)
			(end 0.508 -0.9398)
			(stroke
				(width 0)
				(type default)
			)
			(fill no)
			(layer "F.Fab")
		)
		(pad "1" smd custom
			(at 0 -0.4445)
			(size 0.1397 0.1397)
			(layers "F.Cu" "F.Mask" "F.Paste")
			(net "P1V8_C")
			(options
				(clearance outline)
				(anchor circle)
			)
			(primitives
				(gr_poly
					(pts
						(arc
							(start -0.1778 -0.2794)
							(mid -0.249642 -0.249642)
							(end -0.2794 -0.1778)
						)
						(arc
							(start -0.2794 0.1778)
							(mid -0.249642 0.249642)
							(end -0.1778 0.2794)
						)
						(arc
							(start 0.1778 0.2794)
							(mid 0.249642 0.249642)
							(end 0.2794 0.1778)
						)
						(arc
							(start 0.2794 -0.1778)
							(mid 0.249642 -0.249642)
							(end 0.1778 -0.2794)
						)
					)
					(width 0)
					(fill yes)
				)
			)
		)
		(pad "2" smd custom
			(at 0 0.4445)
			(size 0.1397 0.1397)
			(layers "F.Cu" "F.Mask" "F.Paste")
			(net "ICE1_TMS")
			(options
				(clearance outline)
				(anchor circle)
			)
			(primitives
				(gr_poly
					(pts
						(arc
							(start -0.1778 -0.2794)
							(mid -0.249642 -0.249642)
							(end -0.2794 -0.1778)
						)
						(arc
							(start -0.2794 0.1778)
							(mid -0.249642 0.249642)
							(end -0.1778 0.2794)
						)
						(arc
							(start 0.1778 0.2794)
							(mid 0.249642 0.249642)
							(end 0.2794 0.1778)
						)
						(arc
							(start 0.2794 -0.1778)
							(mid 0.249642 -0.249642)
							(end 0.1778 -0.2794)
						)
					)
					(width 0)
					(fill yes)
				)
			)
		)
	)
	(footprint ""
		(layer "F.Cu")
		(at 334.518 -83.947 180)
		(property "Reference" "R294"
			(at 0 0 180)
			(layer "F.SilkS")
			(hide yes)
			(effects
				(font
					(size 1.27 1.27)
				)
			)
		)
		(property "Value" "0R0402-PAD-1-GP"
			(at 0.064008 -3.993896 180)
			(unlocked yes)
			(layer "F.Fab")
			(hide yes)
			(effects
				(font
					(size 1.016 1.016)
					(thickness 0.1524)
				)
			)
		)
		(property "Device Type" "0R0402-PAD"
			(at 0.064008 -5.517896 180)
			(unlocked yes)
			(layer "F.Fab")
			(hide yes)
			(effects
				(font
					(size 1.016 1.016)
					(thickness 0.1524)
				)
			)
		)
		(duplicate_pad_numbers_are_jumpers no)
		(fp_line
			(start 0.508 -0.9398)
			(end -0.508 -0.9398)
			(stroke
				(width 0.1524)
				(type default)
			)
			(layer "F.SilkS")
		)
		(fp_line
			(start -0.508 -0.9398)
			(end -0.508 0.9398)
			(stroke
				(width 0.1524)
				(type default)
			)
			(layer "F.SilkS")
		)
		(fp_rect
			(start -0.508 0.9398)
			(end 0.508 -0.9398)
			(stroke
				(width 0)
				(type default)
			)
			(fill no)
			(layer "F.CrtYd")
		)
		(fp_rect
			(start -0.508 0.9398)
			(end 0.508 -0.9398)
			(stroke
				(width 0)
				(type default)
			)
			(fill no)
			(layer "F.Fab")
		)
		(pad "1" smd custom
			(at 0 -0.4445 180)
			(size 0.1397 0.1397)
			(layers "F.Cu" "F.Mask" "F.Paste")
			(net "ROMD2_R")
			(options
				(clearance outline)
				(anchor circle)
			)
			(primitives
				(gr_poly
					(pts
						(xy -0.2794 0.3683)
						(arc
							(start -0.2794 -0.2667)
							(mid -0.249642 -0.338542)
							(end -0.1778 -0.3683)
						)
						(arc
							(start 0.1778 -0.3683)
							(mid 0.249642 -0.338542)
							(end 0.2794 -0.2667)
						)
						(xy 0.2794 0.3683)
					)
					(width 0)
					(fill yes)
				)
			)
		)
		(pad "2" smd custom
			(at 0 0.4445 180)
			(size 0.1397 0.1397)
			(layers "F.Cu" "F.Mask" "F.Paste")
			(net "ROMD2")
			(options
				(clearance outline)
				(anchor circle)
			)
			(primitives
				(gr_poly
					(pts
						(arc
							(start -0.1778 0.3683)
							(mid -0.249642 0.338542)
							(end -0.2794 0.2667)
						)
						(xy -0.2794 -0.3683) (xy 0.2794 -0.3683)
						(arc
							(start 0.2794 0.2667)
							(mid 0.249642 0.338542)
							(end 0.1778 0.3683)
						)
					)
					(width 0)
					(fill yes)
				)
			)
		)
	)
	(footprint ""
		(layer "F.Cu")
		(at 306.578 -205.105)
		(property "Reference" "R5300"
			(at 0 0 0)
			(layer "F.SilkS")
			(hide yes)
			(effects
				(font
					(size 1.27 1.27)
				)
			)
		)
		(property "Value" "0R2J-2-GP"
			(at 0.064008 -3.993896 0)
			(unlocked yes)
			(layer "F.Fab")
			(hide yes)
			(effects
				(font
					(size 1.016 1.016)
					(thickness 0.1524)
				)
			)
		)
		(property "Device Type" "R402H16"
			(at 0.064008 -5.517896 0)
			(unlocked yes)
			(layer "F.Fab")
			(hide yes)
			(effects
				(font
					(size 1.016 1.016)
					(thickness 0.1524)
				)
			)
		)
		(duplicate_pad_numbers_are_jumpers no)
		(fp_line
			(start -0.508 -0.9398)
			(end -0.508 0.9398)
			(stroke
				(width 0.1524)
				(type default)
			)
			(layer "F.SilkS")
		)
		(fp_line
			(start 0.508 -0.9398)
			(end -0.508 -0.9398)
			(stroke
				(width 0.1524)
				(type default)
			)
			(layer "F.SilkS")
		)
		(fp_rect
			(start -0.508 0.9398)
			(end 0.508 -0.9398)
			(stroke
				(width 0)
				(type default)
			)
			(fill no)
			(layer "F.CrtYd")
		)
		(fp_rect
			(start -0.508 0.9398)
			(end 0.508 -0.9398)
			(stroke
				(width 0)
				(type default)
			)
			(fill no)
			(layer "F.Fab")
		)
		(pad "1" smd custom
			(at 0 -0.4445)
			(size 0.1397 0.1397)
			(layers "F.Cu" "F.Mask" "F.Paste")
			(net "BMC_I2C_SDA_10")
			(options
				(clearance outline)
				(anchor circle)
			)
			(primitives
				(gr_poly
					(pts
						(arc
							(start -0.1778 -0.2794)
							(mid -0.249642 -0.249642)
							(end -0.2794 -0.1778)
						)
						(arc
							(start -0.2794 0.1778)
							(mid -0.249642 0.249642)
							(end -0.1778 0.2794)
						)
						(arc
							(start 0.1778 0.2794)
							(mid 0.249642 0.249642)
							(end 0.2794 0.1778)
						)
						(arc
							(start 0.2794 -0.1778)
							(mid 0.249642 -0.249642)
							(end 0.1778 -0.2794)
						)
					)
					(width 0)
					(fill yes)
				)
			)
		)
		(pad "2" smd custom
			(at 0 0.4445)
			(size 0.1397 0.1397)
			(layers "F.Cu" "F.Mask" "F.Paste")
			(net "LED_DR_I2C_SDA")
			(options
				(clearance outline)
				(anchor circle)
			)
			(primitives
				(gr_poly
					(pts
						(arc
							(start -0.1778 -0.2794)
							(mid -0.249642 -0.249642)
							(end -0.2794 -0.1778)
						)
						(arc
							(start -0.2794 0.1778)
							(mid -0.249642 0.249642)
							(end -0.1778 0.2794)
						)
						(arc
							(start 0.1778 0.2794)
							(mid 0.249642 0.249642)
							(end 0.2794 0.1778)
						)
						(arc
							(start 0.2794 -0.1778)
							(mid 0.249642 -0.249642)
							(end 0.1778 -0.2794)
						)
					)
					(width 0)
					(fill yes)
				)
			)
		)
	)
	(footprint ""
		(layer "F.Cu")
		(at 266.065 -180.086 90)
		(property "Reference" "R341"
			(at 0 0 90)
			(layer "F.SilkS")
			(hide yes)
			(effects
				(font
					(size 1.27 1.27)
				)
			)
		)
		(property "Value" "3K3R2F-2-GP"
			(at 0.064008 -3.993896 90)
			(unlocked yes)
			(layer "F.Fab")
			(hide yes)
			(effects
				(font
					(size 1.016 1.016)
					(thickness 0.1524)
				)
			)
		)
		(property "Device Type" "R402H16"
			(at 0.064008 -5.517896 90)
			(unlocked yes)
			(layer "F.Fab")
			(hide yes)
			(effects
				(font
					(size 1.016 1.016)
					(thickness 0.1524)
				)
			)
		)
		(duplicate_pad_numbers_are_jumpers no)
		(fp_line
			(start 0.508 -0.9398)
			(end -0.508 -0.9398)
			(stroke
				(width 0.1524)
				(type default)
			)
			(layer "F.SilkS")
		)
		(fp_line
			(start -0.508 -0.9398)
			(end -0.508 0.9398)
			(stroke
				(width 0.1524)
				(type default)
			)
			(layer "F.SilkS")
		)
		(fp_rect
			(start -0.508 0.9398)
			(end 0.508 -0.9398)
			(stroke
				(width 0)
				(type default)
			)
			(fill no)
			(layer "F.CrtYd")
		)
		(fp_rect
			(start -0.508 0.9398)
			(end 0.508 -0.9398)
			(stroke
				(width 0)
				(type default)
			)
			(fill no)
			(layer "F.Fab")
		)
		(pad "1" smd custom
			(at 0 -0.4445 90)
			(size 0.1397 0.1397)
			(layers "F.Cu" "F.Mask" "F.Paste")
			(net "P3V3_STBY")
			(options
				(clearance outline)
				(anchor circle)
			)
			(primitives
				(gr_poly
					(pts
						(arc
							(start -0.1778 -0.2794)
							(mid -0.249642 -0.249642)
							(end -0.2794 -0.1778)
						)
						(arc
							(start -0.2794 0.1778)
							(mid -0.249642 0.249642)
							(end -0.1778 0.2794)
						)
						(arc
							(start 0.1778 0.2794)
							(mid 0.249642 0.249642)
							(end 0.2794 0.1778)
						)
						(arc
							(start 0.2794 -0.1778)
							(mid 0.249642 -0.249642)
							(end 0.1778 -0.2794)
						)
					)
					(width 0)
					(fill yes)
				)
			)
		)
		(pad "2" smd custom
			(at 0 0.4445 90)
			(size 0.1397 0.1397)
			(layers "F.Cu" "F.Mask" "F.Paste")
			(net "ROMA16")
			(options
				(clearance outline)
				(anchor circle)
			)
			(primitives
				(gr_poly
					(pts
						(arc
							(start -0.1778 -0.2794)
							(mid -0.249642 -0.249642)
							(end -0.2794 -0.1778)
						)
						(arc
							(start -0.2794 0.1778)
							(mid -0.249642 0.249642)
							(end -0.1778 0.2794)
						)
						(arc
							(start 0.1778 0.2794)
							(mid 0.249642 0.249642)
							(end 0.2794 0.1778)
						)
						(arc
							(start 0.2794 -0.1778)
							(mid 0.249642 -0.249642)
							(end 0.1778 -0.2794)
						)
					)
					(width 0)
					(fill yes)
				)
			)
		)
	)
	(footprint ""
		(layer "F.Cu")
		(at 183.896 -122.047)
		(property "Reference" "C329"
			(at 0 0 0)
			(layer "F.SilkS")
			(hide yes)
			(effects
				(font
					(size 1.27 1.27)
				)
			)
		)
		(property "Value" "SCD1U25V2KX-2-GP"
			(at 1.1811 -2.7051 0)
			(unlocked yes)
			(layer "F.Fab")
			(hide yes)
			(effects
				(font
					(size 1.016 1.016)
					(thickness 0.1524)
				)
			)
		)
		(property "Device Type" "C402H22"
			(at 1.1811 -4.2291 0)
			(unlocked yes)
			(layer "F.Fab")
			(hide yes)
			(effects
				(font
					(size 1.016 1.016)
					(thickness 0.1524)
				)
			)
		)
		(duplicate_pad_numbers_are_jumpers no)
		(fp_rect
			(start -0.4318 0.9525)
			(end 0.4318 -0.9525)
			(stroke
				(width 0)
				(type default)
			)
			(fill no)
			(layer "F.CrtYd")
		)
		(fp_rect
			(start -0.4318 0.9525)
			(end 0.4318 -0.9525)
			(stroke
				(width 0)
				(type default)
			)
			(fill no)
			(layer "F.Fab")
		)
		(pad "1" smd custom
			(at 0 -0.4445)
			(size 0.1524 0.1524)
			(layers "F.Cu" "F.Mask" "F.Paste")
			(net "P3V3_STBY")
			(options
				(clearance outline)
				(anchor circle)
			)
			(primitives
				(gr_poly
					(pts
						(arc
							(start 0.3048 -0.2032)
							(mid 0.275042 -0.275042)
							(end 0.2032 -0.3048)
						)
						(arc
							(start -0.2032 -0.3048)
							(mid -0.275042 -0.275042)
							(end -0.3048 -0.2032)
						)
						(arc
							(start -0.3048 0.2032)
							(mid -0.275042 0.275042)
							(end -0.2032 0.3048)
						)
						(arc
							(start 0.2032 0.3048)
							(mid 0.275042 0.275042)
							(end 0.3048 0.2032)
						)
					)
					(width 0)
					(fill yes)
				)
			)
		)
		(pad "2" smd custom
			(at 0 0.4445)
			(size 0.1524 0.1524)
			(layers "F.Cu" "F.Mask" "F.Paste")
			(net "GND")
			(options
				(clearance outline)
				(anchor circle)
			)
			(primitives
				(gr_poly
					(pts
						(arc
							(start 0.3048 -0.2032)
							(mid 0.275042 -0.275042)
							(end 0.2032 -0.3048)
						)
						(arc
							(start -0.2032 -0.3048)
							(mid -0.275042 -0.275042)
							(end -0.3048 -0.2032)
						)
						(arc
							(start -0.3048 0.2032)
							(mid -0.275042 0.275042)
							(end -0.2032 0.3048)
						)
						(arc
							(start 0.2032 0.3048)
							(mid 0.275042 0.275042)
							(end 0.3048 0.2032)
						)
					)
					(width 0)
					(fill yes)
				)
			)
		)
	)
	(footprint ""
		(layer "F.Cu")
		(at 264.541 -26.797 -90)
		(property "Reference" "PC55"
			(at 0 0 270)
			(layer "F.SilkS")
			(hide yes)
			(effects
				(font
					(size 1.27 1.27)
				)
			)
		)
		(property "Value" "SCD1U16V3KX-3GP"
			(at 0 -2.8194 270)
			(unlocked yes)
			(layer "F.Fab")
			(hide yes)
			(effects
				(font
					(size 1.016 1.016)
					(thickness 0.1524)
				)
			)
		)
		(property "Device Type" "C603H36"
			(at 0 -4.3434 270)
			(unlocked yes)
			(layer "F.Fab")
			(hide yes)
			(effects
				(font
					(size 1.016 1.016)
					(thickness 0.1524)
				)
			)
		)
		(duplicate_pad_numbers_are_jumpers no)
		(fp_line
			(start 0.508 0)
			(end -0.508 0)
			(stroke
				(width 0.2032)
				(type default)
			)
			(layer "F.SilkS")
		)
		(fp_rect
			(start -0.5842 1.3335)
			(end 0.5842 -1.3335)
			(stroke
				(width 0)
				(type default)
			)
			(fill no)
			(layer "F.CrtYd")
		)
		(fp_rect
			(start -0.5842 1.3335)
			(end 0.5842 -1.3335)
			(stroke
				(width 0)
				(type default)
			)
			(fill no)
			(layer "F.Fab")
		)
		(pad "1" smd custom
			(at 0 -0.762 270)
			(size 0.2159 0.2159)
			(layers "F.Cu" "F.Mask" "F.Paste")
			(net "P1V8_STBY")
			(options
				(clearance outline)
				(anchor circle)
			)
			(primitives
				(gr_poly
					(pts
						(arc
							(start -0.3302 -0.4318)
							(mid -0.402042 -0.402042)
							(end -0.4318 -0.3302)
						)
						(arc
							(start -0.4318 0.3302)
							(mid -0.402042 0.402042)
							(end -0.3302 0.4318)
						)
						(arc
							(start 0.3302 0.4318)
							(mid 0.402042 0.402042)
							(end 0.4318 0.3302)
						)
						(arc
							(start 0.4318 -0.3302)
							(mid 0.402042 -0.402042)
							(end 0.3302 -0.4318)
						)
					)
					(width 0)
					(fill yes)
				)
			)
		)
		(pad "2" smd custom
			(at 0 0.762 270)
			(size 0.2159 0.2159)
			(layers "F.Cu" "F.Mask" "F.Paste")
			(net "GND")
			(options
				(clearance outline)
				(anchor circle)
			)
			(primitives
				(gr_poly
					(pts
						(arc
							(start -0.3302 -0.4318)
							(mid -0.402042 -0.402042)
							(end -0.4318 -0.3302)
						)
						(arc
							(start -0.4318 0.3302)
							(mid -0.402042 0.402042)
							(end -0.3302 0.4318)
						)
						(arc
							(start 0.3302 0.4318)
							(mid 0.402042 0.402042)
							(end 0.4318 0.3302)
						)
						(arc
							(start 0.4318 -0.3302)
							(mid 0.402042 -0.402042)
							(end 0.3302 -0.4318)
						)
					)
					(width 0)
					(fill yes)
				)
			)
		)
	)
	(footprint ""
		(layer "F.Cu")
		(at 51.308 -204.978 -90)
		(property "Reference" "Q93"
			(at 0 0 270)
			(layer "F.SilkS")
			(hide yes)
			(effects
				(font
					(size 1.27 1.27)
				)
			)
		)
		(property "Value" "2N7002A-7-GP"
			(at 0.127 -8.9662 270)
			(unlocked yes)
			(layer "F.Fab")
			(hide yes)
			(effects
				(font
					(size 1.016 1.016)
					(thickness 0.1524)
				)
			)
		)
		(property "Device Type" "SOT23DGS2D4H48"
			(at 0.127 -10.4902 270)
			(unlocked yes)
			(layer "F.Fab")
			(hide yes)
			(effects
				(font
					(size 1.016 1.016)
					(thickness 0.1524)
				)
			)
		)
		(duplicate_pad_numbers_are_jumpers no)
		(fp_line
			(start -1.651 1.778)
			(end 1.651 1.778)
			(stroke
				(width 0.1524)
				(type default)
			)
			(layer "F.SilkS")
		)
		(fp_line
			(start 1.651 1.778)
			(end 1.651 -1.778)
			(stroke
				(width 0.1524)
				(type default)
			)
			(layer "F.SilkS")
		)
		(fp_line
			(start -1.651 -1.778)
			(end -1.651 1.778)
			(stroke
				(width 0.1524)
				(type default)
			)
			(layer "F.SilkS")
		)
		(fp_line
			(start 1.651 -1.778)
			(end -1.651 -1.778)
			(stroke
				(width 0.1524)
				(type default)
			)
			(layer "F.SilkS")
		)
		(fp_poly
			(pts
				(xy -1.778 1.8796) (xy -1.778 -1.8796) (xy 1.778 -1.8796) (xy 1.778 1.8796)
			)
			(stroke
				(width 0)
				(type default)
			)
			(fill no)
			(layer "F.CrtYd")
		)
		(fp_poly
			(pts
				(xy -1.778 1.8796) (xy -1.778 -1.8796) (xy 1.778 -1.8796) (xy 1.778 1.8796)
			)
			(stroke
				(width 0)
				(type default)
			)
			(fill no)
			(layer "F.Fab")
		)
		(pad "D" smd custom
			(at 0 -0.9525 270)
			(size 0.1905 0.1905)
			(layers "F.Cu" "F.Mask" "F.Paste")
			(net "MATED_P12V_EN")
			(options
				(clearance outline)
				(anchor circle)
			)
			(primitives
				(gr_poly
					(pts
						(arc
							(start -0.1778 0.5715)
							(mid -0.321484 0.511984)
							(end -0.381 0.3683)
						)
						(arc
							(start -0.381 -0.3683)
							(mid -0.321484 -0.511984)
							(end -0.1778 -0.5715)
						)
						(arc
							(start 0.1778 -0.5715)
							(mid 0.321484 -0.511984)
							(end 0.381 -0.3683)
						)
						(arc
							(start 0.381 0.3683)
							(mid 0.321484 0.511984)
							(end 0.1778 0.5715)
						)
					)
					(width 0)
					(fill yes)
				)
			)
		)
		(pad "G" smd custom
			(at -0.98425 0.9525 270)
			(size 0.1905 0.1905)
			(layers "F.Cu" "F.Mask" "F.Paste")
			(net "PCIE_MATED#_B")
			(options
				(clearance outline)
				(anchor circle)
			)
			(primitives
				(gr_poly
					(pts
						(arc
							(start -0.1778 0.5715)
							(mid -0.321484 0.511984)
							(end -0.381 0.3683)
						)
						(arc
							(start -0.381 -0.3683)
							(mid -0.321484 -0.511984)
							(end -0.1778 -0.5715)
						)
						(arc
							(start 0.1778 -0.5715)
							(mid 0.321484 -0.511984)
							(end 0.381 -0.3683)
						)
						(arc
							(start 0.381 0.3683)
							(mid 0.321484 0.511984)
							(end 0.1778 0.5715)
						)
					)
					(width 0)
					(fill yes)
				)
			)
		)
		(pad "S" smd custom
			(at 0.98425 0.9525 270)
			(size 0.1905 0.1905)
			(layers "F.Cu" "F.Mask" "F.Paste")
			(net "GND")
			(options
				(clearance outline)
				(anchor circle)
			)
			(primitives
				(gr_poly
					(pts
						(arc
							(start -0.1778 0.5715)
							(mid -0.321484 0.511984)
							(end -0.381 0.3683)
						)
						(arc
							(start -0.381 -0.3683)
							(mid -0.321484 -0.511984)
							(end -0.1778 -0.5715)
						)
						(arc
							(start 0.1778 -0.5715)
							(mid 0.321484 -0.511984)
							(end 0.381 -0.3683)
						)
						(arc
							(start 0.381 0.3683)
							(mid 0.321484 0.511984)
							(end 0.1778 0.5715)
						)
					)
					(width 0)
					(fill yes)
				)
			)
		)
	)
	(footprint ""
		(layer "F.Cu")
		(at 199.840596 -114.573812)
		(property "Reference" "PU100"
			(at 0 0 0)
			(layer "F.SilkS")
			(hide yes)
			(effects
				(font
					(size 1.27 1.27)
				)
			)
		)
		(property "Value" "TPS53312RGTR-GP"
			(at 4.9784 -6.9342 0)
			(unlocked yes)
			(layer "F.Fab")
			(hide yes)
			(effects
				(font
					(size 1.016 1.016)
					(thickness 0.1524)
				)
			)
		)
		(property "Device Type" "QFN16G3-G1D7H40"
			(at 4.9784 -8.4582 0)
			(unlocked yes)
			(layer "F.Fab")
			(hide yes)
			(effects
				(font
					(size 1.016 1.016)
					(thickness 0.1524)
				)
			)
		)
		(duplicate_pad_numbers_are_jumpers no)
		(fp_line
			(start -2.5146 -2.5146)
			(end -2.5146 -1.2446)
			(stroke
				(width 0.1524)
				(type default)
			)
			(layer "F.SilkS")
		)
		(fp_line
			(start -2.5146 1.2446)
			(end -2.5146 2.5146)
			(stroke
				(width 0.1524)
				(type default)
			)
			(layer "F.SilkS")
		)
		(fp_line
			(start -2.5146 2.5146)
			(end -1.2446 2.5146)
			(stroke
				(width 0.1524)
				(type default)
			)
			(layer "F.SilkS")
		)
		(fp_line
			(start -2.262124 -0.750062)
			(end -2.770124 -0.750062)
			(stroke
				(width 0.1524)
				(type default)
			)
			(layer "F.SilkS")
		)
		(fp_line
			(start -1.2446 -2.5146)
			(end -2.5146 -2.5146)
			(stroke
				(width 0.1524)
				(type default)
			)
			(layer "F.SilkS")
		)
		(fp_line
			(start -0.249936 2.262124)
			(end -0.249936 3.024124)
			(stroke
				(width 0.1524)
				(type default)
			)
			(layer "F.SilkS")
		)
		(fp_line
			(start 1.2446 2.5146)
			(end 2.5146 2.5146)
			(stroke
				(width 0.1524)
				(type default)
			)
			(layer "F.SilkS")
		)
		(fp_line
			(start 2.262124 -0.249936)
			(end 2.770124 -0.249936)
			(stroke
				(width 0.1524)
				(type default)
			)
			(layer "F.SilkS")
		)
		(fp_line
			(start 2.5146 2.5146)
			(end 2.5146 1.2446)
			(stroke
				(width 0.1524)
				(type default)
			)
			(layer "F.SilkS")
		)
		(fp_poly
			(pts
				(xy 2.5146 -2.5146) (xy 1.2446 -2.5146) (xy 2.5146 -1.2446)
			)
			(stroke
				(width 0)
				(type default)
			)
			(fill yes)
			(layer "F.SilkS")
		)
		(fp_rect
			(start -1.4986 1.4986)
			(end 1.4986 -1.4986)
			(stroke
				(width 0)
				(type default)
			)
			(fill no)
			(layer "F.CrtYd")
		)
		(fp_poly
			(pts
				(xy 2.5146 -1.4986) (xy -1.4986 -1.4986) (xy -1.4986 1.4986) (xy 1.4986 1.4986) (xy 1.4986 -1.4859)
				(xy 2.5146 -1.4859) (xy 2.5146 2.5146) (xy -2.5146 2.5146) (xy -2.5146 -2.5146) (xy 2.5146 -2.5146)
			)
			(stroke
				(width 0)
				(type default)
			)
			(fill no)
			(layer "F.CrtYd")
		)
		(fp_rect
			(start -2.5146 2.5146)
			(end 2.5146 -2.5146)
			(stroke
				(width 0)
				(type default)
			)
			(fill no)
			(layer "F.Fab")
		)
		(pad "1" smd rect
			(at 0.750062 -1.550924)
			(size 0.3048 0.9144)
			(layers "F.Cu" "F.Mask" "F.Paste")
			(net "P1V5_E_VFB")
		)
		(pad "2" smd rect
			(at 0.249936 -1.538224)
			(size 0.3048 0.9398)
			(layers "F.Cu" "F.Mask" "F.Paste")
			(net "P1V5_E_VRG5")
		)
		(pad "3" smd rect
			(at -0.249936 -1.538224)
			(size 0.3048 0.9398)
			(layers "F.Cu" "F.Mask" "F.Paste")
			(net "P1V5_E_SS")
		)
		(pad "4" smd rect
			(at -0.750062 -1.550924)
			(size 0.3048 0.9144)
			(layers "F.Cu" "F.Mask" "F.Paste")
			(net "AGND_P1V5_E")
		)
		(pad "5" smd rect
			(at -1.550924 -0.750062)
			(size 0.9144 0.3048)
			(layers "F.Cu" "F.Mask" "F.Paste")
			(net "P1V5_E_PG")
		)
		(pad "6" smd rect
			(at -1.538224 -0.249936)
			(size 0.9398 0.3048)
			(layers "F.Cu" "F.Mask" "F.Paste")
			(net "P1V5_E_EN_R")
		)
		(pad "7" smd rect
			(at -1.538224 0.249936)
			(size 0.9398 0.3048)
			(layers "F.Cu" "F.Mask" "F.Paste")
			(net "GND")
		)
		(pad "8" smd rect
			(at -1.550924 0.750062)
			(size 0.9144 0.3048)
			(layers "F.Cu" "F.Mask" "F.Paste")
			(net "GND")
		)
		(pad "9" smd rect
			(at -0.750062 1.550924)
			(size 0.3048 0.9144)
			(layers "F.Cu" "F.Mask" "F.Paste")
			(net "P1V5_E_SW")
		)
		(pad "10" smd rect
			(at -0.249936 1.538224)
			(size 0.3048 0.9398)
			(layers "F.Cu" "F.Mask" "F.Paste")
			(net "P1V5_E_SW")
		)
		(pad "11" smd rect
			(at 0.249936 1.538224)
			(size 0.3048 0.9398)
			(layers "F.Cu" "F.Mask" "F.Paste")
			(net "P1V5_E_SW")
		)
		(pad "12" smd rect
			(at 0.750062 1.550924)
			(size 0.3048 0.9144)
			(layers "F.Cu" "F.Mask" "F.Paste")
			(net "P1V5_E_VBST")
		)
		(pad "13" smd rect
			(at 1.550924 0.750062)
			(size 0.9144 0.3048)
			(layers "F.Cu" "F.Mask" "F.Paste")
			(net "P1V5_E_VIN")
		)
		(pad "14" smd rect
			(at 1.538224 0.249936)
			(size 0.9398 0.3048)
			(layers "F.Cu" "F.Mask" "F.Paste")
			(net "P1V5_E_VIN")
		)
		(pad "15" smd rect
			(at 1.538224 -0.249936)
			(size 0.9398 0.3048)
			(layers "F.Cu" "F.Mask" "F.Paste")
			(net "P1V5_E_VCC")
		)
		(pad "16" smd rect
			(at 1.550924 -0.750062)
			(size 0.9144 0.3048)
			(layers "F.Cu" "F.Mask" "F.Paste")
			(net "P1V5_E_VO")
		)
		(pad "17" smd rect
			(at 0 0)
			(size 1.6764 1.6764)
			(layers "F.Cu" "F.Mask" "F.Paste")
			(net "GND")
		)
	)
	(footprint ""
		(layer "F.Cu")
		(at 99.20097 -115.697)
		(property "Reference" "TP265"
			(at 0 0 0)
			(layer "F.SilkS")
			(hide yes)
			(effects
				(font
					(size 1.27 1.27)
				)
			)
		)
		(property "Value" "TPAD28"
			(at 0.0127 -1.8034 0)
			(unlocked yes)
			(layer "F.Fab")
			(hide yes)
			(effects
				(font
					(size 1.016 1.016)
					(thickness 0.1524)
				)
			)
		)
		(property "Device Type" "TPAD28"
			(at 0.0127 -3.3274 0)
			(unlocked yes)
			(layer "F.Fab")
			(hide yes)
			(effects
				(font
					(size 1.016 1.016)
					(thickness 0.1524)
				)
			)
		)
		(duplicate_pad_numbers_are_jumpers no)
		(fp_poly
			(pts
				(arc
					(start 0.3556 0)
					(mid -0.3556 0)
					(end 0.3556 0)
				)
			)
			(stroke
				(width 0)
				(type default)
			)
			(fill no)
			(layer "F.CrtYd")
		)
		(fp_poly
			(pts
				(arc
					(start 0.6096 0)
					(mid -0.6096 0)
					(end 0.6096 0)
				)
			)
			(stroke
				(width 0)
				(type default)
			)
			(fill no)
			(layer "F.Fab")
		)
		(pad "1" smd circle
			(at 0 0)
			(size 0.7112 0.7112)
			(layers "F.Cu" "F.Mask" "F.Paste")
			(net "SIO_LOAD_IN")
		)
	)
	(footprint ""
		(layer "F.Cu")
		(at 310.388 -112.268 180)
		(property "Reference" "PR18"
			(at 0 0 180)
			(layer "F.SilkS")
			(hide yes)
			(effects
				(font
					(size 1.27 1.27)
				)
			)
		)
		(property "Value" "1K4R2F-1-GP"
			(at 0.064008 -3.993896 180)
			(unlocked yes)
			(layer "F.Fab")
			(hide yes)
			(effects
				(font
					(size 1.016 1.016)
					(thickness 0.1524)
				)
			)
		)
		(property "Device Type" "R402H16"
			(at 0.064008 -5.517896 180)
			(unlocked yes)
			(layer "F.Fab")
			(hide yes)
			(effects
				(font
					(size 1.016 1.016)
					(thickness 0.1524)
				)
			)
		)
		(duplicate_pad_numbers_are_jumpers no)
		(fp_line
			(start 0.508 -0.9398)
			(end -0.508 -0.9398)
			(stroke
				(width 0.1524)
				(type default)
			)
			(layer "F.SilkS")
		)
		(fp_line
			(start -0.508 -0.9398)
			(end -0.508 0.9398)
			(stroke
				(width 0.1524)
				(type default)
			)
			(layer "F.SilkS")
		)
		(fp_rect
			(start -0.508 0.9398)
			(end 0.508 -0.9398)
			(stroke
				(width 0)
				(type default)
			)
			(fill no)
			(layer "F.CrtYd")
		)
		(fp_rect
			(start -0.508 0.9398)
			(end 0.508 -0.9398)
			(stroke
				(width 0)
				(type default)
			)
			(fill no)
			(layer "F.Fab")
		)
		(pad "1" smd custom
			(at 0 -0.4445 180)
			(size 0.1397 0.1397)
			(layers "F.Cu" "F.Mask" "F.Paste")
			(net "P5V_STBY")
			(options
				(clearance outline)
				(anchor circle)
			)
			(primitives
				(gr_poly
					(pts
						(arc
							(start -0.1778 -0.2794)
							(mid -0.249642 -0.249642)
							(end -0.2794 -0.1778)
						)
						(arc
							(start -0.2794 0.1778)
							(mid -0.249642 0.249642)
							(end -0.1778 0.2794)
						)
						(arc
							(start 0.1778 0.2794)
							(mid 0.249642 0.249642)
							(end 0.2794 0.1778)
						)
						(arc
							(start 0.2794 -0.1778)
							(mid 0.249642 -0.249642)
							(end 0.1778 -0.2794)
						)
					)
					(width 0)
					(fill yes)
				)
			)
		)
		(pad "2" smd custom
			(at 0 0.4445 180)
			(size 0.1397 0.1397)
			(layers "F.Cu" "F.Mask" "F.Paste")
			(net "P3V3_STBY_EN")
			(options
				(clearance outline)
				(anchor circle)
			)
			(primitives
				(gr_poly
					(pts
						(arc
							(start -0.1778 -0.2794)
							(mid -0.249642 -0.249642)
							(end -0.2794 -0.1778)
						)
						(arc
							(start -0.2794 0.1778)
							(mid -0.249642 0.249642)
							(end -0.1778 0.2794)
						)
						(arc
							(start 0.1778 0.2794)
							(mid 0.249642 0.249642)
							(end 0.2794 0.1778)
						)
						(arc
							(start 0.2794 -0.1778)
							(mid 0.249642 -0.249642)
							(end 0.1778 -0.2794)
						)
					)
					(width 0)
					(fill yes)
				)
			)
		)
	)
	(footprint ""
		(layer "F.Cu")
		(at 277.740872 -225.116136 180)
		(property "Reference" "PC79"
			(at 0 0 180)
			(layer "F.SilkS")
			(hide yes)
			(effects
				(font
					(size 1.27 1.27)
				)
			)
		)
		(property "Value" "SC10U6D3V5KX-1GP"
			(at -0.0762 -6.1214 180)
			(unlocked yes)
			(layer "F.Fab")
			(hide yes)
			(effects
				(font
					(size 1.016 1.016)
					(thickness 0.1524)
				)
			)
		)
		(property "Device Type" "C805H54"
			(at -0.0762 -8.1534 180)
			(unlocked yes)
			(layer "F.Fab")
			(hide yes)
			(effects
				(font
					(size 1.016 1.016)
					(thickness 0.1524)
				)
			)
		)
		(duplicate_pad_numbers_are_jumpers no)
		(fp_line
			(start 0.635 0)
			(end -0.635 0)
			(stroke
				(width 0.508)
				(type default)
			)
			(layer "F.SilkS")
		)
		(fp_rect
			(start -0.9652 1.778)
			(end 0.9652 -1.778)
			(stroke
				(width 0)
				(type default)
			)
			(fill no)
			(layer "F.CrtYd")
		)
		(fp_poly
			(pts
				(xy -0.9652 -1.778) (xy 0.9652 -1.778) (xy 0.9652 1.778) (xy -0.9652 1.778)
			)
			(stroke
				(width 0)
				(type default)
			)
			(fill no)
			(layer "F.Fab")
		)
		(pad "1" smd rect
			(at 0 -0.9652 180)
			(size 1.397 1.143)
			(layers "F.Cu" "F.Mask" "F.Paste")
			(net "TPS74801_P1V53_STBY_IN")
		)
		(pad "2" smd rect
			(at 0 0.9652 180)
			(size 1.397 1.143)
			(layers "F.Cu" "F.Mask" "F.Paste")
			(net "GND")
		)
	)
	(footprint ""
		(layer "F.Cu")
		(at 331.161136 -200.033128)
		(property "Reference" "R197"
			(at 0 0 0)
			(layer "F.SilkS")
			(hide yes)
			(effects
				(font
					(size 1.27 1.27)
				)
			)
		)
		(property "Value" "8K2R2J-3-GP"
			(at 0.064008 -3.993896 0)
			(unlocked yes)
			(layer "F.Fab")
			(hide yes)
			(effects
				(font
					(size 1.016 1.016)
					(thickness 0.1524)
				)
			)
		)
		(property "Device Type" "R402H16"
			(at 0.064008 -5.517896 0)
			(unlocked yes)
			(layer "F.Fab")
			(hide yes)
			(effects
				(font
					(size 1.016 1.016)
					(thickness 0.1524)
				)
			)
		)
		(duplicate_pad_numbers_are_jumpers no)
		(fp_line
			(start -0.508 -0.9398)
			(end -0.508 0.9398)
			(stroke
				(width 0.1524)
				(type default)
			)
			(layer "F.SilkS")
		)
		(fp_line
			(start 0.508 -0.9398)
			(end -0.508 -0.9398)
			(stroke
				(width 0.1524)
				(type default)
			)
			(layer "F.SilkS")
		)
		(fp_rect
			(start -0.508 0.9398)
			(end 0.508 -0.9398)
			(stroke
				(width 0)
				(type default)
			)
			(fill no)
			(layer "F.CrtYd")
		)
		(fp_rect
			(start -0.508 0.9398)
			(end 0.508 -0.9398)
			(stroke
				(width 0)
				(type default)
			)
			(fill no)
			(layer "F.Fab")
		)
		(pad "1" smd custom
			(at 0 -0.4445)
			(size 0.1397 0.1397)
			(layers "F.Cu" "F.Mask" "F.Paste")
			(net "EEPROM_A0_R")
			(options
				(clearance outline)
				(anchor circle)
			)
			(primitives
				(gr_poly
					(pts
						(arc
							(start -0.1778 -0.2794)
							(mid -0.249642 -0.249642)
							(end -0.2794 -0.1778)
						)
						(arc
							(start -0.2794 0.1778)
							(mid -0.249642 0.249642)
							(end -0.1778 0.2794)
						)
						(arc
							(start 0.1778 0.2794)
							(mid 0.249642 0.249642)
							(end 0.2794 0.1778)
						)
						(arc
							(start 0.2794 -0.1778)
							(mid 0.249642 -0.249642)
							(end 0.1778 -0.2794)
						)
					)
					(width 0)
					(fill yes)
				)
			)
		)
		(pad "2" smd custom
			(at 0 0.4445)
			(size 0.1397 0.1397)
			(layers "F.Cu" "F.Mask" "F.Paste")
			(net "GND")
			(options
				(clearance outline)
				(anchor circle)
			)
			(primitives
				(gr_poly
					(pts
						(arc
							(start -0.1778 -0.2794)
							(mid -0.249642 -0.249642)
							(end -0.2794 -0.1778)
						)
						(arc
							(start -0.2794 0.1778)
							(mid -0.249642 0.249642)
							(end -0.1778 0.2794)
						)
						(arc
							(start 0.1778 0.2794)
							(mid 0.249642 0.249642)
							(end 0.2794 0.1778)
						)
						(arc
							(start 0.2794 -0.1778)
							(mid 0.249642 -0.249642)
							(end 0.1778 -0.2794)
						)
					)
					(width 0)
					(fill yes)
				)
			)
		)
	)
	(footprint ""
		(layer "F.Cu")
		(at 120.847612 -204.978)
		(property "Reference" "SR868"
			(at 0 0 0)
			(layer "F.SilkS")
			(hide yes)
			(effects
				(font
					(size 1.27 1.27)
				)
			)
		)
		(property "Value" "0R2J-2-GP"
			(at 0.064008 -3.993896 0)
			(unlocked yes)
			(layer "F.Fab")
			(hide yes)
			(effects
				(font
					(size 1.016 1.016)
					(thickness 0.1524)
				)
			)
		)
		(property "Device Type" "R402H16"
			(at 0.064008 -5.517896 0)
			(unlocked yes)
			(layer "F.Fab")
			(hide yes)
			(effects
				(font
					(size 1.016 1.016)
					(thickness 0.1524)
				)
			)
		)
		(duplicate_pad_numbers_are_jumpers no)
		(fp_line
			(start -0.508 -0.9398)
			(end -0.508 0.9398)
			(stroke
				(width 0.1524)
				(type default)
			)
			(layer "F.SilkS")
		)
		(fp_line
			(start 0.508 -0.9398)
			(end -0.508 -0.9398)
			(stroke
				(width 0.1524)
				(type default)
			)
			(layer "F.SilkS")
		)
		(fp_rect
			(start -0.508 0.9398)
			(end 0.508 -0.9398)
			(stroke
				(width 0)
				(type default)
			)
			(fill no)
			(layer "F.CrtYd")
		)
		(fp_rect
			(start -0.508 0.9398)
			(end 0.508 -0.9398)
			(stroke
				(width 0)
				(type default)
			)
			(fill no)
			(layer "F.Fab")
		)
		(pad "1" smd custom
			(at 0 -0.4445)
			(size 0.1397 0.1397)
			(layers "F.Cu" "F.Mask" "F.Paste")
			(net "SAS_HDD_REDV_TX7_P")
			(options
				(clearance outline)
				(anchor circle)
			)
			(primitives
				(gr_poly
					(pts
						(arc
							(start -0.1778 -0.2794)
							(mid -0.249642 -0.249642)
							(end -0.2794 -0.1778)
						)
						(arc
							(start -0.2794 0.1778)
							(mid -0.249642 0.249642)
							(end -0.1778 0.2794)
						)
						(arc
							(start 0.1778 0.2794)
							(mid 0.249642 0.249642)
							(end 0.2794 0.1778)
						)
						(arc
							(start 0.2794 -0.1778)
							(mid 0.249642 -0.249642)
							(end 0.1778 -0.2794)
						)
					)
					(width 0)
					(fill yes)
				)
			)
		)
		(pad "2" smd custom
			(at 0 0.4445)
			(size 0.1397 0.1397)
			(layers "F.Cu" "F.Mask" "F.Paste")
			(net "SAS_HDD_REDV_SER_TX7_P")
			(options
				(clearance outline)
				(anchor circle)
			)
			(primitives
				(gr_poly
					(pts
						(arc
							(start -0.1778 -0.2794)
							(mid -0.249642 -0.249642)
							(end -0.2794 -0.1778)
						)
						(arc
							(start -0.2794 0.1778)
							(mid -0.249642 0.249642)
							(end -0.1778 0.2794)
						)
						(arc
							(start 0.1778 0.2794)
							(mid 0.249642 0.249642)
							(end 0.2794 0.1778)
						)
						(arc
							(start 0.2794 -0.1778)
							(mid 0.249642 -0.249642)
							(end 0.1778 -0.2794)
						)
					)
					(width 0)
					(fill yes)
				)
			)
		)
	)
	(footprint ""
		(layer "F.Cu")
		(at 288.798 -160.782 180)
		(property "Reference" "R530"
			(at 0 0 180)
			(layer "F.SilkS")
			(hide yes)
			(effects
				(font
					(size 1.27 1.27)
				)
			)
		)
		(property "Value" "0R2J-2-GP"
			(at 0.064008 -3.993896 180)
			(unlocked yes)
			(layer "F.Fab")
			(hide yes)
			(effects
				(font
					(size 1.016 1.016)
					(thickness 0.1524)
				)
			)
		)
		(property "Device Type" "R402H16"
			(at 0.064008 -5.517896 180)
			(unlocked yes)
			(layer "F.Fab")
			(hide yes)
			(effects
				(font
					(size 1.016 1.016)
					(thickness 0.1524)
				)
			)
		)
		(duplicate_pad_numbers_are_jumpers no)
		(fp_line
			(start 0.508 -0.9398)
			(end -0.508 -0.9398)
			(stroke
				(width 0.1524)
				(type default)
			)
			(layer "F.SilkS")
		)
		(fp_line
			(start -0.508 -0.9398)
			(end -0.508 0.9398)
			(stroke
				(width 0.1524)
				(type default)
			)
			(layer "F.SilkS")
		)
		(fp_rect
			(start -0.508 0.9398)
			(end 0.508 -0.9398)
			(stroke
				(width 0)
				(type default)
			)
			(fill no)
			(layer "F.CrtYd")
		)
		(fp_rect
			(start -0.508 0.9398)
			(end 0.508 -0.9398)
			(stroke
				(width 0)
				(type default)
			)
			(fill no)
			(layer "F.Fab")
		)
		(pad "1" smd custom
			(at 0 -0.4445 180)
			(size 0.1397 0.1397)
			(layers "F.Cu" "F.Mask" "F.Paste")
			(net "FM_BMC_READY_N")
			(options
				(clearance outline)
				(anchor circle)
			)
			(primitives
				(gr_poly
					(pts
						(arc
							(start -0.1778 -0.2794)
							(mid -0.249642 -0.249642)
							(end -0.2794 -0.1778)
						)
						(arc
							(start -0.2794 0.1778)
							(mid -0.249642 0.249642)
							(end -0.1778 0.2794)
						)
						(arc
							(start 0.1778 0.2794)
							(mid 0.249642 0.249642)
							(end 0.2794 0.1778)
						)
						(arc
							(start 0.2794 -0.1778)
							(mid 0.249642 -0.249642)
							(end 0.1778 -0.2794)
						)
					)
					(width 0)
					(fill yes)
				)
			)
		)
		(pad "2" smd custom
			(at 0 0.4445 180)
			(size 0.1397 0.1397)
			(layers "F.Cu" "F.Mask" "F.Paste")
			(net "FM_BMC_READY_N_R")
			(options
				(clearance outline)
				(anchor circle)
			)
			(primitives
				(gr_poly
					(pts
						(arc
							(start -0.1778 -0.2794)
							(mid -0.249642 -0.249642)
							(end -0.2794 -0.1778)
						)
						(arc
							(start -0.2794 0.1778)
							(mid -0.249642 0.249642)
							(end -0.1778 0.2794)
						)
						(arc
							(start 0.1778 0.2794)
							(mid 0.249642 0.249642)
							(end 0.2794 0.1778)
						)
						(arc
							(start 0.2794 -0.1778)
							(mid 0.249642 -0.249642)
							(end 0.1778 -0.2794)
						)
					)
					(width 0)
					(fill yes)
				)
			)
		)
	)
	(footprint ""
		(layer "F.Cu")
		(at 85.452966 -91.44 180)
		(property "Reference" "SC1199"
			(at 0 0 180)
			(layer "F.SilkS")
			(hide yes)
			(effects
				(font
					(size 1.27 1.27)
				)
			)
		)
		(property "Value" "SC10U6D3V5KX-4GP"
			(at -0.0762 -6.1214 180)
			(unlocked yes)
			(layer "F.Fab")
			(hide yes)
			(effects
				(font
					(size 1.016 1.016)
					(thickness 0.1524)
				)
			)
		)
		(property "Device Type" "C805H58"
			(at -0.0762 -8.1534 180)
			(unlocked yes)
			(layer "F.Fab")
			(hide yes)
			(effects
				(font
					(size 1.016 1.016)
					(thickness 0.1524)
				)
			)
		)
		(duplicate_pad_numbers_are_jumpers no)
		(fp_line
			(start 0.635 0)
			(end -0.635 0)
			(stroke
				(width 0.508)
				(type default)
			)
			(layer "F.SilkS")
		)
		(fp_rect
			(start -0.9652 1.778)
			(end 0.9652 -1.778)
			(stroke
				(width 0)
				(type default)
			)
			(fill no)
			(layer "F.CrtYd")
		)
		(fp_poly
			(pts
				(xy -0.9652 -1.778) (xy 0.9652 -1.778) (xy 0.9652 1.778) (xy -0.9652 1.778)
			)
			(stroke
				(width 0)
				(type default)
			)
			(fill no)
			(layer "F.Fab")
		)
		(pad "1" smd rect
			(at 0 -0.9652 180)
			(size 1.397 1.143)
			(layers "F.Cu" "F.Mask" "F.Paste")
			(net "SYSPLL_VDDA09")
		)
		(pad "2" smd rect
			(at 0 0.9652 180)
			(size 1.397 1.143)
			(layers "F.Cu" "F.Mask" "F.Paste")
			(net "GND")
		)
	)
	(footprint ""
		(layer "F.Cu")
		(at 35.383216 -201.09688 -90)
		(property "Reference" "R565"
			(at 0 0 270)
			(layer "F.SilkS")
			(hide yes)
			(effects
				(font
					(size 1.27 1.27)
				)
			)
		)
		(property "Value" "0R2J-2-GP"
			(at 0.064008 -3.993896 270)
			(unlocked yes)
			(layer "F.Fab")
			(hide yes)
			(effects
				(font
					(size 1.016 1.016)
					(thickness 0.1524)
				)
			)
		)
		(property "Device Type" "R402H16"
			(at 0.064008 -5.517896 270)
			(unlocked yes)
			(layer "F.Fab")
			(hide yes)
			(effects
				(font
					(size 1.016 1.016)
					(thickness 0.1524)
				)
			)
		)
		(duplicate_pad_numbers_are_jumpers no)
		(fp_line
			(start -0.508 -0.9398)
			(end -0.508 0.9398)
			(stroke
				(width 0.1524)
				(type default)
			)
			(layer "F.SilkS")
		)
		(fp_line
			(start 0.508 -0.9398)
			(end -0.508 -0.9398)
			(stroke
				(width 0.1524)
				(type default)
			)
			(layer "F.SilkS")
		)
		(fp_rect
			(start -0.508 0.9398)
			(end 0.508 -0.9398)
			(stroke
				(width 0)
				(type default)
			)
			(fill no)
			(layer "F.CrtYd")
		)
		(fp_rect
			(start -0.508 0.9398)
			(end 0.508 -0.9398)
			(stroke
				(width 0)
				(type default)
			)
			(fill no)
			(layer "F.Fab")
		)
		(pad "1" smd custom
			(at 0 -0.4445 270)
			(size 0.1397 0.1397)
			(layers "F.Cu" "F.Mask" "F.Paste")
			(net "ADC_P1V5_C")
			(options
				(clearance outline)
				(anchor circle)
			)
			(primitives
				(gr_poly
					(pts
						(arc
							(start -0.1778 -0.2794)
							(mid -0.249642 -0.249642)
							(end -0.2794 -0.1778)
						)
						(arc
							(start -0.2794 0.1778)
							(mid -0.249642 0.249642)
							(end -0.1778 0.2794)
						)
						(arc
							(start 0.1778 0.2794)
							(mid 0.249642 0.249642)
							(end 0.2794 0.1778)
						)
						(arc
							(start 0.2794 -0.1778)
							(mid 0.249642 -0.249642)
							(end 0.1778 -0.2794)
						)
					)
					(width 0)
					(fill yes)
				)
			)
		)
		(pad "2" smd custom
			(at 0 0.4445 270)
			(size 0.1397 0.1397)
			(layers "F.Cu" "F.Mask" "F.Paste")
			(net "P1V5_C_SENSE")
			(options
				(clearance outline)
				(anchor circle)
			)
			(primitives
				(gr_poly
					(pts
						(arc
							(start -0.1778 -0.2794)
							(mid -0.249642 -0.249642)
							(end -0.2794 -0.1778)
						)
						(arc
							(start -0.2794 0.1778)
							(mid -0.249642 0.249642)
							(end -0.1778 0.2794)
						)
						(arc
							(start 0.1778 0.2794)
							(mid 0.249642 0.249642)
							(end 0.2794 0.1778)
						)
						(arc
							(start 0.2794 -0.1778)
							(mid 0.249642 -0.249642)
							(end 0.1778 -0.2794)
						)
					)
					(width 0)
					(fill yes)
				)
			)
		)
	)
	(footprint ""
		(layer "F.Cu")
		(at 223.647 -121.158 180)
		(property "Reference" "R606"
			(at 0 0 180)
			(layer "F.SilkS")
			(hide yes)
			(effects
				(font
					(size 1.27 1.27)
				)
			)
		)
		(property "Value" "4K7R2F-GP"
			(at 0.064008 -3.993896 180)
			(unlocked yes)
			(layer "F.Fab")
			(hide yes)
			(effects
				(font
					(size 1.016 1.016)
					(thickness 0.1524)
				)
			)
		)
		(property "Device Type" "R402H16"
			(at 0.064008 -5.517896 180)
			(unlocked yes)
			(layer "F.Fab")
			(hide yes)
			(effects
				(font
					(size 1.016 1.016)
					(thickness 0.1524)
				)
			)
		)
		(duplicate_pad_numbers_are_jumpers no)
		(fp_line
			(start 0.508 -0.9398)
			(end -0.508 -0.9398)
			(stroke
				(width 0.1524)
				(type default)
			)
			(layer "F.SilkS")
		)
		(fp_line
			(start -0.508 -0.9398)
			(end -0.508 0.9398)
			(stroke
				(width 0.1524)
				(type default)
			)
			(layer "F.SilkS")
		)
		(fp_rect
			(start -0.508 0.9398)
			(end 0.508 -0.9398)
			(stroke
				(width 0)
				(type default)
			)
			(fill no)
			(layer "F.CrtYd")
		)
		(fp_rect
			(start -0.508 0.9398)
			(end 0.508 -0.9398)
			(stroke
				(width 0)
				(type default)
			)
			(fill no)
			(layer "F.Fab")
		)
		(pad "1" smd custom
			(at 0 -0.4445 180)
			(size 0.1397 0.1397)
			(layers "F.Cu" "F.Mask" "F.Paste")
			(net "P1V8_C_B")
			(options
				(clearance outline)
				(anchor circle)
			)
			(primitives
				(gr_poly
					(pts
						(arc
							(start -0.1778 -0.2794)
							(mid -0.249642 -0.249642)
							(end -0.2794 -0.1778)
						)
						(arc
							(start -0.2794 0.1778)
							(mid -0.249642 0.249642)
							(end -0.1778 0.2794)
						)
						(arc
							(start 0.1778 0.2794)
							(mid 0.249642 0.249642)
							(end 0.2794 0.1778)
						)
						(arc
							(start 0.2794 -0.1778)
							(mid 0.249642 -0.249642)
							(end 0.1778 -0.2794)
						)
					)
					(width 0)
					(fill yes)
				)
			)
		)
		(pad "2" smd custom
			(at 0 0.4445 180)
			(size 0.1397 0.1397)
			(layers "F.Cu" "F.Mask" "F.Paste")
			(net "P1V8_C")
			(options
				(clearance outline)
				(anchor circle)
			)
			(primitives
				(gr_poly
					(pts
						(arc
							(start -0.1778 -0.2794)
							(mid -0.249642 -0.249642)
							(end -0.2794 -0.1778)
						)
						(arc
							(start -0.2794 0.1778)
							(mid -0.249642 0.249642)
							(end -0.1778 0.2794)
						)
						(arc
							(start 0.1778 0.2794)
							(mid 0.249642 0.249642)
							(end 0.2794 0.1778)
						)
						(arc
							(start 0.2794 -0.1778)
							(mid 0.249642 -0.249642)
							(end 0.1778 -0.2794)
						)
					)
					(width 0)
					(fill yes)
				)
			)
		)
	)
	(footprint ""
		(layer "F.Cu")
		(at 49.9872 -231.01554)
		(property "Reference" "C296"
			(at 0 0 0)
			(layer "F.SilkS")
			(hide yes)
			(effects
				(font
					(size 1.27 1.27)
				)
			)
		)
		(property "Value" "SC22U25V5MX-GP"
			(at -0.0762 -6.1214 0)
			(unlocked yes)
			(layer "F.Fab")
			(hide yes)
			(effects
				(font
					(size 1.016 1.016)
					(thickness 0.1524)
				)
			)
		)
		(property "Device Type" "C805H58"
			(at -0.0762 -8.1534 0)
			(unlocked yes)
			(layer "F.Fab")
			(hide yes)
			(effects
				(font
					(size 1.016 1.016)
					(thickness 0.1524)
				)
			)
		)
		(duplicate_pad_numbers_are_jumpers no)
		(fp_line
			(start 0.635 0)
			(end -0.635 0)
			(stroke
				(width 0.508)
				(type default)
			)
			(layer "F.SilkS")
		)
		(fp_rect
			(start -0.9652 1.778)
			(end 0.9652 -1.778)
			(stroke
				(width 0)
				(type default)
			)
			(fill no)
			(layer "F.CrtYd")
		)
		(fp_poly
			(pts
				(xy -0.9652 -1.778) (xy 0.9652 -1.778) (xy 0.9652 1.778) (xy -0.9652 1.778)
			)
			(stroke
				(width 0)
				(type default)
			)
			(fill no)
			(layer "F.Fab")
		)
		(pad "1" smd rect
			(at 0 -0.9652)
			(size 1.397 1.143)
			(layers "F.Cu" "F.Mask" "F.Paste")
			(net "P12V_PCIE")
		)
		(pad "2" smd rect
			(at 0 0.9652)
			(size 1.397 1.143)
			(layers "F.Cu" "F.Mask" "F.Paste")
			(net "GND")
		)
	)
	(footprint ""
		(layer "F.Cu")
		(at 276.850094 -25.791668)
		(property "Reference" "R410"
			(at 0 0 0)
			(layer "F.SilkS")
			(hide yes)
			(effects
				(font
					(size 1.27 1.27)
				)
			)
		)
		(property "Value" "0R2J-2-GP"
			(at 0.064008 -3.993896 0)
			(unlocked yes)
			(layer "F.Fab")
			(hide yes)
			(effects
				(font
					(size 1.016 1.016)
					(thickness 0.1524)
				)
			)
		)
		(property "Device Type" "R402H16"
			(at 0.064008 -5.517896 0)
			(unlocked yes)
			(layer "F.Fab")
			(hide yes)
			(effects
				(font
					(size 1.016 1.016)
					(thickness 0.1524)
				)
			)
		)
		(duplicate_pad_numbers_are_jumpers no)
		(fp_line
			(start -0.508 -0.9398)
			(end -0.508 0.9398)
			(stroke
				(width 0.1524)
				(type default)
			)
			(layer "F.SilkS")
		)
		(fp_line
			(start 0.508 -0.9398)
			(end -0.508 -0.9398)
			(stroke
				(width 0.1524)
				(type default)
			)
			(layer "F.SilkS")
		)
		(fp_rect
			(start -0.508 0.9398)
			(end 0.508 -0.9398)
			(stroke
				(width 0)
				(type default)
			)
			(fill no)
			(layer "F.CrtYd")
		)
		(fp_rect
			(start -0.508 0.9398)
			(end 0.508 -0.9398)
			(stroke
				(width 0)
				(type default)
			)
			(fill no)
			(layer "F.Fab")
		)
		(pad "1" smd custom
			(at 0 -0.4445)
			(size 0.1397 0.1397)
			(layers "F.Cu" "F.Mask" "F.Paste")
			(net "USB_DN_R")
			(options
				(clearance outline)
				(anchor circle)
			)
			(primitives
				(gr_poly
					(pts
						(arc
							(start -0.1778 -0.2794)
							(mid -0.249642 -0.249642)
							(end -0.2794 -0.1778)
						)
						(arc
							(start -0.2794 0.1778)
							(mid -0.249642 0.249642)
							(end -0.1778 0.2794)
						)
						(arc
							(start 0.1778 0.2794)
							(mid 0.249642 0.249642)
							(end 0.2794 0.1778)
						)
						(arc
							(start 0.2794 -0.1778)
							(mid 0.249642 -0.249642)
							(end 0.1778 -0.2794)
						)
					)
					(width 0)
					(fill yes)
				)
			)
		)
		(pad "2" smd custom
			(at 0 0.4445)
			(size 0.1397 0.1397)
			(layers "F.Cu" "F.Mask" "F.Paste")
			(net "USB_P1_F_DN1")
			(options
				(clearance outline)
				(anchor circle)
			)
			(primitives
				(gr_poly
					(pts
						(arc
							(start -0.1778 -0.2794)
							(mid -0.249642 -0.249642)
							(end -0.2794 -0.1778)
						)
						(arc
							(start -0.2794 0.1778)
							(mid -0.249642 0.249642)
							(end -0.1778 0.2794)
						)
						(arc
							(start 0.1778 0.2794)
							(mid 0.249642 0.249642)
							(end 0.2794 0.1778)
						)
						(arc
							(start 0.2794 -0.1778)
							(mid 0.249642 -0.249642)
							(end 0.1778 -0.2794)
						)
					)
					(width 0)
					(fill yes)
				)
			)
		)
	)
	(footprint ""
		(layer "F.Cu")
		(at 214.00897 -69.088)
		(property "Reference" "R14"
			(at 0 0 0)
			(layer "F.SilkS")
			(hide yes)
			(effects
				(font
					(size 1.27 1.27)
				)
			)
		)
		(property "Value" "10KR2F-2-GP"
			(at 0.064008 -3.993896 0)
			(unlocked yes)
			(layer "F.Fab")
			(hide yes)
			(effects
				(font
					(size 1.016 1.016)
					(thickness 0.1524)
				)
			)
		)
		(property "Device Type" "R402H16"
			(at 0.064008 -5.517896 0)
			(unlocked yes)
			(layer "F.Fab")
			(hide yes)
			(effects
				(font
					(size 1.016 1.016)
					(thickness 0.1524)
				)
			)
		)
		(duplicate_pad_numbers_are_jumpers no)
		(fp_line
			(start -0.508 -0.9398)
			(end -0.508 0.9398)
			(stroke
				(width 0.1524)
				(type default)
			)
			(layer "F.SilkS")
		)
		(fp_line
			(start 0.508 -0.9398)
			(end -0.508 -0.9398)
			(stroke
				(width 0.1524)
				(type default)
			)
			(layer "F.SilkS")
		)
		(fp_rect
			(start -0.508 0.9398)
			(end 0.508 -0.9398)
			(stroke
				(width 0)
				(type default)
			)
			(fill no)
			(layer "F.CrtYd")
		)
		(fp_rect
			(start -0.508 0.9398)
			(end 0.508 -0.9398)
			(stroke
				(width 0)
				(type default)
			)
			(fill no)
			(layer "F.Fab")
		)
		(pad "1" smd custom
			(at 0 -0.4445)
			(size 0.1397 0.1397)
			(layers "F.Cu" "F.Mask" "F.Paste")
			(net "SVR_ID3")
			(options
				(clearance outline)
				(anchor circle)
			)
			(primitives
				(gr_poly
					(pts
						(arc
							(start -0.1778 -0.2794)
							(mid -0.249642 -0.249642)
							(end -0.2794 -0.1778)
						)
						(arc
							(start -0.2794 0.1778)
							(mid -0.249642 0.249642)
							(end -0.1778 0.2794)
						)
						(arc
							(start 0.1778 0.2794)
							(mid 0.249642 0.249642)
							(end 0.2794 0.1778)
						)
						(arc
							(start 0.2794 -0.1778)
							(mid 0.249642 -0.249642)
							(end 0.1778 -0.2794)
						)
					)
					(width 0)
					(fill yes)
				)
			)
		)
		(pad "2" smd custom
			(at 0 0.4445)
			(size 0.1397 0.1397)
			(layers "F.Cu" "F.Mask" "F.Paste")
			(net "P3V3_STBY")
			(options
				(clearance outline)
				(anchor circle)
			)
			(primitives
				(gr_poly
					(pts
						(arc
							(start -0.1778 -0.2794)
							(mid -0.249642 -0.249642)
							(end -0.2794 -0.1778)
						)
						(arc
							(start -0.2794 0.1778)
							(mid -0.249642 0.249642)
							(end -0.1778 0.2794)
						)
						(arc
							(start 0.1778 0.2794)
							(mid 0.249642 0.249642)
							(end 0.2794 0.1778)
						)
						(arc
							(start 0.2794 -0.1778)
							(mid 0.249642 -0.249642)
							(end 0.1778 -0.2794)
						)
					)
					(width 0)
					(fill yes)
				)
			)
		)
	)
	(footprint ""
		(layer "F.Cu")
		(at 279.781 -115.824 180)
		(property "Reference" "PR173"
			(at 0 0 180)
			(layer "F.SilkS")
			(hide yes)
			(effects
				(font
					(size 1.27 1.27)
				)
			)
		)
		(property "Value" "4K02R2F-GP"
			(at 0.064008 -3.993896 180)
			(unlocked yes)
			(layer "F.Fab")
			(hide yes)
			(effects
				(font
					(size 1.016 1.016)
					(thickness 0.1524)
				)
			)
		)
		(property "Device Type" "R402H16"
			(at 0.064008 -5.517896 180)
			(unlocked yes)
			(layer "F.Fab")
			(hide yes)
			(effects
				(font
					(size 1.016 1.016)
					(thickness 0.1524)
				)
			)
		)
		(duplicate_pad_numbers_are_jumpers no)
		(fp_line
			(start 0.508 -0.9398)
			(end -0.508 -0.9398)
			(stroke
				(width 0.1524)
				(type default)
			)
			(layer "F.SilkS")
		)
		(fp_line
			(start -0.508 -0.9398)
			(end -0.508 0.9398)
			(stroke
				(width 0.1524)
				(type default)
			)
			(layer "F.SilkS")
		)
		(fp_rect
			(start -0.508 0.9398)
			(end 0.508 -0.9398)
			(stroke
				(width 0)
				(type default)
			)
			(fill no)
			(layer "F.CrtYd")
		)
		(fp_rect
			(start -0.508 0.9398)
			(end 0.508 -0.9398)
			(stroke
				(width 0)
				(type default)
			)
			(fill no)
			(layer "F.Fab")
		)
		(pad "1" smd custom
			(at 0 -0.4445 180)
			(size 0.1397 0.1397)
			(layers "F.Cu" "F.Mask" "F.Paste")
			(net "P1V8_C_EN_G")
			(options
				(clearance outline)
				(anchor circle)
			)
			(primitives
				(gr_poly
					(pts
						(arc
							(start -0.1778 -0.2794)
							(mid -0.249642 -0.249642)
							(end -0.2794 -0.1778)
						)
						(arc
							(start -0.2794 0.1778)
							(mid -0.249642 0.249642)
							(end -0.1778 0.2794)
						)
						(arc
							(start 0.1778 0.2794)
							(mid 0.249642 0.249642)
							(end 0.2794 0.1778)
						)
						(arc
							(start 0.2794 -0.1778)
							(mid 0.249642 -0.249642)
							(end 0.1778 -0.2794)
						)
					)
					(width 0)
					(fill yes)
				)
			)
		)
		(pad "2" smd custom
			(at 0 0.4445 180)
			(size 0.1397 0.1397)
			(layers "F.Cu" "F.Mask" "F.Paste")
			(net "P3V3_STBY")
			(options
				(clearance outline)
				(anchor circle)
			)
			(primitives
				(gr_poly
					(pts
						(arc
							(start -0.1778 -0.2794)
							(mid -0.249642 -0.249642)
							(end -0.2794 -0.1778)
						)
						(arc
							(start -0.2794 0.1778)
							(mid -0.249642 0.249642)
							(end -0.1778 0.2794)
						)
						(arc
							(start 0.1778 0.2794)
							(mid 0.249642 0.249642)
							(end 0.2794 0.1778)
						)
						(arc
							(start 0.2794 -0.1778)
							(mid 0.249642 -0.249642)
							(end 0.1778 -0.2794)
						)
					)
					(width 0)
					(fill yes)
				)
			)
		)
	)
	(footprint ""
		(layer "F.Cu")
		(at 57.658 -224.409 90)
		(property "Reference" "C372"
			(at 0 0 90)
			(layer "F.SilkS")
			(hide yes)
			(effects
				(font
					(size 1.27 1.27)
				)
			)
		)
		(property "Value" "SCD015U25V2KX-GP"
			(at 1.1811 -2.7051 90)
			(unlocked yes)
			(layer "F.Fab")
			(hide yes)
			(effects
				(font
					(size 1.016 1.016)
					(thickness 0.1524)
				)
			)
		)
		(property "Device Type" "C402H22"
			(at 1.1811 -4.2291 90)
			(unlocked yes)
			(layer "F.Fab")
			(hide yes)
			(effects
				(font
					(size 1.016 1.016)
					(thickness 0.1524)
				)
			)
		)
		(duplicate_pad_numbers_are_jumpers no)
		(fp_rect
			(start -0.4318 0.9525)
			(end 0.4318 -0.9525)
			(stroke
				(width 0)
				(type default)
			)
			(fill no)
			(layer "F.CrtYd")
		)
		(fp_rect
			(start -0.4318 0.9525)
			(end 0.4318 -0.9525)
			(stroke
				(width 0)
				(type default)
			)
			(fill no)
			(layer "F.Fab")
		)
		(pad "1" smd custom
			(at 0 -0.4445 90)
			(size 0.1524 0.1524)
			(layers "F.Cu" "F.Mask" "F.Paste")
			(net "MB0_CM_SENSE_P")
			(options
				(clearance outline)
				(anchor circle)
			)
			(primitives
				(gr_poly
					(pts
						(arc
							(start 0.3048 -0.2032)
							(mid 0.275042 -0.275042)
							(end 0.2032 -0.3048)
						)
						(arc
							(start -0.2032 -0.3048)
							(mid -0.275042 -0.275042)
							(end -0.3048 -0.2032)
						)
						(arc
							(start -0.3048 0.2032)
							(mid -0.275042 0.275042)
							(end -0.2032 0.3048)
						)
						(arc
							(start 0.2032 0.3048)
							(mid 0.275042 0.275042)
							(end 0.3048 0.2032)
						)
					)
					(width 0)
					(fill yes)
				)
			)
		)
		(pad "2" smd custom
			(at 0 0.4445 90)
			(size 0.1524 0.1524)
			(layers "F.Cu" "F.Mask" "F.Paste")
			(net "MB0_CM_SENSE_N")
			(options
				(clearance outline)
				(anchor circle)
			)
			(primitives
				(gr_poly
					(pts
						(arc
							(start 0.3048 -0.2032)
							(mid 0.275042 -0.275042)
							(end 0.2032 -0.3048)
						)
						(arc
							(start -0.2032 -0.3048)
							(mid -0.275042 -0.275042)
							(end -0.3048 -0.2032)
						)
						(arc
							(start -0.3048 0.2032)
							(mid -0.275042 0.275042)
							(end -0.2032 0.3048)
						)
						(arc
							(start 0.2032 0.3048)
							(mid 0.275042 0.275042)
							(end 0.3048 0.2032)
						)
					)
					(width 0)
					(fill yes)
				)
			)
		)
	)
	(footprint ""
		(layer "F.Cu")
		(at 334.899 -113.538 180)
		(property "Reference" "PR22"
			(at 0 0 180)
			(layer "F.SilkS")
			(hide yes)
			(effects
				(font
					(size 1.27 1.27)
				)
			)
		)
		(property "Value" "0R2J-2-GP"
			(at 0.064008 -3.993896 180)
			(unlocked yes)
			(layer "F.Fab")
			(hide yes)
			(effects
				(font
					(size 1.016 1.016)
					(thickness 0.1524)
				)
			)
		)
		(property "Device Type" "R402H16"
			(at 0.064008 -5.517896 180)
			(unlocked yes)
			(layer "F.Fab")
			(hide yes)
			(effects
				(font
					(size 1.016 1.016)
					(thickness 0.1524)
				)
			)
		)
		(duplicate_pad_numbers_are_jumpers no)
		(fp_line
			(start 0.508 -0.9398)
			(end -0.508 -0.9398)
			(stroke
				(width 0.1524)
				(type default)
			)
			(layer "F.SilkS")
		)
		(fp_line
			(start -0.508 -0.9398)
			(end -0.508 0.9398)
			(stroke
				(width 0.1524)
				(type default)
			)
			(layer "F.SilkS")
		)
		(fp_rect
			(start -0.508 0.9398)
			(end 0.508 -0.9398)
			(stroke
				(width 0)
				(type default)
			)
			(fill no)
			(layer "F.CrtYd")
		)
		(fp_rect
			(start -0.508 0.9398)
			(end 0.508 -0.9398)
			(stroke
				(width 0)
				(type default)
			)
			(fill no)
			(layer "F.Fab")
		)
		(pad "1" smd custom
			(at 0 -0.4445 180)
			(size 0.1397 0.1397)
			(layers "F.Cu" "F.Mask" "F.Paste")
			(net "P5V_STBY_EN_R")
			(options
				(clearance outline)
				(anchor circle)
			)
			(primitives
				(gr_poly
					(pts
						(arc
							(start -0.1778 -0.2794)
							(mid -0.249642 -0.249642)
							(end -0.2794 -0.1778)
						)
						(arc
							(start -0.2794 0.1778)
							(mid -0.249642 0.249642)
							(end -0.1778 0.2794)
						)
						(arc
							(start 0.1778 0.2794)
							(mid 0.249642 0.249642)
							(end 0.2794 0.1778)
						)
						(arc
							(start 0.2794 -0.1778)
							(mid 0.249642 -0.249642)
							(end 0.1778 -0.2794)
						)
					)
					(width 0)
					(fill yes)
				)
			)
		)
		(pad "2" smd custom
			(at 0 0.4445 180)
			(size 0.1397 0.1397)
			(layers "F.Cu" "F.Mask" "F.Paste")
			(net "MB0_P12V_PWRGOOD")
			(options
				(clearance outline)
				(anchor circle)
			)
			(primitives
				(gr_poly
					(pts
						(arc
							(start -0.1778 -0.2794)
							(mid -0.249642 -0.249642)
							(end -0.2794 -0.1778)
						)
						(arc
							(start -0.2794 0.1778)
							(mid -0.249642 0.249642)
							(end -0.1778 0.2794)
						)
						(arc
							(start 0.1778 0.2794)
							(mid 0.249642 0.249642)
							(end 0.2794 0.1778)
						)
						(arc
							(start 0.2794 -0.1778)
							(mid 0.249642 -0.249642)
							(end 0.1778 -0.2794)
						)
					)
					(width 0)
					(fill yes)
				)
			)
		)
	)
	(footprint ""
		(layer "F.Cu")
		(at 147.193 -92.456 180)
		(property "Reference" "SC1182"
			(at 0 0 180)
			(layer "F.SilkS")
			(hide yes)
			(effects
				(font
					(size 1.27 1.27)
				)
			)
		)
		(property "Value" "SC100U6D3V0MX-2GP"
			(at -0.00254 -4.78536 180)
			(unlocked yes)
			(layer "F.Fab")
			(hide yes)
			(effects
				(font
					(size 1.016 1.016)
					(thickness 0.1524)
				)
			)
		)
		(property "Device Type" "C1210H107"
			(at -0.00254 -6.38048 180)
			(unlocked yes)
			(layer "F.Fab")
			(hide yes)
			(effects
				(font
					(size 1.016 1.016)
					(thickness 0.1524)
				)
			)
		)
		(duplicate_pad_numbers_are_jumpers no)
		(fp_line
			(start 1.5748 2.3368)
			(end 1.5748 0.762)
			(stroke
				(width 0.1524)
				(type default)
			)
			(layer "F.SilkS")
		)
		(fp_line
			(start 1.5748 -0.762)
			(end 1.5748 -2.3368)
			(stroke
				(width 0.1524)
				(type default)
			)
			(layer "F.SilkS")
		)
		(fp_line
			(start 1.5748 -2.3368)
			(end -1.5748 -2.3368)
			(stroke
				(width 0.1524)
				(type default)
			)
			(layer "F.SilkS")
		)
		(fp_line
			(start -1.5748 2.3368)
			(end 1.5748 2.3368)
			(stroke
				(width 0.1524)
				(type default)
			)
			(layer "F.SilkS")
		)
		(fp_line
			(start -1.5748 0.762)
			(end -1.5748 2.3368)
			(stroke
				(width 0.1524)
				(type default)
			)
			(layer "F.SilkS")
		)
		(fp_line
			(start -1.5748 -2.3368)
			(end -1.5748 -0.762)
			(stroke
				(width 0.1524)
				(type default)
			)
			(layer "F.SilkS")
		)
		(fp_rect
			(start -1.651 2.413)
			(end 1.651 -2.413)
			(stroke
				(width 0)
				(type default)
			)
			(fill no)
			(layer "F.CrtYd")
		)
		(fp_poly
			(pts
				(xy 1.651 2.413) (xy 1.651 -2.413) (xy -1.651 -2.413) (xy -1.651 2.413)
			)
			(stroke
				(width 0)
				(type default)
			)
			(fill no)
			(layer "F.Fab")
		)
		(pad "1" smd rect
			(at 0 -1.4732 180)
			(size 2.794 1.397)
			(layers "F.Cu" "F.Mask" "F.Paste")
			(net "GND")
		)
		(pad "2" smd rect
			(at 0 1.4732 180)
			(size 2.794 1.397)
			(layers "F.Cu" "F.Mask" "F.Paste")
			(net "GB_VDDA")
		)
	)
	(footprint ""
		(layer "F.Cu")
		(at 113.792 -27.94 -90)
		(property "Reference" "SR662"
			(at 0 0 270)
			(layer "F.SilkS")
			(hide yes)
			(effects
				(font
					(size 1.27 1.27)
				)
			)
		)
		(property "Value" "10KR2F-2-GP"
			(at 0.064008 -3.993896 270)
			(unlocked yes)
			(layer "F.Fab")
			(hide yes)
			(effects
				(font
					(size 1.016 1.016)
					(thickness 0.1524)
				)
			)
		)
		(property "Device Type" "R402H16"
			(at 0.064008 -5.517896 270)
			(unlocked yes)
			(layer "F.Fab")
			(hide yes)
			(effects
				(font
					(size 1.016 1.016)
					(thickness 0.1524)
				)
			)
		)
		(duplicate_pad_numbers_are_jumpers no)
		(fp_line
			(start -0.508 -0.9398)
			(end -0.508 0.9398)
			(stroke
				(width 0.1524)
				(type default)
			)
			(layer "F.SilkS")
		)
		(fp_line
			(start 0.508 -0.9398)
			(end -0.508 -0.9398)
			(stroke
				(width 0.1524)
				(type default)
			)
			(layer "F.SilkS")
		)
		(fp_rect
			(start -0.508 0.9398)
			(end 0.508 -0.9398)
			(stroke
				(width 0)
				(type default)
			)
			(fill no)
			(layer "F.CrtYd")
		)
		(fp_rect
			(start -0.508 0.9398)
			(end 0.508 -0.9398)
			(stroke
				(width 0)
				(type default)
			)
			(fill no)
			(layer "F.Fab")
		)
		(pad "1" smd custom
			(at 0 -0.4445 270)
			(size 0.1397 0.1397)
			(layers "F.Cu" "F.Mask" "F.Paste")
			(net "P1V8_C")
			(options
				(clearance outline)
				(anchor circle)
			)
			(primitives
				(gr_poly
					(pts
						(arc
							(start -0.1778 -0.2794)
							(mid -0.249642 -0.249642)
							(end -0.2794 -0.1778)
						)
						(arc
							(start -0.2794 0.1778)
							(mid -0.249642 0.249642)
							(end -0.1778 0.2794)
						)
						(arc
							(start 0.1778 0.2794)
							(mid 0.249642 0.249642)
							(end 0.2794 0.1778)
						)
						(arc
							(start 0.2794 -0.1778)
							(mid 0.249642 -0.249642)
							(end 0.1778 -0.2794)
						)
					)
					(width 0)
					(fill yes)
				)
			)
		)
		(pad "2" smd custom
			(at 0 0.4445 270)
			(size 0.1397 0.1397)
			(layers "F.Cu" "F.Mask" "F.Paste")
			(net "SYS_DBMODE3")
			(options
				(clearance outline)
				(anchor circle)
			)
			(primitives
				(gr_poly
					(pts
						(arc
							(start -0.1778 -0.2794)
							(mid -0.249642 -0.249642)
							(end -0.2794 -0.1778)
						)
						(arc
							(start -0.2794 0.1778)
							(mid -0.249642 0.249642)
							(end -0.1778 0.2794)
						)
						(arc
							(start 0.1778 0.2794)
							(mid 0.249642 0.249642)
							(end 0.2794 0.1778)
						)
						(arc
							(start 0.2794 -0.1778)
							(mid 0.249642 -0.249642)
							(end 0.1778 -0.2794)
						)
					)
					(width 0)
					(fill yes)
				)
			)
		)
	)
	(footprint ""
		(layer "F.Cu")
		(at 305.816 -190.246 90)
		(property "Reference" "R226"
			(at 0 0 90)
			(layer "F.SilkS")
			(hide yes)
			(effects
				(font
					(size 1.27 1.27)
				)
			)
		)
		(property "Value" "10KR2F-2-GP"
			(at 0.064008 -3.993896 90)
			(unlocked yes)
			(layer "F.Fab")
			(hide yes)
			(effects
				(font
					(size 1.016 1.016)
					(thickness 0.1524)
				)
			)
		)
		(property "Device Type" "R402H16"
			(at 0.064008 -5.517896 90)
			(unlocked yes)
			(layer "F.Fab")
			(hide yes)
			(effects
				(font
					(size 1.016 1.016)
					(thickness 0.1524)
				)
			)
		)
		(duplicate_pad_numbers_are_jumpers no)
		(fp_line
			(start 0.508 -0.9398)
			(end -0.508 -0.9398)
			(stroke
				(width 0.1524)
				(type default)
			)
			(layer "F.SilkS")
		)
		(fp_line
			(start -0.508 -0.9398)
			(end -0.508 0.9398)
			(stroke
				(width 0.1524)
				(type default)
			)
			(layer "F.SilkS")
		)
		(fp_rect
			(start -0.508 0.9398)
			(end 0.508 -0.9398)
			(stroke
				(width 0)
				(type default)
			)
			(fill no)
			(layer "F.CrtYd")
		)
		(fp_rect
			(start -0.508 0.9398)
			(end 0.508 -0.9398)
			(stroke
				(width 0)
				(type default)
			)
			(fill no)
			(layer "F.Fab")
		)
		(pad "1" smd custom
			(at 0 -0.4445 90)
			(size 0.1397 0.1397)
			(layers "F.Cu" "F.Mask" "F.Paste")
			(net "P3V3_STBY")
			(options
				(clearance outline)
				(anchor circle)
			)
			(primitives
				(gr_poly
					(pts
						(arc
							(start -0.1778 -0.2794)
							(mid -0.249642 -0.249642)
							(end -0.2794 -0.1778)
						)
						(arc
							(start -0.2794 0.1778)
							(mid -0.249642 0.249642)
							(end -0.1778 0.2794)
						)
						(arc
							(start 0.1778 0.2794)
							(mid 0.249642 0.249642)
							(end 0.2794 0.1778)
						)
						(arc
							(start 0.2794 -0.1778)
							(mid 0.249642 -0.249642)
							(end 0.1778 -0.2794)
						)
					)
					(width 0)
					(fill yes)
				)
			)
		)
		(pad "2" smd custom
			(at 0 0.4445 90)
			(size 0.1397 0.1397)
			(layers "F.Cu" "F.Mask" "F.Paste")
			(net "CONN_10G_PRSNT2_N")
			(options
				(clearance outline)
				(anchor circle)
			)
			(primitives
				(gr_poly
					(pts
						(arc
							(start -0.1778 -0.2794)
							(mid -0.249642 -0.249642)
							(end -0.2794 -0.1778)
						)
						(arc
							(start -0.2794 0.1778)
							(mid -0.249642 0.249642)
							(end -0.1778 0.2794)
						)
						(arc
							(start 0.1778 0.2794)
							(mid 0.249642 0.249642)
							(end 0.2794 0.1778)
						)
						(arc
							(start 0.2794 -0.1778)
							(mid 0.249642 -0.249642)
							(end 0.1778 -0.2794)
						)
					)
					(width 0)
					(fill yes)
				)
			)
		)
	)
	(footprint ""
		(layer "F.Cu")
		(at 337.684872 -165.553136 180)
		(property "Reference" "U28"
			(at 0 0 180)
			(layer "F.SilkS")
			(hide yes)
			(effects
				(font
					(size 1.27 1.27)
				)
			)
		)
		(property "Value" "TS5A23157DGSR-GP"
			(at 0 -11.1252 180)
			(unlocked yes)
			(layer "F.Fab")
			(hide yes)
			(effects
				(font
					(size 1.016 1.016)
					(thickness 0.1524)
				)
			)
		)
		(property "Device Type" "MSOP10H44"
			(at 0 -12.6492 180)
			(unlocked yes)
			(layer "F.Fab")
			(hide yes)
			(effects
				(font
					(size 1.016 1.016)
					(thickness 0.1524)
				)
			)
		)
		(duplicate_pad_numbers_are_jumpers no)
		(fp_line
			(start 1.143 1.016)
			(end -2.0066 1.016)
			(stroke
				(width 0.1524)
				(type default)
			)
			(layer "F.SilkS")
		)
		(fp_line
			(start 1.143 -1.016)
			(end 1.143 1.016)
			(stroke
				(width 0.1524)
				(type default)
			)
			(layer "F.SilkS")
		)
		(fp_line
			(start -1.5748 0)
			(end -1.9558 0.381)
			(stroke
				(width 0.1524)
				(type default)
			)
			(layer "F.SilkS")
		)
		(fp_line
			(start -1.5748 0)
			(end -1.9558 -0.381)
			(stroke
				(width 0.1524)
				(type default)
			)
			(layer "F.SilkS")
		)
		(fp_line
			(start -1.8288 1.016)
			(end -1.8288 3.048)
			(stroke
				(width 0.508)
				(type default)
			)
			(layer "F.SilkS")
		)
		(fp_line
			(start -2.0066 1.016)
			(end -2.0066 -1.016)
			(stroke
				(width 0.1524)
				(type default)
			)
			(layer "F.SilkS")
		)
		(fp_line
			(start -2.0066 -1.016)
			(end 1.143 -1.016)
			(stroke
				(width 0.1524)
				(type default)
			)
			(layer "F.SilkS")
		)
		(fp_poly
			(pts
				(xy -2.0828 3.3401) (xy 2.0828 3.3401) (xy 2.0828 -3.3401) (xy -2.0828 -3.3401)
			)
			(stroke
				(width 0)
				(type default)
			)
			(fill no)
			(layer "F.CrtYd")
		)
		(fp_poly
			(pts
				(xy -2.0828 3.3401) (xy 2.0828 3.3401) (xy 2.0828 -3.3401) (xy -2.0828 -3.3401)
			)
			(stroke
				(width 0)
				(type default)
			)
			(fill no)
			(layer "F.Fab")
		)
		(pad "1" smd rect
			(at -0.99949 2.0701 180)
			(size 0.3048 1.524)
			(layers "F.Cu" "F.Mask" "F.Paste")
			(net "BMC_UART_SWITCH_R")
		)
		(pad "2" smd rect
			(at -0.50038 2.0701 180)
			(size 0.3048 1.524)
			(layers "F.Cu" "F.Mask" "F.Paste")
			(net "UART2_TX")
		)
		(pad "3" smd rect
			(at 0 2.0701 180)
			(size 0.3048 1.524)
			(layers "F.Cu" "F.Mask" "F.Paste")
			(net "GND")
		)
		(pad "4" smd rect
			(at 0.50038 2.0701 180)
			(size 0.3048 1.524)
			(layers "F.Cu" "F.Mask" "F.Paste")
			(net "UART2_RX")
		)
		(pad "5" smd rect
			(at 0.99949 2.0701 180)
			(size 0.3048 1.524)
			(layers "F.Cu" "F.Mask" "F.Paste")
			(net "BMC_UART_SWITCH_R")
		)
		(pad "6" smd rect
			(at 0.99949 -2.0701 180)
			(size 0.3048 1.524)
			(layers "F.Cu" "F.Mask" "F.Paste")
			(net "DEBUG_CARD_RX")
		)
		(pad "7" smd rect
			(at 0.50038 -2.0701 180)
			(size 0.3048 1.524)
			(layers "F.Cu" "F.Mask" "F.Paste")
			(net "UART1_RX")
		)
		(pad "8" smd rect
			(at 0 -2.0701 180)
			(size 0.3048 1.524)
			(layers "F.Cu" "F.Mask" "F.Paste")
			(net "P3V3_STBY")
		)
		(pad "9" smd rect
			(at -0.50038 -2.0701 180)
			(size 0.3048 1.524)
			(layers "F.Cu" "F.Mask" "F.Paste")
			(net "UART1_TX")
		)
		(pad "10" smd rect
			(at -0.99949 -2.0701 180)
			(size 0.3048 1.524)
			(layers "F.Cu" "F.Mask" "F.Paste")
			(net "DEBUG_CARD_TX")
		)
	)
	(footprint ""
		(layer "F.Cu")
		(at 314.4774 -217.3224)
		(property "Reference" "R574"
			(at 0 0 0)
			(layer "F.SilkS")
			(hide yes)
			(effects
				(font
					(size 1.27 1.27)
				)
			)
		)
		(property "Value" "0R2J-2-GP"
			(at 0.064008 -3.993896 0)
			(unlocked yes)
			(layer "F.Fab")
			(hide yes)
			(effects
				(font
					(size 1.016 1.016)
					(thickness 0.1524)
				)
			)
		)
		(property "Device Type" "R402H16"
			(at 0.064008 -5.517896 0)
			(unlocked yes)
			(layer "F.Fab")
			(hide yes)
			(effects
				(font
					(size 1.016 1.016)
					(thickness 0.1524)
				)
			)
		)
		(duplicate_pad_numbers_are_jumpers no)
		(fp_line
			(start -0.508 -0.9398)
			(end -0.508 0.9398)
			(stroke
				(width 0.1524)
				(type default)
			)
			(layer "F.SilkS")
		)
		(fp_line
			(start 0.508 -0.9398)
			(end -0.508 -0.9398)
			(stroke
				(width 0.1524)
				(type default)
			)
			(layer "F.SilkS")
		)
		(fp_rect
			(start -0.508 0.9398)
			(end 0.508 -0.9398)
			(stroke
				(width 0)
				(type default)
			)
			(fill no)
			(layer "F.CrtYd")
		)
		(fp_rect
			(start -0.508 0.9398)
			(end 0.508 -0.9398)
			(stroke
				(width 0)
				(type default)
			)
			(fill no)
			(layer "F.Fab")
		)
		(pad "1" smd custom
			(at 0 -0.4445)
			(size 0.1397 0.1397)
			(layers "F.Cu" "F.Mask" "F.Paste")
			(net "JTAG_EXP_TDO")
			(options
				(clearance outline)
				(anchor circle)
			)
			(primitives
				(gr_poly
					(pts
						(arc
							(start -0.1778 -0.2794)
							(mid -0.249642 -0.249642)
							(end -0.2794 -0.1778)
						)
						(arc
							(start -0.2794 0.1778)
							(mid -0.249642 0.249642)
							(end -0.1778 0.2794)
						)
						(arc
							(start 0.1778 0.2794)
							(mid 0.249642 0.249642)
							(end 0.2794 0.1778)
						)
						(arc
							(start 0.2794 -0.1778)
							(mid 0.249642 -0.249642)
							(end 0.1778 -0.2794)
						)
					)
					(width 0)
					(fill yes)
				)
			)
		)
		(pad "2" smd custom
			(at 0 0.4445)
			(size 0.1397 0.1397)
			(layers "F.Cu" "F.Mask" "F.Paste")
			(net "JTAG_EXP_R_TDO")
			(options
				(clearance outline)
				(anchor circle)
			)
			(primitives
				(gr_poly
					(pts
						(arc
							(start -0.1778 -0.2794)
							(mid -0.249642 -0.249642)
							(end -0.2794 -0.1778)
						)
						(arc
							(start -0.2794 0.1778)
							(mid -0.249642 0.249642)
							(end -0.1778 0.2794)
						)
						(arc
							(start 0.1778 0.2794)
							(mid 0.249642 0.249642)
							(end 0.2794 0.1778)
						)
						(arc
							(start 0.2794 -0.1778)
							(mid 0.249642 -0.249642)
							(end 0.1778 -0.2794)
						)
					)
					(width 0)
					(fill yes)
				)
			)
		)
	)
	(footprint ""
		(layer "F.Cu")
		(at 304.419 -219.837 180)
		(property "Reference" "U42"
			(at 0 0 180)
			(layer "F.SilkS")
			(hide yes)
			(effects
				(font
					(size 1.27 1.27)
				)
			)
		)
		(property "Value" "SN74LVC1G00DC-1GP"
			(at -2.3368 -8.6868 180)
			(unlocked yes)
			(layer "F.Fab")
			(hide yes)
			(effects
				(font
					(size 1.016 1.016)
					(thickness 0.1524)
				)
			)
		)
		(property "Device Type" "SC70-5H44"
			(at -2.3114 -10.414 180)
			(unlocked yes)
			(layer "F.Fab")
			(hide yes)
			(effects
				(font
					(size 1.016 1.016)
					(thickness 0.1524)
				)
			)
		)
		(duplicate_pad_numbers_are_jumpers no)
		(fp_line
			(start 1.3843 -1.8034)
			(end 1.3843 -1.1176)
			(stroke
				(width 0.3302)
				(type default)
			)
			(layer "F.SilkS")
		)
		(fp_line
			(start 1.27 1.7018)
			(end -1.27 1.7018)
			(stroke
				(width 0.1524)
				(type default)
			)
			(layer "F.SilkS")
		)
		(fp_line
			(start 1.27 -1.7018)
			(end 1.27 1.7018)
			(stroke
				(width 0.1524)
				(type default)
			)
			(layer "F.SilkS")
		)
		(fp_line
			(start 0.6604 -1.8034)
			(end 1.3843 -1.8034)
			(stroke
				(width 0.3302)
				(type default)
			)
			(layer "F.SilkS")
		)
		(fp_line
			(start -1.27 1.7018)
			(end -1.27 -1.7018)
			(stroke
				(width 0.1524)
				(type default)
			)
			(layer "F.SilkS")
		)
		(fp_line
			(start -1.27 -1.7018)
			(end 1.27 -1.7018)
			(stroke
				(width 0.1524)
				(type default)
			)
			(layer "F.SilkS")
		)
		(fp_rect
			(start -1.524 1.9558)
			(end 1.524 -1.9558)
			(stroke
				(width 0)
				(type default)
			)
			(fill no)
			(layer "F.CrtYd")
		)
		(fp_poly
			(pts
				(xy -1.524 -1.9558) (xy 1.524 -1.9558) (xy 1.524 1.9558) (xy -1.524 1.9558)
			)
			(stroke
				(width 0)
				(type default)
			)
			(fill no)
			(layer "F.Fab")
		)
		(pad "1" smd rect
			(at 0.65024 -0.8255 180)
			(size 0.4064 1.2192)
			(layers "F.Cu" "F.Mask" "F.Paste")
			(net "PMU_PLTRST_N")
		)
		(pad "2" smd rect
			(at 0 -0.8255 180)
			(size 0.4064 1.2192)
			(layers "F.Cu" "F.Mask" "F.Paste")
			(net "BMC_DEBUG_OE_1_N")
		)
		(pad "3" smd rect
			(at -0.65024 -0.8255 180)
			(size 0.4064 1.2192)
			(layers "F.Cu" "F.Mask" "F.Paste")
			(net "GND")
		)
		(pad "4" smd rect
			(at -0.65024 0.8255 180)
			(size 0.4064 1.2192)
			(layers "F.Cu" "F.Mask" "F.Paste")
			(net "DEBUG_OE_1_N")
		)
		(pad "5" smd rect
			(at 0.65024 0.8255 180)
			(size 0.4064 1.2192)
			(layers "F.Cu" "F.Mask" "F.Paste")
			(net "P3V3_STBY")
		)
	)
	(footprint ""
		(layer "F.Cu")
		(at 173.99 -93.726 90)
		(property "Reference" "PTC4"
			(at 0 0 90)
			(layer "F.SilkS")
			(hide yes)
			(effects
				(font
					(size 1.27 1.27)
				)
			)
		)
		(property "Value" "SE470UF2VDM-GP"
			(at 0 -9.6012 90)
			(unlocked yes)
			(layer "F.Fab")
			(hide yes)
			(effects
				(font
					(size 1.016 1.016)
					(thickness 0.1524)
				)
			)
		)
		(property "Device Type" "CT7343H83"
			(at 0 -11.1252 90)
			(unlocked yes)
			(layer "F.Fab")
			(hide yes)
			(effects
				(font
					(size 1.016 1.016)
					(thickness 0.1524)
				)
			)
		)
		(duplicate_pad_numbers_are_jumpers no)
		(fp_line
			(start 2.286 -4.8768)
			(end -2.286 -4.8768)
			(stroke
				(width 0.1524)
				(type default)
			)
			(layer "F.SilkS")
		)
		(fp_line
			(start -2.286 -4.8768)
			(end -2.286 -2.032)
			(stroke
				(width 0.1524)
				(type default)
			)
			(layer "F.SilkS")
		)
		(fp_line
			(start 2.1082 -4.699)
			(end -2.1082 -4.699)
			(stroke
				(width 0.508)
				(type default)
			)
			(layer "F.SilkS")
		)
		(fp_line
			(start 2.286 -2.032)
			(end 2.286 -4.8768)
			(stroke
				(width 0.1524)
				(type default)
			)
			(layer "F.SilkS")
		)
		(fp_line
			(start 2.286 2.032)
			(end 2.286 4.8768)
			(stroke
				(width 0.1524)
				(type default)
			)
			(layer "F.SilkS")
		)
		(fp_line
			(start 2.286 4.8768)
			(end -2.286 4.8768)
			(stroke
				(width 0.1524)
				(type default)
			)
			(layer "F.SilkS")
		)
		(fp_line
			(start -2.286 4.8768)
			(end -2.286 2.032)
			(stroke
				(width 0.1524)
				(type default)
			)
			(layer "F.SilkS")
		)
		(fp_rect
			(start -2.1463 3.6449)
			(end 2.1463 -3.6449)
			(stroke
				(width 0)
				(type default)
			)
			(fill no)
			(layer "F.CrtYd")
		)
		(fp_poly
			(pts
				(xy -2.54 4.953) (xy -2.54 4.2926) (xy -3.81 4.2926) (xy -3.81 -4.2926) (xy -2.54 -4.2926) (xy -2.54 -4.953)
				(xy 2.54 -4.953) (xy 2.54 -4.2926) (xy 3.81 -4.2926) (xy 3.81 -1.6256) (xy 2.1463 -1.6256) (xy 2.1463 -3.6449)
				(xy -2.1463 -3.6449) (xy -2.1463 3.6449) (xy 2.1463 3.6449) (xy 2.1463 -1.6129) (xy 3.81 -1.6129)
				(xy 3.81 4.2926) (xy 2.54 4.2926) (xy 2.54 4.953)
			)
			(stroke
				(width 0)
				(type default)
			)
			(fill no)
			(layer "F.CrtYd")
		)
		(fp_rect
			(start 2.54 4.2926)
			(end 3.81 -4.2926)
			(stroke
				(width 0)
				(type default)
			)
			(fill no)
			(layer "F.Fab")
		)
		(fp_rect
			(start -3.81 4.2926)
			(end -2.54 -4.2926)
			(stroke
				(width 0)
				(type default)
			)
			(fill no)
			(layer "F.Fab")
		)
		(fp_rect
			(start -2.54 4.953)
			(end 2.54 -4.953)
			(stroke
				(width 0)
				(type default)
			)
			(fill no)
			(layer "F.Fab")
		)
		(pad "1" smd rect
			(at 0 -3.1496 90)
			(size 2.413 2.286)
			(layers "F.Cu" "F.Mask" "F.Paste")
			(net "P0V9_E")
		)
		(pad "2" smd rect
			(at 0 3.1496 90)
			(size 2.413 2.286)
			(layers "F.Cu" "F.Mask" "F.Paste")
			(net "GND")
		)
		(zone
			(layer "F.Cu")
			(hatch none 0.5)
			(connect_pads
				(clearance 0)
			)
			(min_thickness 0.25)
			(keepout
				(tracks allowed)
				(vias not_allowed)
				(pads allowed)
				(copperpour not_allowed)
				(footprints allowed)
			)
			(placement
				(enabled no)
				(sheetname "")
			)
			(fill
				(thermal_gap 0.5)
				(thermal_bridge_width 0.5)
				(island_removal_mode 0)
			)
			(polygon
				(pts
					(xy 172.3009 -95.2373) (xy 169.3926 -95.2373) (xy 169.3926 -92.2147) (xy 172.2882 -92.2147) (xy 172.6184 -92.2147)
					(xy 172.6184 -95.2373)
				)
			)
		)
		(zone
			(layer "F.Cu")
			(hatch none 0.5)
			(connect_pads
				(clearance 0)
			)
			(min_thickness 0.25)
			(keepout
				(tracks allowed)
				(vias not_allowed)
				(pads allowed)
				(copperpour not_allowed)
				(footprints allowed)
			)
			(placement
				(enabled no)
				(sheetname "")
			)
			(fill
				(thermal_gap 0.5)
				(thermal_bridge_width 0.5)
				(island_removal_mode 0)
			)
			(polygon
				(pts
					(xy 178.5874 -92.2147) (xy 178.5874 -95.2373) (xy 175.6918 -95.2373) (xy 175.3616 -95.2373) (xy 175.3616 -92.2147)
					(xy 175.6918 -92.2147)
				)
			)
		)
	)
	(footprint ""
		(layer "F.Cu")
		(at 103.13797 -78.105)
		(property "Reference" "STP149"
			(at 0 0 0)
			(layer "F.SilkS")
			(hide yes)
			(effects
				(font
					(size 1.27 1.27)
				)
			)
		)
		(property "Value" "TPAD28"
			(at 0.0127 -1.8034 0)
			(unlocked yes)
			(layer "F.Fab")
			(hide yes)
			(effects
				(font
					(size 1.016 1.016)
					(thickness 0.1524)
				)
			)
		)
		(property "Device Type" "TPAD28"
			(at 0.0127 -3.3274 0)
			(unlocked yes)
			(layer "F.Fab")
			(hide yes)
			(effects
				(font
					(size 1.016 1.016)
					(thickness 0.1524)
				)
			)
		)
		(duplicate_pad_numbers_are_jumpers no)
		(fp_poly
			(pts
				(arc
					(start 0.3556 0)
					(mid -0.3556 0)
					(end 0.3556 0)
				)
			)
			(stroke
				(width 0)
				(type default)
			)
			(fill no)
			(layer "F.CrtYd")
		)
		(fp_poly
			(pts
				(arc
					(start 0.6096 0)
					(mid -0.6096 0)
					(end 0.6096 0)
				)
			)
			(stroke
				(width 0)
				(type default)
			)
			(fill no)
			(layer "F.Fab")
		)
		(pad "1" smd circle
			(at 0 0)
			(size 0.7112 0.7112)
			(layers "F.Cu" "F.Mask" "F.Paste")
			(net "JTAG_EXP_TDI")
		)
	)
	(footprint ""
		(layer "F.Cu")
		(at 166.243 -117.475 -90)
		(property "Reference" "PSP2"
			(at 0 0 270)
			(layer "F.SilkS")
			(hide yes)
			(effects
				(font
					(size 1.27 1.27)
				)
			)
		)
		(property "Value" "COPPER-CLOSE-GP-U"
			(at 0.0762 -2.8702 270)
			(unlocked yes)
			(layer "F.Fab")
			(hide yes)
			(effects
				(font
					(size 1.016 1.016)
					(thickness 0.1524)
				)
			)
		)
		(property "Device Type" "CON2C-U"
			(at 0.0762 -4.3942 270)
			(unlocked yes)
			(layer "F.Fab")
			(hide yes)
			(effects
				(font
					(size 1.016 1.016)
					(thickness 0.1524)
				)
			)
		)
		(duplicate_pad_numbers_are_jumpers no)
		(fp_rect
			(start -0.9398 0.9652)
			(end 0.9398 -0.9652)
			(stroke
				(width 0)
				(type default)
			)
			(fill no)
			(layer "F.CrtYd")
		)
		(fp_rect
			(start -0.9398 0.9652)
			(end 0.9398 -0.9652)
			(stroke
				(width 0)
				(type default)
			)
			(fill no)
			(layer "F.Fab")
		)
		(pad "1" smd custom
			(at 0 -0.5334 270)
			(size 0.17145 0.17145)
			(layers "F.Cu" "F.Mask" "F.Paste")
			(net "GND")
			(options
				(clearance outline)
				(anchor circle)
			)
			(primitives
				(gr_poly
					(pts
						(xy -0.127 0.3429) (xy -0.127 0.1651) (xy -0.635 -0.3429) (xy 0.635 -0.3429) (xy 0.127 0.1651)
						(xy 0.127 0.3429)
					)
					(width 0)
					(fill yes)
				)
			)
		)
		(pad "2" smd custom
			(at 0 0.5334 270)
			(size 0.17145 0.17145)
			(layers "F.Cu" "F.Mask" "F.Paste")
			(net "AGND_P0V9_E")
			(options
				(clearance outline)
				(anchor circle)
			)
			(primitives
				(gr_poly
					(pts
						(xy -0.635 0.3429) (xy -0.127 -0.1651) (xy -0.127 -0.3429) (xy 0.127 -0.3429) (xy 0.127 -0.1651)
						(xy 0.635 0.3429)
					)
					(width 0)
					(fill yes)
				)
			)
		)
	)
	(footprint ""
		(layer "F.Cu")
		(at 84.963 -31.75 180)
		(property "Reference" "SC965"
			(at 0 0 180)
			(layer "F.SilkS")
			(hide yes)
			(effects
				(font
					(size 1.27 1.27)
				)
			)
		)
		(property "Value" "SCD1U6D3V1KX-GP"
			(at -2.8321 -1.7399 180)
			(unlocked yes)
			(layer "F.Fab")
			(hide yes)
			(effects
				(font
					(size 1.016 1.016)
					(thickness 0.1524)
				)
			)
		)
		(property "Device Type" "C0201H13"
			(at -2.8321 -3.2639 180)
			(unlocked yes)
			(layer "F.Fab")
			(hide yes)
			(effects
				(font
					(size 1.016 1.016)
					(thickness 0.1524)
				)
			)
		)
		(duplicate_pad_numbers_are_jumpers no)
		(fp_rect
			(start -0.2794 0.6477)
			(end 0.2794 -0.6477)
			(stroke
				(width 0)
				(type default)
			)
			(fill no)
			(layer "F.CrtYd")
		)
		(fp_rect
			(start -0.2794 0.6477)
			(end 0.2794 -0.6477)
			(stroke
				(width 0)
				(type default)
			)
			(fill no)
			(layer "F.Fab")
		)
		(pad "1" smd custom
			(at 0 -0.2794 180)
			(size 0.0762 0.0762)
			(layers "F.Cu" "F.Mask" "F.Paste")
			(net "SAS0_AVDD")
			(options
				(clearance outline)
				(anchor circle)
			)
			(primitives
				(gr_poly
					(pts
						(arc
							(start 0.1524 -0.127)
							(mid 0.137521 -0.162921)
							(end 0.1016 -0.1778)
						)
						(arc
							(start -0.1016 -0.1778)
							(mid -0.137521 -0.162921)
							(end -0.1524 -0.127)
						)
						(arc
							(start -0.1524 0.127)
							(mid -0.137521 0.162921)
							(end -0.1016 0.1778)
						)
						(arc
							(start 0.1016 0.1778)
							(mid 0.137521 0.162921)
							(end 0.1524 0.127)
						)
					)
					(width 0)
					(fill yes)
				)
			)
		)
		(pad "2" smd custom
			(at 0 0.2794 180)
			(size 0.0762 0.0762)
			(layers "F.Cu" "F.Mask" "F.Paste")
			(net "GND")
			(options
				(clearance outline)
				(anchor circle)
			)
			(primitives
				(gr_poly
					(pts
						(arc
							(start 0.1524 -0.127)
							(mid 0.137521 -0.162921)
							(end 0.1016 -0.1778)
						)
						(arc
							(start -0.1016 -0.1778)
							(mid -0.137521 -0.162921)
							(end -0.1524 -0.127)
						)
						(arc
							(start -0.1524 0.127)
							(mid -0.137521 0.162921)
							(end -0.1016 0.1778)
						)
						(arc
							(start 0.1016 0.1778)
							(mid 0.137521 0.162921)
							(end 0.1524 0.127)
						)
					)
					(width 0)
					(fill yes)
				)
			)
		)
	)
	(footprint ""
		(layer "F.Cu")
		(at 95.70847 -109.474 -90)
		(property "Reference" "SR744"
			(at 0 0 270)
			(layer "F.SilkS")
			(hide yes)
			(effects
				(font
					(size 1.27 1.27)
				)
			)
		)
		(property "Value" "2K2R2F-GP"
			(at 0.064008 -3.993896 270)
			(unlocked yes)
			(layer "F.Fab")
			(hide yes)
			(effects
				(font
					(size 1.016 1.016)
					(thickness 0.1524)
				)
			)
		)
		(property "Device Type" "R402H16"
			(at 0.064008 -5.517896 270)
			(unlocked yes)
			(layer "F.Fab")
			(hide yes)
			(effects
				(font
					(size 1.016 1.016)
					(thickness 0.1524)
				)
			)
		)
		(duplicate_pad_numbers_are_jumpers no)
		(fp_line
			(start -0.508 -0.9398)
			(end -0.508 0.9398)
			(stroke
				(width 0.1524)
				(type default)
			)
			(layer "F.SilkS")
		)
		(fp_line
			(start 0.508 -0.9398)
			(end -0.508 -0.9398)
			(stroke
				(width 0.1524)
				(type default)
			)
			(layer "F.SilkS")
		)
		(fp_rect
			(start -0.508 0.9398)
			(end 0.508 -0.9398)
			(stroke
				(width 0)
				(type default)
			)
			(fill no)
			(layer "F.CrtYd")
		)
		(fp_rect
			(start -0.508 0.9398)
			(end 0.508 -0.9398)
			(stroke
				(width 0)
				(type default)
			)
			(fill no)
			(layer "F.Fab")
		)
		(pad "1" smd custom
			(at 0 -0.4445 270)
			(size 0.1397 0.1397)
			(layers "F.Cu" "F.Mask" "F.Paste")
			(net "EXP_I2C_SCL_2")
			(options
				(clearance outline)
				(anchor circle)
			)
			(primitives
				(gr_poly
					(pts
						(arc
							(start -0.1778 -0.2794)
							(mid -0.249642 -0.249642)
							(end -0.2794 -0.1778)
						)
						(arc
							(start -0.2794 0.1778)
							(mid -0.249642 0.249642)
							(end -0.1778 0.2794)
						)
						(arc
							(start 0.1778 0.2794)
							(mid 0.249642 0.249642)
							(end 0.2794 0.1778)
						)
						(arc
							(start 0.2794 -0.1778)
							(mid 0.249642 -0.249642)
							(end 0.1778 -0.2794)
						)
					)
					(width 0)
					(fill yes)
				)
			)
		)
		(pad "2" smd custom
			(at 0 0.4445 270)
			(size 0.1397 0.1397)
			(layers "F.Cu" "F.Mask" "F.Paste")
			(net "P1V8_E")
			(options
				(clearance outline)
				(anchor circle)
			)
			(primitives
				(gr_poly
					(pts
						(arc
							(start -0.1778 -0.2794)
							(mid -0.249642 -0.249642)
							(end -0.2794 -0.1778)
						)
						(arc
							(start -0.2794 0.1778)
							(mid -0.249642 0.249642)
							(end -0.1778 0.2794)
						)
						(arc
							(start 0.1778 0.2794)
							(mid 0.249642 0.249642)
							(end 0.2794 0.1778)
						)
						(arc
							(start 0.2794 -0.1778)
							(mid 0.249642 -0.249642)
							(end 0.1778 -0.2794)
						)
					)
					(width 0)
					(fill yes)
				)
			)
		)
	)
	(footprint ""
		(layer "F.Cu")
		(at 89.662 -224.663 -90)
		(property "Reference" "SR310"
			(at 0 0 270)
			(layer "F.SilkS")
			(hide yes)
			(effects
				(font
					(size 1.27 1.27)
				)
			)
		)
		(property "Value" "0R2J-2-GP"
			(at 0.064008 -3.993896 270)
			(unlocked yes)
			(layer "F.Fab")
			(hide yes)
			(effects
				(font
					(size 1.016 1.016)
					(thickness 0.1524)
				)
			)
		)
		(property "Device Type" "R402H16"
			(at 0.064008 -5.517896 270)
			(unlocked yes)
			(layer "F.Fab")
			(hide yes)
			(effects
				(font
					(size 1.016 1.016)
					(thickness 0.1524)
				)
			)
		)
		(duplicate_pad_numbers_are_jumpers no)
		(fp_line
			(start -0.508 -0.9398)
			(end -0.508 0.9398)
			(stroke
				(width 0.1524)
				(type default)
			)
			(layer "F.SilkS")
		)
		(fp_line
			(start 0.508 -0.9398)
			(end -0.508 -0.9398)
			(stroke
				(width 0.1524)
				(type default)
			)
			(layer "F.SilkS")
		)
		(fp_rect
			(start -0.508 0.9398)
			(end 0.508 -0.9398)
			(stroke
				(width 0)
				(type default)
			)
			(fill no)
			(layer "F.CrtYd")
		)
		(fp_rect
			(start -0.508 0.9398)
			(end 0.508 -0.9398)
			(stroke
				(width 0)
				(type default)
			)
			(fill no)
			(layer "F.Fab")
		)
		(pad "1" smd custom
			(at 0 -0.4445 270)
			(size 0.1397 0.1397)
			(layers "F.Cu" "F.Mask" "F.Paste")
			(net "FAULT_SCL")
			(options
				(clearance outline)
				(anchor circle)
			)
			(primitives
				(gr_poly
					(pts
						(arc
							(start -0.1778 -0.2794)
							(mid -0.249642 -0.249642)
							(end -0.2794 -0.1778)
						)
						(arc
							(start -0.2794 0.1778)
							(mid -0.249642 0.249642)
							(end -0.1778 0.2794)
						)
						(arc
							(start 0.1778 0.2794)
							(mid 0.249642 0.249642)
							(end 0.2794 0.1778)
						)
						(arc
							(start 0.2794 -0.1778)
							(mid 0.249642 -0.249642)
							(end 0.1778 -0.2794)
						)
					)
					(width 0)
					(fill yes)
				)
			)
		)
		(pad "2" smd custom
			(at 0 0.4445 270)
			(size 0.1397 0.1397)
			(layers "F.Cu" "F.Mask" "F.Paste")
			(net "EXP_SCL_L_0")
			(options
				(clearance outline)
				(anchor circle)
			)
			(primitives
				(gr_poly
					(pts
						(arc
							(start -0.1778 -0.2794)
							(mid -0.249642 -0.249642)
							(end -0.2794 -0.1778)
						)
						(arc
							(start -0.2794 0.1778)
							(mid -0.249642 0.249642)
							(end -0.1778 0.2794)
						)
						(arc
							(start 0.1778 0.2794)
							(mid 0.249642 0.249642)
							(end 0.2794 0.1778)
						)
						(arc
							(start 0.2794 -0.1778)
							(mid 0.249642 -0.249642)
							(end 0.1778 -0.2794)
						)
					)
					(width 0)
					(fill yes)
				)
			)
		)
	)
	(footprint ""
		(layer "F.Cu")
		(at 217.805 -165.354)
		(property "Reference" "C84"
			(at 0 0 0)
			(layer "F.SilkS")
			(hide yes)
			(effects
				(font
					(size 1.27 1.27)
				)
			)
		)
		(property "Value" "SCD1U16V2KX-3GP"
			(at 1.1811 -2.7051 0)
			(unlocked yes)
			(layer "F.Fab")
			(hide yes)
			(effects
				(font
					(size 1.016 1.016)
					(thickness 0.1524)
				)
			)
		)
		(property "Device Type" "C402H22"
			(at 1.1811 -4.2291 0)
			(unlocked yes)
			(layer "F.Fab")
			(hide yes)
			(effects
				(font
					(size 1.016 1.016)
					(thickness 0.1524)
				)
			)
		)
		(duplicate_pad_numbers_are_jumpers no)
		(fp_rect
			(start -0.4318 0.9525)
			(end 0.4318 -0.9525)
			(stroke
				(width 0)
				(type default)
			)
			(fill no)
			(layer "F.CrtYd")
		)
		(fp_rect
			(start -0.4318 0.9525)
			(end 0.4318 -0.9525)
			(stroke
				(width 0)
				(type default)
			)
			(fill no)
			(layer "F.Fab")
		)
		(pad "1" smd custom
			(at 0 -0.4445)
			(size 0.1524 0.1524)
			(layers "F.Cu" "F.Mask" "F.Paste")
			(net "P3V3_STBY")
			(options
				(clearance outline)
				(anchor circle)
			)
			(primitives
				(gr_poly
					(pts
						(arc
							(start 0.3048 -0.2032)
							(mid 0.275042 -0.275042)
							(end 0.2032 -0.3048)
						)
						(arc
							(start -0.2032 -0.3048)
							(mid -0.275042 -0.275042)
							(end -0.3048 -0.2032)
						)
						(arc
							(start -0.3048 0.2032)
							(mid -0.275042 0.275042)
							(end -0.2032 0.3048)
						)
						(arc
							(start 0.2032 0.3048)
							(mid 0.275042 0.275042)
							(end 0.3048 0.2032)
						)
					)
					(width 0)
					(fill yes)
				)
			)
		)
		(pad "2" smd custom
			(at 0 0.4445)
			(size 0.1524 0.1524)
			(layers "F.Cu" "F.Mask" "F.Paste")
			(net "GND")
			(options
				(clearance outline)
				(anchor circle)
			)
			(primitives
				(gr_poly
					(pts
						(arc
							(start 0.3048 -0.2032)
							(mid 0.275042 -0.275042)
							(end 0.2032 -0.3048)
						)
						(arc
							(start -0.2032 -0.3048)
							(mid -0.275042 -0.275042)
							(end -0.3048 -0.2032)
						)
						(arc
							(start -0.3048 0.2032)
							(mid -0.275042 0.275042)
							(end -0.2032 0.3048)
						)
						(arc
							(start 0.2032 0.3048)
							(mid 0.275042 0.275042)
							(end 0.3048 0.2032)
						)
					)
					(width 0)
					(fill yes)
				)
			)
		)
	)
	(footprint ""
		(layer "F.Cu")
		(at 331.978 -92.202 90)
		(property "Reference" "PC36"
			(at 0 0 90)
			(layer "F.SilkS")
			(hide yes)
			(effects
				(font
					(size 1.27 1.27)
				)
			)
		)
		(property "Value" "SC22U6D3V3MX-1-GP"
			(at 0 -2.8194 90)
			(unlocked yes)
			(layer "F.Fab")
			(hide yes)
			(effects
				(font
					(size 1.016 1.016)
					(thickness 0.1524)
				)
			)
		)
		(property "Device Type" "C603H40"
			(at 0 -4.3434 90)
			(unlocked yes)
			(layer "F.Fab")
			(hide yes)
			(effects
				(font
					(size 1.016 1.016)
					(thickness 0.1524)
				)
			)
		)
		(duplicate_pad_numbers_are_jumpers no)
		(fp_line
			(start 0.508 0)
			(end -0.508 0)
			(stroke
				(width 0.2032)
				(type default)
			)
			(layer "F.SilkS")
		)
		(fp_rect
			(start -0.5842 1.3335)
			(end 0.5842 -1.3335)
			(stroke
				(width 0)
				(type default)
			)
			(fill no)
			(layer "F.CrtYd")
		)
		(fp_rect
			(start -0.5842 1.3335)
			(end 0.5842 -1.3335)
			(stroke
				(width 0)
				(type default)
			)
			(fill no)
			(layer "F.Fab")
		)
		(pad "1" smd custom
			(at 0 -0.762 90)
			(size 0.2159 0.2159)
			(layers "F.Cu" "F.Mask" "F.Paste")
			(net "P3V3_STBY")
			(options
				(clearance outline)
				(anchor circle)
			)
			(primitives
				(gr_poly
					(pts
						(arc
							(start -0.3302 -0.4318)
							(mid -0.402042 -0.402042)
							(end -0.4318 -0.3302)
						)
						(arc
							(start -0.4318 0.3302)
							(mid -0.402042 0.402042)
							(end -0.3302 0.4318)
						)
						(arc
							(start 0.3302 0.4318)
							(mid 0.402042 0.402042)
							(end 0.4318 0.3302)
						)
						(arc
							(start 0.4318 -0.3302)
							(mid 0.402042 -0.402042)
							(end 0.3302 -0.4318)
						)
					)
					(width 0)
					(fill yes)
				)
			)
		)
		(pad "2" smd custom
			(at 0 0.762 90)
			(size 0.2159 0.2159)
			(layers "F.Cu" "F.Mask" "F.Paste")
			(net "GND")
			(options
				(clearance outline)
				(anchor circle)
			)
			(primitives
				(gr_poly
					(pts
						(arc
							(start -0.3302 -0.4318)
							(mid -0.402042 -0.402042)
							(end -0.4318 -0.3302)
						)
						(arc
							(start -0.4318 0.3302)
							(mid -0.402042 0.402042)
							(end -0.3302 0.4318)
						)
						(arc
							(start 0.3302 0.4318)
							(mid 0.402042 0.402042)
							(end 0.4318 0.3302)
						)
						(arc
							(start 0.4318 -0.3302)
							(mid 0.402042 -0.402042)
							(end 0.3302 -0.4318)
						)
					)
					(width 0)
					(fill yes)
				)
			)
		)
	)
	(footprint ""
		(layer "F.Cu")
		(at 261.493 -31.115)
		(property "Reference" "PR40"
			(at 0 0 0)
			(layer "F.SilkS")
			(hide yes)
			(effects
				(font
					(size 1.27 1.27)
				)
			)
		)
		(property "Value" "0R2J-2-GP"
			(at 0.064008 -3.993896 0)
			(unlocked yes)
			(layer "F.Fab")
			(hide yes)
			(effects
				(font
					(size 1.016 1.016)
					(thickness 0.1524)
				)
			)
		)
		(property "Device Type" "R402H16"
			(at 0.064008 -5.517896 0)
			(unlocked yes)
			(layer "F.Fab")
			(hide yes)
			(effects
				(font
					(size 1.016 1.016)
					(thickness 0.1524)
				)
			)
		)
		(duplicate_pad_numbers_are_jumpers no)
		(fp_line
			(start -0.508 -0.9398)
			(end -0.508 0.9398)
			(stroke
				(width 0.1524)
				(type default)
			)
			(layer "F.SilkS")
		)
		(fp_line
			(start 0.508 -0.9398)
			(end -0.508 -0.9398)
			(stroke
				(width 0.1524)
				(type default)
			)
			(layer "F.SilkS")
		)
		(fp_rect
			(start -0.508 0.9398)
			(end 0.508 -0.9398)
			(stroke
				(width 0)
				(type default)
			)
			(fill no)
			(layer "F.CrtYd")
		)
		(fp_rect
			(start -0.508 0.9398)
			(end 0.508 -0.9398)
			(stroke
				(width 0)
				(type default)
			)
			(fill no)
			(layer "F.Fab")
		)
		(pad "1" smd custom
			(at 0 -0.4445)
			(size 0.1397 0.1397)
			(layers "F.Cu" "F.Mask" "F.Paste")
			(net "P1V8_STBY_EN")
			(options
				(clearance outline)
				(anchor circle)
			)
			(primitives
				(gr_poly
					(pts
						(arc
							(start -0.1778 -0.2794)
							(mid -0.249642 -0.249642)
							(end -0.2794 -0.1778)
						)
						(arc
							(start -0.2794 0.1778)
							(mid -0.249642 0.249642)
							(end -0.1778 0.2794)
						)
						(arc
							(start 0.1778 0.2794)
							(mid 0.249642 0.249642)
							(end 0.2794 0.1778)
						)
						(arc
							(start 0.2794 -0.1778)
							(mid 0.249642 -0.249642)
							(end 0.1778 -0.2794)
						)
					)
					(width 0)
					(fill yes)
				)
			)
		)
		(pad "2" smd custom
			(at 0 0.4445)
			(size 0.1397 0.1397)
			(layers "F.Cu" "F.Mask" "F.Paste")
			(net "P3V3_STBY_PG")
			(options
				(clearance outline)
				(anchor circle)
			)
			(primitives
				(gr_poly
					(pts
						(arc
							(start -0.1778 -0.2794)
							(mid -0.249642 -0.249642)
							(end -0.2794 -0.1778)
						)
						(arc
							(start -0.2794 0.1778)
							(mid -0.249642 0.249642)
							(end -0.1778 0.2794)
						)
						(arc
							(start 0.1778 0.2794)
							(mid 0.249642 0.249642)
							(end 0.2794 0.1778)
						)
						(arc
							(start 0.2794 -0.1778)
							(mid 0.249642 -0.249642)
							(end 0.1778 -0.2794)
						)
					)
					(width 0)
					(fill yes)
				)
			)
		)
	)
	(footprint ""
		(layer "F.Cu")
		(at 273.558 -63.246)
		(property "Reference" "R520"
			(at 0 0 0)
			(layer "F.SilkS")
			(hide yes)
			(effects
				(font
					(size 1.27 1.27)
				)
			)
		)
		(property "Value" "D008R2512F-GP"
			(at 0.0762 -11.4046 0)
			(unlocked yes)
			(layer "F.Fab")
			(hide yes)
			(effects
				(font
					(size 1.016 1.016)
					(thickness 0.1524)
				)
			)
		)
		(property "Device Type" "R2512H38"
			(at 0.0762 -13.1318 0)
			(unlocked yes)
			(layer "F.Fab")
			(hide yes)
			(effects
				(font
					(size 1.016 1.016)
					(thickness 0.1524)
				)
			)
		)
		(duplicate_pad_numbers_are_jumpers no)
		(fp_line
			(start -2.0574 -3.9878)
			(end -2.0574 3.9878)
			(stroke
				(width 0.1524)
				(type default)
			)
			(layer "F.SilkS")
		)
		(fp_line
			(start -2.0574 3.9878)
			(end 2.0574 3.9878)
			(stroke
				(width 0.1524)
				(type default)
			)
			(layer "F.SilkS")
		)
		(fp_line
			(start 2.0574 -3.9878)
			(end -2.0574 -3.9878)
			(stroke
				(width 0.1524)
				(type default)
			)
			(layer "F.SilkS")
		)
		(fp_line
			(start 2.0574 3.9878)
			(end 2.0574 -3.9878)
			(stroke
				(width 0.1524)
				(type default)
			)
			(layer "F.SilkS")
		)
		(fp_rect
			(start -2.1336 4.064)
			(end 2.1336 -4.064)
			(stroke
				(width 0)
				(type default)
			)
			(fill no)
			(layer "F.CrtYd")
		)
		(fp_rect
			(start -2.1336 4.064)
			(end 2.1336 -4.064)
			(stroke
				(width 0)
				(type default)
			)
			(fill no)
			(layer "F.Fab")
		)
		(pad "1" smd rect
			(at 0 -2.794)
			(size 3.5052 1.778)
			(layers "F.Cu" "F.Mask" "F.Paste")
			(net "P12V_PCIE")
		)
		(pad "2" smd rect
			(at 0 2.794)
			(size 3.5052 1.778)
			(layers "F.Cu" "F.Mask" "F.Paste")
			(net "VSENSE_HSC_MSB")
		)
	)
	(footprint ""
		(layer "F.Cu")
		(at 290.377372 -191.862456 180)
		(property "Reference" "R229"
			(at 0 0 180)
			(layer "F.SilkS")
			(hide yes)
			(effects
				(font
					(size 1.27 1.27)
				)
			)
		)
		(property "Value" "240R2F-1-GP"
			(at 0.064008 -3.993896 180)
			(unlocked yes)
			(layer "F.Fab")
			(hide yes)
			(effects
				(font
					(size 1.016 1.016)
					(thickness 0.1524)
				)
			)
		)
		(property "Device Type" "R402H16"
			(at 0.064008 -5.517896 180)
			(unlocked yes)
			(layer "F.Fab")
			(hide yes)
			(effects
				(font
					(size 1.016 1.016)
					(thickness 0.1524)
				)
			)
		)
		(duplicate_pad_numbers_are_jumpers no)
		(fp_line
			(start 0.508 -0.9398)
			(end -0.508 -0.9398)
			(stroke
				(width 0.1524)
				(type default)
			)
			(layer "F.SilkS")
		)
		(fp_line
			(start -0.508 -0.9398)
			(end -0.508 0.9398)
			(stroke
				(width 0.1524)
				(type default)
			)
			(layer "F.SilkS")
		)
		(fp_rect
			(start -0.508 0.9398)
			(end 0.508 -0.9398)
			(stroke
				(width 0)
				(type default)
			)
			(fill no)
			(layer "F.CrtYd")
		)
		(fp_rect
			(start -0.508 0.9398)
			(end 0.508 -0.9398)
			(stroke
				(width 0)
				(type default)
			)
			(fill no)
			(layer "F.Fab")
		)
		(pad "1" smd custom
			(at 0 -0.4445 180)
			(size 0.1397 0.1397)
			(layers "F.Cu" "F.Mask" "F.Paste")
			(net "GND")
			(options
				(clearance outline)
				(anchor circle)
			)
			(primitives
				(gr_poly
					(pts
						(arc
							(start -0.1778 -0.2794)
							(mid -0.249642 -0.249642)
							(end -0.2794 -0.1778)
						)
						(arc
							(start -0.2794 0.1778)
							(mid -0.249642 0.249642)
							(end -0.1778 0.2794)
						)
						(arc
							(start 0.1778 0.2794)
							(mid 0.249642 0.249642)
							(end 0.2794 0.1778)
						)
						(arc
							(start 0.2794 -0.1778)
							(mid 0.249642 -0.249642)
							(end 0.1778 -0.2794)
						)
					)
					(width 0)
					(fill yes)
				)
			)
		)
		(pad "2" smd custom
			(at 0 0.4445 180)
			(size 0.1397 0.1397)
			(layers "F.Cu" "F.Mask" "F.Paste")
			(net "PD_ZQ")
			(options
				(clearance outline)
				(anchor circle)
			)
			(primitives
				(gr_poly
					(pts
						(arc
							(start -0.1778 -0.2794)
							(mid -0.249642 -0.249642)
							(end -0.2794 -0.1778)
						)
						(arc
							(start -0.2794 0.1778)
							(mid -0.249642 0.249642)
							(end -0.1778 0.2794)
						)
						(arc
							(start 0.1778 0.2794)
							(mid 0.249642 0.249642)
							(end 0.2794 0.1778)
						)
						(arc
							(start 0.2794 -0.1778)
							(mid 0.249642 -0.249642)
							(end 0.1778 -0.2794)
						)
					)
					(width 0)
					(fill yes)
				)
			)
		)
	)
	(footprint ""
		(layer "F.Cu")
		(at 318.008 -163.322 -90)
		(property "Reference" "R262"
			(at 0 0 270)
			(layer "F.SilkS")
			(hide yes)
			(effects
				(font
					(size 1.27 1.27)
				)
			)
		)
		(property "Value" "10KR2F-2-GP"
			(at 0.064008 -3.993896 270)
			(unlocked yes)
			(layer "F.Fab")
			(hide yes)
			(effects
				(font
					(size 1.016 1.016)
					(thickness 0.1524)
				)
			)
		)
		(property "Device Type" "R402H16"
			(at 0.064008 -5.517896 270)
			(unlocked yes)
			(layer "F.Fab")
			(hide yes)
			(effects
				(font
					(size 1.016 1.016)
					(thickness 0.1524)
				)
			)
		)
		(duplicate_pad_numbers_are_jumpers no)
		(fp_line
			(start -0.508 -0.9398)
			(end -0.508 0.9398)
			(stroke
				(width 0.1524)
				(type default)
			)
			(layer "F.SilkS")
		)
		(fp_line
			(start 0.508 -0.9398)
			(end -0.508 -0.9398)
			(stroke
				(width 0.1524)
				(type default)
			)
			(layer "F.SilkS")
		)
		(fp_rect
			(start -0.508 0.9398)
			(end 0.508 -0.9398)
			(stroke
				(width 0)
				(type default)
			)
			(fill no)
			(layer "F.CrtYd")
		)
		(fp_rect
			(start -0.508 0.9398)
			(end 0.508 -0.9398)
			(stroke
				(width 0)
				(type default)
			)
			(fill no)
			(layer "F.Fab")
		)
		(pad "1" smd custom
			(at 0 -0.4445 270)
			(size 0.1397 0.1397)
			(layers "F.Cu" "F.Mask" "F.Paste")
			(net "P3V3_STBY")
			(options
				(clearance outline)
				(anchor circle)
			)
			(primitives
				(gr_poly
					(pts
						(arc
							(start -0.1778 -0.2794)
							(mid -0.249642 -0.249642)
							(end -0.2794 -0.1778)
						)
						(arc
							(start -0.2794 0.1778)
							(mid -0.249642 0.249642)
							(end -0.1778 0.2794)
						)
						(arc
							(start 0.1778 0.2794)
							(mid 0.249642 0.249642)
							(end 0.2794 0.1778)
						)
						(arc
							(start 0.2794 -0.1778)
							(mid 0.249642 -0.249642)
							(end 0.1778 -0.2794)
						)
					)
					(width 0)
					(fill yes)
				)
			)
		)
		(pad "2" smd custom
			(at 0 0.4445 270)
			(size 0.1397 0.1397)
			(layers "F.Cu" "F.Mask" "F.Paste")
			(net "PU_BMC0_SCL12")
			(options
				(clearance outline)
				(anchor circle)
			)
			(primitives
				(gr_poly
					(pts
						(arc
							(start -0.1778 -0.2794)
							(mid -0.249642 -0.249642)
							(end -0.2794 -0.1778)
						)
						(arc
							(start -0.2794 0.1778)
							(mid -0.249642 0.249642)
							(end -0.1778 0.2794)
						)
						(arc
							(start 0.1778 0.2794)
							(mid 0.249642 0.249642)
							(end 0.2794 0.1778)
						)
						(arc
							(start 0.2794 -0.1778)
							(mid 0.249642 -0.249642)
							(end 0.1778 -0.2794)
						)
					)
					(width 0)
					(fill yes)
				)
			)
		)
	)
	(footprint ""
		(layer "F.Cu")
		(at 112.846612 -222.885)
		(property "Reference" "SR882"
			(at 0 0 0)
			(layer "F.SilkS")
			(hide yes)
			(effects
				(font
					(size 1.27 1.27)
				)
			)
		)
		(property "Value" "0R2J-2-GP"
			(at 0.064008 -3.993896 0)
			(unlocked yes)
			(layer "F.Fab")
			(hide yes)
			(effects
				(font
					(size 1.016 1.016)
					(thickness 0.1524)
				)
			)
		)
		(property "Device Type" "R402H16"
			(at 0.064008 -5.517896 0)
			(unlocked yes)
			(layer "F.Fab")
			(hide yes)
			(effects
				(font
					(size 1.016 1.016)
					(thickness 0.1524)
				)
			)
		)
		(duplicate_pad_numbers_are_jumpers no)
		(fp_line
			(start -0.508 -0.9398)
			(end -0.508 0.9398)
			(stroke
				(width 0.1524)
				(type default)
			)
			(layer "F.SilkS")
		)
		(fp_line
			(start 0.508 -0.9398)
			(end -0.508 -0.9398)
			(stroke
				(width 0.1524)
				(type default)
			)
			(layer "F.SilkS")
		)
		(fp_rect
			(start -0.508 0.9398)
			(end 0.508 -0.9398)
			(stroke
				(width 0)
				(type default)
			)
			(fill no)
			(layer "F.CrtYd")
		)
		(fp_rect
			(start -0.508 0.9398)
			(end 0.508 -0.9398)
			(stroke
				(width 0)
				(type default)
			)
			(fill no)
			(layer "F.Fab")
		)
		(pad "1" smd custom
			(at 0 -0.4445)
			(size 0.1397 0.1397)
			(layers "F.Cu" "F.Mask" "F.Paste")
			(net "SAS_HDD_CONN_SER_TX8_N")
			(options
				(clearance outline)
				(anchor circle)
			)
			(primitives
				(gr_poly
					(pts
						(arc
							(start -0.1778 -0.2794)
							(mid -0.249642 -0.249642)
							(end -0.2794 -0.1778)
						)
						(arc
							(start -0.2794 0.1778)
							(mid -0.249642 0.249642)
							(end -0.1778 0.2794)
						)
						(arc
							(start 0.1778 0.2794)
							(mid 0.249642 0.249642)
							(end 0.2794 0.1778)
						)
						(arc
							(start 0.2794 -0.1778)
							(mid 0.249642 -0.249642)
							(end 0.1778 -0.2794)
						)
					)
					(width 0)
					(fill yes)
				)
			)
		)
		(pad "2" smd custom
			(at 0 0.4445)
			(size 0.1397 0.1397)
			(layers "F.Cu" "F.Mask" "F.Paste")
			(net "SAS_HDD_CONN_TX8_N")
			(options
				(clearance outline)
				(anchor circle)
			)
			(primitives
				(gr_poly
					(pts
						(arc
							(start -0.1778 -0.2794)
							(mid -0.249642 -0.249642)
							(end -0.2794 -0.1778)
						)
						(arc
							(start -0.2794 0.1778)
							(mid -0.249642 0.249642)
							(end -0.1778 0.2794)
						)
						(arc
							(start 0.1778 0.2794)
							(mid 0.249642 0.249642)
							(end 0.2794 0.1778)
						)
						(arc
							(start 0.2794 -0.1778)
							(mid 0.249642 -0.249642)
							(end 0.1778 -0.2794)
						)
					)
					(width 0)
					(fill yes)
				)
			)
		)
	)
	(footprint ""
		(layer "F.Cu")
		(at 333.912718 -146.662648 -90)
		(property "Reference" "C318"
			(at 0 0 270)
			(layer "F.SilkS")
			(hide yes)
			(effects
				(font
					(size 1.27 1.27)
				)
			)
		)
		(property "Value" "SC1U6D3V3KX-2GP"
			(at 0 -2.8194 270)
			(unlocked yes)
			(layer "F.Fab")
			(hide yes)
			(effects
				(font
					(size 1.016 1.016)
					(thickness 0.1524)
				)
			)
		)
		(property "Device Type" "C603H36"
			(at 0 -4.3434 270)
			(unlocked yes)
			(layer "F.Fab")
			(hide yes)
			(effects
				(font
					(size 1.016 1.016)
					(thickness 0.1524)
				)
			)
		)
		(duplicate_pad_numbers_are_jumpers no)
		(fp_line
			(start 0.508 0)
			(end -0.508 0)
			(stroke
				(width 0.2032)
				(type default)
			)
			(layer "F.SilkS")
		)
		(fp_rect
			(start -0.5842 1.3335)
			(end 0.5842 -1.3335)
			(stroke
				(width 0)
				(type default)
			)
			(fill no)
			(layer "F.CrtYd")
		)
		(fp_rect
			(start -0.5842 1.3335)
			(end 0.5842 -1.3335)
			(stroke
				(width 0)
				(type default)
			)
			(fill no)
			(layer "F.Fab")
		)
		(pad "1" smd custom
			(at 0 -0.762 270)
			(size 0.2159 0.2159)
			(layers "F.Cu" "F.Mask" "F.Paste")
			(net "USB_RESET_N")
			(options
				(clearance outline)
				(anchor circle)
			)
			(primitives
				(gr_poly
					(pts
						(arc
							(start -0.3302 -0.4318)
							(mid -0.402042 -0.402042)
							(end -0.4318 -0.3302)
						)
						(arc
							(start -0.4318 0.3302)
							(mid -0.402042 0.402042)
							(end -0.3302 0.4318)
						)
						(arc
							(start 0.3302 0.4318)
							(mid 0.402042 0.402042)
							(end 0.4318 0.3302)
						)
						(arc
							(start 0.4318 -0.3302)
							(mid 0.402042 -0.402042)
							(end 0.3302 -0.4318)
						)
					)
					(width 0)
					(fill yes)
				)
			)
		)
		(pad "2" smd custom
			(at 0 0.762 270)
			(size 0.2159 0.2159)
			(layers "F.Cu" "F.Mask" "F.Paste")
			(net "GND")
			(options
				(clearance outline)
				(anchor circle)
			)
			(primitives
				(gr_poly
					(pts
						(arc
							(start -0.3302 -0.4318)
							(mid -0.402042 -0.402042)
							(end -0.4318 -0.3302)
						)
						(arc
							(start -0.4318 0.3302)
							(mid -0.402042 0.402042)
							(end -0.3302 0.4318)
						)
						(arc
							(start 0.3302 0.4318)
							(mid 0.402042 0.402042)
							(end 0.4318 0.3302)
						)
						(arc
							(start 0.4318 -0.3302)
							(mid 0.402042 -0.402042)
							(end 0.3302 -0.4318)
						)
					)
					(width 0)
					(fill yes)
				)
			)
		)
	)
	(footprint ""
		(layer "F.Cu")
		(at 164.153596 -147.720812 90)
		(property "Reference" "SU62"
			(at 0 0 90)
			(layer "F.SilkS")
			(hide yes)
			(effects
				(font
					(size 1.27 1.27)
				)
			)
		)
		(property "Value" "PCA9306DCTT-GP"
			(at 0 -11.6332 90)
			(unlocked yes)
			(layer "F.Fab")
			(hide yes)
			(effects
				(font
					(size 1.016 1.016)
					(thickness 0.1524)
				)
			)
		)
		(property "Device Type" "SSOIC8H52"
			(at 0 -13.1572 90)
			(unlocked yes)
			(layer "F.Fab")
			(hide yes)
			(effects
				(font
					(size 1.016 1.016)
					(thickness 0.1524)
				)
			)
		)
		(duplicate_pad_numbers_are_jumpers no)
		(fp_line
			(start 1.0668 -0.5842)
			(end 1.0668 0.5842)
			(stroke
				(width 0.1524)
				(type default)
			)
			(layer "F.SilkS")
		)
		(fp_line
			(start -1.7018 -0.5842)
			(end 1.0668 -0.5842)
			(stroke
				(width 0.1524)
				(type default)
			)
			(layer "F.SilkS")
		)
		(fp_line
			(start -1.7018 -0.5842)
			(end -1.7018 2.286)
			(stroke
				(width 0.1524)
				(type default)
			)
			(layer "F.SilkS")
		)
		(fp_line
			(start -1.397 0)
			(end -1.7018 -0.3048)
			(stroke
				(width 0.1524)
				(type default)
			)
			(layer "F.SilkS")
		)
		(fp_line
			(start -1.397 0)
			(end -1.7018 0.3048)
			(stroke
				(width 0.1524)
				(type default)
			)
			(layer "F.SilkS")
		)
		(fp_line
			(start 1.0668 0.5842)
			(end -1.524 0.5842)
			(stroke
				(width 0.1524)
				(type default)
			)
			(layer "F.SilkS")
		)
		(fp_line
			(start -1.524 0.5842)
			(end -1.524 2.286)
			(stroke
				(width 0.508)
				(type default)
			)
			(layer "F.SilkS")
		)
		(fp_poly
			(pts
				(xy -1.1684 -0.5842) (xy 1.0668 -0.5842) (xy 1.0668 0.5842) (xy -1.1684 0.5842)
			)
			(stroke
				(width 0)
				(type default)
			)
			(fill yes)
			(layer "F.SilkS")
		)
		(fp_poly
			(pts
				(xy -1.778 2.54) (xy 1.778 2.54) (xy 1.778 -2.54) (xy -1.778 -2.54)
			)
			(stroke
				(width 0)
				(type default)
			)
			(fill no)
			(layer "F.CrtYd")
		)
		(fp_poly
			(pts
				(xy -1.778 -2.54) (xy 1.778 -2.54) (xy 1.778 2.54) (xy -1.778 2.54)
			)
			(stroke
				(width 0)
				(type default)
			)
			(fill no)
			(layer "F.Fab")
		)
		(pad "1" smd rect
			(at -0.97536 1.6256 90)
			(size 0.3556 1.524)
			(layers "F.Cu" "F.Mask" "F.Paste")
			(net "GND")
		)
		(pad "2" smd rect
			(at -0.32512 1.6256 90)
			(size 0.3556 1.524)
			(layers "F.Cu" "F.Mask" "F.Paste")
			(net "P1V8_C")
		)
		(pad "3" smd rect
			(at 0.32512 1.6256 90)
			(size 0.3556 1.524)
			(layers "F.Cu" "F.Mask" "F.Paste")
			(net "IOC_SCL_4")
		)
		(pad "4" smd rect
			(at 0.97536 1.6256 90)
			(size 0.3556 1.524)
			(layers "F.Cu" "F.Mask" "F.Paste")
			(net "IOC_SDA_4")
		)
		(pad "5" smd rect
			(at 0.97536 -1.6256 90)
			(size 0.3556 1.524)
			(layers "F.Cu" "F.Mask" "F.Paste")
			(net "IOC_P3V3_SDA_14")
		)
		(pad "6" smd rect
			(at 0.32512 -1.6256 90)
			(size 0.3556 1.524)
			(layers "F.Cu" "F.Mask" "F.Paste")
			(net "IOC_P3V3_SCL_14")
		)
		(pad "7" smd rect
			(at -0.32512 -1.6256 90)
			(size 0.3556 1.524)
			(layers "F.Cu" "F.Mask" "F.Paste")
			(net "IOC_I2C_VREF")
		)
		(pad "8" smd rect
			(at -0.97536 -1.6256 90)
			(size 0.3556 1.524)
			(layers "F.Cu" "F.Mask" "F.Paste")
			(net "IOC_I2C_VREF")
		)
	)
	(footprint ""
		(layer "F.Cu")
		(at 41.402 -178.943 180)
		(property "Reference" "SR1272"
			(at 0 0 180)
			(layer "F.SilkS")
			(hide yes)
			(effects
				(font
					(size 1.27 1.27)
				)
			)
		)
		(property "Value" "1KR2J-1-GP"
			(at 0.064008 -3.993896 180)
			(unlocked yes)
			(layer "F.Fab")
			(hide yes)
			(effects
				(font
					(size 1.016 1.016)
					(thickness 0.1524)
				)
			)
		)
		(property "Device Type" "R402H16"
			(at 0.064008 -5.517896 180)
			(unlocked yes)
			(layer "F.Fab")
			(hide yes)
			(effects
				(font
					(size 1.016 1.016)
					(thickness 0.1524)
				)
			)
		)
		(duplicate_pad_numbers_are_jumpers no)
		(fp_line
			(start 0.508 -0.9398)
			(end -0.508 -0.9398)
			(stroke
				(width 0.1524)
				(type default)
			)
			(layer "F.SilkS")
		)
		(fp_line
			(start -0.508 -0.9398)
			(end -0.508 0.9398)
			(stroke
				(width 0.1524)
				(type default)
			)
			(layer "F.SilkS")
		)
		(fp_rect
			(start -0.508 0.9398)
			(end 0.508 -0.9398)
			(stroke
				(width 0)
				(type default)
			)
			(fill no)
			(layer "F.CrtYd")
		)
		(fp_rect
			(start -0.508 0.9398)
			(end 0.508 -0.9398)
			(stroke
				(width 0)
				(type default)
			)
			(fill no)
			(layer "F.Fab")
		)
		(pad "1" smd custom
			(at 0 -0.4445 180)
			(size 0.1397 0.1397)
			(layers "F.Cu" "F.Mask" "F.Paste")
			(net "RST_BTN_R")
			(options
				(clearance outline)
				(anchor circle)
			)
			(primitives
				(gr_poly
					(pts
						(arc
							(start -0.1778 -0.2794)
							(mid -0.249642 -0.249642)
							(end -0.2794 -0.1778)
						)
						(arc
							(start -0.2794 0.1778)
							(mid -0.249642 0.249642)
							(end -0.1778 0.2794)
						)
						(arc
							(start 0.1778 0.2794)
							(mid 0.249642 0.249642)
							(end 0.2794 0.1778)
						)
						(arc
							(start 0.2794 -0.1778)
							(mid 0.249642 -0.249642)
							(end 0.1778 -0.2794)
						)
					)
					(width 0)
					(fill yes)
				)
			)
		)
		(pad "2" smd custom
			(at 0 0.4445 180)
			(size 0.1397 0.1397)
			(layers "F.Cu" "F.Mask" "F.Paste")
			(net "P1V8_E")
			(options
				(clearance outline)
				(anchor circle)
			)
			(primitives
				(gr_poly
					(pts
						(arc
							(start -0.1778 -0.2794)
							(mid -0.249642 -0.249642)
							(end -0.2794 -0.1778)
						)
						(arc
							(start -0.2794 0.1778)
							(mid -0.249642 0.249642)
							(end -0.1778 0.2794)
						)
						(arc
							(start 0.1778 0.2794)
							(mid 0.249642 0.249642)
							(end 0.2794 0.1778)
						)
						(arc
							(start 0.2794 -0.1778)
							(mid 0.249642 -0.249642)
							(end 0.1778 -0.2794)
						)
					)
					(width 0)
					(fill yes)
				)
			)
		)
	)
	(footprint ""
		(layer "F.Cu")
		(at 194.818 -116.205)
		(property "Reference" "PR9020"
			(at 0 0 0)
			(layer "F.SilkS")
			(hide yes)
			(effects
				(font
					(size 1.27 1.27)
				)
			)
		)
		(property "Value" "0R2J-2-GP"
			(at 0.064008 -3.993896 0)
			(unlocked yes)
			(layer "F.Fab")
			(hide yes)
			(effects
				(font
					(size 1.016 1.016)
					(thickness 0.1524)
				)
			)
		)
		(property "Device Type" "R402H16"
			(at 0.064008 -5.517896 0)
			(unlocked yes)
			(layer "F.Fab")
			(hide yes)
			(effects
				(font
					(size 1.016 1.016)
					(thickness 0.1524)
				)
			)
		)
		(duplicate_pad_numbers_are_jumpers no)
		(fp_line
			(start -0.508 -0.9398)
			(end -0.508 0.9398)
			(stroke
				(width 0.1524)
				(type default)
			)
			(layer "F.SilkS")
		)
		(fp_line
			(start 0.508 -0.9398)
			(end -0.508 -0.9398)
			(stroke
				(width 0.1524)
				(type default)
			)
			(layer "F.SilkS")
		)
		(fp_rect
			(start -0.508 0.9398)
			(end 0.508 -0.9398)
			(stroke
				(width 0)
				(type default)
			)
			(fill no)
			(layer "F.CrtYd")
		)
		(fp_rect
			(start -0.508 0.9398)
			(end 0.508 -0.9398)
			(stroke
				(width 0)
				(type default)
			)
			(fill no)
			(layer "F.Fab")
		)
		(pad "1" smd custom
			(at 0 -0.4445)
			(size 0.1397 0.1397)
			(layers "F.Cu" "F.Mask" "F.Paste")
			(net "P1V8_E_PG")
			(options
				(clearance outline)
				(anchor circle)
			)
			(primitives
				(gr_poly
					(pts
						(arc
							(start -0.1778 -0.2794)
							(mid -0.249642 -0.249642)
							(end -0.2794 -0.1778)
						)
						(arc
							(start -0.2794 0.1778)
							(mid -0.249642 0.249642)
							(end -0.1778 0.2794)
						)
						(arc
							(start 0.1778 0.2794)
							(mid 0.249642 0.249642)
							(end 0.2794 0.1778)
						)
						(arc
							(start 0.2794 -0.1778)
							(mid 0.249642 -0.249642)
							(end 0.1778 -0.2794)
						)
					)
					(width 0)
					(fill yes)
				)
			)
		)
		(pad "2" smd custom
			(at 0 0.4445)
			(size 0.1397 0.1397)
			(layers "F.Cu" "F.Mask" "F.Paste")
			(net "P1V5_E_EN_R")
			(options
				(clearance outline)
				(anchor circle)
			)
			(primitives
				(gr_poly
					(pts
						(arc
							(start -0.1778 -0.2794)
							(mid -0.249642 -0.249642)
							(end -0.2794 -0.1778)
						)
						(arc
							(start -0.2794 0.1778)
							(mid -0.249642 0.249642)
							(end -0.1778 0.2794)
						)
						(arc
							(start 0.1778 0.2794)
							(mid 0.249642 0.249642)
							(end 0.2794 0.1778)
						)
						(arc
							(start 0.2794 -0.1778)
							(mid 0.249642 -0.249642)
							(end 0.1778 -0.2794)
						)
					)
					(width 0)
					(fill yes)
				)
			)
		)
	)
	(footprint ""
		(layer "F.Cu")
		(at 317.881 -50.165 90)
		(property "Reference" "C249"
			(at 0 0 90)
			(layer "F.SilkS")
			(hide yes)
			(effects
				(font
					(size 1.27 1.27)
				)
			)
		)
		(property "Value" "SCD1U16V2KX-3GP"
			(at 1.1811 -2.7051 90)
			(unlocked yes)
			(layer "F.Fab")
			(hide yes)
			(effects
				(font
					(size 1.016 1.016)
					(thickness 0.1524)
				)
			)
		)
		(property "Device Type" "C402H22"
			(at 1.1811 -4.2291 90)
			(unlocked yes)
			(layer "F.Fab")
			(hide yes)
			(effects
				(font
					(size 1.016 1.016)
					(thickness 0.1524)
				)
			)
		)
		(duplicate_pad_numbers_are_jumpers no)
		(fp_rect
			(start -0.4318 0.9525)
			(end 0.4318 -0.9525)
			(stroke
				(width 0)
				(type default)
			)
			(fill no)
			(layer "F.CrtYd")
		)
		(fp_rect
			(start -0.4318 0.9525)
			(end 0.4318 -0.9525)
			(stroke
				(width 0)
				(type default)
			)
			(fill no)
			(layer "F.Fab")
		)
		(pad "1" smd custom
			(at 0 -0.4445 90)
			(size 0.1524 0.1524)
			(layers "F.Cu" "F.Mask" "F.Paste")
			(net "P5V_STBY")
			(options
				(clearance outline)
				(anchor circle)
			)
			(primitives
				(gr_poly
					(pts
						(arc
							(start 0.3048 -0.2032)
							(mid 0.275042 -0.275042)
							(end 0.2032 -0.3048)
						)
						(arc
							(start -0.2032 -0.3048)
							(mid -0.275042 -0.275042)
							(end -0.3048 -0.2032)
						)
						(arc
							(start -0.3048 0.2032)
							(mid -0.275042 0.275042)
							(end -0.2032 0.3048)
						)
						(arc
							(start 0.2032 0.3048)
							(mid 0.275042 0.275042)
							(end 0.3048 0.2032)
						)
					)
					(width 0)
					(fill yes)
				)
			)
		)
		(pad "2" smd custom
			(at 0 0.4445 90)
			(size 0.1524 0.1524)
			(layers "F.Cu" "F.Mask" "F.Paste")
			(net "GND")
			(options
				(clearance outline)
				(anchor circle)
			)
			(primitives
				(gr_poly
					(pts
						(arc
							(start 0.3048 -0.2032)
							(mid 0.275042 -0.275042)
							(end 0.2032 -0.3048)
						)
						(arc
							(start -0.2032 -0.3048)
							(mid -0.275042 -0.275042)
							(end -0.3048 -0.2032)
						)
						(arc
							(start -0.3048 0.2032)
							(mid -0.275042 0.275042)
							(end -0.2032 0.3048)
						)
						(arc
							(start 0.2032 0.3048)
							(mid 0.275042 0.275042)
							(end 0.3048 0.2032)
						)
					)
					(width 0)
					(fill yes)
				)
			)
		)
	)
	(footprint ""
		(layer "F.Cu")
		(at 279.781 -182.372)
		(property "Reference" "TP98"
			(at 0 0 0)
			(layer "F.SilkS")
			(hide yes)
			(effects
				(font
					(size 1.27 1.27)
				)
			)
		)
		(property "Value" "TPAD28"
			(at 0.0127 -1.8034 0)
			(unlocked yes)
			(layer "F.Fab")
			(hide yes)
			(effects
				(font
					(size 1.016 1.016)
					(thickness 0.1524)
				)
			)
		)
		(property "Device Type" "TPAD28"
			(at 0.0127 -3.3274 0)
			(unlocked yes)
			(layer "F.Fab")
			(hide yes)
			(effects
				(font
					(size 1.016 1.016)
					(thickness 0.1524)
				)
			)
		)
		(duplicate_pad_numbers_are_jumpers no)
		(fp_poly
			(pts
				(arc
					(start 0.3556 0)
					(mid -0.3556 0)
					(end 0.3556 0)
				)
			)
			(stroke
				(width 0)
				(type default)
			)
			(fill no)
			(layer "F.CrtYd")
		)
		(fp_poly
			(pts
				(arc
					(start 0.6096 0)
					(mid -0.6096 0)
					(end 0.6096 0)
				)
			)
			(stroke
				(width 0)
				(type default)
			)
			(fill no)
			(layer "F.Fab")
		)
		(pad "1" smd circle
			(at 0 0)
			(size 0.7112 0.7112)
			(layers "F.Cu" "F.Mask" "F.Paste")
			(net "TP_BMC_GPIOR5")
		)
	)
	(footprint ""
		(layer "F.Cu")
		(at 285.75 -161.544 180)
		(property "Reference" "R328"
			(at 0 0 180)
			(layer "F.SilkS")
			(hide yes)
			(effects
				(font
					(size 1.27 1.27)
				)
			)
		)
		(property "Value" "0R2J-2-GP"
			(at 0.064008 -3.993896 180)
			(unlocked yes)
			(layer "F.Fab")
			(hide yes)
			(effects
				(font
					(size 1.016 1.016)
					(thickness 0.1524)
				)
			)
		)
		(property "Device Type" "R402H16"
			(at 0.064008 -5.517896 180)
			(unlocked yes)
			(layer "F.Fab")
			(hide yes)
			(effects
				(font
					(size 1.016 1.016)
					(thickness 0.1524)
				)
			)
		)
		(duplicate_pad_numbers_are_jumpers no)
		(fp_line
			(start 0.508 -0.9398)
			(end -0.508 -0.9398)
			(stroke
				(width 0.1524)
				(type default)
			)
			(layer "F.SilkS")
		)
		(fp_line
			(start -0.508 -0.9398)
			(end -0.508 0.9398)
			(stroke
				(width 0.1524)
				(type default)
			)
			(layer "F.SilkS")
		)
		(fp_rect
			(start -0.508 0.9398)
			(end 0.508 -0.9398)
			(stroke
				(width 0)
				(type default)
			)
			(fill no)
			(layer "F.CrtYd")
		)
		(fp_rect
			(start -0.508 0.9398)
			(end 0.508 -0.9398)
			(stroke
				(width 0)
				(type default)
			)
			(fill no)
			(layer "F.Fab")
		)
		(pad "1" smd custom
			(at 0 -0.4445 180)
			(size 0.1397 0.1397)
			(layers "F.Cu" "F.Mask" "F.Paste")
			(net "SYS_RSTBTN_N")
			(options
				(clearance outline)
				(anchor circle)
			)
			(primitives
				(gr_poly
					(pts
						(arc
							(start -0.1778 -0.2794)
							(mid -0.249642 -0.249642)
							(end -0.2794 -0.1778)
						)
						(arc
							(start -0.2794 0.1778)
							(mid -0.249642 0.249642)
							(end -0.1778 0.2794)
						)
						(arc
							(start 0.1778 0.2794)
							(mid 0.249642 0.249642)
							(end 0.2794 0.1778)
						)
						(arc
							(start 0.2794 -0.1778)
							(mid 0.249642 -0.249642)
							(end 0.1778 -0.2794)
						)
					)
					(width 0)
					(fill yes)
				)
			)
		)
		(pad "2" smd custom
			(at 0 0.4445 180)
			(size 0.1397 0.1397)
			(layers "F.Cu" "F.Mask" "F.Paste")
			(net "SYS_RSTBTN_N_R")
			(options
				(clearance outline)
				(anchor circle)
			)
			(primitives
				(gr_poly
					(pts
						(arc
							(start -0.1778 -0.2794)
							(mid -0.249642 -0.249642)
							(end -0.2794 -0.1778)
						)
						(arc
							(start -0.2794 0.1778)
							(mid -0.249642 0.249642)
							(end -0.1778 0.2794)
						)
						(arc
							(start 0.1778 0.2794)
							(mid 0.249642 0.249642)
							(end 0.2794 0.1778)
						)
						(arc
							(start 0.2794 -0.1778)
							(mid 0.249642 -0.249642)
							(end 0.1778 -0.2794)
						)
					)
					(width 0)
					(fill yes)
				)
			)
		)
	)
	(footprint ""
		(layer "F.Cu")
		(at 103.01097 -76.454)
		(property "Reference" "SR859"
			(at 0 0 0)
			(layer "F.SilkS")
			(hide yes)
			(effects
				(font
					(size 1.27 1.27)
				)
			)
		)
		(property "Value" "0R2J-2-GP"
			(at 0.064008 -3.993896 0)
			(unlocked yes)
			(layer "F.Fab")
			(hide yes)
			(effects
				(font
					(size 1.016 1.016)
					(thickness 0.1524)
				)
			)
		)
		(property "Device Type" "R402H16"
			(at 0.064008 -5.517896 0)
			(unlocked yes)
			(layer "F.Fab")
			(hide yes)
			(effects
				(font
					(size 1.016 1.016)
					(thickness 0.1524)
				)
			)
		)
		(duplicate_pad_numbers_are_jumpers no)
		(fp_line
			(start -0.508 -0.9398)
			(end -0.508 0.9398)
			(stroke
				(width 0.1524)
				(type default)
			)
			(layer "F.SilkS")
		)
		(fp_line
			(start 0.508 -0.9398)
			(end -0.508 -0.9398)
			(stroke
				(width 0.1524)
				(type default)
			)
			(layer "F.SilkS")
		)
		(fp_rect
			(start -0.508 0.9398)
			(end 0.508 -0.9398)
			(stroke
				(width 0)
				(type default)
			)
			(fill no)
			(layer "F.CrtYd")
		)
		(fp_rect
			(start -0.508 0.9398)
			(end 0.508 -0.9398)
			(stroke
				(width 0)
				(type default)
			)
			(fill no)
			(layer "F.Fab")
		)
		(pad "1" smd custom
			(at 0 -0.4445)
			(size 0.1397 0.1397)
			(layers "F.Cu" "F.Mask" "F.Paste")
			(net "JTAG_EXP_TDI")
			(options
				(clearance outline)
				(anchor circle)
			)
			(primitives
				(gr_poly
					(pts
						(arc
							(start -0.1778 -0.2794)
							(mid -0.249642 -0.249642)
							(end -0.2794 -0.1778)
						)
						(arc
							(start -0.2794 0.1778)
							(mid -0.249642 0.249642)
							(end -0.1778 0.2794)
						)
						(arc
							(start 0.1778 0.2794)
							(mid 0.249642 0.249642)
							(end 0.2794 0.1778)
						)
						(arc
							(start 0.2794 -0.1778)
							(mid 0.249642 -0.249642)
							(end 0.1778 -0.2794)
						)
					)
					(width 0)
					(fill yes)
				)
			)
		)
		(pad "2" smd custom
			(at 0 0.4445)
			(size 0.1397 0.1397)
			(layers "F.Cu" "F.Mask" "F.Paste")
			(net "JTAG_BMC_L_TDO")
			(options
				(clearance outline)
				(anchor circle)
			)
			(primitives
				(gr_poly
					(pts
						(arc
							(start -0.1778 -0.2794)
							(mid -0.249642 -0.249642)
							(end -0.2794 -0.1778)
						)
						(arc
							(start -0.2794 0.1778)
							(mid -0.249642 0.249642)
							(end -0.1778 0.2794)
						)
						(arc
							(start 0.1778 0.2794)
							(mid 0.249642 0.249642)
							(end 0.2794 0.1778)
						)
						(arc
							(start 0.2794 -0.1778)
							(mid 0.249642 -0.249642)
							(end 0.1778 -0.2794)
						)
					)
					(width 0)
					(fill yes)
				)
			)
		)
	)
	(footprint ""
		(layer "F.Cu")
		(at 291.592 -150.495 90)
		(property "Reference" "C233"
			(at 0 0 90)
			(layer "F.SilkS")
			(hide yes)
			(effects
				(font
					(size 1.27 1.27)
				)
			)
		)
		(property "Value" "SC1U6D3V3KX-2GP"
			(at 0 -2.8194 90)
			(unlocked yes)
			(layer "F.Fab")
			(hide yes)
			(effects
				(font
					(size 1.016 1.016)
					(thickness 0.1524)
				)
			)
		)
		(property "Device Type" "C603H36"
			(at 0 -4.3434 90)
			(unlocked yes)
			(layer "F.Fab")
			(hide yes)
			(effects
				(font
					(size 1.016 1.016)
					(thickness 0.1524)
				)
			)
		)
		(duplicate_pad_numbers_are_jumpers no)
		(fp_line
			(start 0.508 0)
			(end -0.508 0)
			(stroke
				(width 0.2032)
				(type default)
			)
			(layer "F.SilkS")
		)
		(fp_rect
			(start -0.5842 1.3335)
			(end 0.5842 -1.3335)
			(stroke
				(width 0)
				(type default)
			)
			(fill no)
			(layer "F.CrtYd")
		)
		(fp_rect
			(start -0.5842 1.3335)
			(end 0.5842 -1.3335)
			(stroke
				(width 0)
				(type default)
			)
			(fill no)
			(layer "F.Fab")
		)
		(pad "1" smd custom
			(at 0 -0.762 90)
			(size 0.2159 0.2159)
			(layers "F.Cu" "F.Mask" "F.Paste")
			(net "P3V3_STBY")
			(options
				(clearance outline)
				(anchor circle)
			)
			(primitives
				(gr_poly
					(pts
						(arc
							(start -0.3302 -0.4318)
							(mid -0.402042 -0.402042)
							(end -0.4318 -0.3302)
						)
						(arc
							(start -0.4318 0.3302)
							(mid -0.402042 0.402042)
							(end -0.3302 0.4318)
						)
						(arc
							(start 0.3302 0.4318)
							(mid 0.402042 0.402042)
							(end 0.4318 0.3302)
						)
						(arc
							(start 0.4318 -0.3302)
							(mid 0.402042 -0.402042)
							(end 0.3302 -0.4318)
						)
					)
					(width 0)
					(fill yes)
				)
			)
		)
		(pad "2" smd custom
			(at 0 0.762 90)
			(size 0.2159 0.2159)
			(layers "F.Cu" "F.Mask" "F.Paste")
			(net "GND")
			(options
				(clearance outline)
				(anchor circle)
			)
			(primitives
				(gr_poly
					(pts
						(arc
							(start -0.3302 -0.4318)
							(mid -0.402042 -0.402042)
							(end -0.4318 -0.3302)
						)
						(arc
							(start -0.4318 0.3302)
							(mid -0.402042 0.402042)
							(end -0.3302 0.4318)
						)
						(arc
							(start 0.3302 0.4318)
							(mid 0.402042 0.402042)
							(end 0.4318 0.3302)
						)
						(arc
							(start 0.4318 -0.3302)
							(mid 0.402042 -0.402042)
							(end 0.3302 -0.4318)
						)
					)
					(width 0)
					(fill yes)
				)
			)
		)
	)
	(footprint ""
		(layer "F.Cu")
		(at 194.183 -35.179 -90)
		(property "Reference" "R464"
			(at 0 0 270)
			(layer "F.SilkS")
			(hide yes)
			(effects
				(font
					(size 1.27 1.27)
				)
			)
		)
		(property "Value" "0R2J-2-GP"
			(at 0.064008 -3.993896 270)
			(unlocked yes)
			(layer "F.Fab")
			(hide yes)
			(effects
				(font
					(size 1.016 1.016)
					(thickness 0.1524)
				)
			)
		)
		(property "Device Type" "R402H16"
			(at 0.064008 -5.517896 270)
			(unlocked yes)
			(layer "F.Fab")
			(hide yes)
			(effects
				(font
					(size 1.016 1.016)
					(thickness 0.1524)
				)
			)
		)
		(duplicate_pad_numbers_are_jumpers no)
		(fp_line
			(start -0.508 -0.9398)
			(end -0.508 0.9398)
			(stroke
				(width 0.1524)
				(type default)
			)
			(layer "F.SilkS")
		)
		(fp_line
			(start 0.508 -0.9398)
			(end -0.508 -0.9398)
			(stroke
				(width 0.1524)
				(type default)
			)
			(layer "F.SilkS")
		)
		(fp_rect
			(start -0.508 0.9398)
			(end 0.508 -0.9398)
			(stroke
				(width 0)
				(type default)
			)
			(fill no)
			(layer "F.CrtYd")
		)
		(fp_rect
			(start -0.508 0.9398)
			(end 0.508 -0.9398)
			(stroke
				(width 0)
				(type default)
			)
			(fill no)
			(layer "F.Fab")
		)
		(pad "1" smd custom
			(at 0 -0.4445 270)
			(size 0.1397 0.1397)
			(layers "F.Cu" "F.Mask" "F.Paste")
			(net "GND")
			(options
				(clearance outline)
				(anchor circle)
			)
			(primitives
				(gr_poly
					(pts
						(arc
							(start -0.1778 -0.2794)
							(mid -0.249642 -0.249642)
							(end -0.2794 -0.1778)
						)
						(arc
							(start -0.2794 0.1778)
							(mid -0.249642 0.249642)
							(end -0.1778 0.2794)
						)
						(arc
							(start 0.1778 0.2794)
							(mid 0.249642 0.249642)
							(end 0.2794 0.1778)
						)
						(arc
							(start 0.2794 -0.1778)
							(mid 0.249642 -0.249642)
							(end 0.1778 -0.2794)
						)
					)
					(width 0)
					(fill yes)
				)
			)
		)
		(pad "2" smd custom
			(at 0 0.4445 270)
			(size 0.1397 0.1397)
			(layers "F.Cu" "F.Mask" "F.Paste")
			(net "RMII_BMC_PHY_TXD0")
			(options
				(clearance outline)
				(anchor circle)
			)
			(primitives
				(gr_poly
					(pts
						(arc
							(start -0.1778 -0.2794)
							(mid -0.249642 -0.249642)
							(end -0.2794 -0.1778)
						)
						(arc
							(start -0.2794 0.1778)
							(mid -0.249642 0.249642)
							(end -0.1778 0.2794)
						)
						(arc
							(start 0.1778 0.2794)
							(mid 0.249642 0.249642)
							(end 0.2794 0.1778)
						)
						(arc
							(start 0.2794 -0.1778)
							(mid 0.249642 -0.249642)
							(end 0.1778 -0.2794)
						)
					)
					(width 0)
					(fill yes)
				)
			)
		)
	)
	(footprint ""
		(layer "F.Cu")
		(at 88.011 -231.775 180)
		(property "Reference" "R669"
			(at 0 0 180)
			(layer "F.SilkS")
			(hide yes)
			(effects
				(font
					(size 1.27 1.27)
				)
			)
		)
		(property "Value" "0R2J-2-GP"
			(at 0.064008 -3.993896 180)
			(unlocked yes)
			(layer "F.Fab")
			(hide yes)
			(effects
				(font
					(size 1.016 1.016)
					(thickness 0.1524)
				)
			)
		)
		(property "Device Type" "R402H16"
			(at 0.064008 -5.517896 180)
			(unlocked yes)
			(layer "F.Fab")
			(hide yes)
			(effects
				(font
					(size 1.016 1.016)
					(thickness 0.1524)
				)
			)
		)
		(duplicate_pad_numbers_are_jumpers no)
		(fp_line
			(start 0.508 -0.9398)
			(end -0.508 -0.9398)
			(stroke
				(width 0.1524)
				(type default)
			)
			(layer "F.SilkS")
		)
		(fp_line
			(start -0.508 -0.9398)
			(end -0.508 0.9398)
			(stroke
				(width 0.1524)
				(type default)
			)
			(layer "F.SilkS")
		)
		(fp_rect
			(start -0.508 0.9398)
			(end 0.508 -0.9398)
			(stroke
				(width 0)
				(type default)
			)
			(fill no)
			(layer "F.CrtYd")
		)
		(fp_rect
			(start -0.508 0.9398)
			(end 0.508 -0.9398)
			(stroke
				(width 0)
				(type default)
			)
			(fill no)
			(layer "F.Fab")
		)
		(pad "1" smd custom
			(at 0 -0.4445 180)
			(size 0.1397 0.1397)
			(layers "F.Cu" "F.Mask" "F.Paste")
			(net "SAS_FAULT_LED12")
			(options
				(clearance outline)
				(anchor circle)
			)
			(primitives
				(gr_poly
					(pts
						(arc
							(start -0.1778 -0.2794)
							(mid -0.249642 -0.249642)
							(end -0.2794 -0.1778)
						)
						(arc
							(start -0.2794 0.1778)
							(mid -0.249642 0.249642)
							(end -0.1778 0.2794)
						)
						(arc
							(start 0.1778 0.2794)
							(mid 0.249642 0.249642)
							(end 0.2794 0.1778)
						)
						(arc
							(start 0.2794 -0.1778)
							(mid 0.249642 -0.249642)
							(end 0.1778 -0.2794)
						)
					)
					(width 0)
					(fill yes)
				)
			)
		)
		(pad "2" smd custom
			(at 0 0.4445 180)
			(size 0.1397 0.1397)
			(layers "F.Cu" "F.Mask" "F.Paste")
			(net "SAS_HDD_LED_12")
			(options
				(clearance outline)
				(anchor circle)
			)
			(primitives
				(gr_poly
					(pts
						(arc
							(start -0.1778 -0.2794)
							(mid -0.249642 -0.249642)
							(end -0.2794 -0.1778)
						)
						(arc
							(start -0.2794 0.1778)
							(mid -0.249642 0.249642)
							(end -0.1778 0.2794)
						)
						(arc
							(start 0.1778 0.2794)
							(mid 0.249642 0.249642)
							(end 0.2794 0.1778)
						)
						(arc
							(start 0.2794 -0.1778)
							(mid 0.249642 -0.249642)
							(end 0.1778 -0.2794)
						)
					)
					(width 0)
					(fill yes)
				)
			)
		)
	)
	(footprint ""
		(layer "F.Cu")
		(at 105.29697 -114.3 180)
		(property "Reference" "SC1086"
			(at 0 0 180)
			(layer "F.SilkS")
			(hide yes)
			(effects
				(font
					(size 1.27 1.27)
				)
			)
		)
		(property "Value" "SCD01U10V1KX-GP"
			(at -2.8321 -1.7399 180)
			(unlocked yes)
			(layer "F.Fab")
			(hide yes)
			(effects
				(font
					(size 1.016 1.016)
					(thickness 0.1524)
				)
			)
		)
		(property "Device Type" "C0201H13"
			(at -2.8321 -3.2639 180)
			(unlocked yes)
			(layer "F.Fab")
			(hide yes)
			(effects
				(font
					(size 1.016 1.016)
					(thickness 0.1524)
				)
			)
		)
		(duplicate_pad_numbers_are_jumpers no)
		(fp_rect
			(start -0.2794 0.6477)
			(end 0.2794 -0.6477)
			(stroke
				(width 0)
				(type default)
			)
			(fill no)
			(layer "F.CrtYd")
		)
		(fp_rect
			(start -0.2794 0.6477)
			(end 0.2794 -0.6477)
			(stroke
				(width 0)
				(type default)
			)
			(fill no)
			(layer "F.Fab")
		)
		(pad "1" smd custom
			(at 0 -0.2794 180)
			(size 0.0762 0.0762)
			(layers "F.Cu" "F.Mask" "F.Paste")
			(net "SAS_HDD_TX9_N")
			(options
				(clearance outline)
				(anchor circle)
			)
			(primitives
				(gr_poly
					(pts
						(arc
							(start 0.1524 -0.127)
							(mid 0.137521 -0.162921)
							(end 0.1016 -0.1778)
						)
						(arc
							(start -0.1016 -0.1778)
							(mid -0.137521 -0.162921)
							(end -0.1524 -0.127)
						)
						(arc
							(start -0.1524 0.127)
							(mid -0.137521 0.162921)
							(end -0.1016 0.1778)
						)
						(arc
							(start 0.1016 0.1778)
							(mid 0.137521 0.162921)
							(end 0.1524 0.127)
						)
					)
					(width 0)
					(fill yes)
				)
			)
		)
		(pad "2" smd custom
			(at 0 0.2794 180)
			(size 0.0762 0.0762)
			(layers "F.Cu" "F.Mask" "F.Paste")
			(net "SAS_EXP_GF_TX_DN13")
			(options
				(clearance outline)
				(anchor circle)
			)
			(primitives
				(gr_poly
					(pts
						(arc
							(start 0.1524 -0.127)
							(mid 0.137521 -0.162921)
							(end 0.1016 -0.1778)
						)
						(arc
							(start -0.1016 -0.1778)
							(mid -0.137521 -0.162921)
							(end -0.1524 -0.127)
						)
						(arc
							(start -0.1524 0.127)
							(mid -0.137521 0.162921)
							(end -0.1016 0.1778)
						)
						(arc
							(start 0.1016 0.1778)
							(mid 0.137521 0.162921)
							(end 0.1524 0.127)
						)
					)
					(width 0)
					(fill yes)
				)
			)
		)
	)
	(footprint ""
		(layer "F.Cu")
		(at 271.272 -169.672 90)
		(property "Reference" "R268"
			(at 0 0 90)
			(layer "F.SilkS")
			(hide yes)
			(effects
				(font
					(size 1.27 1.27)
				)
			)
		)
		(property "Value" "10KR2F-2-GP"
			(at 0.064008 -3.993896 90)
			(unlocked yes)
			(layer "F.Fab")
			(hide yes)
			(effects
				(font
					(size 1.016 1.016)
					(thickness 0.1524)
				)
			)
		)
		(property "Device Type" "R402H16"
			(at 0.064008 -5.517896 90)
			(unlocked yes)
			(layer "F.Fab")
			(hide yes)
			(effects
				(font
					(size 1.016 1.016)
					(thickness 0.1524)
				)
			)
		)
		(duplicate_pad_numbers_are_jumpers no)
		(fp_line
			(start 0.508 -0.9398)
			(end -0.508 -0.9398)
			(stroke
				(width 0.1524)
				(type default)
			)
			(layer "F.SilkS")
		)
		(fp_line
			(start -0.508 -0.9398)
			(end -0.508 0.9398)
			(stroke
				(width 0.1524)
				(type default)
			)
			(layer "F.SilkS")
		)
		(fp_rect
			(start -0.508 0.9398)
			(end 0.508 -0.9398)
			(stroke
				(width 0)
				(type default)
			)
			(fill no)
			(layer "F.CrtYd")
		)
		(fp_rect
			(start -0.508 0.9398)
			(end 0.508 -0.9398)
			(stroke
				(width 0)
				(type default)
			)
			(fill no)
			(layer "F.Fab")
		)
		(pad "1" smd custom
			(at 0 -0.4445 90)
			(size 0.1397 0.1397)
			(layers "F.Cu" "F.Mask" "F.Paste")
			(net "P3V3_STBY")
			(options
				(clearance outline)
				(anchor circle)
			)
			(primitives
				(gr_poly
					(pts
						(arc
							(start -0.1778 -0.2794)
							(mid -0.249642 -0.249642)
							(end -0.2794 -0.1778)
						)
						(arc
							(start -0.2794 0.1778)
							(mid -0.249642 0.249642)
							(end -0.1778 0.2794)
						)
						(arc
							(start 0.1778 0.2794)
							(mid 0.249642 0.249642)
							(end 0.2794 0.1778)
						)
						(arc
							(start 0.2794 -0.1778)
							(mid 0.249642 -0.249642)
							(end 0.1778 -0.2794)
						)
					)
					(width 0)
					(fill yes)
				)
			)
		)
		(pad "2" smd custom
			(at 0 0.4445 90)
			(size 0.1397 0.1397)
			(layers "F.Cu" "F.Mask" "F.Paste")
			(net "BMC_MBC_I2C_E_SDA")
			(options
				(clearance outline)
				(anchor circle)
			)
			(primitives
				(gr_poly
					(pts
						(arc
							(start -0.1778 -0.2794)
							(mid -0.249642 -0.249642)
							(end -0.2794 -0.1778)
						)
						(arc
							(start -0.2794 0.1778)
							(mid -0.249642 0.249642)
							(end -0.1778 0.2794)
						)
						(arc
							(start 0.1778 0.2794)
							(mid 0.249642 0.249642)
							(end 0.2794 0.1778)
						)
						(arc
							(start 0.2794 -0.1778)
							(mid 0.249642 -0.249642)
							(end 0.1778 -0.2794)
						)
					)
					(width 0)
					(fill yes)
				)
			)
		)
	)
	(footprint ""
		(layer "F.Cu")
		(at 174.117 -120.142 90)
		(property "Reference" "PC172"
			(at 0 0 90)
			(layer "F.SilkS")
			(hide yes)
			(effects
				(font
					(size 1.27 1.27)
				)
			)
		)
		(property "Value" "SCD1U50V3KX-GP"
			(at 0 -2.8194 90)
			(unlocked yes)
			(layer "F.Fab")
			(hide yes)
			(effects
				(font
					(size 1.016 1.016)
					(thickness 0.1524)
				)
			)
		)
		(property "Device Type" "C603H36"
			(at 0 -4.3434 90)
			(unlocked yes)
			(layer "F.Fab")
			(hide yes)
			(effects
				(font
					(size 1.016 1.016)
					(thickness 0.1524)
				)
			)
		)
		(duplicate_pad_numbers_are_jumpers no)
		(fp_line
			(start 0.508 0)
			(end -0.508 0)
			(stroke
				(width 0.2032)
				(type default)
			)
			(layer "F.SilkS")
		)
		(fp_rect
			(start -0.5842 1.3335)
			(end 0.5842 -1.3335)
			(stroke
				(width 0)
				(type default)
			)
			(fill no)
			(layer "F.CrtYd")
		)
		(fp_rect
			(start -0.5842 1.3335)
			(end 0.5842 -1.3335)
			(stroke
				(width 0)
				(type default)
			)
			(fill no)
			(layer "F.Fab")
		)
		(pad "1" smd custom
			(at 0 -0.762 90)
			(size 0.2159 0.2159)
			(layers "F.Cu" "F.Mask" "F.Paste")
			(net "P0V9_E_VIN")
			(options
				(clearance outline)
				(anchor circle)
			)
			(primitives
				(gr_poly
					(pts
						(arc
							(start -0.3302 -0.4318)
							(mid -0.402042 -0.402042)
							(end -0.4318 -0.3302)
						)
						(arc
							(start -0.4318 0.3302)
							(mid -0.402042 0.402042)
							(end -0.3302 0.4318)
						)
						(arc
							(start 0.3302 0.4318)
							(mid 0.402042 0.402042)
							(end 0.4318 0.3302)
						)
						(arc
							(start 0.4318 -0.3302)
							(mid 0.402042 -0.402042)
							(end 0.3302 -0.4318)
						)
					)
					(width 0)
					(fill yes)
				)
			)
		)
		(pad "2" smd custom
			(at 0 0.762 90)
			(size 0.2159 0.2159)
			(layers "F.Cu" "F.Mask" "F.Paste")
			(net "GND")
			(options
				(clearance outline)
				(anchor circle)
			)
			(primitives
				(gr_poly
					(pts
						(arc
							(start -0.3302 -0.4318)
							(mid -0.402042 -0.402042)
							(end -0.4318 -0.3302)
						)
						(arc
							(start -0.4318 0.3302)
							(mid -0.402042 0.402042)
							(end -0.3302 0.4318)
						)
						(arc
							(start 0.3302 0.4318)
							(mid 0.402042 0.402042)
							(end 0.4318 0.3302)
						)
						(arc
							(start 0.4318 -0.3302)
							(mid 0.402042 -0.402042)
							(end 0.3302 -0.4318)
						)
					)
					(width 0)
					(fill yes)
				)
			)
		)
	)
	(footprint ""
		(layer "F.Cu")
		(at 208.095596 -118.129812 90)
		(property "Reference" "PG6"
			(at 0 0 90)
			(layer "F.SilkS")
			(hide yes)
			(effects
				(font
					(size 1.27 1.27)
				)
			)
		)
		(property "Value" "COPPER-CLOSE-GP-U"
			(at 0.0762 -2.8702 90)
			(unlocked yes)
			(layer "F.Fab")
			(hide yes)
			(effects
				(font
					(size 1.016 1.016)
					(thickness 0.1524)
				)
			)
		)
		(property "Device Type" "CON2C-U"
			(at 0.0762 -4.3942 90)
			(unlocked yes)
			(layer "F.Fab")
			(hide yes)
			(effects
				(font
					(size 1.016 1.016)
					(thickness 0.1524)
				)
			)
		)
		(duplicate_pad_numbers_are_jumpers no)
		(fp_rect
			(start -0.9398 0.9652)
			(end 0.9398 -0.9652)
			(stroke
				(width 0)
				(type default)
			)
			(fill no)
			(layer "F.CrtYd")
		)
		(fp_rect
			(start -0.9398 0.9652)
			(end 0.9398 -0.9652)
			(stroke
				(width 0)
				(type default)
			)
			(fill no)
			(layer "F.Fab")
		)
		(pad "1" smd custom
			(at 0 -0.5334 90)
			(size 0.17145 0.17145)
			(layers "F.Cu" "F.Mask" "F.Paste")
			(net "AGND_P1V5_E")
			(options
				(clearance outline)
				(anchor circle)
			)
			(primitives
				(gr_poly
					(pts
						(xy -0.127 0.3429) (xy -0.127 0.1651) (xy -0.635 -0.3429) (xy 0.635 -0.3429) (xy 0.127 0.1651)
						(xy 0.127 0.3429)
					)
					(width 0)
					(fill yes)
				)
			)
		)
		(pad "2" smd custom
			(at 0 0.5334 90)
			(size 0.17145 0.17145)
			(layers "F.Cu" "F.Mask" "F.Paste")
			(net "GND")
			(options
				(clearance outline)
				(anchor circle)
			)
			(primitives
				(gr_poly
					(pts
						(xy -0.635 0.3429) (xy -0.127 -0.1651) (xy -0.127 -0.3429) (xy 0.127 -0.3429) (xy 0.127 -0.1651)
						(xy 0.635 0.3429)
					)
					(width 0)
					(fill yes)
				)
			)
		)
	)
	(footprint ""
		(layer "F.Cu")
		(at 278.638 -115.824 180)
		(property "Reference" "PR174"
			(at 0 0 180)
			(layer "F.SilkS")
			(hide yes)
			(effects
				(font
					(size 1.27 1.27)
				)
			)
		)
		(property "Value" "4K02R2F-GP"
			(at 0.064008 -3.993896 180)
			(unlocked yes)
			(layer "F.Fab")
			(hide yes)
			(effects
				(font
					(size 1.016 1.016)
					(thickness 0.1524)
				)
			)
		)
		(property "Device Type" "R402H16"
			(at 0.064008 -5.517896 180)
			(unlocked yes)
			(layer "F.Fab")
			(hide yes)
			(effects
				(font
					(size 1.016 1.016)
					(thickness 0.1524)
				)
			)
		)
		(duplicate_pad_numbers_are_jumpers no)
		(fp_line
			(start 0.508 -0.9398)
			(end -0.508 -0.9398)
			(stroke
				(width 0.1524)
				(type default)
			)
			(layer "F.SilkS")
		)
		(fp_line
			(start -0.508 -0.9398)
			(end -0.508 0.9398)
			(stroke
				(width 0.1524)
				(type default)
			)
			(layer "F.SilkS")
		)
		(fp_rect
			(start -0.508 0.9398)
			(end 0.508 -0.9398)
			(stroke
				(width 0)
				(type default)
			)
			(fill no)
			(layer "F.CrtYd")
		)
		(fp_rect
			(start -0.508 0.9398)
			(end 0.508 -0.9398)
			(stroke
				(width 0)
				(type default)
			)
			(fill no)
			(layer "F.Fab")
		)
		(pad "1" smd custom
			(at 0 -0.4445 180)
			(size 0.1397 0.1397)
			(layers "F.Cu" "F.Mask" "F.Paste")
			(net "P1V8_C_EN_B")
			(options
				(clearance outline)
				(anchor circle)
			)
			(primitives
				(gr_poly
					(pts
						(arc
							(start -0.1778 -0.2794)
							(mid -0.249642 -0.249642)
							(end -0.2794 -0.1778)
						)
						(arc
							(start -0.2794 0.1778)
							(mid -0.249642 0.249642)
							(end -0.1778 0.2794)
						)
						(arc
							(start 0.1778 0.2794)
							(mid 0.249642 0.249642)
							(end 0.2794 0.1778)
						)
						(arc
							(start 0.2794 -0.1778)
							(mid 0.249642 -0.249642)
							(end 0.1778 -0.2794)
						)
					)
					(width 0)
					(fill yes)
				)
			)
		)
		(pad "2" smd custom
			(at 0 0.4445 180)
			(size 0.1397 0.1397)
			(layers "F.Cu" "F.Mask" "F.Paste")
			(net "P3V3_STBY")
			(options
				(clearance outline)
				(anchor circle)
			)
			(primitives
				(gr_poly
					(pts
						(arc
							(start -0.1778 -0.2794)
							(mid -0.249642 -0.249642)
							(end -0.2794 -0.1778)
						)
						(arc
							(start -0.2794 0.1778)
							(mid -0.249642 0.249642)
							(end -0.1778 0.2794)
						)
						(arc
							(start 0.1778 0.2794)
							(mid 0.249642 0.249642)
							(end 0.2794 0.1778)
						)
						(arc
							(start 0.2794 -0.1778)
							(mid 0.249642 -0.249642)
							(end 0.1778 -0.2794)
						)
					)
					(width 0)
					(fill yes)
				)
			)
		)
	)
	(footprint ""
		(layer "F.Cu")
		(at 88.392 -21.463 180)
		(property "Reference" "PC214"
			(at 0 0 180)
			(layer "F.SilkS")
			(hide yes)
			(effects
				(font
					(size 1.27 1.27)
				)
			)
		)
		(property "Value" "SC6800P50V3KX-GP"
			(at 0 -2.8194 180)
			(unlocked yes)
			(layer "F.Fab")
			(hide yes)
			(effects
				(font
					(size 1.016 1.016)
					(thickness 0.1524)
				)
			)
		)
		(property "Device Type" "C603"
			(at 0 -4.3434 180)
			(unlocked yes)
			(layer "F.Fab")
			(hide yes)
			(effects
				(font
					(size 1.016 1.016)
					(thickness 0.1524)
				)
			)
		)
		(duplicate_pad_numbers_are_jumpers no)
		(fp_line
			(start 0.508 0)
			(end -0.508 0)
			(stroke
				(width 0.2032)
				(type default)
			)
			(layer "F.SilkS")
		)
		(fp_rect
			(start -0.5842 1.3335)
			(end 0.5842 -1.3335)
			(stroke
				(width 0)
				(type default)
			)
			(fill no)
			(layer "F.CrtYd")
		)
		(fp_rect
			(start -0.5842 1.3335)
			(end 0.5842 -1.3335)
			(stroke
				(width 0)
				(type default)
			)
			(fill no)
			(layer "F.Fab")
		)
		(pad "1" smd custom
			(at 0 -0.762 180)
			(size 0.2159 0.2159)
			(layers "F.Cu" "F.Mask" "F.Paste")
			(net "VT235_VFB")
			(options
				(clearance outline)
				(anchor circle)
			)
			(primitives
				(gr_poly
					(pts
						(arc
							(start -0.3302 -0.4318)
							(mid -0.402042 -0.402042)
							(end -0.4318 -0.3302)
						)
						(arc
							(start -0.4318 0.3302)
							(mid -0.402042 0.402042)
							(end -0.3302 0.4318)
						)
						(arc
							(start 0.3302 0.4318)
							(mid 0.402042 0.402042)
							(end 0.4318 0.3302)
						)
						(arc
							(start 0.4318 -0.3302)
							(mid 0.402042 -0.402042)
							(end 0.3302 -0.4318)
						)
					)
					(width 0)
					(fill yes)
				)
			)
		)
		(pad "2" smd custom
			(at 0 0.762 180)
			(size 0.2159 0.2159)
			(layers "F.Cu" "F.Mask" "F.Paste")
			(net "VT235_VDES")
			(options
				(clearance outline)
				(anchor circle)
			)
			(primitives
				(gr_poly
					(pts
						(arc
							(start -0.3302 -0.4318)
							(mid -0.402042 -0.402042)
							(end -0.4318 -0.3302)
						)
						(arc
							(start -0.4318 0.3302)
							(mid -0.402042 0.402042)
							(end -0.3302 0.4318)
						)
						(arc
							(start 0.3302 0.4318)
							(mid 0.402042 0.402042)
							(end 0.4318 0.3302)
						)
						(arc
							(start 0.4318 -0.3302)
							(mid 0.402042 -0.402042)
							(end 0.3302 -0.4318)
						)
					)
					(width 0)
					(fill yes)
				)
			)
		)
	)
	(footprint ""
		(layer "F.Cu")
		(at 136.906 -98.806 180)
		(property "Reference" "SC1266"
			(at 0 0 180)
			(layer "F.SilkS")
			(hide yes)
			(effects
				(font
					(size 1.27 1.27)
				)
			)
		)
		(property "Value" "SCD01U10V1KX-GP"
			(at -2.8321 -1.7399 180)
			(unlocked yes)
			(layer "F.Fab")
			(hide yes)
			(effects
				(font
					(size 1.016 1.016)
					(thickness 0.1524)
				)
			)
		)
		(property "Device Type" "C0201H13"
			(at -2.8321 -3.2639 180)
			(unlocked yes)
			(layer "F.Fab")
			(hide yes)
			(effects
				(font
					(size 1.016 1.016)
					(thickness 0.1524)
				)
			)
		)
		(duplicate_pad_numbers_are_jumpers no)
		(fp_rect
			(start -0.2794 0.6477)
			(end 0.2794 -0.6477)
			(stroke
				(width 0)
				(type default)
			)
			(fill no)
			(layer "F.CrtYd")
		)
		(fp_rect
			(start -0.2794 0.6477)
			(end 0.2794 -0.6477)
			(stroke
				(width 0)
				(type default)
			)
			(fill no)
			(layer "F.Fab")
		)
		(pad "1" smd custom
			(at 0 -0.2794 180)
			(size 0.0762 0.0762)
			(layers "F.Cu" "F.Mask" "F.Paste")
			(net "3X24_SAS_TX20_P")
			(options
				(clearance outline)
				(anchor circle)
			)
			(primitives
				(gr_poly
					(pts
						(arc
							(start 0.1524 -0.127)
							(mid 0.137521 -0.162921)
							(end 0.1016 -0.1778)
						)
						(arc
							(start -0.1016 -0.1778)
							(mid -0.137521 -0.162921)
							(end -0.1524 -0.127)
						)
						(arc
							(start -0.1524 0.127)
							(mid -0.137521 0.162921)
							(end -0.1016 0.1778)
						)
						(arc
							(start 0.1016 0.1778)
							(mid 0.137521 0.162921)
							(end 0.1524 0.127)
						)
					)
					(width 0)
					(fill yes)
				)
			)
		)
		(pad "2" smd custom
			(at 0 0.2794 180)
			(size 0.0762 0.0762)
			(layers "F.Cu" "F.Mask" "F.Paste")
			(net "SAS_EXP_GF_TX_DP0")
			(options
				(clearance outline)
				(anchor circle)
			)
			(primitives
				(gr_poly
					(pts
						(arc
							(start 0.1524 -0.127)
							(mid 0.137521 -0.162921)
							(end 0.1016 -0.1778)
						)
						(arc
							(start -0.1016 -0.1778)
							(mid -0.137521 -0.162921)
							(end -0.1524 -0.127)
						)
						(arc
							(start -0.1524 0.127)
							(mid -0.137521 0.162921)
							(end -0.1016 0.1778)
						)
						(arc
							(start 0.1016 0.1778)
							(mid 0.137521 0.162921)
							(end 0.1524 0.127)
						)
					)
					(width 0)
					(fill yes)
				)
			)
		)
	)
	(footprint ""
		(layer "F.Cu")
		(at 345.44 -108.331)
		(property "Reference" "PC6"
			(at 0 0 0)
			(layer "F.SilkS")
			(hide yes)
			(effects
				(font
					(size 1.27 1.27)
				)
			)
		)
		(property "Value" "SCD1U25V3KX-GP"
			(at 0 -2.8194 0)
			(unlocked yes)
			(layer "F.Fab")
			(hide yes)
			(effects
				(font
					(size 1.016 1.016)
					(thickness 0.1524)
				)
			)
		)
		(property "Device Type" "C603H36"
			(at 0 -4.3434 0)
			(unlocked yes)
			(layer "F.Fab")
			(hide yes)
			(effects
				(font
					(size 1.016 1.016)
					(thickness 0.1524)
				)
			)
		)
		(duplicate_pad_numbers_are_jumpers no)
		(fp_line
			(start 0.508 0)
			(end -0.508 0)
			(stroke
				(width 0.2032)
				(type default)
			)
			(layer "F.SilkS")
		)
		(fp_rect
			(start -0.5842 1.3335)
			(end 0.5842 -1.3335)
			(stroke
				(width 0)
				(type default)
			)
			(fill no)
			(layer "F.CrtYd")
		)
		(fp_rect
			(start -0.5842 1.3335)
			(end 0.5842 -1.3335)
			(stroke
				(width 0)
				(type default)
			)
			(fill no)
			(layer "F.Fab")
		)
		(pad "1" smd custom
			(at 0 -0.762)
			(size 0.2159 0.2159)
			(layers "F.Cu" "F.Mask" "F.Paste")
			(net "P5V_STBY_VIN")
			(options
				(clearance outline)
				(anchor circle)
			)
			(primitives
				(gr_poly
					(pts
						(arc
							(start -0.3302 -0.4318)
							(mid -0.402042 -0.402042)
							(end -0.4318 -0.3302)
						)
						(arc
							(start -0.4318 0.3302)
							(mid -0.402042 0.402042)
							(end -0.3302 0.4318)
						)
						(arc
							(start 0.3302 0.4318)
							(mid 0.402042 0.402042)
							(end 0.4318 0.3302)
						)
						(arc
							(start 0.4318 -0.3302)
							(mid 0.402042 -0.402042)
							(end 0.3302 -0.4318)
						)
					)
					(width 0)
					(fill yes)
				)
			)
		)
		(pad "2" smd custom
			(at 0 0.762)
			(size 0.2159 0.2159)
			(layers "F.Cu" "F.Mask" "F.Paste")
			(net "GND")
			(options
				(clearance outline)
				(anchor circle)
			)
			(primitives
				(gr_poly
					(pts
						(arc
							(start -0.3302 -0.4318)
							(mid -0.402042 -0.402042)
							(end -0.4318 -0.3302)
						)
						(arc
							(start -0.4318 0.3302)
							(mid -0.402042 0.402042)
							(end -0.3302 0.4318)
						)
						(arc
							(start 0.3302 0.4318)
							(mid 0.402042 0.402042)
							(end 0.4318 0.3302)
						)
						(arc
							(start 0.4318 -0.3302)
							(mid 0.402042 -0.402042)
							(end 0.3302 -0.4318)
						)
					)
					(width 0)
					(fill yes)
				)
			)
		)
	)
	(footprint ""
		(layer "F.Cu")
		(at 46.670722 -136.498584 90)
		(property "Reference" "SR795"
			(at 0 0 90)
			(layer "F.SilkS")
			(hide yes)
			(effects
				(font
					(size 1.27 1.27)
				)
			)
		)
		(property "Value" "4K7R2F-GP"
			(at 0.064008 -3.993896 90)
			(unlocked yes)
			(layer "F.Fab")
			(hide yes)
			(effects
				(font
					(size 1.016 1.016)
					(thickness 0.1524)
				)
			)
		)
		(property "Device Type" "R402H16"
			(at 0.064008 -5.517896 90)
			(unlocked yes)
			(layer "F.Fab")
			(hide yes)
			(effects
				(font
					(size 1.016 1.016)
					(thickness 0.1524)
				)
			)
		)
		(duplicate_pad_numbers_are_jumpers no)
		(fp_line
			(start 0.508 -0.9398)
			(end -0.508 -0.9398)
			(stroke
				(width 0.1524)
				(type default)
			)
			(layer "F.SilkS")
		)
		(fp_line
			(start -0.508 -0.9398)
			(end -0.508 0.9398)
			(stroke
				(width 0.1524)
				(type default)
			)
			(layer "F.SilkS")
		)
		(fp_rect
			(start -0.508 0.9398)
			(end 0.508 -0.9398)
			(stroke
				(width 0)
				(type default)
			)
			(fill no)
			(layer "F.CrtYd")
		)
		(fp_rect
			(start -0.508 0.9398)
			(end 0.508 -0.9398)
			(stroke
				(width 0)
				(type default)
			)
			(fill no)
			(layer "F.Fab")
		)
		(pad "1" smd custom
			(at 0 -0.4445 90)
			(size 0.1397 0.1397)
			(layers "F.Cu" "F.Mask" "F.Paste")
			(net "P1V8_E")
			(options
				(clearance outline)
				(anchor circle)
			)
			(primitives
				(gr_poly
					(pts
						(arc
							(start -0.1778 -0.2794)
							(mid -0.249642 -0.249642)
							(end -0.2794 -0.1778)
						)
						(arc
							(start -0.2794 0.1778)
							(mid -0.249642 0.249642)
							(end -0.1778 0.2794)
						)
						(arc
							(start 0.1778 0.2794)
							(mid 0.249642 0.249642)
							(end 0.2794 0.1778)
						)
						(arc
							(start 0.2794 -0.1778)
							(mid 0.249642 -0.249642)
							(end 0.1778 -0.2794)
						)
					)
					(width 0)
					(fill yes)
				)
			)
		)
		(pad "2" smd custom
			(at 0 0.4445 90)
			(size 0.1397 0.1397)
			(layers "F.Cu" "F.Mask" "F.Paste")
			(net "RESET_AND_N")
			(options
				(clearance outline)
				(anchor circle)
			)
			(primitives
				(gr_poly
					(pts
						(arc
							(start -0.1778 -0.2794)
							(mid -0.249642 -0.249642)
							(end -0.2794 -0.1778)
						)
						(arc
							(start -0.2794 0.1778)
							(mid -0.249642 0.249642)
							(end -0.1778 0.2794)
						)
						(arc
							(start 0.1778 0.2794)
							(mid 0.249642 0.249642)
							(end 0.2794 0.1778)
						)
						(arc
							(start 0.2794 -0.1778)
							(mid 0.249642 -0.249642)
							(end 0.1778 -0.2794)
						)
					)
					(width 0)
					(fill yes)
				)
			)
		)
	)
	(footprint ""
		(layer "F.Cu")
		(at 198.062596 -121.177812)
		(property "Reference" "PR9017"
			(at 0 0 0)
			(layer "F.SilkS")
			(hide yes)
			(effects
				(font
					(size 1.27 1.27)
				)
			)
		)
		(property "Value" "10KR2F-2-GP"
			(at 0.064008 -3.993896 0)
			(unlocked yes)
			(layer "F.Fab")
			(hide yes)
			(effects
				(font
					(size 1.016 1.016)
					(thickness 0.1524)
				)
			)
		)
		(property "Device Type" "R402H16"
			(at 0.064008 -5.517896 0)
			(unlocked yes)
			(layer "F.Fab")
			(hide yes)
			(effects
				(font
					(size 1.016 1.016)
					(thickness 0.1524)
				)
			)
		)
		(duplicate_pad_numbers_are_jumpers no)
		(fp_line
			(start -0.508 -0.9398)
			(end -0.508 0.9398)
			(stroke
				(width 0.1524)
				(type default)
			)
			(layer "F.SilkS")
		)
		(fp_line
			(start 0.508 -0.9398)
			(end -0.508 -0.9398)
			(stroke
				(width 0.1524)
				(type default)
			)
			(layer "F.SilkS")
		)
		(fp_rect
			(start -0.508 0.9398)
			(end 0.508 -0.9398)
			(stroke
				(width 0)
				(type default)
			)
			(fill no)
			(layer "F.CrtYd")
		)
		(fp_rect
			(start -0.508 0.9398)
			(end 0.508 -0.9398)
			(stroke
				(width 0)
				(type default)
			)
			(fill no)
			(layer "F.Fab")
		)
		(pad "1" smd custom
			(at 0 -0.4445)
			(size 0.1397 0.1397)
			(layers "F.Cu" "F.Mask" "F.Paste")
			(net "P1V5_E_PG")
			(options
				(clearance outline)
				(anchor circle)
			)
			(primitives
				(gr_poly
					(pts
						(arc
							(start -0.1778 -0.2794)
							(mid -0.249642 -0.249642)
							(end -0.2794 -0.1778)
						)
						(arc
							(start -0.2794 0.1778)
							(mid -0.249642 0.249642)
							(end -0.1778 0.2794)
						)
						(arc
							(start 0.1778 0.2794)
							(mid 0.249642 0.249642)
							(end 0.2794 0.1778)
						)
						(arc
							(start 0.2794 -0.1778)
							(mid 0.249642 -0.249642)
							(end 0.1778 -0.2794)
						)
					)
					(width 0)
					(fill yes)
				)
			)
		)
		(pad "2" smd custom
			(at 0 0.4445)
			(size 0.1397 0.1397)
			(layers "F.Cu" "F.Mask" "F.Paste")
			(net "P1V5_E_VRG5")
			(options
				(clearance outline)
				(anchor circle)
			)
			(primitives
				(gr_poly
					(pts
						(arc
							(start -0.1778 -0.2794)
							(mid -0.249642 -0.249642)
							(end -0.2794 -0.1778)
						)
						(arc
							(start -0.2794 0.1778)
							(mid -0.249642 0.249642)
							(end -0.1778 0.2794)
						)
						(arc
							(start 0.1778 0.2794)
							(mid 0.249642 0.249642)
							(end 0.2794 0.1778)
						)
						(arc
							(start 0.2794 -0.1778)
							(mid 0.249642 -0.249642)
							(end 0.1778 -0.2794)
						)
					)
					(width 0)
					(fill yes)
				)
			)
		)
	)
	(footprint ""
		(layer "F.Cu")
		(at 78.8924 -11.3792 90)
		(property "Reference" "PC206"
			(at 0 0 90)
			(layer "F.SilkS")
			(hide yes)
			(effects
				(font
					(size 1.27 1.27)
				)
			)
		)
		(property "Value" "SC10U25V6KX-1GP"
			(at -0.0762 -5.1308 90)
			(unlocked yes)
			(layer "F.Fab")
			(hide yes)
			(effects
				(font
					(size 1.016 1.016)
					(thickness 0.1524)
				)
			)
		)
		(property "Device Type" "C1206H71"
			(at -0.127 -6.6548 90)
			(unlocked yes)
			(layer "F.Fab")
			(hide yes)
			(effects
				(font
					(size 1.016 1.016)
					(thickness 0.1524)
				)
			)
		)
		(duplicate_pad_numbers_are_jumpers no)
		(fp_line
			(start 1.016 -2.2352)
			(end 1.016 -0.8382)
			(stroke
				(width 0.1524)
				(type default)
			)
			(layer "F.SilkS")
		)
		(fp_line
			(start -1.016 -2.2352)
			(end 1.016 -2.2352)
			(stroke
				(width 0.1524)
				(type default)
			)
			(layer "F.SilkS")
		)
		(fp_line
			(start -1.016 -0.8382)
			(end -1.016 -2.2352)
			(stroke
				(width 0.1524)
				(type default)
			)
			(layer "F.SilkS")
		)
		(fp_line
			(start 1.016 0.8382)
			(end 1.016 2.2352)
			(stroke
				(width 0.1524)
				(type default)
			)
			(layer "F.SilkS")
		)
		(fp_line
			(start 1.016 2.2352)
			(end -1.016 2.2352)
			(stroke
				(width 0.1524)
				(type default)
			)
			(layer "F.SilkS")
		)
		(fp_line
			(start -1.016 2.2352)
			(end -1.016 0.8382)
			(stroke
				(width 0.1524)
				(type default)
			)
			(layer "F.SilkS")
		)
		(fp_rect
			(start -1.0922 2.3114)
			(end 1.0922 -2.3114)
			(stroke
				(width 0)
				(type default)
			)
			(fill no)
			(layer "F.CrtYd")
		)
		(fp_poly
			(pts
				(xy 1.0922 -2.3114) (xy 1.0922 2.3114) (xy -1.0922 2.3114) (xy -1.0922 -2.3114)
			)
			(stroke
				(width 0)
				(type default)
			)
			(fill no)
			(layer "F.Fab")
		)
		(pad "1" smd rect
			(at 0 -1.397 90)
			(size 1.651 1.27)
			(layers "F.Cu" "F.Mask" "F.Paste")
			(net "VT235_VDDH")
		)
		(pad "2" smd rect
			(at 0 1.397 90)
			(size 1.651 1.27)
			(layers "F.Cu" "F.Mask" "F.Paste")
			(net "GND")
		)
	)
	(footprint ""
		(layer "F.Cu")
		(at 179.569872 -195.194936 -90)
		(property "Reference" "U24"
			(at 0 0 270)
			(layer "F.SilkS")
			(hide yes)
			(effects
				(font
					(size 1.27 1.27)
				)
			)
		)
		(property "Value" "PCA9511ADP-T-GP"
			(at 0 -13.1572 270)
			(unlocked yes)
			(layer "F.Fab")
			(hide yes)
			(effects
				(font
					(size 1.016 1.016)
					(thickness 0.1524)
				)
			)
		)
		(property "Device Type" "SSOIC8-2H44"
			(at 0 -15.1892 270)
			(unlocked yes)
			(layer "F.Fab")
			(hide yes)
			(effects
				(font
					(size 1.016 1.016)
					(thickness 0.1524)
				)
			)
		)
		(duplicate_pad_numbers_are_jumpers no)
		(fp_line
			(start -1.7018 1.0414)
			(end -1.7018 2.9718)
			(stroke
				(width 0.635)
				(type default)
			)
			(layer "F.SilkS")
		)
		(fp_line
			(start -1.9304 1.016)
			(end -1.9304 -1.016)
			(stroke
				(width 0.1524)
				(type default)
			)
			(layer "F.SilkS")
		)
		(fp_line
			(start 1.0922 1.016)
			(end -1.9304 1.016)
			(stroke
				(width 0.1524)
				(type default)
			)
			(layer "F.SilkS")
		)
		(fp_line
			(start -1.524 0)
			(end -1.9304 0.4064)
			(stroke
				(width 0.1524)
				(type default)
			)
			(layer "F.SilkS")
		)
		(fp_line
			(start -1.524 0)
			(end -1.9304 -0.4064)
			(stroke
				(width 0.1524)
				(type default)
			)
			(layer "F.SilkS")
		)
		(fp_line
			(start -1.9304 -1.016)
			(end 1.0922 -1.016)
			(stroke
				(width 0.1524)
				(type default)
			)
			(layer "F.SilkS")
		)
		(fp_line
			(start 1.0922 -1.016)
			(end 1.0922 1.016)
			(stroke
				(width 0.1524)
				(type default)
			)
			(layer "F.SilkS")
		)
		(fp_poly
			(pts
				(xy -1.1938 -1.016) (xy 1.0922 -1.016) (xy 1.0922 1.016) (xy -1.1938 1.016)
			)
			(stroke
				(width 0)
				(type default)
			)
			(fill yes)
			(layer "F.SilkS")
		)
		(fp_rect
			(start -2.0066 3.3401)
			(end 2.0066 -3.3401)
			(stroke
				(width 0)
				(type default)
			)
			(fill no)
			(layer "F.CrtYd")
		)
		(fp_poly
			(pts
				(xy -2.0066 -3.3401) (xy 2.0066 -3.3401) (xy 2.0066 3.3401) (xy -2.0066 3.3401)
			)
			(stroke
				(width 0)
				(type default)
			)
			(fill no)
			(layer "F.Fab")
		)
		(pad "1" smd rect
			(at -0.97536 2.0701 270)
			(size 0.4064 1.524)
			(layers "F.Cu" "F.Mask" "F.Paste")
			(net "I2C_C_BUFF_EN")
		)
		(pad "2" smd rect
			(at -0.32512 2.0701 270)
			(size 0.4064 1.524)
			(layers "F.Cu" "F.Mask" "F.Paste")
			(net "BMC_I2C_C_SCL")
		)
		(pad "3" smd rect
			(at 0.32512 2.0701 270)
			(size 0.4064 1.524)
			(layers "F.Cu" "F.Mask" "F.Paste")
			(net "SAS_I2C_C_BUF_SCL")
		)
		(pad "4" smd rect
			(at 0.97536 2.0701 270)
			(size 0.4064 1.524)
			(layers "F.Cu" "F.Mask" "F.Paste")
			(net "GND")
		)
		(pad "5" smd rect
			(at 0.97536 -2.0701 270)
			(size 0.4064 1.524)
			(layers "F.Cu" "F.Mask" "F.Paste")
			(net "I2C_C_BUF_READY")
		)
		(pad "6" smd rect
			(at 0.32512 -2.0701 270)
			(size 0.4064 1.524)
			(layers "F.Cu" "F.Mask" "F.Paste")
			(net "SAS_I2C_C_BUF_SDA")
		)
		(pad "7" smd rect
			(at -0.32512 -2.0701 270)
			(size 0.4064 1.524)
			(layers "F.Cu" "F.Mask" "F.Paste")
			(net "BMC_I2C_C_SDA")
		)
		(pad "8" smd rect
			(at -0.97536 -2.0701 270)
			(size 0.4064 1.524)
			(layers "F.Cu" "F.Mask" "F.Paste")
			(net "P3V3_STBY")
		)
	)
	(footprint ""
		(layer "F.Cu")
		(at 173.630844 -27.366976 90)
		(property "Reference" "R405"
			(at 0 0 90)
			(layer "F.SilkS")
			(hide yes)
			(effects
				(font
					(size 1.27 1.27)
				)
			)
		)
		(property "Value" "49D9R2F-GP"
			(at 0.064008 -3.993896 90)
			(unlocked yes)
			(layer "F.Fab")
			(hide yes)
			(effects
				(font
					(size 1.016 1.016)
					(thickness 0.1524)
				)
			)
		)
		(property "Device Type" "R402H16"
			(at 0.064008 -5.517896 90)
			(unlocked yes)
			(layer "F.Fab")
			(hide yes)
			(effects
				(font
					(size 1.016 1.016)
					(thickness 0.1524)
				)
			)
		)
		(duplicate_pad_numbers_are_jumpers no)
		(fp_line
			(start 0.508 -0.9398)
			(end -0.508 -0.9398)
			(stroke
				(width 0.1524)
				(type default)
			)
			(layer "F.SilkS")
		)
		(fp_line
			(start -0.508 -0.9398)
			(end -0.508 0.9398)
			(stroke
				(width 0.1524)
				(type default)
			)
			(layer "F.SilkS")
		)
		(fp_rect
			(start -0.508 0.9398)
			(end 0.508 -0.9398)
			(stroke
				(width 0)
				(type default)
			)
			(fill no)
			(layer "F.CrtYd")
		)
		(fp_rect
			(start -0.508 0.9398)
			(end 0.508 -0.9398)
			(stroke
				(width 0)
				(type default)
			)
			(fill no)
			(layer "F.Fab")
		)
		(pad "1" smd custom
			(at 0 -0.4445 90)
			(size 0.1397 0.1397)
			(layers "F.Cu" "F.Mask" "F.Paste")
			(net "MOD_IMC_FAB_D_COP")
			(options
				(clearance outline)
				(anchor circle)
			)
			(primitives
				(gr_poly
					(pts
						(arc
							(start -0.1778 -0.2794)
							(mid -0.249642 -0.249642)
							(end -0.2794 -0.1778)
						)
						(arc
							(start -0.2794 0.1778)
							(mid -0.249642 0.249642)
							(end -0.1778 0.2794)
						)
						(arc
							(start 0.1778 0.2794)
							(mid 0.249642 0.249642)
							(end 0.2794 0.1778)
						)
						(arc
							(start 0.2794 -0.1778)
							(mid 0.249642 -0.249642)
							(end 0.1778 -0.2794)
						)
					)
					(width 0)
					(fill yes)
				)
			)
		)
		(pad "2" smd custom
			(at 0 0.4445 90)
			(size 0.1397 0.1397)
			(layers "F.Cu" "F.Mask" "F.Paste")
			(net "BCM5221_TX_C_DN")
			(options
				(clearance outline)
				(anchor circle)
			)
			(primitives
				(gr_poly
					(pts
						(arc
							(start -0.1778 -0.2794)
							(mid -0.249642 -0.249642)
							(end -0.2794 -0.1778)
						)
						(arc
							(start -0.2794 0.1778)
							(mid -0.249642 0.249642)
							(end -0.1778 0.2794)
						)
						(arc
							(start 0.1778 0.2794)
							(mid 0.249642 0.249642)
							(end 0.2794 0.1778)
						)
						(arc
							(start 0.2794 -0.1778)
							(mid 0.249642 -0.249642)
							(end 0.1778 -0.2794)
						)
					)
					(width 0)
					(fill yes)
				)
			)
		)
	)
	(footprint ""
		(layer "F.Cu")
		(at 92.27947 -102.93858 90)
		(property "Reference" "SR816"
			(at 0 0 90)
			(layer "F.SilkS")
			(hide yes)
			(effects
				(font
					(size 1.27 1.27)
				)
			)
		)
		(property "Value" "4K75R2F-1-GP"
			(at 0.064008 -3.993896 90)
			(unlocked yes)
			(layer "F.Fab")
			(hide yes)
			(effects
				(font
					(size 1.016 1.016)
					(thickness 0.1524)
				)
			)
		)
		(property "Device Type" "R402H16"
			(at 0.064008 -5.517896 90)
			(unlocked yes)
			(layer "F.Fab")
			(hide yes)
			(effects
				(font
					(size 1.016 1.016)
					(thickness 0.1524)
				)
			)
		)
		(duplicate_pad_numbers_are_jumpers no)
		(fp_line
			(start 0.508 -0.9398)
			(end -0.508 -0.9398)
			(stroke
				(width 0.1524)
				(type default)
			)
			(layer "F.SilkS")
		)
		(fp_line
			(start -0.508 -0.9398)
			(end -0.508 0.9398)
			(stroke
				(width 0.1524)
				(type default)
			)
			(layer "F.SilkS")
		)
		(fp_rect
			(start -0.508 0.9398)
			(end 0.508 -0.9398)
			(stroke
				(width 0)
				(type default)
			)
			(fill no)
			(layer "F.CrtYd")
		)
		(fp_rect
			(start -0.508 0.9398)
			(end 0.508 -0.9398)
			(stroke
				(width 0)
				(type default)
			)
			(fill no)
			(layer "F.Fab")
		)
		(pad "1" smd custom
			(at 0 -0.4445 90)
			(size 0.1397 0.1397)
			(layers "F.Cu" "F.Mask" "F.Paste")
			(net "P1V8_E")
			(options
				(clearance outline)
				(anchor circle)
			)
			(primitives
				(gr_poly
					(pts
						(arc
							(start -0.1778 -0.2794)
							(mid -0.249642 -0.249642)
							(end -0.2794 -0.1778)
						)
						(arc
							(start -0.2794 0.1778)
							(mid -0.249642 0.249642)
							(end -0.1778 0.2794)
						)
						(arc
							(start 0.1778 0.2794)
							(mid 0.249642 0.249642)
							(end 0.2794 0.1778)
						)
						(arc
							(start 0.2794 -0.1778)
							(mid 0.249642 -0.249642)
							(end 0.1778 -0.2794)
						)
					)
					(width 0)
					(fill yes)
				)
			)
		)
		(pad "2" smd custom
			(at 0 0.4445 90)
			(size 0.1397 0.1397)
			(layers "F.Cu" "F.Mask" "F.Paste")
			(net "SDB_RX")
			(options
				(clearance outline)
				(anchor circle)
			)
			(primitives
				(gr_poly
					(pts
						(arc
							(start -0.1778 -0.2794)
							(mid -0.249642 -0.249642)
							(end -0.2794 -0.1778)
						)
						(arc
							(start -0.2794 0.1778)
							(mid -0.249642 0.249642)
							(end -0.1778 0.2794)
						)
						(arc
							(start 0.1778 0.2794)
							(mid 0.249642 0.249642)
							(end 0.2794 0.1778)
						)
						(arc
							(start 0.2794 -0.1778)
							(mid 0.249642 -0.249642)
							(end 0.1778 -0.2794)
						)
					)
					(width 0)
					(fill yes)
				)
			)
		)
	)
	(footprint ""
		(layer "F.Cu")
		(at 53.594 -209.042 -90)
		(property "Reference" "C339"
			(at 0 0 270)
			(layer "F.SilkS")
			(hide yes)
			(effects
				(font
					(size 1.27 1.27)
				)
			)
		)
		(property "Value" "SC22U6D3V5MX-2GP"
			(at -0.0762 -6.1214 270)
			(unlocked yes)
			(layer "F.Fab")
			(hide yes)
			(effects
				(font
					(size 1.016 1.016)
					(thickness 0.1524)
				)
			)
		)
		(property "Device Type" "C805H58"
			(at -0.0762 -8.1534 270)
			(unlocked yes)
			(layer "F.Fab")
			(hide yes)
			(effects
				(font
					(size 1.016 1.016)
					(thickness 0.1524)
				)
			)
		)
		(duplicate_pad_numbers_are_jumpers no)
		(fp_line
			(start 0.635 0)
			(end -0.635 0)
			(stroke
				(width 0.508)
				(type default)
			)
			(layer "F.SilkS")
		)
		(fp_rect
			(start -0.9652 1.778)
			(end 0.9652 -1.778)
			(stroke
				(width 0)
				(type default)
			)
			(fill no)
			(layer "F.CrtYd")
		)
		(fp_poly
			(pts
				(xy -0.9652 -1.778) (xy 0.9652 -1.778) (xy 0.9652 1.778) (xy -0.9652 1.778)
			)
			(stroke
				(width 0)
				(type default)
			)
			(fill no)
			(layer "F.Fab")
		)
		(pad "1" smd rect
			(at 0 -0.9652 270)
			(size 1.397 1.143)
			(layers "F.Cu" "F.Mask" "F.Paste")
			(net "MB0_HS_ENABLE")
		)
		(pad "2" smd rect
			(at 0 0.9652 270)
			(size 1.397 1.143)
			(layers "F.Cu" "F.Mask" "F.Paste")
			(net "GND")
		)
	)
	(footprint ""
		(layer "F.Cu")
		(at 273.177 -225.552)
		(property "Reference" "PR77"
			(at 0 0 0)
			(layer "F.SilkS")
			(hide yes)
			(effects
				(font
					(size 1.27 1.27)
				)
			)
		)
		(property "Value" "0R6J-3-GP"
			(at -0.0508 -4.8514 0)
			(unlocked yes)
			(layer "F.Fab")
			(hide yes)
			(effects
				(font
					(size 1.016 1.016)
					(thickness 0.1524)
				)
			)
		)
		(property "Device Type" "R1206H28"
			(at 0 -6.3754 0)
			(unlocked yes)
			(layer "F.Fab")
			(hide yes)
			(effects
				(font
					(size 1.016 1.016)
					(thickness 0.1524)
				)
			)
		)
		(duplicate_pad_numbers_are_jumpers no)
		(fp_line
			(start -1.016 -2.2352)
			(end 1.016 -2.2352)
			(stroke
				(width 0.1524)
				(type default)
			)
			(layer "F.SilkS")
		)
		(fp_line
			(start -1.016 2.2352)
			(end -1.016 -2.2352)
			(stroke
				(width 0.1524)
				(type default)
			)
			(layer "F.SilkS")
		)
		(fp_line
			(start 1.016 -2.2352)
			(end 1.016 2.2352)
			(stroke
				(width 0.1524)
				(type default)
			)
			(layer "F.SilkS")
		)
		(fp_line
			(start 1.016 2.2352)
			(end -1.016 2.2352)
			(stroke
				(width 0.1524)
				(type default)
			)
			(layer "F.SilkS")
		)
		(fp_rect
			(start -1.0922 2.3114)
			(end 1.0922 -2.3114)
			(stroke
				(width 0)
				(type default)
			)
			(fill no)
			(layer "F.CrtYd")
		)
		(fp_poly
			(pts
				(xy -1.0922 -2.3114) (xy 1.0922 -2.3114) (xy 1.0922 2.3114) (xy -1.0922 2.3114)
			)
			(stroke
				(width 0)
				(type default)
			)
			(fill no)
			(layer "F.Fab")
		)
		(pad "1" smd rect
			(at 0 -1.397)
			(size 1.651 1.27)
			(layers "F.Cu" "F.Mask" "F.Paste")
			(net "P1V8_STBY")
		)
		(pad "2" smd rect
			(at 0 1.397)
			(size 1.651 1.27)
			(layers "F.Cu" "F.Mask" "F.Paste")
			(net "TPS74801_P1V53_STBY_IN")
		)
	)
	(footprint ""
		(layer "F.Cu")
		(at 299.637958 -58.293 180)
		(property "Reference" "C285"
			(at 0 0 180)
			(layer "F.SilkS")
			(hide yes)
			(effects
				(font
					(size 1.27 1.27)
				)
			)
		)
		(property "Value" "SCD1U25V2KX-2-GP"
			(at 1.1811 -2.7051 180)
			(unlocked yes)
			(layer "F.Fab")
			(hide yes)
			(effects
				(font
					(size 1.016 1.016)
					(thickness 0.1524)
				)
			)
		)
		(property "Device Type" "C402H22"
			(at 1.1811 -4.2291 180)
			(unlocked yes)
			(layer "F.Fab")
			(hide yes)
			(effects
				(font
					(size 1.016 1.016)
					(thickness 0.1524)
				)
			)
		)
		(duplicate_pad_numbers_are_jumpers no)
		(fp_rect
			(start -0.4318 0.9525)
			(end 0.4318 -0.9525)
			(stroke
				(width 0)
				(type default)
			)
			(fill no)
			(layer "F.CrtYd")
		)
		(fp_rect
			(start -0.4318 0.9525)
			(end 0.4318 -0.9525)
			(stroke
				(width 0)
				(type default)
			)
			(fill no)
			(layer "F.Fab")
		)
		(pad "1" smd custom
			(at 0 -0.4445 180)
			(size 0.1524 0.1524)
			(layers "F.Cu" "F.Mask" "F.Paste")
			(net "P3V3_STBY")
			(options
				(clearance outline)
				(anchor circle)
			)
			(primitives
				(gr_poly
					(pts
						(arc
							(start 0.3048 -0.2032)
							(mid 0.275042 -0.275042)
							(end 0.2032 -0.3048)
						)
						(arc
							(start -0.2032 -0.3048)
							(mid -0.275042 -0.275042)
							(end -0.3048 -0.2032)
						)
						(arc
							(start -0.3048 0.2032)
							(mid -0.275042 0.275042)
							(end -0.2032 0.3048)
						)
						(arc
							(start 0.2032 0.3048)
							(mid 0.275042 0.275042)
							(end 0.3048 0.2032)
						)
					)
					(width 0)
					(fill yes)
				)
			)
		)
		(pad "2" smd custom
			(at 0 0.4445 180)
			(size 0.1524 0.1524)
			(layers "F.Cu" "F.Mask" "F.Paste")
			(net "GND")
			(options
				(clearance outline)
				(anchor circle)
			)
			(primitives
				(gr_poly
					(pts
						(arc
							(start 0.3048 -0.2032)
							(mid 0.275042 -0.275042)
							(end 0.2032 -0.3048)
						)
						(arc
							(start -0.2032 -0.3048)
							(mid -0.275042 -0.275042)
							(end -0.3048 -0.2032)
						)
						(arc
							(start -0.3048 0.2032)
							(mid -0.275042 0.275042)
							(end -0.2032 0.3048)
						)
						(arc
							(start 0.2032 0.3048)
							(mid 0.275042 0.275042)
							(end 0.3048 0.2032)
						)
					)
					(width 0)
					(fill yes)
				)
			)
		)
	)
	(footprint ""
		(layer "F.Cu")
		(at 219.075 -162.433 90)
		(property "Reference" "U182"
			(at 0 0 90)
			(layer "F.SilkS")
			(hide yes)
			(effects
				(font
					(size 1.27 1.27)
				)
			)
		)
		(property "Value" "74AVC1T45DCKR-GP"
			(at -2.3622 -8.2042 90)
			(unlocked yes)
			(layer "F.Fab")
			(hide yes)
			(effects
				(font
					(size 1.016 1.016)
					(thickness 0.1524)
				)
			)
		)
		(property "Device Type" "SC70-6H44"
			(at -2.3622 -10.1092 90)
			(unlocked yes)
			(layer "F.Fab")
			(hide yes)
			(effects
				(font
					(size 1.016 1.016)
					(thickness 0.1524)
				)
			)
		)
		(duplicate_pad_numbers_are_jumpers no)
		(fp_line
			(start 1.4478 -1.7018)
			(end -1.4478 -1.7018)
			(stroke
				(width 0.1524)
				(type default)
			)
			(layer "F.SilkS")
		)
		(fp_line
			(start -1.4478 -1.7018)
			(end -1.4478 1.7018)
			(stroke
				(width 0.1524)
				(type default)
			)
			(layer "F.SilkS")
		)
		(fp_line
			(start 1.4478 1.7018)
			(end 1.4478 -1.7018)
			(stroke
				(width 0.1524)
				(type default)
			)
			(layer "F.SilkS")
		)
		(fp_line
			(start -1.4478 1.7018)
			(end 1.4478 1.7018)
			(stroke
				(width 0.1524)
				(type default)
			)
			(layer "F.SilkS")
		)
		(fp_line
			(start -0.5715 1.7907)
			(end -1.5494 1.7907)
			(stroke
				(width 0.3302)
				(type default)
			)
			(layer "F.SilkS")
		)
		(fp_line
			(start -1.5494 1.7907)
			(end -1.5494 0.8255)
			(stroke
				(width 0.3302)
				(type default)
			)
			(layer "F.SilkS")
		)
		(fp_poly
			(pts
				(xy -0.6604 1.7272) (xy -1.016 2.0828) (xy -0.3048 2.0828)
			)
			(stroke
				(width 0)
				(type default)
			)
			(fill yes)
			(layer "F.SilkS")
		)
		(fp_poly
			(pts
				(xy -1.524 -1.778) (xy 1.524 -1.778) (xy 1.524 1.778) (xy -1.524 1.778)
			)
			(stroke
				(width 0)
				(type default)
			)
			(fill no)
			(layer "F.CrtYd")
		)
		(fp_poly
			(pts
				(xy -1.524 -1.778) (xy 1.524 -1.778) (xy 1.524 1.778) (xy -1.524 1.778)
			)
			(stroke
				(width 0)
				(type default)
			)
			(fill no)
			(layer "F.Fab")
		)
		(pad "1" smd rect
			(at -0.65024 0.9398 90)
			(size 0.4064 1.016)
			(layers "F.Cu" "F.Mask" "F.Paste")
			(net "P3V3_STBY")
		)
		(pad "2" smd rect
			(at 0 0.9398 90)
			(size 0.4064 1.016)
			(layers "F.Cu" "F.Mask" "F.Paste")
			(net "GND")
		)
		(pad "3" smd rect
			(at 0.65024 0.9398 90)
			(size 0.4064 1.016)
			(layers "F.Cu" "F.Mask" "F.Paste")
			(net "JTAG_IOC_TDO_L")
		)
		(pad "4" smd rect
			(at 0.65024 -0.9398 90)
			(size 0.4064 1.016)
			(layers "F.Cu" "F.Mask" "F.Paste")
			(net "JTAG_IOC_TDO")
		)
		(pad "5" smd rect
			(at 0 -0.9398 90)
			(size 0.4064 1.016)
			(layers "F.Cu" "F.Mask" "F.Paste")
			(net "GND")
		)
		(pad "6" smd rect
			(at -0.65024 -0.9398 90)
			(size 0.4064 1.016)
			(layers "F.Cu" "F.Mask" "F.Paste")
			(net "P1V8_STBY")
		)
	)
	(footprint ""
		(layer "F.Cu")
		(at 208.407 -101.092 -90)
		(property "Reference" "PC142"
			(at 0 0 270)
			(layer "F.SilkS")
			(hide yes)
			(effects
				(font
					(size 1.27 1.27)
				)
			)
		)
		(property "Value" "SC10U6D3V5KX-1GP"
			(at -0.0762 -6.1214 270)
			(unlocked yes)
			(layer "F.Fab")
			(hide yes)
			(effects
				(font
					(size 1.016 1.016)
					(thickness 0.1524)
				)
			)
		)
		(property "Device Type" "C805H54"
			(at -0.0762 -8.1534 270)
			(unlocked yes)
			(layer "F.Fab")
			(hide yes)
			(effects
				(font
					(size 1.016 1.016)
					(thickness 0.1524)
				)
			)
		)
		(duplicate_pad_numbers_are_jumpers no)
		(fp_line
			(start 0.635 0)
			(end -0.635 0)
			(stroke
				(width 0.508)
				(type default)
			)
			(layer "F.SilkS")
		)
		(fp_rect
			(start -0.9652 1.778)
			(end 0.9652 -1.778)
			(stroke
				(width 0)
				(type default)
			)
			(fill no)
			(layer "F.CrtYd")
		)
		(fp_poly
			(pts
				(xy -0.9652 -1.778) (xy 0.9652 -1.778) (xy 0.9652 1.778) (xy -0.9652 1.778)
			)
			(stroke
				(width 0)
				(type default)
			)
			(fill no)
			(layer "F.Fab")
		)
		(pad "1" smd rect
			(at 0 -0.9652 270)
			(size 1.397 1.143)
			(layers "F.Cu" "F.Mask" "F.Paste")
			(net "P1V5_C")
		)
		(pad "2" smd rect
			(at 0 0.9652 270)
			(size 1.397 1.143)
			(layers "F.Cu" "F.Mask" "F.Paste")
			(net "GND")
		)
	)
	(footprint ""
		(layer "F.Cu")
		(at 318.008 -174.752 -90)
		(property "Reference" "R582"
			(at 0 0 270)
			(layer "F.SilkS")
			(hide yes)
			(effects
				(font
					(size 1.27 1.27)
				)
			)
		)
		(property "Value" "0R2J-2-GP"
			(at 0.064008 -3.993896 270)
			(unlocked yes)
			(layer "F.Fab")
			(hide yes)
			(effects
				(font
					(size 1.016 1.016)
					(thickness 0.1524)
				)
			)
		)
		(property "Device Type" "R402H16"
			(at 0.064008 -5.517896 270)
			(unlocked yes)
			(layer "F.Fab")
			(hide yes)
			(effects
				(font
					(size 1.016 1.016)
					(thickness 0.1524)
				)
			)
		)
		(duplicate_pad_numbers_are_jumpers no)
		(fp_line
			(start -0.508 -0.9398)
			(end -0.508 0.9398)
			(stroke
				(width 0.1524)
				(type default)
			)
			(layer "F.SilkS")
		)
		(fp_line
			(start 0.508 -0.9398)
			(end -0.508 -0.9398)
			(stroke
				(width 0.1524)
				(type default)
			)
			(layer "F.SilkS")
		)
		(fp_rect
			(start -0.508 0.9398)
			(end 0.508 -0.9398)
			(stroke
				(width 0)
				(type default)
			)
			(fill no)
			(layer "F.CrtYd")
		)
		(fp_rect
			(start -0.508 0.9398)
			(end 0.508 -0.9398)
			(stroke
				(width 0)
				(type default)
			)
			(fill no)
			(layer "F.Fab")
		)
		(pad "1" smd custom
			(at 0 -0.4445 270)
			(size 0.1397 0.1397)
			(layers "F.Cu" "F.Mask" "F.Paste")
			(net "BMC_JTAG_L")
			(options
				(clearance outline)
				(anchor circle)
			)
			(primitives
				(gr_poly
					(pts
						(arc
							(start -0.1778 -0.2794)
							(mid -0.249642 -0.249642)
							(end -0.2794 -0.1778)
						)
						(arc
							(start -0.2794 0.1778)
							(mid -0.249642 0.249642)
							(end -0.1778 0.2794)
						)
						(arc
							(start 0.1778 0.2794)
							(mid 0.249642 0.249642)
							(end 0.2794 0.1778)
						)
						(arc
							(start 0.2794 -0.1778)
							(mid 0.249642 -0.249642)
							(end 0.1778 -0.2794)
						)
					)
					(width 0)
					(fill yes)
				)
			)
		)
		(pad "2" smd custom
			(at 0 0.4445 270)
			(size 0.1397 0.1397)
			(layers "F.Cu" "F.Mask" "F.Paste")
			(net "BMC_JTAG_L_R")
			(options
				(clearance outline)
				(anchor circle)
			)
			(primitives
				(gr_poly
					(pts
						(arc
							(start -0.1778 -0.2794)
							(mid -0.249642 -0.249642)
							(end -0.2794 -0.1778)
						)
						(arc
							(start -0.2794 0.1778)
							(mid -0.249642 0.249642)
							(end -0.1778 0.2794)
						)
						(arc
							(start 0.1778 0.2794)
							(mid 0.249642 0.249642)
							(end 0.2794 0.1778)
						)
						(arc
							(start 0.2794 -0.1778)
							(mid 0.249642 -0.249642)
							(end 0.1778 -0.2794)
						)
					)
					(width 0)
					(fill yes)
				)
			)
		)
	)
	(footprint ""
		(layer "F.Cu")
		(at 233.426 -17.907 -90)
		(property "Reference" "R532"
			(at 0 0 270)
			(layer "F.SilkS")
			(hide yes)
			(effects
				(font
					(size 1.27 1.27)
				)
			)
		)
		(property "Value" "1KR2F-3-GP"
			(at 0.064008 -3.993896 270)
			(unlocked yes)
			(layer "F.Fab")
			(hide yes)
			(effects
				(font
					(size 1.016 1.016)
					(thickness 0.1524)
				)
			)
		)
		(property "Device Type" "R402H16"
			(at 0.064008 -5.517896 270)
			(unlocked yes)
			(layer "F.Fab")
			(hide yes)
			(effects
				(font
					(size 1.016 1.016)
					(thickness 0.1524)
				)
			)
		)
		(duplicate_pad_numbers_are_jumpers no)
		(fp_line
			(start -0.508 -0.9398)
			(end -0.508 0.9398)
			(stroke
				(width 0.1524)
				(type default)
			)
			(layer "F.SilkS")
		)
		(fp_line
			(start 0.508 -0.9398)
			(end -0.508 -0.9398)
			(stroke
				(width 0.1524)
				(type default)
			)
			(layer "F.SilkS")
		)
		(fp_rect
			(start -0.508 0.9398)
			(end 0.508 -0.9398)
			(stroke
				(width 0)
				(type default)
			)
			(fill no)
			(layer "F.CrtYd")
		)
		(fp_rect
			(start -0.508 0.9398)
			(end 0.508 -0.9398)
			(stroke
				(width 0)
				(type default)
			)
			(fill no)
			(layer "F.Fab")
		)
		(pad "1" smd custom
			(at 0 -0.4445 270)
			(size 0.1397 0.1397)
			(layers "F.Cu" "F.Mask" "F.Paste")
			(net "ENCLO_LED_BLUE_OUT")
			(options
				(clearance outline)
				(anchor circle)
			)
			(primitives
				(gr_poly
					(pts
						(arc
							(start -0.1778 -0.2794)
							(mid -0.249642 -0.249642)
							(end -0.2794 -0.1778)
						)
						(arc
							(start -0.2794 0.1778)
							(mid -0.249642 0.249642)
							(end -0.1778 0.2794)
						)
						(arc
							(start 0.1778 0.2794)
							(mid 0.249642 0.249642)
							(end 0.2794 0.1778)
						)
						(arc
							(start 0.2794 -0.1778)
							(mid 0.249642 -0.249642)
							(end 0.1778 -0.2794)
						)
					)
					(width 0)
					(fill yes)
				)
			)
		)
		(pad "2" smd custom
			(at 0 0.4445 270)
			(size 0.1397 0.1397)
			(layers "F.Cu" "F.Mask" "F.Paste")
			(net "ENCLO_LED_RED_G")
			(options
				(clearance outline)
				(anchor circle)
			)
			(primitives
				(gr_poly
					(pts
						(arc
							(start -0.1778 -0.2794)
							(mid -0.249642 -0.249642)
							(end -0.2794 -0.1778)
						)
						(arc
							(start -0.2794 0.1778)
							(mid -0.249642 0.249642)
							(end -0.1778 0.2794)
						)
						(arc
							(start 0.1778 0.2794)
							(mid 0.249642 0.249642)
							(end 0.2794 0.1778)
						)
						(arc
							(start 0.2794 -0.1778)
							(mid 0.249642 -0.249642)
							(end 0.1778 -0.2794)
						)
					)
					(width 0)
					(fill yes)
				)
			)
		)
	)
	(footprint ""
		(layer "F.Cu")
		(at 303.911 -192.913 180)
		(property "Reference" "C85"
			(at 0 0 180)
			(layer "F.SilkS")
			(hide yes)
			(effects
				(font
					(size 1.27 1.27)
				)
			)
		)
		(property "Value" "SCD1U16V2KX-3GP"
			(at 1.1811 -2.7051 180)
			(unlocked yes)
			(layer "F.Fab")
			(hide yes)
			(effects
				(font
					(size 1.016 1.016)
					(thickness 0.1524)
				)
			)
		)
		(property "Device Type" "C402H22"
			(at 1.1811 -4.2291 180)
			(unlocked yes)
			(layer "F.Fab")
			(hide yes)
			(effects
				(font
					(size 1.016 1.016)
					(thickness 0.1524)
				)
			)
		)
		(duplicate_pad_numbers_are_jumpers no)
		(fp_rect
			(start -0.4318 0.9525)
			(end 0.4318 -0.9525)
			(stroke
				(width 0)
				(type default)
			)
			(fill no)
			(layer "F.CrtYd")
		)
		(fp_rect
			(start -0.4318 0.9525)
			(end 0.4318 -0.9525)
			(stroke
				(width 0)
				(type default)
			)
			(fill no)
			(layer "F.Fab")
		)
		(pad "1" smd custom
			(at 0 -0.4445 180)
			(size 0.1524 0.1524)
			(layers "F.Cu" "F.Mask" "F.Paste")
			(net "P3V3_STBY")
			(options
				(clearance outline)
				(anchor circle)
			)
			(primitives
				(gr_poly
					(pts
						(arc
							(start 0.3048 -0.2032)
							(mid 0.275042 -0.275042)
							(end 0.2032 -0.3048)
						)
						(arc
							(start -0.2032 -0.3048)
							(mid -0.275042 -0.275042)
							(end -0.3048 -0.2032)
						)
						(arc
							(start -0.3048 0.2032)
							(mid -0.275042 0.275042)
							(end -0.2032 0.3048)
						)
						(arc
							(start 0.2032 0.3048)
							(mid 0.275042 0.275042)
							(end 0.3048 0.2032)
						)
					)
					(width 0)
					(fill yes)
				)
			)
		)
		(pad "2" smd custom
			(at 0 0.4445 180)
			(size 0.1524 0.1524)
			(layers "F.Cu" "F.Mask" "F.Paste")
			(net "GND")
			(options
				(clearance outline)
				(anchor circle)
			)
			(primitives
				(gr_poly
					(pts
						(arc
							(start 0.3048 -0.2032)
							(mid 0.275042 -0.275042)
							(end 0.2032 -0.3048)
						)
						(arc
							(start -0.2032 -0.3048)
							(mid -0.275042 -0.275042)
							(end -0.3048 -0.2032)
						)
						(arc
							(start -0.3048 0.2032)
							(mid -0.275042 0.275042)
							(end -0.2032 0.3048)
						)
						(arc
							(start 0.2032 0.3048)
							(mid 0.275042 0.275042)
							(end 0.3048 0.2032)
						)
					)
					(width 0)
					(fill yes)
				)
			)
		)
	)
	(footprint ""
		(layer "F.Cu")
		(at 300.482 -61.976 -90)
		(property "Reference" "R207"
			(at 0 0 270)
			(layer "F.SilkS")
			(hide yes)
			(effects
				(font
					(size 1.27 1.27)
				)
			)
		)
		(property "Value" "0R2J-2-GP"
			(at 0.064008 -3.993896 270)
			(unlocked yes)
			(layer "F.Fab")
			(hide yes)
			(effects
				(font
					(size 1.016 1.016)
					(thickness 0.1524)
				)
			)
		)
		(property "Device Type" "R402H16"
			(at 0.064008 -5.517896 270)
			(unlocked yes)
			(layer "F.Fab")
			(hide yes)
			(effects
				(font
					(size 1.016 1.016)
					(thickness 0.1524)
				)
			)
		)
		(duplicate_pad_numbers_are_jumpers no)
		(fp_line
			(start -0.508 -0.9398)
			(end -0.508 0.9398)
			(stroke
				(width 0.1524)
				(type default)
			)
			(layer "F.SilkS")
		)
		(fp_line
			(start 0.508 -0.9398)
			(end -0.508 -0.9398)
			(stroke
				(width 0.1524)
				(type default)
			)
			(layer "F.SilkS")
		)
		(fp_rect
			(start -0.508 0.9398)
			(end 0.508 -0.9398)
			(stroke
				(width 0)
				(type default)
			)
			(fill no)
			(layer "F.CrtYd")
		)
		(fp_rect
			(start -0.508 0.9398)
			(end 0.508 -0.9398)
			(stroke
				(width 0)
				(type default)
			)
			(fill no)
			(layer "F.Fab")
		)
		(pad "1" smd custom
			(at 0 -0.4445 270)
			(size 0.1397 0.1397)
			(layers "F.Cu" "F.Mask" "F.Paste")
			(net "PMU_WAKE_N_R")
			(options
				(clearance outline)
				(anchor circle)
			)
			(primitives
				(gr_poly
					(pts
						(arc
							(start -0.1778 -0.2794)
							(mid -0.249642 -0.249642)
							(end -0.2794 -0.1778)
						)
						(arc
							(start -0.2794 0.1778)
							(mid -0.249642 0.249642)
							(end -0.1778 0.2794)
						)
						(arc
							(start 0.1778 0.2794)
							(mid 0.249642 0.249642)
							(end 0.2794 0.1778)
						)
						(arc
							(start 0.2794 -0.1778)
							(mid 0.249642 -0.249642)
							(end 0.1778 -0.2794)
						)
					)
					(width 0)
					(fill yes)
				)
			)
		)
		(pad "2" smd custom
			(at 0 0.4445 270)
			(size 0.1397 0.1397)
			(layers "F.Cu" "F.Mask" "F.Paste")
			(net "PMU_WAKE_N")
			(options
				(clearance outline)
				(anchor circle)
			)
			(primitives
				(gr_poly
					(pts
						(arc
							(start -0.1778 -0.2794)
							(mid -0.249642 -0.249642)
							(end -0.2794 -0.1778)
						)
						(arc
							(start -0.2794 0.1778)
							(mid -0.249642 0.249642)
							(end -0.1778 0.2794)
						)
						(arc
							(start 0.1778 0.2794)
							(mid 0.249642 0.249642)
							(end 0.2794 0.1778)
						)
						(arc
							(start 0.2794 -0.1778)
							(mid 0.249642 -0.249642)
							(end 0.1778 -0.2794)
						)
					)
					(width 0)
					(fill yes)
				)
			)
		)
	)
	(footprint ""
		(layer "F.Cu")
		(at 166.878 -101.473 180)
		(property "Reference" "PC183"
			(at 0 0 180)
			(layer "F.SilkS")
			(hide yes)
			(effects
				(font
					(size 1.27 1.27)
				)
			)
		)
		(property "Value" "SC47U6D3V5MX-1-GP"
			(at -0.0762 -6.1214 180)
			(unlocked yes)
			(layer "F.Fab")
			(hide yes)
			(effects
				(font
					(size 1.016 1.016)
					(thickness 0.1524)
				)
			)
		)
		(property "Device Type" "C805H54"
			(at -0.0762 -8.1534 180)
			(unlocked yes)
			(layer "F.Fab")
			(hide yes)
			(effects
				(font
					(size 1.016 1.016)
					(thickness 0.1524)
				)
			)
		)
		(duplicate_pad_numbers_are_jumpers no)
		(fp_line
			(start 0.635 0)
			(end -0.635 0)
			(stroke
				(width 0.508)
				(type default)
			)
			(layer "F.SilkS")
		)
		(fp_rect
			(start -0.9652 1.778)
			(end 0.9652 -1.778)
			(stroke
				(width 0)
				(type default)
			)
			(fill no)
			(layer "F.CrtYd")
		)
		(fp_poly
			(pts
				(xy -0.9652 -1.778) (xy 0.9652 -1.778) (xy 0.9652 1.778) (xy -0.9652 1.778)
			)
			(stroke
				(width 0)
				(type default)
			)
			(fill no)
			(layer "F.Fab")
		)
		(pad "1" smd rect
			(at 0 -0.9652 180)
			(size 1.397 1.143)
			(layers "F.Cu" "F.Mask" "F.Paste")
			(net "P0V9_E")
		)
		(pad "2" smd rect
			(at 0 0.9652 180)
			(size 1.397 1.143)
			(layers "F.Cu" "F.Mask" "F.Paste")
			(net "GND")
		)
	)
	(footprint ""
		(layer "F.Cu")
		(at 26.366216 -193.34988)
		(property "Reference" "R651"
			(at 0 0 0)
			(layer "F.SilkS")
			(hide yes)
			(effects
				(font
					(size 1.27 1.27)
				)
			)
		)
		(property "Value" "4K7R2F-GP"
			(at 0.064008 -3.993896 0)
			(unlocked yes)
			(layer "F.Fab")
			(hide yes)
			(effects
				(font
					(size 1.016 1.016)
					(thickness 0.1524)
				)
			)
		)
		(property "Device Type" "R402H16"
			(at 0.064008 -5.517896 0)
			(unlocked yes)
			(layer "F.Fab")
			(hide yes)
			(effects
				(font
					(size 1.016 1.016)
					(thickness 0.1524)
				)
			)
		)
		(duplicate_pad_numbers_are_jumpers no)
		(fp_line
			(start -0.508 -0.9398)
			(end -0.508 0.9398)
			(stroke
				(width 0.1524)
				(type default)
			)
			(layer "F.SilkS")
		)
		(fp_line
			(start 0.508 -0.9398)
			(end -0.508 -0.9398)
			(stroke
				(width 0.1524)
				(type default)
			)
			(layer "F.SilkS")
		)
		(fp_rect
			(start -0.508 0.9398)
			(end 0.508 -0.9398)
			(stroke
				(width 0)
				(type default)
			)
			(fill no)
			(layer "F.CrtYd")
		)
		(fp_rect
			(start -0.508 0.9398)
			(end 0.508 -0.9398)
			(stroke
				(width 0)
				(type default)
			)
			(fill no)
			(layer "F.Fab")
		)
		(pad "1" smd custom
			(at 0 -0.4445)
			(size 0.1397 0.1397)
			(layers "F.Cu" "F.Mask" "F.Paste")
			(net "P3V3_STBY")
			(options
				(clearance outline)
				(anchor circle)
			)
			(primitives
				(gr_poly
					(pts
						(arc
							(start -0.1778 -0.2794)
							(mid -0.249642 -0.249642)
							(end -0.2794 -0.1778)
						)
						(arc
							(start -0.2794 0.1778)
							(mid -0.249642 0.249642)
							(end -0.1778 0.2794)
						)
						(arc
							(start 0.1778 0.2794)
							(mid 0.249642 0.249642)
							(end 0.2794 0.1778)
						)
						(arc
							(start 0.2794 -0.1778)
							(mid 0.249642 -0.249642)
							(end 0.1778 -0.2794)
						)
					)
					(width 0)
					(fill yes)
				)
			)
		)
		(pad "2" smd custom
			(at 0 0.4445)
			(size 0.1397 0.1397)
			(layers "F.Cu" "F.Mask" "F.Paste")
			(net "IO_EXP_HDD_PRE_A0")
			(options
				(clearance outline)
				(anchor circle)
			)
			(primitives
				(gr_poly
					(pts
						(arc
							(start -0.1778 -0.2794)
							(mid -0.249642 -0.249642)
							(end -0.2794 -0.1778)
						)
						(arc
							(start -0.2794 0.1778)
							(mid -0.249642 0.249642)
							(end -0.1778 0.2794)
						)
						(arc
							(start 0.1778 0.2794)
							(mid 0.249642 0.249642)
							(end 0.2794 0.1778)
						)
						(arc
							(start 0.2794 -0.1778)
							(mid 0.249642 -0.249642)
							(end 0.1778 -0.2794)
						)
					)
					(width 0)
					(fill yes)
				)
			)
		)
	)
	(footprint ""
		(layer "F.Cu")
		(at 339.979 -114.808 -90)
		(property "Reference" "PC11"
			(at 0 0 270)
			(layer "F.SilkS")
			(hide yes)
			(effects
				(font
					(size 1.27 1.27)
				)
			)
		)
		(property "Value" "SC3300P50V2KX-1GP"
			(at 1.1811 -2.7051 270)
			(unlocked yes)
			(layer "F.Fab")
			(hide yes)
			(effects
				(font
					(size 1.016 1.016)
					(thickness 0.1524)
				)
			)
		)
		(property "Device Type" "C402H22"
			(at 1.1811 -4.2291 270)
			(unlocked yes)
			(layer "F.Fab")
			(hide yes)
			(effects
				(font
					(size 1.016 1.016)
					(thickness 0.1524)
				)
			)
		)
		(duplicate_pad_numbers_are_jumpers no)
		(fp_rect
			(start -0.4318 0.9525)
			(end 0.4318 -0.9525)
			(stroke
				(width 0)
				(type default)
			)
			(fill no)
			(layer "F.CrtYd")
		)
		(fp_rect
			(start -0.4318 0.9525)
			(end 0.4318 -0.9525)
			(stroke
				(width 0)
				(type default)
			)
			(fill no)
			(layer "F.Fab")
		)
		(pad "1" smd custom
			(at 0 -0.4445 270)
			(size 0.1524 0.1524)
			(layers "F.Cu" "F.Mask" "F.Paste")
			(net "P5V_STBY_SS")
			(options
				(clearance outline)
				(anchor circle)
			)
			(primitives
				(gr_poly
					(pts
						(arc
							(start 0.3048 -0.2032)
							(mid 0.275042 -0.275042)
							(end 0.2032 -0.3048)
						)
						(arc
							(start -0.2032 -0.3048)
							(mid -0.275042 -0.275042)
							(end -0.3048 -0.2032)
						)
						(arc
							(start -0.3048 0.2032)
							(mid -0.275042 0.275042)
							(end -0.2032 0.3048)
						)
						(arc
							(start 0.2032 0.3048)
							(mid 0.275042 0.275042)
							(end 0.3048 0.2032)
						)
					)
					(width 0)
					(fill yes)
				)
			)
		)
		(pad "2" smd custom
			(at 0 0.4445 270)
			(size 0.1524 0.1524)
			(layers "F.Cu" "F.Mask" "F.Paste")
			(net "AGND_P5V_STBY")
			(options
				(clearance outline)
				(anchor circle)
			)
			(primitives
				(gr_poly
					(pts
						(arc
							(start 0.3048 -0.2032)
							(mid 0.275042 -0.275042)
							(end 0.2032 -0.3048)
						)
						(arc
							(start -0.2032 -0.3048)
							(mid -0.275042 -0.275042)
							(end -0.3048 -0.2032)
						)
						(arc
							(start -0.3048 0.2032)
							(mid -0.275042 0.275042)
							(end -0.2032 0.3048)
						)
						(arc
							(start 0.2032 0.3048)
							(mid 0.275042 0.275042)
							(end 0.3048 0.2032)
						)
					)
					(width 0)
					(fill yes)
				)
			)
		)
	)
	(footprint ""
		(layer "F.Cu")
		(at 333.912718 -153.393648 -90)
		(property "Reference" "C155"
			(at 0 0 270)
			(layer "F.SilkS")
			(hide yes)
			(effects
				(font
					(size 1.27 1.27)
				)
			)
		)
		(property "Value" "SC1U10V2KX-4-GP"
			(at 1.1811 -2.7051 270)
			(unlocked yes)
			(layer "F.Fab")
			(hide yes)
			(effects
				(font
					(size 1.016 1.016)
					(thickness 0.1524)
				)
			)
		)
		(property "Device Type" "C402H22"
			(at 1.1811 -4.2291 270)
			(unlocked yes)
			(layer "F.Fab")
			(hide yes)
			(effects
				(font
					(size 1.016 1.016)
					(thickness 0.1524)
				)
			)
		)
		(duplicate_pad_numbers_are_jumpers no)
		(fp_rect
			(start -0.4318 0.9525)
			(end 0.4318 -0.9525)
			(stroke
				(width 0)
				(type default)
			)
			(fill no)
			(layer "F.CrtYd")
		)
		(fp_rect
			(start -0.4318 0.9525)
			(end 0.4318 -0.9525)
			(stroke
				(width 0)
				(type default)
			)
			(fill no)
			(layer "F.Fab")
		)
		(pad "1" smd custom
			(at 0 -0.4445 270)
			(size 0.1524 0.1524)
			(layers "F.Cu" "F.Mask" "F.Paste")
			(net "P3V3_STBY")
			(options
				(clearance outline)
				(anchor circle)
			)
			(primitives
				(gr_poly
					(pts
						(arc
							(start 0.3048 -0.2032)
							(mid 0.275042 -0.275042)
							(end 0.2032 -0.3048)
						)
						(arc
							(start -0.2032 -0.3048)
							(mid -0.275042 -0.275042)
							(end -0.3048 -0.2032)
						)
						(arc
							(start -0.3048 0.2032)
							(mid -0.275042 0.275042)
							(end -0.2032 0.3048)
						)
						(arc
							(start 0.2032 0.3048)
							(mid 0.275042 0.275042)
							(end 0.3048 0.2032)
						)
					)
					(width 0)
					(fill yes)
				)
			)
		)
		(pad "2" smd custom
			(at 0 0.4445 270)
			(size 0.1524 0.1524)
			(layers "F.Cu" "F.Mask" "F.Paste")
			(net "GND")
			(options
				(clearance outline)
				(anchor circle)
			)
			(primitives
				(gr_poly
					(pts
						(arc
							(start 0.3048 -0.2032)
							(mid 0.275042 -0.275042)
							(end 0.2032 -0.3048)
						)
						(arc
							(start -0.2032 -0.3048)
							(mid -0.275042 -0.275042)
							(end -0.3048 -0.2032)
						)
						(arc
							(start -0.3048 0.2032)
							(mid -0.275042 0.275042)
							(end -0.2032 0.3048)
						)
						(arc
							(start 0.2032 0.3048)
							(mid 0.275042 0.275042)
							(end 0.3048 0.2032)
						)
					)
					(width 0)
					(fill yes)
				)
			)
		)
	)
	(footprint ""
		(layer "F.Cu")
		(at 176.03597 -66.421)
		(property "Reference" "TP149"
			(at 0 0 0)
			(layer "F.SilkS")
			(hide yes)
			(effects
				(font
					(size 1.27 1.27)
				)
			)
		)
		(property "Value" "TPAD28"
			(at 0.0127 -1.8034 0)
			(unlocked yes)
			(layer "F.Fab")
			(hide yes)
			(effects
				(font
					(size 1.016 1.016)
					(thickness 0.1524)
				)
			)
		)
		(property "Device Type" "TPAD28"
			(at 0.0127 -3.3274 0)
			(unlocked yes)
			(layer "F.Fab")
			(hide yes)
			(effects
				(font
					(size 1.016 1.016)
					(thickness 0.1524)
				)
			)
		)
		(duplicate_pad_numbers_are_jumpers no)
		(fp_poly
			(pts
				(arc
					(start 0.3556 0)
					(mid -0.3556 0)
					(end 0.3556 0)
				)
			)
			(stroke
				(width 0)
				(type default)
			)
			(fill no)
			(layer "F.CrtYd")
		)
		(fp_poly
			(pts
				(arc
					(start 0.6096 0)
					(mid -0.6096 0)
					(end 0.6096 0)
				)
			)
			(stroke
				(width 0)
				(type default)
			)
			(fill no)
			(layer "F.Fab")
		)
		(pad "1" smd circle
			(at 0 0)
			(size 0.7112 0.7112)
			(layers "F.Cu" "F.Mask" "F.Paste")
			(net "TP_MSB_A41")
		)
	)
	(footprint ""
		(layer "F.Cu")
		(at 217.12428 -87.98052 180)
		(property "Reference" "SC1098"
			(at 0 0 180)
			(layer "F.SilkS")
			(hide yes)
			(effects
				(font
					(size 1.27 1.27)
				)
			)
		)
		(property "Value" "SCD1U16V2KX-3GP"
			(at 1.1811 -2.7051 180)
			(unlocked yes)
			(layer "F.Fab")
			(hide yes)
			(effects
				(font
					(size 1.016 1.016)
					(thickness 0.1524)
				)
			)
		)
		(property "Device Type" "C402H22"
			(at 1.1811 -4.2291 180)
			(unlocked yes)
			(layer "F.Fab")
			(hide yes)
			(effects
				(font
					(size 1.016 1.016)
					(thickness 0.1524)
				)
			)
		)
		(duplicate_pad_numbers_are_jumpers no)
		(fp_rect
			(start -0.4318 0.9525)
			(end 0.4318 -0.9525)
			(stroke
				(width 0)
				(type default)
			)
			(fill no)
			(layer "F.CrtYd")
		)
		(fp_rect
			(start -0.4318 0.9525)
			(end 0.4318 -0.9525)
			(stroke
				(width 0)
				(type default)
			)
			(fill no)
			(layer "F.Fab")
		)
		(pad "1" smd custom
			(at 0 -0.4445 180)
			(size 0.1524 0.1524)
			(layers "F.Cu" "F.Mask" "F.Paste")
			(net "P1V8_C")
			(options
				(clearance outline)
				(anchor circle)
			)
			(primitives
				(gr_poly
					(pts
						(arc
							(start 0.3048 -0.2032)
							(mid 0.275042 -0.275042)
							(end 0.2032 -0.3048)
						)
						(arc
							(start -0.2032 -0.3048)
							(mid -0.275042 -0.275042)
							(end -0.3048 -0.2032)
						)
						(arc
							(start -0.3048 0.2032)
							(mid -0.275042 0.275042)
							(end -0.2032 0.3048)
						)
						(arc
							(start 0.2032 0.3048)
							(mid 0.275042 0.275042)
							(end 0.3048 0.2032)
						)
					)
					(width 0)
					(fill yes)
				)
			)
		)
		(pad "2" smd custom
			(at 0 0.4445 180)
			(size 0.1524 0.1524)
			(layers "F.Cu" "F.Mask" "F.Paste")
			(net "GND")
			(options
				(clearance outline)
				(anchor circle)
			)
			(primitives
				(gr_poly
					(pts
						(arc
							(start 0.3048 -0.2032)
							(mid 0.275042 -0.275042)
							(end 0.2032 -0.3048)
						)
						(arc
							(start -0.2032 -0.3048)
							(mid -0.275042 -0.275042)
							(end -0.3048 -0.2032)
						)
						(arc
							(start -0.3048 0.2032)
							(mid -0.275042 0.275042)
							(end -0.2032 0.3048)
						)
						(arc
							(start 0.2032 0.3048)
							(mid 0.275042 0.275042)
							(end 0.3048 0.2032)
						)
					)
					(width 0)
					(fill yes)
				)
			)
		)
	)
	(footprint ""
		(layer "F.Cu")
		(at 78.73619 -56.228488 -90)
		(property "Reference" "SC929"
			(at 0 0 270)
			(layer "F.SilkS")
			(hide yes)
			(effects
				(font
					(size 1.27 1.27)
				)
			)
		)
		(property "Value" "SC1U6D3V1MX-GP"
			(at 1.9177 2.0193 270)
			(unlocked yes)
			(layer "F.Fab")
			(hide yes)
			(effects
				(font
					(size 1.016 1.016)
					(thickness 0.1524)
				)
			)
		)
		(property "Device Type" "C0201H14"
			(at 1.9177 0.4953 270)
			(unlocked yes)
			(layer "F.Fab")
			(hide yes)
			(effects
				(font
					(size 1.016 1.016)
					(thickness 0.1524)
				)
			)
		)
		(duplicate_pad_numbers_are_jumpers no)
		(fp_rect
			(start -0.1524 0.3048)
			(end 0.1524 -0.3048)
			(stroke
				(width 0)
				(type default)
			)
			(fill no)
			(layer "F.CrtYd")
		)
		(fp_poly
			(pts
				(xy -0.2794 0.6477) (xy -0.2794 -0.6477) (xy 0.2794 -0.6477) (xy 0.2794 -0.1905) (xy 0.1524 -0.1905)
				(xy 0.1524 -0.3048) (xy -0.1524 -0.3048) (xy -0.1524 0.3048) (xy 0.1524 0.3048) (xy 0.1524 -0.1778)
				(xy 0.2794 -0.1778) (xy 0.2794 0.6477)
			)
			(stroke
				(width 0)
				(type default)
			)
			(fill no)
			(layer "F.CrtYd")
		)
		(fp_rect
			(start -0.2794 0.6477)
			(end 0.2794 -0.6477)
			(stroke
				(width 0)
				(type default)
			)
			(fill no)
			(layer "F.Fab")
		)
		(pad "1" smd custom
			(at 0 -0.2794 270)
			(size 0.0762 0.0762)
			(layers "F.Cu" "F.Mask" "F.Paste")
			(net "SHELL_PLL_VDD")
			(options
				(clearance outline)
				(anchor circle)
			)
			(primitives
				(gr_poly
					(pts
						(arc
							(start 0.1524 -0.127)
							(mid 0.137521 -0.162921)
							(end 0.1016 -0.1778)
						)
						(arc
							(start -0.1016 -0.1778)
							(mid -0.137521 -0.162921)
							(end -0.1524 -0.127)
						)
						(arc
							(start -0.1524 0.127)
							(mid -0.137521 0.162921)
							(end -0.1016 0.1778)
						)
						(arc
							(start 0.1016 0.1778)
							(mid 0.137521 0.162921)
							(end 0.1524 0.127)
						)
					)
					(width 0)
					(fill yes)
				)
			)
		)
		(pad "2" smd custom
			(at 0 0.2794 270)
			(size 0.0762 0.0762)
			(layers "F.Cu" "F.Mask" "F.Paste")
			(net "GND")
			(options
				(clearance outline)
				(anchor circle)
			)
			(primitives
				(gr_poly
					(pts
						(arc
							(start 0.1524 -0.127)
							(mid 0.137521 -0.162921)
							(end 0.1016 -0.1778)
						)
						(arc
							(start -0.1016 -0.1778)
							(mid -0.137521 -0.162921)
							(end -0.1524 -0.127)
						)
						(arc
							(start -0.1524 0.127)
							(mid -0.137521 0.162921)
							(end -0.1016 0.1778)
						)
						(arc
							(start 0.1016 0.1778)
							(mid 0.137521 0.162921)
							(end 0.1524 0.127)
						)
					)
					(width 0)
					(fill yes)
				)
			)
		)
	)
	(footprint ""
		(layer "F.Cu")
		(at 89.643966 -63.119)
		(property "Reference" "SR678"
			(at 0 0 0)
			(layer "F.SilkS")
			(hide yes)
			(effects
				(font
					(size 1.27 1.27)
				)
			)
		)
		(property "Value" "4K7R2F-GP"
			(at 0.064008 -3.993896 0)
			(unlocked yes)
			(layer "F.Fab")
			(hide yes)
			(effects
				(font
					(size 1.016 1.016)
					(thickness 0.1524)
				)
			)
		)
		(property "Device Type" "R402H16"
			(at 0.064008 -5.517896 0)
			(unlocked yes)
			(layer "F.Fab")
			(hide yes)
			(effects
				(font
					(size 1.016 1.016)
					(thickness 0.1524)
				)
			)
		)
		(duplicate_pad_numbers_are_jumpers no)
		(fp_line
			(start -0.508 -0.9398)
			(end -0.508 0.9398)
			(stroke
				(width 0.1524)
				(type default)
			)
			(layer "F.SilkS")
		)
		(fp_line
			(start 0.508 -0.9398)
			(end -0.508 -0.9398)
			(stroke
				(width 0.1524)
				(type default)
			)
			(layer "F.SilkS")
		)
		(fp_rect
			(start -0.508 0.9398)
			(end 0.508 -0.9398)
			(stroke
				(width 0)
				(type default)
			)
			(fill no)
			(layer "F.CrtYd")
		)
		(fp_rect
			(start -0.508 0.9398)
			(end 0.508 -0.9398)
			(stroke
				(width 0)
				(type default)
			)
			(fill no)
			(layer "F.Fab")
		)
		(pad "1" smd custom
			(at 0 -0.4445)
			(size 0.1397 0.1397)
			(layers "F.Cu" "F.Mask" "F.Paste")
			(net "P1V8_C")
			(options
				(clearance outline)
				(anchor circle)
			)
			(primitives
				(gr_poly
					(pts
						(arc
							(start -0.1778 -0.2794)
							(mid -0.249642 -0.249642)
							(end -0.2794 -0.1778)
						)
						(arc
							(start -0.2794 0.1778)
							(mid -0.249642 0.249642)
							(end -0.1778 0.2794)
						)
						(arc
							(start 0.1778 0.2794)
							(mid 0.249642 0.249642)
							(end 0.2794 0.1778)
						)
						(arc
							(start 0.2794 -0.1778)
							(mid 0.249642 -0.249642)
							(end 0.1778 -0.2794)
						)
					)
					(width 0)
					(fill yes)
				)
			)
		)
		(pad "2" smd custom
			(at 0 0.4445)
			(size 0.1397 0.1397)
			(layers "F.Cu" "F.Mask" "F.Paste")
			(net "ICE0_TMS")
			(options
				(clearance outline)
				(anchor circle)
			)
			(primitives
				(gr_poly
					(pts
						(arc
							(start -0.1778 -0.2794)
							(mid -0.249642 -0.249642)
							(end -0.2794 -0.1778)
						)
						(arc
							(start -0.2794 0.1778)
							(mid -0.249642 0.249642)
							(end -0.1778 0.2794)
						)
						(arc
							(start 0.1778 0.2794)
							(mid 0.249642 0.249642)
							(end 0.2794 0.1778)
						)
						(arc
							(start 0.2794 -0.1778)
							(mid 0.249642 -0.249642)
							(end 0.1778 -0.2794)
						)
					)
					(width 0)
					(fill yes)
				)
			)
		)
	)
	(footprint ""
		(layer "F.Cu")
		(at 301.752 -161.163)
		(property "Reference" "TP92"
			(at 0 0 0)
			(layer "F.SilkS")
			(hide yes)
			(effects
				(font
					(size 1.27 1.27)
				)
			)
		)
		(property "Value" "TPAD28"
			(at 0.0127 -1.8034 0)
			(unlocked yes)
			(layer "F.Fab")
			(hide yes)
			(effects
				(font
					(size 1.016 1.016)
					(thickness 0.1524)
				)
			)
		)
		(property "Device Type" "TPAD28"
			(at 0.0127 -3.3274 0)
			(unlocked yes)
			(layer "F.Fab")
			(hide yes)
			(effects
				(font
					(size 1.016 1.016)
					(thickness 0.1524)
				)
			)
		)
		(duplicate_pad_numbers_are_jumpers no)
		(fp_poly
			(pts
				(arc
					(start 0.3556 0)
					(mid -0.3556 0)
					(end 0.3556 0)
				)
			)
			(stroke
				(width 0)
				(type default)
			)
			(fill no)
			(layer "F.CrtYd")
		)
		(fp_poly
			(pts
				(arc
					(start 0.6096 0)
					(mid -0.6096 0)
					(end 0.6096 0)
				)
			)
			(stroke
				(width 0)
				(type default)
			)
			(fill no)
			(layer "F.Fab")
		)
		(pad "1" smd circle
			(at 0 0)
			(size 0.7112 0.7112)
			(layers "F.Cu" "F.Mask" "F.Paste")
			(net "TP_GPIOH3")
		)
	)
	(footprint ""
		(layer "F.Cu")
		(at 301.117 -162.433)
		(property "Reference" "TP95"
			(at 0 0 0)
			(layer "F.SilkS")
			(hide yes)
			(effects
				(font
					(size 1.27 1.27)
				)
			)
		)
		(property "Value" "TPAD28"
			(at 0.0127 -1.8034 0)
			(unlocked yes)
			(layer "F.Fab")
			(hide yes)
			(effects
				(font
					(size 1.016 1.016)
					(thickness 0.1524)
				)
			)
		)
		(property "Device Type" "TPAD28"
			(at 0.0127 -3.3274 0)
			(unlocked yes)
			(layer "F.Fab")
			(hide yes)
			(effects
				(font
					(size 1.016 1.016)
					(thickness 0.1524)
				)
			)
		)
		(duplicate_pad_numbers_are_jumpers no)
		(fp_poly
			(pts
				(arc
					(start 0.3556 0)
					(mid -0.3556 0)
					(end 0.3556 0)
				)
			)
			(stroke
				(width 0)
				(type default)
			)
			(fill no)
			(layer "F.CrtYd")
		)
		(fp_poly
			(pts
				(arc
					(start 0.6096 0)
					(mid -0.6096 0)
					(end 0.6096 0)
				)
			)
			(stroke
				(width 0)
				(type default)
			)
			(fill no)
			(layer "F.Fab")
		)
		(pad "1" smd circle
			(at 0 0)
			(size 0.7112 0.7112)
			(layers "F.Cu" "F.Mask" "F.Paste")
			(net "TP_GPIOH6")
		)
	)
	(footprint ""
		(layer "F.Cu")
		(at 304.918872 -204.288136 -90)
		(property "Reference" "C142"
			(at 0 0 270)
			(layer "F.SilkS")
			(hide yes)
			(effects
				(font
					(size 1.27 1.27)
				)
			)
		)
		(property "Value" "SCD1U16V2KX-3GP"
			(at 1.1811 -2.7051 270)
			(unlocked yes)
			(layer "F.Fab")
			(hide yes)
			(effects
				(font
					(size 1.016 1.016)
					(thickness 0.1524)
				)
			)
		)
		(property "Device Type" "C402H22"
			(at 1.1811 -4.2291 270)
			(unlocked yes)
			(layer "F.Fab")
			(hide yes)
			(effects
				(font
					(size 1.016 1.016)
					(thickness 0.1524)
				)
			)
		)
		(duplicate_pad_numbers_are_jumpers no)
		(fp_rect
			(start -0.4318 0.9525)
			(end 0.4318 -0.9525)
			(stroke
				(width 0)
				(type default)
			)
			(fill no)
			(layer "F.CrtYd")
		)
		(fp_rect
			(start -0.4318 0.9525)
			(end 0.4318 -0.9525)
			(stroke
				(width 0)
				(type default)
			)
			(fill no)
			(layer "F.Fab")
		)
		(pad "1" smd custom
			(at 0 -0.4445 270)
			(size 0.1524 0.1524)
			(layers "F.Cu" "F.Mask" "F.Paste")
			(net "P3V3_STBY")
			(options
				(clearance outline)
				(anchor circle)
			)
			(primitives
				(gr_poly
					(pts
						(arc
							(start 0.3048 -0.2032)
							(mid 0.275042 -0.275042)
							(end 0.2032 -0.3048)
						)
						(arc
							(start -0.2032 -0.3048)
							(mid -0.275042 -0.275042)
							(end -0.3048 -0.2032)
						)
						(arc
							(start -0.3048 0.2032)
							(mid -0.275042 0.275042)
							(end -0.2032 0.3048)
						)
						(arc
							(start 0.2032 0.3048)
							(mid 0.275042 0.275042)
							(end 0.3048 0.2032)
						)
					)
					(width 0)
					(fill yes)
				)
			)
		)
		(pad "2" smd custom
			(at 0 0.4445 270)
			(size 0.1524 0.1524)
			(layers "F.Cu" "F.Mask" "F.Paste")
			(net "GND")
			(options
				(clearance outline)
				(anchor circle)
			)
			(primitives
				(gr_poly
					(pts
						(arc
							(start 0.3048 -0.2032)
							(mid 0.275042 -0.275042)
							(end 0.2032 -0.3048)
						)
						(arc
							(start -0.2032 -0.3048)
							(mid -0.275042 -0.275042)
							(end -0.3048 -0.2032)
						)
						(arc
							(start -0.3048 0.2032)
							(mid -0.275042 0.275042)
							(end -0.2032 0.3048)
						)
						(arc
							(start 0.2032 0.3048)
							(mid 0.275042 0.275042)
							(end 0.3048 0.2032)
						)
					)
					(width 0)
					(fill yes)
				)
			)
		)
	)
	(footprint ""
		(layer "F.Cu")
		(at 279.273 -191.77 180)
		(property "Reference" "C202"
			(at 0 0 180)
			(layer "F.SilkS")
			(hide yes)
			(effects
				(font
					(size 1.27 1.27)
				)
			)
		)
		(property "Value" "SCD1U16V2KX-3GP"
			(at 1.1811 -2.7051 180)
			(unlocked yes)
			(layer "F.Fab")
			(hide yes)
			(effects
				(font
					(size 1.016 1.016)
					(thickness 0.1524)
				)
			)
		)
		(property "Device Type" "C402H22"
			(at 1.1811 -4.2291 180)
			(unlocked yes)
			(layer "F.Fab")
			(hide yes)
			(effects
				(font
					(size 1.016 1.016)
					(thickness 0.1524)
				)
			)
		)
		(duplicate_pad_numbers_are_jumpers no)
		(fp_rect
			(start -0.4318 0.9525)
			(end 0.4318 -0.9525)
			(stroke
				(width 0)
				(type default)
			)
			(fill no)
			(layer "F.CrtYd")
		)
		(fp_rect
			(start -0.4318 0.9525)
			(end 0.4318 -0.9525)
			(stroke
				(width 0)
				(type default)
			)
			(fill no)
			(layer "F.Fab")
		)
		(pad "1" smd custom
			(at 0 -0.4445 180)
			(size 0.1524 0.1524)
			(layers "F.Cu" "F.Mask" "F.Paste")
			(net "V1PLLAV12")
			(options
				(clearance outline)
				(anchor circle)
			)
			(primitives
				(gr_poly
					(pts
						(arc
							(start 0.3048 -0.2032)
							(mid 0.275042 -0.275042)
							(end 0.2032 -0.3048)
						)
						(arc
							(start -0.2032 -0.3048)
							(mid -0.275042 -0.275042)
							(end -0.3048 -0.2032)
						)
						(arc
							(start -0.3048 0.2032)
							(mid -0.275042 0.275042)
							(end -0.2032 0.3048)
						)
						(arc
							(start 0.2032 0.3048)
							(mid 0.275042 0.275042)
							(end 0.3048 0.2032)
						)
					)
					(width 0)
					(fill yes)
				)
			)
		)
		(pad "2" smd custom
			(at 0 0.4445 180)
			(size 0.1524 0.1524)
			(layers "F.Cu" "F.Mask" "F.Paste")
			(net "GND")
			(options
				(clearance outline)
				(anchor circle)
			)
			(primitives
				(gr_poly
					(pts
						(arc
							(start 0.3048 -0.2032)
							(mid 0.275042 -0.275042)
							(end 0.2032 -0.3048)
						)
						(arc
							(start -0.2032 -0.3048)
							(mid -0.275042 -0.275042)
							(end -0.3048 -0.2032)
						)
						(arc
							(start -0.3048 0.2032)
							(mid -0.275042 0.275042)
							(end -0.2032 0.3048)
						)
						(arc
							(start 0.2032 0.3048)
							(mid 0.275042 0.275042)
							(end 0.3048 0.2032)
						)
					)
					(width 0)
					(fill yes)
				)
			)
		)
	)
	(footprint ""
		(layer "F.Cu")
		(at 193.167 -14.097 -90)
		(property "Reference" "R5306"
			(at 0 0 270)
			(layer "F.SilkS")
			(hide yes)
			(effects
				(font
					(size 1.27 1.27)
				)
			)
		)
		(property "Value" "0R2J-2-GP"
			(at 0.064008 -3.993896 270)
			(unlocked yes)
			(layer "F.Fab")
			(hide yes)
			(effects
				(font
					(size 1.016 1.016)
					(thickness 0.1524)
				)
			)
		)
		(property "Device Type" "R402H16"
			(at 0.064008 -5.517896 270)
			(unlocked yes)
			(layer "F.Fab")
			(hide yes)
			(effects
				(font
					(size 1.016 1.016)
					(thickness 0.1524)
				)
			)
		)
		(duplicate_pad_numbers_are_jumpers no)
		(fp_line
			(start -0.508 -0.9398)
			(end -0.508 0.9398)
			(stroke
				(width 0.1524)
				(type default)
			)
			(layer "F.SilkS")
		)
		(fp_line
			(start 0.508 -0.9398)
			(end -0.508 -0.9398)
			(stroke
				(width 0.1524)
				(type default)
			)
			(layer "F.SilkS")
		)
		(fp_rect
			(start -0.508 0.9398)
			(end 0.508 -0.9398)
			(stroke
				(width 0)
				(type default)
			)
			(fill no)
			(layer "F.CrtYd")
		)
		(fp_rect
			(start -0.508 0.9398)
			(end 0.508 -0.9398)
			(stroke
				(width 0)
				(type default)
			)
			(fill no)
			(layer "F.Fab")
		)
		(pad "1" smd custom
			(at 0 -0.4445 270)
			(size 0.1397 0.1397)
			(layers "F.Cu" "F.Mask" "F.Paste")
			(net "BMC_I2C_SDA_10")
			(options
				(clearance outline)
				(anchor circle)
			)
			(primitives
				(gr_poly
					(pts
						(arc
							(start -0.1778 -0.2794)
							(mid -0.249642 -0.249642)
							(end -0.2794 -0.1778)
						)
						(arc
							(start -0.2794 0.1778)
							(mid -0.249642 0.249642)
							(end -0.1778 0.2794)
						)
						(arc
							(start 0.1778 0.2794)
							(mid 0.249642 0.249642)
							(end 0.2794 0.1778)
						)
						(arc
							(start 0.2794 -0.1778)
							(mid 0.249642 -0.249642)
							(end 0.1778 -0.2794)
						)
					)
					(width 0)
					(fill yes)
				)
			)
		)
		(pad "2" smd custom
			(at 0 0.4445 270)
			(size 0.1397 0.1397)
			(layers "F.Cu" "F.Mask" "F.Paste")
			(net "TEMP_1_SDA")
			(options
				(clearance outline)
				(anchor circle)
			)
			(primitives
				(gr_poly
					(pts
						(arc
							(start -0.1778 -0.2794)
							(mid -0.249642 -0.249642)
							(end -0.2794 -0.1778)
						)
						(arc
							(start -0.2794 0.1778)
							(mid -0.249642 0.249642)
							(end -0.1778 0.2794)
						)
						(arc
							(start 0.1778 0.2794)
							(mid 0.249642 0.249642)
							(end 0.2794 0.1778)
						)
						(arc
							(start 0.2794 -0.1778)
							(mid 0.249642 -0.249642)
							(end 0.1778 -0.2794)
						)
					)
					(width 0)
					(fill yes)
				)
			)
		)
	)
	(footprint ""
		(layer "F.Cu")
		(at 80.372966 -89.916 90)
		(property "Reference" "SR838"
			(at 0 0 90)
			(layer "F.SilkS")
			(hide yes)
			(effects
				(font
					(size 1.27 1.27)
				)
			)
		)
		(property "Value" "10R2F-L-GP"
			(at 0.064008 -3.993896 90)
			(unlocked yes)
			(layer "F.Fab")
			(hide yes)
			(effects
				(font
					(size 1.016 1.016)
					(thickness 0.1524)
				)
			)
		)
		(property "Device Type" "R402H14"
			(at 0.064008 -5.517896 90)
			(unlocked yes)
			(layer "F.Fab")
			(hide yes)
			(effects
				(font
					(size 1.016 1.016)
					(thickness 0.1524)
				)
			)
		)
		(duplicate_pad_numbers_are_jumpers no)
		(fp_line
			(start 0.508 -0.9398)
			(end -0.508 -0.9398)
			(stroke
				(width 0.1524)
				(type default)
			)
			(layer "F.SilkS")
		)
		(fp_line
			(start -0.508 -0.9398)
			(end -0.508 0.9398)
			(stroke
				(width 0.1524)
				(type default)
			)
			(layer "F.SilkS")
		)
		(fp_rect
			(start -0.508 0.9398)
			(end 0.508 -0.9398)
			(stroke
				(width 0)
				(type default)
			)
			(fill no)
			(layer "F.CrtYd")
		)
		(fp_rect
			(start -0.508 0.9398)
			(end 0.508 -0.9398)
			(stroke
				(width 0)
				(type default)
			)
			(fill no)
			(layer "F.Fab")
		)
		(pad "1" smd custom
			(at 0 -0.4445 90)
			(size 0.1397 0.1397)
			(layers "F.Cu" "F.Mask" "F.Paste")
			(net "P0V9_E")
			(options
				(clearance outline)
				(anchor circle)
			)
			(primitives
				(gr_poly
					(pts
						(arc
							(start -0.1778 -0.2794)
							(mid -0.249642 -0.249642)
							(end -0.2794 -0.1778)
						)
						(arc
							(start -0.2794 0.1778)
							(mid -0.249642 0.249642)
							(end -0.1778 0.2794)
						)
						(arc
							(start 0.1778 0.2794)
							(mid 0.249642 0.249642)
							(end 0.2794 0.1778)
						)
						(arc
							(start 0.2794 -0.1778)
							(mid 0.249642 -0.249642)
							(end 0.1778 -0.2794)
						)
					)
					(width 0)
					(fill yes)
				)
			)
		)
		(pad "2" smd custom
			(at 0 0.4445 90)
			(size 0.1397 0.1397)
			(layers "F.Cu" "F.Mask" "F.Paste")
			(net "SYSPLL_VDDA09")
			(options
				(clearance outline)
				(anchor circle)
			)
			(primitives
				(gr_poly
					(pts
						(arc
							(start -0.1778 -0.2794)
							(mid -0.249642 -0.249642)
							(end -0.2794 -0.1778)
						)
						(arc
							(start -0.2794 0.1778)
							(mid -0.249642 0.249642)
							(end -0.1778 0.2794)
						)
						(arc
							(start 0.1778 0.2794)
							(mid 0.249642 0.249642)
							(end 0.2794 0.1778)
						)
						(arc
							(start 0.2794 -0.1778)
							(mid 0.249642 -0.249642)
							(end 0.1778 -0.2794)
						)
					)
					(width 0)
					(fill yes)
				)
			)
		)
	)
	(footprint ""
		(layer "F.Cu")
		(at 289.932872 -218.004136 -90)
		(property "Reference" "PR79"
			(at 0 0 270)
			(layer "F.SilkS")
			(hide yes)
			(effects
				(font
					(size 1.27 1.27)
				)
			)
		)
		(property "Value" "4K42R2F-GP"
			(at 0.064008 -3.993896 270)
			(unlocked yes)
			(layer "F.Fab")
			(hide yes)
			(effects
				(font
					(size 1.016 1.016)
					(thickness 0.1524)
				)
			)
		)
		(property "Device Type" "R402H16"
			(at 0.064008 -5.517896 270)
			(unlocked yes)
			(layer "F.Fab")
			(hide yes)
			(effects
				(font
					(size 1.016 1.016)
					(thickness 0.1524)
				)
			)
		)
		(duplicate_pad_numbers_are_jumpers no)
		(fp_line
			(start -0.508 -0.9398)
			(end -0.508 0.9398)
			(stroke
				(width 0.1524)
				(type default)
			)
			(layer "F.SilkS")
		)
		(fp_line
			(start 0.508 -0.9398)
			(end -0.508 -0.9398)
			(stroke
				(width 0.1524)
				(type default)
			)
			(layer "F.SilkS")
		)
		(fp_rect
			(start -0.508 0.9398)
			(end 0.508 -0.9398)
			(stroke
				(width 0)
				(type default)
			)
			(fill no)
			(layer "F.CrtYd")
		)
		(fp_rect
			(start -0.508 0.9398)
			(end 0.508 -0.9398)
			(stroke
				(width 0)
				(type default)
			)
			(fill no)
			(layer "F.Fab")
		)
		(pad "1" smd custom
			(at 0 -0.4445 270)
			(size 0.1397 0.1397)
			(layers "F.Cu" "F.Mask" "F.Paste")
			(net "TPS74801_1V53_STBY_OUT")
			(options
				(clearance outline)
				(anchor circle)
			)
			(primitives
				(gr_poly
					(pts
						(arc
							(start -0.1778 -0.2794)
							(mid -0.249642 -0.249642)
							(end -0.2794 -0.1778)
						)
						(arc
							(start -0.2794 0.1778)
							(mid -0.249642 0.249642)
							(end -0.1778 0.2794)
						)
						(arc
							(start 0.1778 0.2794)
							(mid 0.249642 0.249642)
							(end 0.2794 0.1778)
						)
						(arc
							(start 0.2794 -0.1778)
							(mid 0.249642 -0.249642)
							(end 0.1778 -0.2794)
						)
					)
					(width 0)
					(fill yes)
				)
			)
		)
		(pad "2" smd custom
			(at 0 0.4445 270)
			(size 0.1397 0.1397)
			(layers "F.Cu" "F.Mask" "F.Paste")
			(net "TPS74801_1V53_STBY_FB")
			(options
				(clearance outline)
				(anchor circle)
			)
			(primitives
				(gr_poly
					(pts
						(arc
							(start -0.1778 -0.2794)
							(mid -0.249642 -0.249642)
							(end -0.2794 -0.1778)
						)
						(arc
							(start -0.2794 0.1778)
							(mid -0.249642 0.249642)
							(end -0.1778 0.2794)
						)
						(arc
							(start 0.1778 0.2794)
							(mid 0.249642 0.249642)
							(end 0.2794 0.1778)
						)
						(arc
							(start 0.2794 -0.1778)
							(mid 0.249642 -0.249642)
							(end 0.1778 -0.2794)
						)
					)
					(width 0)
					(fill yes)
				)
			)
		)
	)
	(footprint ""
		(layer "F.Cu")
		(at 191.897 -25.273 -90)
		(property "Reference" "R442"
			(at 0 0 270)
			(layer "F.SilkS")
			(hide yes)
			(effects
				(font
					(size 1.27 1.27)
				)
			)
		)
		(property "Value" "0R2J-2-GP"
			(at 0.064008 -3.993896 270)
			(unlocked yes)
			(layer "F.Fab")
			(hide yes)
			(effects
				(font
					(size 1.016 1.016)
					(thickness 0.1524)
				)
			)
		)
		(property "Device Type" "R402H16"
			(at 0.064008 -5.517896 270)
			(unlocked yes)
			(layer "F.Fab")
			(hide yes)
			(effects
				(font
					(size 1.016 1.016)
					(thickness 0.1524)
				)
			)
		)
		(duplicate_pad_numbers_are_jumpers no)
		(fp_line
			(start -0.508 -0.9398)
			(end -0.508 0.9398)
			(stroke
				(width 0.1524)
				(type default)
			)
			(layer "F.SilkS")
		)
		(fp_line
			(start 0.508 -0.9398)
			(end -0.508 -0.9398)
			(stroke
				(width 0.1524)
				(type default)
			)
			(layer "F.SilkS")
		)
		(fp_rect
			(start -0.508 0.9398)
			(end 0.508 -0.9398)
			(stroke
				(width 0)
				(type default)
			)
			(fill no)
			(layer "F.CrtYd")
		)
		(fp_rect
			(start -0.508 0.9398)
			(end 0.508 -0.9398)
			(stroke
				(width 0)
				(type default)
			)
			(fill no)
			(layer "F.Fab")
		)
		(pad "1" smd custom
			(at 0 -0.4445 270)
			(size 0.1397 0.1397)
			(layers "F.Cu" "F.Mask" "F.Paste")
			(net "GND")
			(options
				(clearance outline)
				(anchor circle)
			)
			(primitives
				(gr_poly
					(pts
						(arc
							(start -0.1778 -0.2794)
							(mid -0.249642 -0.249642)
							(end -0.2794 -0.1778)
						)
						(arc
							(start -0.2794 0.1778)
							(mid -0.249642 0.249642)
							(end -0.1778 0.2794)
						)
						(arc
							(start 0.1778 0.2794)
							(mid 0.249642 0.249642)
							(end 0.2794 0.1778)
						)
						(arc
							(start 0.2794 -0.1778)
							(mid 0.249642 -0.249642)
							(end 0.1778 -0.2794)
						)
					)
					(width 0)
					(fill yes)
				)
			)
		)
		(pad "2" smd custom
			(at 0 0.4445 270)
			(size 0.1397 0.1397)
			(layers "F.Cu" "F.Mask" "F.Paste")
			(net "RMII_PHY_BMC_RXD0")
			(options
				(clearance outline)
				(anchor circle)
			)
			(primitives
				(gr_poly
					(pts
						(arc
							(start -0.1778 -0.2794)
							(mid -0.249642 -0.249642)
							(end -0.2794 -0.1778)
						)
						(arc
							(start -0.2794 0.1778)
							(mid -0.249642 0.249642)
							(end -0.1778 0.2794)
						)
						(arc
							(start 0.1778 0.2794)
							(mid 0.249642 0.249642)
							(end 0.2794 0.1778)
						)
						(arc
							(start 0.2794 -0.1778)
							(mid 0.249642 -0.249642)
							(end 0.1778 -0.2794)
						)
					)
					(width 0)
					(fill yes)
				)
			)
		)
	)
	(footprint ""
		(layer "F.Cu")
		(at 171.598844 -27.399996 -90)
		(property "Reference" "C237"
			(at 0 0 270)
			(layer "F.SilkS")
			(hide yes)
			(effects
				(font
					(size 1.27 1.27)
				)
			)
		)
		(property "Value" "SCD1U16V2KX-3GP"
			(at 1.1811 -2.7051 270)
			(unlocked yes)
			(layer "F.Fab")
			(hide yes)
			(effects
				(font
					(size 1.016 1.016)
					(thickness 0.1524)
				)
			)
		)
		(property "Device Type" "C402H22"
			(at 1.1811 -4.2291 270)
			(unlocked yes)
			(layer "F.Fab")
			(hide yes)
			(effects
				(font
					(size 1.016 1.016)
					(thickness 0.1524)
				)
			)
		)
		(duplicate_pad_numbers_are_jumpers no)
		(fp_rect
			(start -0.4318 0.9525)
			(end 0.4318 -0.9525)
			(stroke
				(width 0)
				(type default)
			)
			(fill no)
			(layer "F.CrtYd")
		)
		(fp_rect
			(start -0.4318 0.9525)
			(end 0.4318 -0.9525)
			(stroke
				(width 0)
				(type default)
			)
			(fill no)
			(layer "F.Fab")
		)
		(pad "1" smd custom
			(at 0 -0.4445 270)
			(size 0.1524 0.1524)
			(layers "F.Cu" "F.Mask" "F.Paste")
			(net "MOD_IMC_FAB_D_COP")
			(options
				(clearance outline)
				(anchor circle)
			)
			(primitives
				(gr_poly
					(pts
						(arc
							(start 0.3048 -0.2032)
							(mid 0.275042 -0.275042)
							(end 0.2032 -0.3048)
						)
						(arc
							(start -0.2032 -0.3048)
							(mid -0.275042 -0.275042)
							(end -0.3048 -0.2032)
						)
						(arc
							(start -0.3048 0.2032)
							(mid -0.275042 0.275042)
							(end -0.2032 0.3048)
						)
						(arc
							(start 0.2032 0.3048)
							(mid 0.275042 0.275042)
							(end 0.3048 0.2032)
						)
					)
					(width 0)
					(fill yes)
				)
			)
		)
		(pad "2" smd custom
			(at 0 0.4445 270)
			(size 0.1524 0.1524)
			(layers "F.Cu" "F.Mask" "F.Paste")
			(net "GND")
			(options
				(clearance outline)
				(anchor circle)
			)
			(primitives
				(gr_poly
					(pts
						(arc
							(start 0.3048 -0.2032)
							(mid 0.275042 -0.275042)
							(end 0.2032 -0.3048)
						)
						(arc
							(start -0.2032 -0.3048)
							(mid -0.275042 -0.275042)
							(end -0.3048 -0.2032)
						)
						(arc
							(start -0.3048 0.2032)
							(mid -0.275042 0.275042)
							(end -0.2032 0.3048)
						)
						(arc
							(start 0.2032 0.3048)
							(mid 0.275042 0.275042)
							(end 0.3048 0.2032)
						)
					)
					(width 0)
					(fill yes)
				)
			)
		)
	)
	(footprint ""
		(layer "F.Cu")
		(at 116.09197 -78.232)
		(property "Reference" "STP109"
			(at 0 0 0)
			(layer "F.SilkS")
			(hide yes)
			(effects
				(font
					(size 1.27 1.27)
				)
			)
		)
		(property "Value" "TPAD28"
			(at 0.0127 -1.8034 0)
			(unlocked yes)
			(layer "F.Fab")
			(hide yes)
			(effects
				(font
					(size 1.016 1.016)
					(thickness 0.1524)
				)
			)
		)
		(property "Device Type" "TPAD28"
			(at 0.0127 -3.3274 0)
			(unlocked yes)
			(layer "F.Fab")
			(hide yes)
			(effects
				(font
					(size 1.016 1.016)
					(thickness 0.1524)
				)
			)
		)
		(duplicate_pad_numbers_are_jumpers no)
		(fp_poly
			(pts
				(arc
					(start 0.3556 0)
					(mid -0.3556 0)
					(end 0.3556 0)
				)
			)
			(stroke
				(width 0)
				(type default)
			)
			(fill no)
			(layer "F.CrtYd")
		)
		(fp_poly
			(pts
				(arc
					(start 0.6096 0)
					(mid -0.6096 0)
					(end 0.6096 0)
				)
			)
			(stroke
				(width 0)
				(type default)
			)
			(fill no)
			(layer "F.Fab")
		)
		(pad "1" smd circle
			(at 0 0)
			(size 0.7112 0.7112)
			(layers "F.Cu" "F.Mask" "F.Paste")
			(net "TEST_MUX_42")
		)
	)
	(footprint ""
		(layer "F.Cu")
		(at 199.644 -216.789 90)
		(property "Reference" "U173"
			(at 0 0 90)
			(layer "F.SilkS")
			(hide yes)
			(effects
				(font
					(size 1.27 1.27)
				)
			)
		)
		(property "Value" "SN74LVC1G08DCKR-GP"
			(at -2.3368 -8.6868 90)
			(unlocked yes)
			(layer "F.Fab")
			(hide yes)
			(effects
				(font
					(size 1.016 1.016)
					(thickness 0.1524)
				)
			)
		)
		(property "Device Type" "SC70-5H44"
			(at -2.3114 -10.414 90)
			(unlocked yes)
			(layer "F.Fab")
			(hide yes)
			(effects
				(font
					(size 1.016 1.016)
					(thickness 0.1524)
				)
			)
		)
		(duplicate_pad_numbers_are_jumpers no)
		(fp_line
			(start 1.3843 -1.8034)
			(end 1.3843 -1.1176)
			(stroke
				(width 0.3302)
				(type default)
			)
			(layer "F.SilkS")
		)
		(fp_line
			(start 0.6604 -1.8034)
			(end 1.3843 -1.8034)
			(stroke
				(width 0.3302)
				(type default)
			)
			(layer "F.SilkS")
		)
		(fp_line
			(start 1.27 -1.7018)
			(end 1.27 1.7018)
			(stroke
				(width 0.1524)
				(type default)
			)
			(layer "F.SilkS")
		)
		(fp_line
			(start -1.27 -1.7018)
			(end 1.27 -1.7018)
			(stroke
				(width 0.1524)
				(type default)
			)
			(layer "F.SilkS")
		)
		(fp_line
			(start 1.27 1.7018)
			(end -1.27 1.7018)
			(stroke
				(width 0.1524)
				(type default)
			)
			(layer "F.SilkS")
		)
		(fp_line
			(start -1.27 1.7018)
			(end -1.27 -1.7018)
			(stroke
				(width 0.1524)
				(type default)
			)
			(layer "F.SilkS")
		)
		(fp_rect
			(start -1.524 1.9558)
			(end 1.524 -1.9558)
			(stroke
				(width 0)
				(type default)
			)
			(fill no)
			(layer "F.CrtYd")
		)
		(fp_poly
			(pts
				(xy -1.524 -1.9558) (xy 1.524 -1.9558) (xy 1.524 1.9558) (xy -1.524 1.9558)
			)
			(stroke
				(width 0)
				(type default)
			)
			(fill no)
			(layer "F.Fab")
		)
		(pad "1" smd rect
			(at 0.65024 -0.8255 90)
			(size 0.4064 1.2192)
			(layers "F.Cu" "F.Mask" "F.Paste")
			(net "RSTBTN_OUT_N")
		)
		(pad "2" smd rect
			(at 0 -0.8255 90)
			(size 0.4064 1.2192)
			(layers "F.Cu" "F.Mask" "F.Paste")
			(net "BMC_RSTBTN_N")
		)
		(pad "3" smd rect
			(at -0.65024 -0.8255 90)
			(size 0.4064 1.2192)
			(layers "F.Cu" "F.Mask" "F.Paste")
			(net "GND")
		)
		(pad "4" smd rect
			(at -0.65024 0.8255 90)
			(size 0.4064 1.2192)
			(layers "F.Cu" "F.Mask" "F.Paste")
			(net "CPU_EXP_RESET_N")
		)
		(pad "5" smd rect
			(at 0.65024 0.8255 90)
			(size 0.4064 1.2192)
			(layers "F.Cu" "F.Mask" "F.Paste")
			(net "P3V3_STBY")
		)
	)
	(footprint ""
		(layer "F.Cu")
		(at 180.721 -147.828 -90)
		(property "Reference" "SR918"
			(at 0 0 270)
			(layer "F.SilkS")
			(hide yes)
			(effects
				(font
					(size 1.27 1.27)
				)
			)
		)
		(property "Value" "4K7R2F-GP"
			(at 0.064008 -3.993896 270)
			(unlocked yes)
			(layer "F.Fab")
			(hide yes)
			(effects
				(font
					(size 1.016 1.016)
					(thickness 0.1524)
				)
			)
		)
		(property "Device Type" "R402H16"
			(at 0.064008 -5.517896 270)
			(unlocked yes)
			(layer "F.Fab")
			(hide yes)
			(effects
				(font
					(size 1.016 1.016)
					(thickness 0.1524)
				)
			)
		)
		(duplicate_pad_numbers_are_jumpers no)
		(fp_line
			(start -0.508 -0.9398)
			(end -0.508 0.9398)
			(stroke
				(width 0.1524)
				(type default)
			)
			(layer "F.SilkS")
		)
		(fp_line
			(start 0.508 -0.9398)
			(end -0.508 -0.9398)
			(stroke
				(width 0.1524)
				(type default)
			)
			(layer "F.SilkS")
		)
		(fp_rect
			(start -0.508 0.9398)
			(end 0.508 -0.9398)
			(stroke
				(width 0)
				(type default)
			)
			(fill no)
			(layer "F.CrtYd")
		)
		(fp_rect
			(start -0.508 0.9398)
			(end 0.508 -0.9398)
			(stroke
				(width 0)
				(type default)
			)
			(fill no)
			(layer "F.Fab")
		)
		(pad "1" smd custom
			(at 0 -0.4445 270)
			(size 0.1397 0.1397)
			(layers "F.Cu" "F.Mask" "F.Paste")
			(net "BMC_I2C_C_SDA")
			(options
				(clearance outline)
				(anchor circle)
			)
			(primitives
				(gr_poly
					(pts
						(arc
							(start -0.1778 -0.2794)
							(mid -0.249642 -0.249642)
							(end -0.2794 -0.1778)
						)
						(arc
							(start -0.2794 0.1778)
							(mid -0.249642 0.249642)
							(end -0.1778 0.2794)
						)
						(arc
							(start 0.1778 0.2794)
							(mid 0.249642 0.249642)
							(end 0.2794 0.1778)
						)
						(arc
							(start 0.2794 -0.1778)
							(mid 0.249642 -0.249642)
							(end 0.1778 -0.2794)
						)
					)
					(width 0)
					(fill yes)
				)
			)
		)
		(pad "2" smd custom
			(at 0 0.4445 270)
			(size 0.1397 0.1397)
			(layers "F.Cu" "F.Mask" "F.Paste")
			(net "P3V3_STBY")
			(options
				(clearance outline)
				(anchor circle)
			)
			(primitives
				(gr_poly
					(pts
						(arc
							(start -0.1778 -0.2794)
							(mid -0.249642 -0.249642)
							(end -0.2794 -0.1778)
						)
						(arc
							(start -0.2794 0.1778)
							(mid -0.249642 0.249642)
							(end -0.1778 0.2794)
						)
						(arc
							(start 0.1778 0.2794)
							(mid 0.249642 0.249642)
							(end 0.2794 0.1778)
						)
						(arc
							(start 0.2794 -0.1778)
							(mid 0.249642 -0.249642)
							(end 0.1778 -0.2794)
						)
					)
					(width 0)
					(fill yes)
				)
			)
		)
	)
	(footprint ""
		(layer "F.Cu")
		(at 277.994872 -220.290136 90)
		(property "Reference" "PR81"
			(at 0 0 90)
			(layer "F.SilkS")
			(hide yes)
			(effects
				(font
					(size 1.27 1.27)
				)
			)
		)
		(property "Value" "0R2J-2-GP"
			(at 0.064008 -3.993896 90)
			(unlocked yes)
			(layer "F.Fab")
			(hide yes)
			(effects
				(font
					(size 1.016 1.016)
					(thickness 0.1524)
				)
			)
		)
		(property "Device Type" "R402H16"
			(at 0.064008 -5.517896 90)
			(unlocked yes)
			(layer "F.Fab")
			(hide yes)
			(effects
				(font
					(size 1.016 1.016)
					(thickness 0.1524)
				)
			)
		)
		(duplicate_pad_numbers_are_jumpers no)
		(fp_line
			(start 0.508 -0.9398)
			(end -0.508 -0.9398)
			(stroke
				(width 0.1524)
				(type default)
			)
			(layer "F.SilkS")
		)
		(fp_line
			(start -0.508 -0.9398)
			(end -0.508 0.9398)
			(stroke
				(width 0.1524)
				(type default)
			)
			(layer "F.SilkS")
		)
		(fp_rect
			(start -0.508 0.9398)
			(end 0.508 -0.9398)
			(stroke
				(width 0)
				(type default)
			)
			(fill no)
			(layer "F.CrtYd")
		)
		(fp_rect
			(start -0.508 0.9398)
			(end 0.508 -0.9398)
			(stroke
				(width 0)
				(type default)
			)
			(fill no)
			(layer "F.Fab")
		)
		(pad "1" smd custom
			(at 0 -0.4445 90)
			(size 0.1397 0.1397)
			(layers "F.Cu" "F.Mask" "F.Paste")
			(net "P3V3_STBY")
			(options
				(clearance outline)
				(anchor circle)
			)
			(primitives
				(gr_poly
					(pts
						(arc
							(start -0.1778 -0.2794)
							(mid -0.249642 -0.249642)
							(end -0.2794 -0.1778)
						)
						(arc
							(start -0.2794 0.1778)
							(mid -0.249642 0.249642)
							(end -0.1778 0.2794)
						)
						(arc
							(start 0.1778 0.2794)
							(mid 0.249642 0.249642)
							(end 0.2794 0.1778)
						)
						(arc
							(start 0.2794 -0.1778)
							(mid 0.249642 -0.249642)
							(end 0.1778 -0.2794)
						)
					)
					(width 0)
					(fill yes)
				)
			)
		)
		(pad "2" smd custom
			(at 0 0.4445 90)
			(size 0.1397 0.1397)
			(layers "F.Cu" "F.Mask" "F.Paste")
			(net "TPS74801_1V53_STBY_BIAS")
			(options
				(clearance outline)
				(anchor circle)
			)
			(primitives
				(gr_poly
					(pts
						(arc
							(start -0.1778 -0.2794)
							(mid -0.249642 -0.249642)
							(end -0.2794 -0.1778)
						)
						(arc
							(start -0.2794 0.1778)
							(mid -0.249642 0.249642)
							(end -0.1778 0.2794)
						)
						(arc
							(start 0.1778 0.2794)
							(mid 0.249642 0.249642)
							(end 0.2794 0.1778)
						)
						(arc
							(start 0.2794 -0.1778)
							(mid 0.249642 -0.249642)
							(end 0.1778 -0.2794)
						)
					)
					(width 0)
					(fill yes)
				)
			)
		)
	)
	(footprint ""
		(layer "F.Cu")
		(at 120.339612 -221.996 180)
		(property "Reference" "SR876"
			(at 0 0 180)
			(layer "F.SilkS")
			(hide yes)
			(effects
				(font
					(size 1.27 1.27)
				)
			)
		)
		(property "Value" "0R2J-2-GP"
			(at 0.064008 -3.993896 180)
			(unlocked yes)
			(layer "F.Fab")
			(hide yes)
			(effects
				(font
					(size 1.016 1.016)
					(thickness 0.1524)
				)
			)
		)
		(property "Device Type" "R402H16"
			(at 0.064008 -5.517896 180)
			(unlocked yes)
			(layer "F.Fab")
			(hide yes)
			(effects
				(font
					(size 1.016 1.016)
					(thickness 0.1524)
				)
			)
		)
		(duplicate_pad_numbers_are_jumpers no)
		(fp_line
			(start 0.508 -0.9398)
			(end -0.508 -0.9398)
			(stroke
				(width 0.1524)
				(type default)
			)
			(layer "F.SilkS")
		)
		(fp_line
			(start -0.508 -0.9398)
			(end -0.508 0.9398)
			(stroke
				(width 0.1524)
				(type default)
			)
			(layer "F.SilkS")
		)
		(fp_rect
			(start -0.508 0.9398)
			(end 0.508 -0.9398)
			(stroke
				(width 0)
				(type default)
			)
			(fill no)
			(layer "F.CrtYd")
		)
		(fp_rect
			(start -0.508 0.9398)
			(end 0.508 -0.9398)
			(stroke
				(width 0)
				(type default)
			)
			(fill no)
			(layer "F.Fab")
		)
		(pad "1" smd custom
			(at 0 -0.4445 180)
			(size 0.1397 0.1397)
			(layers "F.Cu" "F.Mask" "F.Paste")
			(net "REDV_TX7_N")
			(options
				(clearance outline)
				(anchor circle)
			)
			(primitives
				(gr_poly
					(pts
						(arc
							(start -0.1778 -0.2794)
							(mid -0.249642 -0.249642)
							(end -0.2794 -0.1778)
						)
						(arc
							(start -0.2794 0.1778)
							(mid -0.249642 0.249642)
							(end -0.1778 0.2794)
						)
						(arc
							(start 0.1778 0.2794)
							(mid 0.249642 0.249642)
							(end 0.2794 0.1778)
						)
						(arc
							(start 0.2794 -0.1778)
							(mid 0.249642 -0.249642)
							(end 0.1778 -0.2794)
						)
					)
					(width 0)
					(fill yes)
				)
			)
		)
		(pad "2" smd custom
			(at 0 0.4445 180)
			(size 0.1397 0.1397)
			(layers "F.Cu" "F.Mask" "F.Paste")
			(net "SAS_HDD_CONN_TX7_N")
			(options
				(clearance outline)
				(anchor circle)
			)
			(primitives
				(gr_poly
					(pts
						(arc
							(start -0.1778 -0.2794)
							(mid -0.249642 -0.249642)
							(end -0.2794 -0.1778)
						)
						(arc
							(start -0.2794 0.1778)
							(mid -0.249642 0.249642)
							(end -0.1778 0.2794)
						)
						(arc
							(start 0.1778 0.2794)
							(mid 0.249642 0.249642)
							(end 0.2794 0.1778)
						)
						(arc
							(start 0.2794 -0.1778)
							(mid 0.249642 -0.249642)
							(end 0.1778 -0.2794)
						)
					)
					(width 0)
					(fill yes)
				)
			)
		)
	)
	(footprint ""
		(layer "F.Cu")
		(at 272.288 -41.148)
		(property "Reference" "PC41"
			(at 0 0 0)
			(layer "F.SilkS")
			(hide yes)
			(effects
				(font
					(size 1.27 1.27)
				)
			)
		)
		(property "Value" "SC22U25V5MX-GP"
			(at -0.0762 -6.1214 0)
			(unlocked yes)
			(layer "F.Fab")
			(hide yes)
			(effects
				(font
					(size 1.016 1.016)
					(thickness 0.1524)
				)
			)
		)
		(property "Device Type" "C805H58"
			(at -0.0762 -8.1534 0)
			(unlocked yes)
			(layer "F.Fab")
			(hide yes)
			(effects
				(font
					(size 1.016 1.016)
					(thickness 0.1524)
				)
			)
		)
		(duplicate_pad_numbers_are_jumpers no)
		(fp_line
			(start 0.635 0)
			(end -0.635 0)
			(stroke
				(width 0.508)
				(type default)
			)
			(layer "F.SilkS")
		)
		(fp_rect
			(start -0.9652 1.778)
			(end 0.9652 -1.778)
			(stroke
				(width 0)
				(type default)
			)
			(fill no)
			(layer "F.CrtYd")
		)
		(fp_poly
			(pts
				(xy -0.9652 -1.778) (xy 0.9652 -1.778) (xy 0.9652 1.778) (xy -0.9652 1.778)
			)
			(stroke
				(width 0)
				(type default)
			)
			(fill no)
			(layer "F.Fab")
		)
		(pad "1" smd rect
			(at 0 -0.9652)
			(size 1.397 1.143)
			(layers "F.Cu" "F.Mask" "F.Paste")
			(net "P1V8_STBY_VIN")
		)
		(pad "2" smd rect
			(at 0 0.9652)
			(size 1.397 1.143)
			(layers "F.Cu" "F.Mask" "F.Paste")
			(net "GND")
		)
	)
	(footprint ""
		(layer "F.Cu")
		(at 174.107348 -127.879856 90)
		(property "Reference" "PC174"
			(at 0 0 90)
			(layer "F.SilkS")
			(hide yes)
			(effects
				(font
					(size 1.27 1.27)
				)
			)
		)
		(property "Value" "SC22U25V5MX-GP"
			(at -0.0762 -6.1214 90)
			(unlocked yes)
			(layer "F.Fab")
			(hide yes)
			(effects
				(font
					(size 1.016 1.016)
					(thickness 0.1524)
				)
			)
		)
		(property "Device Type" "C805H58"
			(at -0.0762 -8.1534 90)
			(unlocked yes)
			(layer "F.Fab")
			(hide yes)
			(effects
				(font
					(size 1.016 1.016)
					(thickness 0.1524)
				)
			)
		)
		(duplicate_pad_numbers_are_jumpers no)
		(fp_line
			(start 0.635 0)
			(end -0.635 0)
			(stroke
				(width 0.508)
				(type default)
			)
			(layer "F.SilkS")
		)
		(fp_rect
			(start -0.9652 1.778)
			(end 0.9652 -1.778)
			(stroke
				(width 0)
				(type default)
			)
			(fill no)
			(layer "F.CrtYd")
		)
		(fp_poly
			(pts
				(xy -0.9652 -1.778) (xy 0.9652 -1.778) (xy 0.9652 1.778) (xy -0.9652 1.778)
			)
			(stroke
				(width 0)
				(type default)
			)
			(fill no)
			(layer "F.Fab")
		)
		(pad "1" smd rect
			(at 0 -0.9652 90)
			(size 1.397 1.143)
			(layers "F.Cu" "F.Mask" "F.Paste")
			(net "P0V9_E_VIN")
		)
		(pad "2" smd rect
			(at 0 0.9652 90)
			(size 1.397 1.143)
			(layers "F.Cu" "F.Mask" "F.Paste")
			(net "GND")
		)
	)
	(footprint ""
		(layer "F.Cu")
		(at 312.547 -192.405 90)
		(property "Reference" "R803"
			(at 0 0 90)
			(layer "F.SilkS")
			(hide yes)
			(effects
				(font
					(size 1.27 1.27)
				)
			)
		)
		(property "Value" "4K7R2F-GP"
			(at 0.064008 -3.993896 90)
			(unlocked yes)
			(layer "F.Fab")
			(hide yes)
			(effects
				(font
					(size 1.016 1.016)
					(thickness 0.1524)
				)
			)
		)
		(property "Device Type" "R402H16"
			(at 0.064008 -5.517896 90)
			(unlocked yes)
			(layer "F.Fab")
			(hide yes)
			(effects
				(font
					(size 1.016 1.016)
					(thickness 0.1524)
				)
			)
		)
		(duplicate_pad_numbers_are_jumpers no)
		(fp_line
			(start 0.508 -0.9398)
			(end -0.508 -0.9398)
			(stroke
				(width 0.1524)
				(type default)
			)
			(layer "F.SilkS")
		)
		(fp_line
			(start -0.508 -0.9398)
			(end -0.508 0.9398)
			(stroke
				(width 0.1524)
				(type default)
			)
			(layer "F.SilkS")
		)
		(fp_rect
			(start -0.508 0.9398)
			(end 0.508 -0.9398)
			(stroke
				(width 0)
				(type default)
			)
			(fill no)
			(layer "F.CrtYd")
		)
		(fp_rect
			(start -0.508 0.9398)
			(end 0.508 -0.9398)
			(stroke
				(width 0)
				(type default)
			)
			(fill no)
			(layer "F.Fab")
		)
		(pad "1" smd custom
			(at 0 -0.4445 90)
			(size 0.1397 0.1397)
			(layers "F.Cu" "F.Mask" "F.Paste")
			(net "P3V3_STBY")
			(options
				(clearance outline)
				(anchor circle)
			)
			(primitives
				(gr_poly
					(pts
						(arc
							(start -0.1778 -0.2794)
							(mid -0.249642 -0.249642)
							(end -0.2794 -0.1778)
						)
						(arc
							(start -0.2794 0.1778)
							(mid -0.249642 0.249642)
							(end -0.1778 0.2794)
						)
						(arc
							(start 0.1778 0.2794)
							(mid 0.249642 0.249642)
							(end 0.2794 0.1778)
						)
						(arc
							(start 0.2794 -0.1778)
							(mid 0.249642 -0.249642)
							(end 0.1778 -0.2794)
						)
					)
					(width 0)
					(fill yes)
				)
			)
		)
		(pad "2" smd custom
			(at 0 0.4445 90)
			(size 0.1397 0.1397)
			(layers "F.Cu" "F.Mask" "F.Paste")
			(net "JTAG_BMC_TMS")
			(options
				(clearance outline)
				(anchor circle)
			)
			(primitives
				(gr_poly
					(pts
						(arc
							(start -0.1778 -0.2794)
							(mid -0.249642 -0.249642)
							(end -0.2794 -0.1778)
						)
						(arc
							(start -0.2794 0.1778)
							(mid -0.249642 0.249642)
							(end -0.1778 0.2794)
						)
						(arc
							(start 0.1778 0.2794)
							(mid 0.249642 0.249642)
							(end 0.2794 0.1778)
						)
						(arc
							(start 0.2794 -0.1778)
							(mid 0.249642 -0.249642)
							(end 0.1778 -0.2794)
						)
					)
					(width 0)
					(fill yes)
				)
			)
		)
	)
	(footprint ""
		(layer "F.Cu")
		(at 192.024 -147.701 180)
		(property "Reference" "SC1110"
			(at 0 0 180)
			(layer "F.SilkS")
			(hide yes)
			(effects
				(font
					(size 1.27 1.27)
				)
			)
		)
		(property "Value" "SCD1U16V2KX-3GP"
			(at 1.1811 -2.7051 180)
			(unlocked yes)
			(layer "F.Fab")
			(hide yes)
			(effects
				(font
					(size 1.016 1.016)
					(thickness 0.1524)
				)
			)
		)
		(property "Device Type" "C402H22"
			(at 1.1811 -4.2291 180)
			(unlocked yes)
			(layer "F.Fab")
			(hide yes)
			(effects
				(font
					(size 1.016 1.016)
					(thickness 0.1524)
				)
			)
		)
		(duplicate_pad_numbers_are_jumpers no)
		(fp_rect
			(start -0.4318 0.9525)
			(end 0.4318 -0.9525)
			(stroke
				(width 0)
				(type default)
			)
			(fill no)
			(layer "F.CrtYd")
		)
		(fp_rect
			(start -0.4318 0.9525)
			(end 0.4318 -0.9525)
			(stroke
				(width 0)
				(type default)
			)
			(fill no)
			(layer "F.Fab")
		)
		(pad "1" smd custom
			(at 0 -0.4445 180)
			(size 0.1524 0.1524)
			(layers "F.Cu" "F.Mask" "F.Paste")
			(net "P1V8_E")
			(options
				(clearance outline)
				(anchor circle)
			)
			(primitives
				(gr_poly
					(pts
						(arc
							(start 0.3048 -0.2032)
							(mid 0.275042 -0.275042)
							(end 0.2032 -0.3048)
						)
						(arc
							(start -0.2032 -0.3048)
							(mid -0.275042 -0.275042)
							(end -0.3048 -0.2032)
						)
						(arc
							(start -0.3048 0.2032)
							(mid -0.275042 0.275042)
							(end -0.2032 0.3048)
						)
						(arc
							(start 0.2032 0.3048)
							(mid 0.275042 0.275042)
							(end 0.3048 0.2032)
						)
					)
					(width 0)
					(fill yes)
				)
			)
		)
		(pad "2" smd custom
			(at 0 0.4445 180)
			(size 0.1524 0.1524)
			(layers "F.Cu" "F.Mask" "F.Paste")
			(net "GND")
			(options
				(clearance outline)
				(anchor circle)
			)
			(primitives
				(gr_poly
					(pts
						(arc
							(start 0.3048 -0.2032)
							(mid 0.275042 -0.275042)
							(end 0.2032 -0.3048)
						)
						(arc
							(start -0.2032 -0.3048)
							(mid -0.275042 -0.275042)
							(end -0.3048 -0.2032)
						)
						(arc
							(start -0.3048 0.2032)
							(mid -0.275042 0.275042)
							(end -0.2032 0.3048)
						)
						(arc
							(start 0.2032 0.3048)
							(mid 0.275042 0.275042)
							(end 0.3048 0.2032)
						)
					)
					(width 0)
					(fill yes)
				)
			)
		)
	)
	(footprint ""
		(layer "F.Cu")
		(at 265.049 -20.447 -90)
		(property "Reference" "PC58"
			(at 0 0 270)
			(layer "F.SilkS")
			(hide yes)
			(effects
				(font
					(size 1.27 1.27)
				)
			)
		)
		(property "Value" "SC100U6D3V6MX-GP"
			(at -0.0762 -5.1308 270)
			(unlocked yes)
			(layer "F.Fab")
			(hide yes)
			(effects
				(font
					(size 1.016 1.016)
					(thickness 0.1524)
				)
			)
		)
		(property "Device Type" "C1206H71"
			(at -0.127 -6.6548 270)
			(unlocked yes)
			(layer "F.Fab")
			(hide yes)
			(effects
				(font
					(size 1.016 1.016)
					(thickness 0.1524)
				)
			)
		)
		(duplicate_pad_numbers_are_jumpers no)
		(fp_line
			(start -1.016 2.2352)
			(end -1.016 0.8382)
			(stroke
				(width 0.1524)
				(type default)
			)
			(layer "F.SilkS")
		)
		(fp_line
			(start 1.016 2.2352)
			(end -1.016 2.2352)
			(stroke
				(width 0.1524)
				(type default)
			)
			(layer "F.SilkS")
		)
		(fp_line
			(start 1.016 0.8382)
			(end 1.016 2.2352)
			(stroke
				(width 0.1524)
				(type default)
			)
			(layer "F.SilkS")
		)
		(fp_line
			(start -1.016 -0.8382)
			(end -1.016 -2.2352)
			(stroke
				(width 0.1524)
				(type default)
			)
			(layer "F.SilkS")
		)
		(fp_line
			(start -1.016 -2.2352)
			(end 1.016 -2.2352)
			(stroke
				(width 0.1524)
				(type default)
			)
			(layer "F.SilkS")
		)
		(fp_line
			(start 1.016 -2.2352)
			(end 1.016 -0.8382)
			(stroke
				(width 0.1524)
				(type default)
			)
			(layer "F.SilkS")
		)
		(fp_rect
			(start -1.0922 2.3114)
			(end 1.0922 -2.3114)
			(stroke
				(width 0)
				(type default)
			)
			(fill no)
			(layer "F.CrtYd")
		)
		(fp_poly
			(pts
				(xy 1.0922 -2.3114) (xy 1.0922 2.3114) (xy -1.0922 2.3114) (xy -1.0922 -2.3114)
			)
			(stroke
				(width 0)
				(type default)
			)
			(fill no)
			(layer "F.Fab")
		)
		(pad "1" smd rect
			(at 0 -1.397 270)
			(size 1.651 1.27)
			(layers "F.Cu" "F.Mask" "F.Paste")
			(net "P1V8_STBY")
		)
		(pad "2" smd rect
			(at 0 1.397 270)
			(size 1.651 1.27)
			(layers "F.Cu" "F.Mask" "F.Paste")
			(net "GND")
		)
	)
	(footprint ""
		(layer "F.Cu")
		(at 115.678966 -25.781 -90)
		(property "Reference" "SLED26"
			(at 0 0 270)
			(layer "F.SilkS")
			(hide yes)
			(effects
				(font
					(size 1.27 1.27)
				)
			)
		)
		(property "Value" "LED-YG-51-GP"
			(at -2.6924 -1.4224 270)
			(unlocked yes)
			(layer "F.Fab")
			(hide yes)
			(effects
				(font
					(size 1.016 1.016)
					(thickness 0.1524)
				)
			)
		)
		(property "Device Type" "LED1608AKH40"
			(at -2.6924 -2.9464 270)
			(unlocked yes)
			(layer "F.Fab")
			(hide yes)
			(effects
				(font
					(size 1.016 1.016)
					(thickness 0.1524)
				)
			)
		)
		(duplicate_pad_numbers_are_jumpers no)
		(fp_line
			(start -0.7493 1.651)
			(end -0.7493 1.1811)
			(stroke
				(width 0.3302)
				(type default)
			)
			(layer "F.SilkS")
		)
		(fp_line
			(start 0.7493 1.651)
			(end 0.7493 1.1811)
			(stroke
				(width 0.3302)
				(type default)
			)
			(layer "F.SilkS")
		)
		(fp_line
			(start -0.5969 1.5494)
			(end 0.5842 1.5494)
			(stroke
				(width 0.508)
				(type default)
			)
			(layer "F.SilkS")
		)
		(fp_line
			(start -0.6604 1.3716)
			(end -0.6604 -1.3716)
			(stroke
				(width 0.1524)
				(type default)
			)
			(layer "F.SilkS")
		)
		(fp_line
			(start 0.6604 1.3716)
			(end -0.6604 1.3716)
			(stroke
				(width 0.1524)
				(type default)
			)
			(layer "F.SilkS")
		)
		(fp_line
			(start -0.6604 -1.3716)
			(end 0.6604 -1.3716)
			(stroke
				(width 0.1524)
				(type default)
			)
			(layer "F.SilkS")
		)
		(fp_line
			(start 0.6604 -1.3716)
			(end 0.6604 1.3716)
			(stroke
				(width 0.1524)
				(type default)
			)
			(layer "F.SilkS")
		)
		(fp_rect
			(start -0.6223 1.3335)
			(end 0.6223 -1.3335)
			(stroke
				(width 0)
				(type default)
			)
			(fill no)
			(layer "F.CrtYd")
		)
		(fp_rect
			(start -0.6223 1.3335)
			(end 0.6223 -1.3335)
			(stroke
				(width 0)
				(type default)
			)
			(fill no)
			(layer "F.Fab")
		)
		(pad "A" smd custom
			(at 0 -0.762 270)
			(size 0.2159 0.2159)
			(layers "F.Cu" "F.Mask" "F.Paste")
			(net "SYS_ERROR_LED_R")
			(options
				(clearance outline)
				(anchor circle)
			)
			(primitives
				(gr_poly
					(pts
						(arc
							(start -0.3302 -0.4318)
							(mid -0.402042 -0.402042)
							(end -0.4318 -0.3302)
						)
						(arc
							(start -0.4318 0.3302)
							(mid -0.402042 0.402042)
							(end -0.3302 0.4318)
						)
						(arc
							(start 0.3302 0.4318)
							(mid 0.402042 0.402042)
							(end 0.4318 0.3302)
						)
						(arc
							(start 0.4318 -0.3302)
							(mid 0.402042 -0.402042)
							(end 0.3302 -0.4318)
						)
					)
					(width 0)
					(fill yes)
				)
			)
		)
		(pad "K" smd custom
			(at 0 0.762 270)
			(size 0.2159 0.2159)
			(layers "F.Cu" "F.Mask" "F.Paste")
			(net "SYS_ERROR_LED_D")
			(options
				(clearance outline)
				(anchor circle)
			)
			(primitives
				(gr_poly
					(pts
						(arc
							(start -0.3302 -0.4318)
							(mid -0.402042 -0.402042)
							(end -0.4318 -0.3302)
						)
						(arc
							(start -0.4318 0.3302)
							(mid -0.402042 0.402042)
							(end -0.3302 0.4318)
						)
						(arc
							(start 0.3302 0.4318)
							(mid 0.402042 0.402042)
							(end 0.4318 0.3302)
						)
						(arc
							(start 0.4318 -0.3302)
							(mid 0.402042 -0.402042)
							(end 0.3302 -0.4318)
						)
					)
					(width 0)
					(fill yes)
				)
			)
		)
	)
	(footprint ""
		(layer "F.Cu")
		(at 114.497612 -222.885)
		(property "Reference" "SR878"
			(at 0 0 0)
			(layer "F.SilkS")
			(hide yes)
			(effects
				(font
					(size 1.27 1.27)
				)
			)
		)
		(property "Value" "0R2J-2-GP"
			(at 0.064008 -3.993896 0)
			(unlocked yes)
			(layer "F.Fab")
			(hide yes)
			(effects
				(font
					(size 1.016 1.016)
					(thickness 0.1524)
				)
			)
		)
		(property "Device Type" "R402H16"
			(at 0.064008 -5.517896 0)
			(unlocked yes)
			(layer "F.Fab")
			(hide yes)
			(effects
				(font
					(size 1.016 1.016)
					(thickness 0.1524)
				)
			)
		)
		(duplicate_pad_numbers_are_jumpers no)
		(fp_line
			(start -0.508 -0.9398)
			(end -0.508 0.9398)
			(stroke
				(width 0.1524)
				(type default)
			)
			(layer "F.SilkS")
		)
		(fp_line
			(start 0.508 -0.9398)
			(end -0.508 -0.9398)
			(stroke
				(width 0.1524)
				(type default)
			)
			(layer "F.SilkS")
		)
		(fp_rect
			(start -0.508 0.9398)
			(end 0.508 -0.9398)
			(stroke
				(width 0)
				(type default)
			)
			(fill no)
			(layer "F.CrtYd")
		)
		(fp_rect
			(start -0.508 0.9398)
			(end 0.508 -0.9398)
			(stroke
				(width 0)
				(type default)
			)
			(fill no)
			(layer "F.Fab")
		)
		(pad "1" smd custom
			(at 0 -0.4445)
			(size 0.1397 0.1397)
			(layers "F.Cu" "F.Mask" "F.Paste")
			(net "SAS_HDD_CONN_SER_TX8_P")
			(options
				(clearance outline)
				(anchor circle)
			)
			(primitives
				(gr_poly
					(pts
						(arc
							(start -0.1778 -0.2794)
							(mid -0.249642 -0.249642)
							(end -0.2794 -0.1778)
						)
						(arc
							(start -0.2794 0.1778)
							(mid -0.249642 0.249642)
							(end -0.1778 0.2794)
						)
						(arc
							(start 0.1778 0.2794)
							(mid 0.249642 0.249642)
							(end 0.2794 0.1778)
						)
						(arc
							(start 0.2794 -0.1778)
							(mid 0.249642 -0.249642)
							(end 0.1778 -0.2794)
						)
					)
					(width 0)
					(fill yes)
				)
			)
		)
		(pad "2" smd custom
			(at 0 0.4445)
			(size 0.1397 0.1397)
			(layers "F.Cu" "F.Mask" "F.Paste")
			(net "SAS_HDD_CONN_TX8_P")
			(options
				(clearance outline)
				(anchor circle)
			)
			(primitives
				(gr_poly
					(pts
						(arc
							(start -0.1778 -0.2794)
							(mid -0.249642 -0.249642)
							(end -0.2794 -0.1778)
						)
						(arc
							(start -0.2794 0.1778)
							(mid -0.249642 0.249642)
							(end -0.1778 0.2794)
						)
						(arc
							(start 0.1778 0.2794)
							(mid 0.249642 0.249642)
							(end 0.2794 0.1778)
						)
						(arc
							(start 0.2794 -0.1778)
							(mid 0.249642 -0.249642)
							(end 0.1778 -0.2794)
						)
					)
					(width 0)
					(fill yes)
				)
			)
		)
	)
	(footprint ""
		(layer "F.Cu")
		(at 320.294 -198.882 -90)
		(property "Reference" "R546"
			(at 0 0 270)
			(layer "F.SilkS")
			(hide yes)
			(effects
				(font
					(size 1.27 1.27)
				)
			)
		)
		(property "Value" "10KR2F-2-GP"
			(at 0.064008 -3.993896 270)
			(unlocked yes)
			(layer "F.Fab")
			(hide yes)
			(effects
				(font
					(size 1.016 1.016)
					(thickness 0.1524)
				)
			)
		)
		(property "Device Type" "R402H16"
			(at 0.064008 -5.517896 270)
			(unlocked yes)
			(layer "F.Fab")
			(hide yes)
			(effects
				(font
					(size 1.016 1.016)
					(thickness 0.1524)
				)
			)
		)
		(duplicate_pad_numbers_are_jumpers no)
		(fp_line
			(start -0.508 -0.9398)
			(end -0.508 0.9398)
			(stroke
				(width 0.1524)
				(type default)
			)
			(layer "F.SilkS")
		)
		(fp_line
			(start 0.508 -0.9398)
			(end -0.508 -0.9398)
			(stroke
				(width 0.1524)
				(type default)
			)
			(layer "F.SilkS")
		)
		(fp_rect
			(start -0.508 0.9398)
			(end 0.508 -0.9398)
			(stroke
				(width 0)
				(type default)
			)
			(fill no)
			(layer "F.CrtYd")
		)
		(fp_rect
			(start -0.508 0.9398)
			(end 0.508 -0.9398)
			(stroke
				(width 0)
				(type default)
			)
			(fill no)
			(layer "F.Fab")
		)
		(pad "1" smd custom
			(at 0 -0.4445 270)
			(size 0.1397 0.1397)
			(layers "F.Cu" "F.Mask" "F.Paste")
			(net "P3V3_STBY")
			(options
				(clearance outline)
				(anchor circle)
			)
			(primitives
				(gr_poly
					(pts
						(arc
							(start -0.1778 -0.2794)
							(mid -0.249642 -0.249642)
							(end -0.2794 -0.1778)
						)
						(arc
							(start -0.2794 0.1778)
							(mid -0.249642 0.249642)
							(end -0.1778 0.2794)
						)
						(arc
							(start 0.1778 0.2794)
							(mid 0.249642 0.249642)
							(end 0.2794 0.1778)
						)
						(arc
							(start 0.2794 -0.1778)
							(mid 0.249642 -0.249642)
							(end 0.1778 -0.2794)
						)
					)
					(width 0)
					(fill yes)
				)
			)
		)
		(pad "2" smd custom
			(at 0 0.4445 270)
			(size 0.1397 0.1397)
			(layers "F.Cu" "F.Mask" "F.Paste")
			(net "BMC_JTAG_L_EN")
			(options
				(clearance outline)
				(anchor circle)
			)
			(primitives
				(gr_poly
					(pts
						(arc
							(start -0.1778 -0.2794)
							(mid -0.249642 -0.249642)
							(end -0.2794 -0.1778)
						)
						(arc
							(start -0.2794 0.1778)
							(mid -0.249642 0.249642)
							(end -0.1778 0.2794)
						)
						(arc
							(start 0.1778 0.2794)
							(mid 0.249642 0.249642)
							(end 0.2794 0.1778)
						)
						(arc
							(start 0.2794 -0.1778)
							(mid 0.249642 -0.249642)
							(end 0.1778 -0.2794)
						)
					)
					(width 0)
					(fill yes)
				)
			)
		)
	)
	(footprint ""
		(layer "F.Cu")
		(at 47.5742 -114.7572 180)
		(property "Reference" "SR942"
			(at 0 0 180)
			(layer "F.SilkS")
			(hide yes)
			(effects
				(font
					(size 1.27 1.27)
				)
			)
		)
		(property "Value" "0R2J-2-GP"
			(at 0.064008 -3.993896 180)
			(unlocked yes)
			(layer "F.Fab")
			(hide yes)
			(effects
				(font
					(size 1.016 1.016)
					(thickness 0.1524)
				)
			)
		)
		(property "Device Type" "R402H16"
			(at 0.064008 -5.517896 180)
			(unlocked yes)
			(layer "F.Fab")
			(hide yes)
			(effects
				(font
					(size 1.016 1.016)
					(thickness 0.1524)
				)
			)
		)
		(duplicate_pad_numbers_are_jumpers no)
		(fp_line
			(start 0.508 -0.9398)
			(end -0.508 -0.9398)
			(stroke
				(width 0.1524)
				(type default)
			)
			(layer "F.SilkS")
		)
		(fp_line
			(start -0.508 -0.9398)
			(end -0.508 0.9398)
			(stroke
				(width 0.1524)
				(type default)
			)
			(layer "F.SilkS")
		)
		(fp_rect
			(start -0.508 0.9398)
			(end 0.508 -0.9398)
			(stroke
				(width 0)
				(type default)
			)
			(fill no)
			(layer "F.CrtYd")
		)
		(fp_rect
			(start -0.508 0.9398)
			(end 0.508 -0.9398)
			(stroke
				(width 0)
				(type default)
			)
			(fill no)
			(layer "F.Fab")
		)
		(pad "1" smd custom
			(at 0 -0.4445 180)
			(size 0.1397 0.1397)
			(layers "F.Cu" "F.Mask" "F.Paste")
			(net "BMC_R_TXD5")
			(options
				(clearance outline)
				(anchor circle)
			)
			(primitives
				(gr_poly
					(pts
						(arc
							(start -0.1778 -0.2794)
							(mid -0.249642 -0.249642)
							(end -0.2794 -0.1778)
						)
						(arc
							(start -0.2794 0.1778)
							(mid -0.249642 0.249642)
							(end -0.1778 0.2794)
						)
						(arc
							(start 0.1778 0.2794)
							(mid 0.249642 0.249642)
							(end 0.2794 0.1778)
						)
						(arc
							(start 0.2794 -0.1778)
							(mid 0.249642 -0.249642)
							(end 0.1778 -0.2794)
						)
					)
					(width 0)
					(fill yes)
				)
			)
		)
		(pad "2" smd custom
			(at 0 0.4445 180)
			(size 0.1397 0.1397)
			(layers "F.Cu" "F.Mask" "F.Paste")
			(net "BMC_TXD5")
			(options
				(clearance outline)
				(anchor circle)
			)
			(primitives
				(gr_poly
					(pts
						(arc
							(start -0.1778 -0.2794)
							(mid -0.249642 -0.249642)
							(end -0.2794 -0.1778)
						)
						(arc
							(start -0.2794 0.1778)
							(mid -0.249642 0.249642)
							(end -0.1778 0.2794)
						)
						(arc
							(start 0.1778 0.2794)
							(mid 0.249642 0.249642)
							(end 0.2794 0.1778)
						)
						(arc
							(start 0.2794 -0.1778)
							(mid 0.249642 -0.249642)
							(end 0.1778 -0.2794)
						)
					)
					(width 0)
					(fill yes)
				)
			)
		)
	)
	(footprint ""
		(layer "F.Cu")
		(at 95.70847 -106.045 -90)
		(property "Reference" "SR792"
			(at 0 0 270)
			(layer "F.SilkS")
			(hide yes)
			(effects
				(font
					(size 1.27 1.27)
				)
			)
		)
		(property "Value" "0R2J-2-GP"
			(at 0.064008 -3.993896 270)
			(unlocked yes)
			(layer "F.Fab")
			(hide yes)
			(effects
				(font
					(size 1.016 1.016)
					(thickness 0.1524)
				)
			)
		)
		(property "Device Type" "R402H16"
			(at 0.064008 -5.517896 270)
			(unlocked yes)
			(layer "F.Fab")
			(hide yes)
			(effects
				(font
					(size 1.016 1.016)
					(thickness 0.1524)
				)
			)
		)
		(duplicate_pad_numbers_are_jumpers no)
		(fp_line
			(start -0.508 -0.9398)
			(end -0.508 0.9398)
			(stroke
				(width 0.1524)
				(type default)
			)
			(layer "F.SilkS")
		)
		(fp_line
			(start 0.508 -0.9398)
			(end -0.508 -0.9398)
			(stroke
				(width 0.1524)
				(type default)
			)
			(layer "F.SilkS")
		)
		(fp_rect
			(start -0.508 0.9398)
			(end 0.508 -0.9398)
			(stroke
				(width 0)
				(type default)
			)
			(fill no)
			(layer "F.CrtYd")
		)
		(fp_rect
			(start -0.508 0.9398)
			(end 0.508 -0.9398)
			(stroke
				(width 0)
				(type default)
			)
			(fill no)
			(layer "F.Fab")
		)
		(pad "1" smd custom
			(at 0 -0.4445 270)
			(size 0.1397 0.1397)
			(layers "F.Cu" "F.Mask" "F.Paste")
			(net "SMART_RX")
			(options
				(clearance outline)
				(anchor circle)
			)
			(primitives
				(gr_poly
					(pts
						(arc
							(start -0.1778 -0.2794)
							(mid -0.249642 -0.249642)
							(end -0.2794 -0.1778)
						)
						(arc
							(start -0.2794 0.1778)
							(mid -0.249642 0.249642)
							(end -0.1778 0.2794)
						)
						(arc
							(start 0.1778 0.2794)
							(mid 0.249642 0.249642)
							(end 0.2794 0.1778)
						)
						(arc
							(start 0.2794 -0.1778)
							(mid 0.249642 -0.249642)
							(end 0.1778 -0.2794)
						)
					)
					(width 0)
					(fill yes)
				)
			)
		)
		(pad "2" smd custom
			(at 0 0.4445 270)
			(size 0.1397 0.1397)
			(layers "F.Cu" "F.Mask" "F.Paste")
			(net "SAS_SMART_RX")
			(options
				(clearance outline)
				(anchor circle)
			)
			(primitives
				(gr_poly
					(pts
						(arc
							(start -0.1778 -0.2794)
							(mid -0.249642 -0.249642)
							(end -0.2794 -0.1778)
						)
						(arc
							(start -0.2794 0.1778)
							(mid -0.249642 0.249642)
							(end -0.1778 0.2794)
						)
						(arc
							(start 0.1778 0.2794)
							(mid 0.249642 0.249642)
							(end 0.2794 0.1778)
						)
						(arc
							(start 0.2794 -0.1778)
							(mid 0.249642 -0.249642)
							(end 0.1778 -0.2794)
						)
					)
					(width 0)
					(fill yes)
				)
			)
		)
	)
	(footprint ""
		(layer "F.Cu")
		(at 166.233856 -110.880652 90)
		(property "Reference" "R610"
			(at 0 0 90)
			(layer "F.SilkS")
			(hide yes)
			(effects
				(font
					(size 1.27 1.27)
				)
			)
		)
		(property "Value" "4K7R2F-GP"
			(at 0.064008 -3.993896 90)
			(unlocked yes)
			(layer "F.Fab")
			(hide yes)
			(effects
				(font
					(size 1.016 1.016)
					(thickness 0.1524)
				)
			)
		)
		(property "Device Type" "R402H16"
			(at 0.064008 -5.517896 90)
			(unlocked yes)
			(layer "F.Fab")
			(hide yes)
			(effects
				(font
					(size 1.016 1.016)
					(thickness 0.1524)
				)
			)
		)
		(duplicate_pad_numbers_are_jumpers no)
		(fp_line
			(start 0.508 -0.9398)
			(end -0.508 -0.9398)
			(stroke
				(width 0.1524)
				(type default)
			)
			(layer "F.SilkS")
		)
		(fp_line
			(start -0.508 -0.9398)
			(end -0.508 0.9398)
			(stroke
				(width 0.1524)
				(type default)
			)
			(layer "F.SilkS")
		)
		(fp_rect
			(start -0.508 0.9398)
			(end 0.508 -0.9398)
			(stroke
				(width 0)
				(type default)
			)
			(fill no)
			(layer "F.CrtYd")
		)
		(fp_rect
			(start -0.508 0.9398)
			(end 0.508 -0.9398)
			(stroke
				(width 0)
				(type default)
			)
			(fill no)
			(layer "F.Fab")
		)
		(pad "1" smd custom
			(at 0 -0.4445 90)
			(size 0.1397 0.1397)
			(layers "F.Cu" "F.Mask" "F.Paste")
			(net "P3V3_STBY")
			(options
				(clearance outline)
				(anchor circle)
			)
			(primitives
				(gr_poly
					(pts
						(arc
							(start -0.1778 -0.2794)
							(mid -0.249642 -0.249642)
							(end -0.2794 -0.1778)
						)
						(arc
							(start -0.2794 0.1778)
							(mid -0.249642 0.249642)
							(end -0.1778 0.2794)
						)
						(arc
							(start 0.1778 0.2794)
							(mid 0.249642 0.249642)
							(end 0.2794 0.1778)
						)
						(arc
							(start 0.2794 -0.1778)
							(mid 0.249642 -0.249642)
							(end 0.1778 -0.2794)
						)
					)
					(width 0)
					(fill yes)
				)
			)
		)
		(pad "2" smd custom
			(at 0 0.4445 90)
			(size 0.1397 0.1397)
			(layers "F.Cu" "F.Mask" "F.Paste")
			(net "P0V9_E_PG")
			(options
				(clearance outline)
				(anchor circle)
			)
			(primitives
				(gr_poly
					(pts
						(arc
							(start -0.1778 -0.2794)
							(mid -0.249642 -0.249642)
							(end -0.2794 -0.1778)
						)
						(arc
							(start -0.2794 0.1778)
							(mid -0.249642 0.249642)
							(end -0.1778 0.2794)
						)
						(arc
							(start 0.1778 0.2794)
							(mid 0.249642 0.249642)
							(end 0.2794 0.1778)
						)
						(arc
							(start 0.2794 -0.1778)
							(mid 0.249642 -0.249642)
							(end 0.1778 -0.2794)
						)
					)
					(width 0)
					(fill yes)
				)
			)
		)
	)
	(footprint ""
		(layer "F.Cu")
		(at 331.597 -143.383 -90)
		(property "Reference" "C317"
			(at 0 0 270)
			(layer "F.SilkS")
			(hide yes)
			(effects
				(font
					(size 1.27 1.27)
				)
			)
		)
		(property "Value" "SC1U6D3V3KX-2GP"
			(at 0 -2.8194 270)
			(unlocked yes)
			(layer "F.Fab")
			(hide yes)
			(effects
				(font
					(size 1.016 1.016)
					(thickness 0.1524)
				)
			)
		)
		(property "Device Type" "C603H36"
			(at 0 -4.3434 270)
			(unlocked yes)
			(layer "F.Fab")
			(hide yes)
			(effects
				(font
					(size 1.016 1.016)
					(thickness 0.1524)
				)
			)
		)
		(duplicate_pad_numbers_are_jumpers no)
		(fp_line
			(start 0.508 0)
			(end -0.508 0)
			(stroke
				(width 0.2032)
				(type default)
			)
			(layer "F.SilkS")
		)
		(fp_rect
			(start -0.5842 1.3335)
			(end 0.5842 -1.3335)
			(stroke
				(width 0)
				(type default)
			)
			(fill no)
			(layer "F.CrtYd")
		)
		(fp_rect
			(start -0.5842 1.3335)
			(end 0.5842 -1.3335)
			(stroke
				(width 0)
				(type default)
			)
			(fill no)
			(layer "F.Fab")
		)
		(pad "1" smd custom
			(at 0 -0.762 270)
			(size 0.2159 0.2159)
			(layers "F.Cu" "F.Mask" "F.Paste")
			(net "P3V3_STBY")
			(options
				(clearance outline)
				(anchor circle)
			)
			(primitives
				(gr_poly
					(pts
						(arc
							(start -0.3302 -0.4318)
							(mid -0.402042 -0.402042)
							(end -0.4318 -0.3302)
						)
						(arc
							(start -0.4318 0.3302)
							(mid -0.402042 0.402042)
							(end -0.3302 0.4318)
						)
						(arc
							(start 0.3302 0.4318)
							(mid 0.402042 0.402042)
							(end 0.4318 0.3302)
						)
						(arc
							(start 0.4318 -0.3302)
							(mid 0.402042 -0.402042)
							(end 0.3302 -0.4318)
						)
					)
					(width 0)
					(fill yes)
				)
			)
		)
		(pad "2" smd custom
			(at 0 0.762 270)
			(size 0.2159 0.2159)
			(layers "F.Cu" "F.Mask" "F.Paste")
			(net "GND")
			(options
				(clearance outline)
				(anchor circle)
			)
			(primitives
				(gr_poly
					(pts
						(arc
							(start -0.3302 -0.4318)
							(mid -0.402042 -0.402042)
							(end -0.4318 -0.3302)
						)
						(arc
							(start -0.4318 0.3302)
							(mid -0.402042 0.402042)
							(end -0.3302 0.4318)
						)
						(arc
							(start 0.3302 0.4318)
							(mid 0.402042 0.402042)
							(end 0.4318 0.3302)
						)
						(arc
							(start 0.4318 -0.3302)
							(mid 0.402042 -0.402042)
							(end 0.3302 -0.4318)
						)
					)
					(width 0)
					(fill yes)
				)
			)
		)
	)
	(footprint ""
		(layer "F.Cu")
		(at 231.013 -14.478 180)
		(property "Reference" "Q9"
			(at 0 0 180)
			(layer "F.SilkS")
			(hide yes)
			(effects
				(font
					(size 1.27 1.27)
				)
			)
		)
		(property "Value" "2N7002A-7-GP"
			(at 0.127 -8.9662 180)
			(unlocked yes)
			(layer "F.Fab")
			(hide yes)
			(effects
				(font
					(size 1.016 1.016)
					(thickness 0.1524)
				)
			)
		)
		(property "Device Type" "SOT23DGS2D4H48"
			(at 0.127 -10.4902 180)
			(unlocked yes)
			(layer "F.Fab")
			(hide yes)
			(effects
				(font
					(size 1.016 1.016)
					(thickness 0.1524)
				)
			)
		)
		(duplicate_pad_numbers_are_jumpers no)
		(fp_line
			(start 1.651 1.778)
			(end 1.651 -1.778)
			(stroke
				(width 0.1524)
				(type default)
			)
			(layer "F.SilkS")
		)
		(fp_line
			(start 1.651 -1.778)
			(end -1.651 -1.778)
			(stroke
				(width 0.1524)
				(type default)
			)
			(layer "F.SilkS")
		)
		(fp_line
			(start -1.651 1.778)
			(end 1.651 1.778)
			(stroke
				(width 0.1524)
				(type default)
			)
			(layer "F.SilkS")
		)
		(fp_line
			(start -1.651 -1.778)
			(end -1.651 1.778)
			(stroke
				(width 0.1524)
				(type default)
			)
			(layer "F.SilkS")
		)
		(fp_poly
			(pts
				(xy -1.778 1.8796) (xy -1.778 -1.8796) (xy 1.778 -1.8796) (xy 1.778 1.8796)
			)
			(stroke
				(width 0)
				(type default)
			)
			(fill no)
			(layer "F.CrtYd")
		)
		(fp_poly
			(pts
				(xy -1.778 1.8796) (xy -1.778 -1.8796) (xy 1.778 -1.8796) (xy 1.778 1.8796)
			)
			(stroke
				(width 0)
				(type default)
			)
			(fill no)
			(layer "F.Fab")
		)
		(pad "D" smd custom
			(at 0 -0.9525 180)
			(size 0.1905 0.1905)
			(layers "F.Cu" "F.Mask" "F.Paste")
			(net "ENCLO_LED_RED_D")
			(options
				(clearance outline)
				(anchor circle)
			)
			(primitives
				(gr_poly
					(pts
						(arc
							(start -0.1778 0.5715)
							(mid -0.321484 0.511984)
							(end -0.381 0.3683)
						)
						(arc
							(start -0.381 -0.3683)
							(mid -0.321484 -0.511984)
							(end -0.1778 -0.5715)
						)
						(arc
							(start 0.1778 -0.5715)
							(mid 0.321484 -0.511984)
							(end 0.381 -0.3683)
						)
						(arc
							(start 0.381 0.3683)
							(mid 0.321484 0.511984)
							(end 0.1778 0.5715)
						)
					)
					(width 0)
					(fill yes)
				)
			)
		)
		(pad "G" smd custom
			(at -0.98425 0.9525 180)
			(size 0.1905 0.1905)
			(layers "F.Cu" "F.Mask" "F.Paste")
			(net "ENCLO_LED_RED_G")
			(options
				(clearance outline)
				(anchor circle)
			)
			(primitives
				(gr_poly
					(pts
						(arc
							(start -0.1778 0.5715)
							(mid -0.321484 0.511984)
							(end -0.381 0.3683)
						)
						(arc
							(start -0.381 -0.3683)
							(mid -0.321484 -0.511984)
							(end -0.1778 -0.5715)
						)
						(arc
							(start 0.1778 -0.5715)
							(mid 0.321484 -0.511984)
							(end 0.381 -0.3683)
						)
						(arc
							(start 0.381 0.3683)
							(mid 0.321484 0.511984)
							(end 0.1778 0.5715)
						)
					)
					(width 0)
					(fill yes)
				)
			)
		)
		(pad "S" smd custom
			(at 0.98425 0.9525 180)
			(size 0.1905 0.1905)
			(layers "F.Cu" "F.Mask" "F.Paste")
			(net "GND")
			(options
				(clearance outline)
				(anchor circle)
			)
			(primitives
				(gr_poly
					(pts
						(arc
							(start -0.1778 0.5715)
							(mid -0.321484 0.511984)
							(end -0.381 0.3683)
						)
						(arc
							(start -0.381 -0.3683)
							(mid -0.321484 -0.511984)
							(end -0.1778 -0.5715)
						)
						(arc
							(start 0.1778 -0.5715)
							(mid 0.321484 -0.511984)
							(end 0.381 -0.3683)
						)
						(arc
							(start 0.381 0.3683)
							(mid 0.321484 0.511984)
							(end 0.1778 0.5715)
						)
					)
					(width 0)
					(fill yes)
				)
			)
		)
	)
	(footprint ""
		(layer "F.Cu")
		(at 152.019 -56.642 -90)
		(property "Reference" "SR691"
			(at 0 0 270)
			(layer "F.SilkS")
			(hide yes)
			(effects
				(font
					(size 1.27 1.27)
				)
			)
		)
		(property "Value" "10KR2F-2-GP"
			(at 0.064008 -3.993896 270)
			(unlocked yes)
			(layer "F.Fab")
			(hide yes)
			(effects
				(font
					(size 1.016 1.016)
					(thickness 0.1524)
				)
			)
		)
		(property "Device Type" "R402H16"
			(at 0.064008 -5.517896 270)
			(unlocked yes)
			(layer "F.Fab")
			(hide yes)
			(effects
				(font
					(size 1.016 1.016)
					(thickness 0.1524)
				)
			)
		)
		(duplicate_pad_numbers_are_jumpers no)
		(fp_line
			(start -0.508 -0.9398)
			(end -0.508 0.9398)
			(stroke
				(width 0.1524)
				(type default)
			)
			(layer "F.SilkS")
		)
		(fp_line
			(start 0.508 -0.9398)
			(end -0.508 -0.9398)
			(stroke
				(width 0.1524)
				(type default)
			)
			(layer "F.SilkS")
		)
		(fp_rect
			(start -0.508 0.9398)
			(end 0.508 -0.9398)
			(stroke
				(width 0)
				(type default)
			)
			(fill no)
			(layer "F.CrtYd")
		)
		(fp_rect
			(start -0.508 0.9398)
			(end 0.508 -0.9398)
			(stroke
				(width 0)
				(type default)
			)
			(fill no)
			(layer "F.Fab")
		)
		(pad "1" smd custom
			(at 0 -0.4445 270)
			(size 0.1397 0.1397)
			(layers "F.Cu" "F.Mask" "F.Paste")
			(net "P1V8_C")
			(options
				(clearance outline)
				(anchor circle)
			)
			(primitives
				(gr_poly
					(pts
						(arc
							(start -0.1778 -0.2794)
							(mid -0.249642 -0.249642)
							(end -0.2794 -0.1778)
						)
						(arc
							(start -0.2794 0.1778)
							(mid -0.249642 0.249642)
							(end -0.1778 0.2794)
						)
						(arc
							(start 0.1778 0.2794)
							(mid 0.249642 0.249642)
							(end 0.2794 0.1778)
						)
						(arc
							(start 0.2794 -0.1778)
							(mid 0.249642 -0.249642)
							(end 0.1778 -0.2794)
						)
					)
					(width 0)
					(fill yes)
				)
			)
		)
		(pad "2" smd custom
			(at 0 0.4445 270)
			(size 0.1397 0.1397)
			(layers "F.Cu" "F.Mask" "F.Paste")
			(net "XM_ADDR_7")
			(options
				(clearance outline)
				(anchor circle)
			)
			(primitives
				(gr_poly
					(pts
						(arc
							(start -0.1778 -0.2794)
							(mid -0.249642 -0.249642)
							(end -0.2794 -0.1778)
						)
						(arc
							(start -0.2794 0.1778)
							(mid -0.249642 0.249642)
							(end -0.1778 0.2794)
						)
						(arc
							(start 0.1778 0.2794)
							(mid 0.249642 0.249642)
							(end 0.2794 0.1778)
						)
						(arc
							(start 0.2794 -0.1778)
							(mid 0.249642 -0.249642)
							(end 0.1778 -0.2794)
						)
					)
					(width 0)
					(fill yes)
				)
			)
		)
	)
	(footprint ""
		(layer "F.Cu")
		(at 173.49597 -67.183)
		(property "Reference" "C292"
			(at 0 0 0)
			(layer "F.SilkS")
			(hide yes)
			(effects
				(font
					(size 1.27 1.27)
				)
			)
		)
		(property "Value" "SCD1U25V2KX-2-GP"
			(at 1.1811 -2.7051 0)
			(unlocked yes)
			(layer "F.Fab")
			(hide yes)
			(effects
				(font
					(size 1.016 1.016)
					(thickness 0.1524)
				)
			)
		)
		(property "Device Type" "C402H22"
			(at 1.1811 -4.2291 0)
			(unlocked yes)
			(layer "F.Fab")
			(hide yes)
			(effects
				(font
					(size 1.016 1.016)
					(thickness 0.1524)
				)
			)
		)
		(duplicate_pad_numbers_are_jumpers no)
		(fp_rect
			(start -0.4318 0.9525)
			(end 0.4318 -0.9525)
			(stroke
				(width 0)
				(type default)
			)
			(fill no)
			(layer "F.CrtYd")
		)
		(fp_rect
			(start -0.4318 0.9525)
			(end 0.4318 -0.9525)
			(stroke
				(width 0)
				(type default)
			)
			(fill no)
			(layer "F.Fab")
		)
		(pad "1" smd custom
			(at 0 -0.4445)
			(size 0.1524 0.1524)
			(layers "F.Cu" "F.Mask" "F.Paste")
			(net "TP_MSB_A46_GBE_RX_N")
			(options
				(clearance outline)
				(anchor circle)
			)
			(primitives
				(gr_poly
					(pts
						(arc
							(start 0.3048 -0.2032)
							(mid 0.275042 -0.275042)
							(end 0.2032 -0.3048)
						)
						(arc
							(start -0.2032 -0.3048)
							(mid -0.275042 -0.275042)
							(end -0.3048 -0.2032)
						)
						(arc
							(start -0.3048 0.2032)
							(mid -0.275042 0.275042)
							(end -0.2032 0.3048)
						)
						(arc
							(start 0.2032 0.3048)
							(mid 0.275042 0.275042)
							(end 0.3048 0.2032)
						)
					)
					(width 0)
					(fill yes)
				)
			)
		)
		(pad "2" smd custom
			(at 0 0.4445)
			(size 0.1524 0.1524)
			(layers "F.Cu" "F.Mask" "F.Paste")
			(net "GND")
			(options
				(clearance outline)
				(anchor circle)
			)
			(primitives
				(gr_poly
					(pts
						(arc
							(start 0.3048 -0.2032)
							(mid 0.275042 -0.275042)
							(end 0.2032 -0.3048)
						)
						(arc
							(start -0.2032 -0.3048)
							(mid -0.275042 -0.275042)
							(end -0.3048 -0.2032)
						)
						(arc
							(start -0.3048 0.2032)
							(mid -0.275042 0.275042)
							(end -0.2032 0.3048)
						)
						(arc
							(start 0.2032 0.3048)
							(mid 0.275042 0.275042)
							(end 0.3048 0.2032)
						)
					)
					(width 0)
					(fill yes)
				)
			)
		)
	)
	(footprint ""
		(layer "F.Cu")
		(at 317.290958 -62.357 -90)
		(property "Reference" "R255"
			(at 0 0 270)
			(layer "F.SilkS")
			(hide yes)
			(effects
				(font
					(size 1.27 1.27)
				)
			)
		)
		(property "Value" "0R2J-2-GP"
			(at 0.064008 -3.993896 270)
			(unlocked yes)
			(layer "F.Fab")
			(hide yes)
			(effects
				(font
					(size 1.016 1.016)
					(thickness 0.1524)
				)
			)
		)
		(property "Device Type" "R402H16"
			(at 0.064008 -5.517896 270)
			(unlocked yes)
			(layer "F.Fab")
			(hide yes)
			(effects
				(font
					(size 1.016 1.016)
					(thickness 0.1524)
				)
			)
		)
		(duplicate_pad_numbers_are_jumpers no)
		(fp_line
			(start -0.508 -0.9398)
			(end -0.508 0.9398)
			(stroke
				(width 0.1524)
				(type default)
			)
			(layer "F.SilkS")
		)
		(fp_line
			(start 0.508 -0.9398)
			(end -0.508 -0.9398)
			(stroke
				(width 0.1524)
				(type default)
			)
			(layer "F.SilkS")
		)
		(fp_rect
			(start -0.508 0.9398)
			(end 0.508 -0.9398)
			(stroke
				(width 0)
				(type default)
			)
			(fill no)
			(layer "F.CrtYd")
		)
		(fp_rect
			(start -0.508 0.9398)
			(end 0.508 -0.9398)
			(stroke
				(width 0)
				(type default)
			)
			(fill no)
			(layer "F.Fab")
		)
		(pad "1" smd custom
			(at 0 -0.4445 270)
			(size 0.1397 0.1397)
			(layers "F.Cu" "F.Mask" "F.Paste")
			(net "BMC_MBC_I2C_E_SDA")
			(options
				(clearance outline)
				(anchor circle)
			)
			(primitives
				(gr_poly
					(pts
						(arc
							(start -0.1778 -0.2794)
							(mid -0.249642 -0.249642)
							(end -0.2794 -0.1778)
						)
						(arc
							(start -0.2794 0.1778)
							(mid -0.249642 0.249642)
							(end -0.1778 0.2794)
						)
						(arc
							(start 0.1778 0.2794)
							(mid 0.249642 0.249642)
							(end 0.2794 0.1778)
						)
						(arc
							(start 0.2794 -0.1778)
							(mid 0.249642 -0.249642)
							(end 0.1778 -0.2794)
						)
					)
					(width 0)
					(fill yes)
				)
			)
		)
		(pad "2" smd custom
			(at 0 0.4445 270)
			(size 0.1397 0.1397)
			(layers "F.Cu" "F.Mask" "F.Paste")
			(net "I2C_BMC_MSB_DATA_R")
			(options
				(clearance outline)
				(anchor circle)
			)
			(primitives
				(gr_poly
					(pts
						(arc
							(start -0.1778 -0.2794)
							(mid -0.249642 -0.249642)
							(end -0.2794 -0.1778)
						)
						(arc
							(start -0.2794 0.1778)
							(mid -0.249642 0.249642)
							(end -0.1778 0.2794)
						)
						(arc
							(start 0.1778 0.2794)
							(mid 0.249642 0.249642)
							(end 0.2794 0.1778)
						)
						(arc
							(start 0.2794 -0.1778)
							(mid 0.249642 -0.249642)
							(end 0.1778 -0.2794)
						)
					)
					(width 0)
					(fill yes)
				)
			)
		)
	)
	(footprint ""
		(layer "F.Cu")
		(at 17.214088 -202.185016)
		(property "Reference" "SR580"
			(at 0 0 0)
			(layer "F.SilkS")
			(hide yes)
			(effects
				(font
					(size 1.27 1.27)
				)
			)
		)
		(property "Value" "200KR2F-L-GP"
			(at 0.064008 -3.993896 0)
			(unlocked yes)
			(layer "F.Fab")
			(hide yes)
			(effects
				(font
					(size 1.016 1.016)
					(thickness 0.1524)
				)
			)
		)
		(property "Device Type" "R402H16"
			(at 0.064008 -5.517896 0)
			(unlocked yes)
			(layer "F.Fab")
			(hide yes)
			(effects
				(font
					(size 1.016 1.016)
					(thickness 0.1524)
				)
			)
		)
		(duplicate_pad_numbers_are_jumpers no)
		(fp_line
			(start -0.508 -0.9398)
			(end -0.508 0.9398)
			(stroke
				(width 0.1524)
				(type default)
			)
			(layer "F.SilkS")
		)
		(fp_line
			(start 0.508 -0.9398)
			(end -0.508 -0.9398)
			(stroke
				(width 0.1524)
				(type default)
			)
			(layer "F.SilkS")
		)
		(fp_rect
			(start -0.508 0.9398)
			(end 0.508 -0.9398)
			(stroke
				(width 0)
				(type default)
			)
			(fill no)
			(layer "F.CrtYd")
		)
		(fp_rect
			(start -0.508 0.9398)
			(end 0.508 -0.9398)
			(stroke
				(width 0)
				(type default)
			)
			(fill no)
			(layer "F.Fab")
		)
		(pad "1" smd custom
			(at 0 -0.4445)
			(size 0.1397 0.1397)
			(layers "F.Cu" "F.Mask" "F.Paste")
			(net "BMC_I2C10_EN")
			(options
				(clearance outline)
				(anchor circle)
			)
			(primitives
				(gr_poly
					(pts
						(arc
							(start -0.1778 -0.2794)
							(mid -0.249642 -0.249642)
							(end -0.2794 -0.1778)
						)
						(arc
							(start -0.2794 0.1778)
							(mid -0.249642 0.249642)
							(end -0.1778 0.2794)
						)
						(arc
							(start 0.1778 0.2794)
							(mid 0.249642 0.249642)
							(end 0.2794 0.1778)
						)
						(arc
							(start 0.2794 -0.1778)
							(mid 0.249642 -0.249642)
							(end 0.1778 -0.2794)
						)
					)
					(width 0)
					(fill yes)
				)
			)
		)
		(pad "2" smd custom
			(at 0 0.4445)
			(size 0.1397 0.1397)
			(layers "F.Cu" "F.Mask" "F.Paste")
			(net "P3V3_STBY")
			(options
				(clearance outline)
				(anchor circle)
			)
			(primitives
				(gr_poly
					(pts
						(arc
							(start -0.1778 -0.2794)
							(mid -0.249642 -0.249642)
							(end -0.2794 -0.1778)
						)
						(arc
							(start -0.2794 0.1778)
							(mid -0.249642 0.249642)
							(end -0.1778 0.2794)
						)
						(arc
							(start 0.1778 0.2794)
							(mid 0.249642 0.249642)
							(end 0.2794 0.1778)
						)
						(arc
							(start 0.2794 -0.1778)
							(mid 0.249642 -0.249642)
							(end 0.1778 -0.2794)
						)
					)
					(width 0)
					(fill yes)
				)
			)
		)
	)
	(footprint ""
		(layer "F.Cu")
		(at 112.973612 -205.867 180)
		(property "Reference" "SR879"
			(at 0 0 180)
			(layer "F.SilkS")
			(hide yes)
			(effects
				(font
					(size 1.27 1.27)
				)
			)
		)
		(property "Value" "0R2J-2-GP"
			(at 0.064008 -3.993896 180)
			(unlocked yes)
			(layer "F.Fab")
			(hide yes)
			(effects
				(font
					(size 1.016 1.016)
					(thickness 0.1524)
				)
			)
		)
		(property "Device Type" "R402H16"
			(at 0.064008 -5.517896 180)
			(unlocked yes)
			(layer "F.Fab")
			(hide yes)
			(effects
				(font
					(size 1.016 1.016)
					(thickness 0.1524)
				)
			)
		)
		(duplicate_pad_numbers_are_jumpers no)
		(fp_line
			(start 0.508 -0.9398)
			(end -0.508 -0.9398)
			(stroke
				(width 0.1524)
				(type default)
			)
			(layer "F.SilkS")
		)
		(fp_line
			(start -0.508 -0.9398)
			(end -0.508 0.9398)
			(stroke
				(width 0.1524)
				(type default)
			)
			(layer "F.SilkS")
		)
		(fp_rect
			(start -0.508 0.9398)
			(end 0.508 -0.9398)
			(stroke
				(width 0)
				(type default)
			)
			(fill no)
			(layer "F.CrtYd")
		)
		(fp_rect
			(start -0.508 0.9398)
			(end 0.508 -0.9398)
			(stroke
				(width 0)
				(type default)
			)
			(fill no)
			(layer "F.Fab")
		)
		(pad "1" smd custom
			(at 0 -0.4445 180)
			(size 0.1397 0.1397)
			(layers "F.Cu" "F.Mask" "F.Paste")
			(net "SAS_HDD_REDV_TX8_P")
			(options
				(clearance outline)
				(anchor circle)
			)
			(primitives
				(gr_poly
					(pts
						(arc
							(start -0.1778 -0.2794)
							(mid -0.249642 -0.249642)
							(end -0.2794 -0.1778)
						)
						(arc
							(start -0.2794 0.1778)
							(mid -0.249642 0.249642)
							(end -0.1778 0.2794)
						)
						(arc
							(start 0.1778 0.2794)
							(mid 0.249642 0.249642)
							(end 0.2794 0.1778)
						)
						(arc
							(start 0.2794 -0.1778)
							(mid 0.249642 -0.249642)
							(end 0.1778 -0.2794)
						)
					)
					(width 0)
					(fill yes)
				)
			)
		)
		(pad "2" smd custom
			(at 0 0.4445 180)
			(size 0.1397 0.1397)
			(layers "F.Cu" "F.Mask" "F.Paste")
			(net "REDV_TX8_P")
			(options
				(clearance outline)
				(anchor circle)
			)
			(primitives
				(gr_poly
					(pts
						(arc
							(start -0.1778 -0.2794)
							(mid -0.249642 -0.249642)
							(end -0.2794 -0.1778)
						)
						(arc
							(start -0.2794 0.1778)
							(mid -0.249642 0.249642)
							(end -0.1778 0.2794)
						)
						(arc
							(start 0.1778 0.2794)
							(mid 0.249642 0.249642)
							(end 0.2794 0.1778)
						)
						(arc
							(start 0.2794 -0.1778)
							(mid 0.249642 -0.249642)
							(end 0.1778 -0.2794)
						)
					)
					(width 0)
					(fill yes)
				)
			)
		)
	)
	(footprint ""
		(layer "F.Cu")
		(at 98.171 -60.325)
		(property "Reference" "STP38"
			(at 0 0 0)
			(layer "F.SilkS")
			(hide yes)
			(effects
				(font
					(size 1.27 1.27)
				)
			)
		)
		(property "Value" "TPAD28"
			(at 0.0127 -1.8034 0)
			(unlocked yes)
			(layer "F.Fab")
			(hide yes)
			(effects
				(font
					(size 1.016 1.016)
					(thickness 0.1524)
				)
			)
		)
		(property "Device Type" "TPAD28"
			(at 0.0127 -3.3274 0)
			(unlocked yes)
			(layer "F.Fab")
			(hide yes)
			(effects
				(font
					(size 1.016 1.016)
					(thickness 0.1524)
				)
			)
		)
		(duplicate_pad_numbers_are_jumpers no)
		(fp_poly
			(pts
				(arc
					(start 0.3556 0)
					(mid -0.3556 0)
					(end 0.3556 0)
				)
			)
			(stroke
				(width 0)
				(type default)
			)
			(fill no)
			(layer "F.CrtYd")
		)
		(fp_poly
			(pts
				(arc
					(start 0.6096 0)
					(mid -0.6096 0)
					(end 0.6096 0)
				)
			)
			(stroke
				(width 0)
				(type default)
			)
			(fill no)
			(layer "F.Fab")
		)
		(pad "1" smd circle
			(at 0 0)
			(size 0.7112 0.7112)
			(layers "F.Cu" "F.Mask" "F.Paste")
			(net "ICE1_TDO")
		)
	)
	(footprint ""
		(layer "F.Cu")
		(at 271.272 -170.942 90)
		(property "Reference" "R269"
			(at 0 0 90)
			(layer "F.SilkS")
			(hide yes)
			(effects
				(font
					(size 1.27 1.27)
				)
			)
		)
		(property "Value" "10KR2F-2-GP"
			(at 0.064008 -3.993896 90)
			(unlocked yes)
			(layer "F.Fab")
			(hide yes)
			(effects
				(font
					(size 1.016 1.016)
					(thickness 0.1524)
				)
			)
		)
		(property "Device Type" "R402H16"
			(at 0.064008 -5.517896 90)
			(unlocked yes)
			(layer "F.Fab")
			(hide yes)
			(effects
				(font
					(size 1.016 1.016)
					(thickness 0.1524)
				)
			)
		)
		(duplicate_pad_numbers_are_jumpers no)
		(fp_line
			(start 0.508 -0.9398)
			(end -0.508 -0.9398)
			(stroke
				(width 0.1524)
				(type default)
			)
			(layer "F.SilkS")
		)
		(fp_line
			(start -0.508 -0.9398)
			(end -0.508 0.9398)
			(stroke
				(width 0.1524)
				(type default)
			)
			(layer "F.SilkS")
		)
		(fp_rect
			(start -0.508 0.9398)
			(end 0.508 -0.9398)
			(stroke
				(width 0)
				(type default)
			)
			(fill no)
			(layer "F.CrtYd")
		)
		(fp_rect
			(start -0.508 0.9398)
			(end 0.508 -0.9398)
			(stroke
				(width 0)
				(type default)
			)
			(fill no)
			(layer "F.Fab")
		)
		(pad "1" smd custom
			(at 0 -0.4445 90)
			(size 0.1397 0.1397)
			(layers "F.Cu" "F.Mask" "F.Paste")
			(net "P3V3_STBY")
			(options
				(clearance outline)
				(anchor circle)
			)
			(primitives
				(gr_poly
					(pts
						(arc
							(start -0.1778 -0.2794)
							(mid -0.249642 -0.249642)
							(end -0.2794 -0.1778)
						)
						(arc
							(start -0.2794 0.1778)
							(mid -0.249642 0.249642)
							(end -0.1778 0.2794)
						)
						(arc
							(start 0.1778 0.2794)
							(mid 0.249642 0.249642)
							(end 0.2794 0.1778)
						)
						(arc
							(start 0.2794 -0.1778)
							(mid 0.249642 -0.249642)
							(end 0.1778 -0.2794)
						)
					)
					(width 0)
					(fill yes)
				)
			)
		)
		(pad "2" smd custom
			(at 0 0.4445 90)
			(size 0.1397 0.1397)
			(layers "F.Cu" "F.Mask" "F.Paste")
			(net "BMC_MBC_I2C_E_SCL")
			(options
				(clearance outline)
				(anchor circle)
			)
			(primitives
				(gr_poly
					(pts
						(arc
							(start -0.1778 -0.2794)
							(mid -0.249642 -0.249642)
							(end -0.2794 -0.1778)
						)
						(arc
							(start -0.2794 0.1778)
							(mid -0.249642 0.249642)
							(end -0.1778 0.2794)
						)
						(arc
							(start 0.1778 0.2794)
							(mid 0.249642 0.249642)
							(end 0.2794 0.1778)
						)
						(arc
							(start 0.2794 -0.1778)
							(mid 0.249642 -0.249642)
							(end 0.1778 -0.2794)
						)
					)
					(width 0)
					(fill yes)
				)
			)
		)
	)
	(footprint ""
		(layer "F.Cu")
		(at 21.667216 -225.09988 180)
		(property "Reference" "SC429"
			(at 0 0 180)
			(layer "F.SilkS")
			(hide yes)
			(effects
				(font
					(size 1.27 1.27)
				)
			)
		)
		(property "Value" "SCD1U16V2KX-3GP"
			(at 1.1811 -2.7051 180)
			(unlocked yes)
			(layer "F.Fab")
			(hide yes)
			(effects
				(font
					(size 1.016 1.016)
					(thickness 0.1524)
				)
			)
		)
		(property "Device Type" "C402H22"
			(at 1.1811 -4.2291 180)
			(unlocked yes)
			(layer "F.Fab")
			(hide yes)
			(effects
				(font
					(size 1.016 1.016)
					(thickness 0.1524)
				)
			)
		)
		(duplicate_pad_numbers_are_jumpers no)
		(fp_rect
			(start -0.4318 0.9525)
			(end 0.4318 -0.9525)
			(stroke
				(width 0)
				(type default)
			)
			(fill no)
			(layer "F.CrtYd")
		)
		(fp_rect
			(start -0.4318 0.9525)
			(end 0.4318 -0.9525)
			(stroke
				(width 0)
				(type default)
			)
			(fill no)
			(layer "F.Fab")
		)
		(pad "1" smd custom
			(at 0 -0.4445 180)
			(size 0.1524 0.1524)
			(layers "F.Cu" "F.Mask" "F.Paste")
			(net "P3V3_STBY")
			(options
				(clearance outline)
				(anchor circle)
			)
			(primitives
				(gr_poly
					(pts
						(arc
							(start 0.3048 -0.2032)
							(mid 0.275042 -0.275042)
							(end 0.2032 -0.3048)
						)
						(arc
							(start -0.2032 -0.3048)
							(mid -0.275042 -0.275042)
							(end -0.3048 -0.2032)
						)
						(arc
							(start -0.3048 0.2032)
							(mid -0.275042 0.275042)
							(end -0.2032 0.3048)
						)
						(arc
							(start 0.2032 0.3048)
							(mid 0.275042 0.275042)
							(end 0.3048 0.2032)
						)
					)
					(width 0)
					(fill yes)
				)
			)
		)
		(pad "2" smd custom
			(at 0 0.4445 180)
			(size 0.1524 0.1524)
			(layers "F.Cu" "F.Mask" "F.Paste")
			(net "GND")
			(options
				(clearance outline)
				(anchor circle)
			)
			(primitives
				(gr_poly
					(pts
						(arc
							(start 0.3048 -0.2032)
							(mid 0.275042 -0.275042)
							(end 0.2032 -0.3048)
						)
						(arc
							(start -0.2032 -0.3048)
							(mid -0.275042 -0.275042)
							(end -0.3048 -0.2032)
						)
						(arc
							(start -0.3048 0.2032)
							(mid -0.275042 0.275042)
							(end -0.2032 0.3048)
						)
						(arc
							(start 0.2032 0.3048)
							(mid 0.275042 0.275042)
							(end 0.3048 0.2032)
						)
					)
					(width 0)
					(fill yes)
				)
			)
		)
	)
	(footprint ""
		(layer "F.Cu")
		(at 95.25 -69.342 180)
		(property "Reference" "SC968"
			(at 0 0 180)
			(layer "F.SilkS")
			(hide yes)
			(effects
				(font
					(size 1.27 1.27)
				)
			)
		)
		(property "Value" "SC1U10V2KX-4-GP"
			(at 1.1811 -2.7051 180)
			(unlocked yes)
			(layer "F.Fab")
			(hide yes)
			(effects
				(font
					(size 1.016 1.016)
					(thickness 0.1524)
				)
			)
		)
		(property "Device Type" "C402H22"
			(at 1.1811 -4.2291 180)
			(unlocked yes)
			(layer "F.Fab")
			(hide yes)
			(effects
				(font
					(size 1.016 1.016)
					(thickness 0.1524)
				)
			)
		)
		(duplicate_pad_numbers_are_jumpers no)
		(fp_rect
			(start -0.4318 0.9525)
			(end 0.4318 -0.9525)
			(stroke
				(width 0)
				(type default)
			)
			(fill no)
			(layer "F.CrtYd")
		)
		(fp_rect
			(start -0.4318 0.9525)
			(end 0.4318 -0.9525)
			(stroke
				(width 0)
				(type default)
			)
			(fill no)
			(layer "F.Fab")
		)
		(pad "1" smd custom
			(at 0 -0.4445 180)
			(size 0.1524 0.1524)
			(layers "F.Cu" "F.Mask" "F.Paste")
			(net "P1V8_C")
			(options
				(clearance outline)
				(anchor circle)
			)
			(primitives
				(gr_poly
					(pts
						(arc
							(start 0.3048 -0.2032)
							(mid 0.275042 -0.275042)
							(end 0.2032 -0.3048)
						)
						(arc
							(start -0.2032 -0.3048)
							(mid -0.275042 -0.275042)
							(end -0.3048 -0.2032)
						)
						(arc
							(start -0.3048 0.2032)
							(mid -0.275042 0.275042)
							(end -0.2032 0.3048)
						)
						(arc
							(start 0.2032 0.3048)
							(mid 0.275042 0.275042)
							(end 0.3048 0.2032)
						)
					)
					(width 0)
					(fill yes)
				)
			)
		)
		(pad "2" smd custom
			(at 0 0.4445 180)
			(size 0.1524 0.1524)
			(layers "F.Cu" "F.Mask" "F.Paste")
			(net "GND")
			(options
				(clearance outline)
				(anchor circle)
			)
			(primitives
				(gr_poly
					(pts
						(arc
							(start 0.3048 -0.2032)
							(mid 0.275042 -0.275042)
							(end 0.2032 -0.3048)
						)
						(arc
							(start -0.2032 -0.3048)
							(mid -0.275042 -0.275042)
							(end -0.3048 -0.2032)
						)
						(arc
							(start -0.3048 0.2032)
							(mid -0.275042 0.275042)
							(end -0.2032 0.3048)
						)
						(arc
							(start 0.2032 0.3048)
							(mid 0.275042 0.275042)
							(end 0.3048 0.2032)
						)
					)
					(width 0)
					(fill yes)
				)
			)
		)
	)
	(footprint ""
		(layer "F.Cu")
		(at 221.361 -105.156 -90)
		(property "Reference" "PR124"
			(at 0 0 270)
			(layer "F.SilkS")
			(hide yes)
			(effects
				(font
					(size 1.27 1.27)
				)
			)
		)
		(property "Value" "0R2J-2-GP"
			(at 0.064008 -3.993896 270)
			(unlocked yes)
			(layer "F.Fab")
			(hide yes)
			(effects
				(font
					(size 1.016 1.016)
					(thickness 0.1524)
				)
			)
		)
		(property "Device Type" "R402H16"
			(at 0.064008 -5.517896 270)
			(unlocked yes)
			(layer "F.Fab")
			(hide yes)
			(effects
				(font
					(size 1.016 1.016)
					(thickness 0.1524)
				)
			)
		)
		(duplicate_pad_numbers_are_jumpers no)
		(fp_line
			(start -0.508 -0.9398)
			(end -0.508 0.9398)
			(stroke
				(width 0.1524)
				(type default)
			)
			(layer "F.SilkS")
		)
		(fp_line
			(start 0.508 -0.9398)
			(end -0.508 -0.9398)
			(stroke
				(width 0.1524)
				(type default)
			)
			(layer "F.SilkS")
		)
		(fp_rect
			(start -0.508 0.9398)
			(end 0.508 -0.9398)
			(stroke
				(width 0)
				(type default)
			)
			(fill no)
			(layer "F.CrtYd")
		)
		(fp_rect
			(start -0.508 0.9398)
			(end 0.508 -0.9398)
			(stroke
				(width 0)
				(type default)
			)
			(fill no)
			(layer "F.Fab")
		)
		(pad "1" smd custom
			(at 0 -0.4445 270)
			(size 0.1397 0.1397)
			(layers "F.Cu" "F.Mask" "F.Paste")
			(net "P3V3_STBY")
			(options
				(clearance outline)
				(anchor circle)
			)
			(primitives
				(gr_poly
					(pts
						(arc
							(start -0.1778 -0.2794)
							(mid -0.249642 -0.249642)
							(end -0.2794 -0.1778)
						)
						(arc
							(start -0.2794 0.1778)
							(mid -0.249642 0.249642)
							(end -0.1778 0.2794)
						)
						(arc
							(start 0.1778 0.2794)
							(mid 0.249642 0.249642)
							(end 0.2794 0.1778)
						)
						(arc
							(start 0.2794 -0.1778)
							(mid 0.249642 -0.249642)
							(end 0.1778 -0.2794)
						)
					)
					(width 0)
					(fill yes)
				)
			)
		)
		(pad "2" smd custom
			(at 0 0.4445 270)
			(size 0.1397 0.1397)
			(layers "F.Cu" "F.Mask" "F.Paste")
			(net "TPS74801_1V5_C_BIAS")
			(options
				(clearance outline)
				(anchor circle)
			)
			(primitives
				(gr_poly
					(pts
						(arc
							(start -0.1778 -0.2794)
							(mid -0.249642 -0.249642)
							(end -0.2794 -0.1778)
						)
						(arc
							(start -0.2794 0.1778)
							(mid -0.249642 0.249642)
							(end -0.1778 0.2794)
						)
						(arc
							(start 0.1778 0.2794)
							(mid 0.249642 0.249642)
							(end 0.2794 0.1778)
						)
						(arc
							(start 0.2794 -0.1778)
							(mid 0.249642 -0.249642)
							(end 0.1778 -0.2794)
						)
					)
					(width 0)
					(fill yes)
				)
			)
		)
	)
	(footprint ""
		(layer "F.Cu")
		(at 346.075 -114.808 180)
		(property "Reference" "PC5"
			(at 0 0 180)
			(layer "F.SilkS")
			(hide yes)
			(effects
				(font
					(size 1.27 1.27)
				)
			)
		)
		(property "Value" "SC1U25V3KX-GP"
			(at 0 -2.8194 180)
			(unlocked yes)
			(layer "F.Fab")
			(hide yes)
			(effects
				(font
					(size 1.016 1.016)
					(thickness 0.1524)
				)
			)
		)
		(property "Device Type" "C603H36"
			(at 0 -4.3434 180)
			(unlocked yes)
			(layer "F.Fab")
			(hide yes)
			(effects
				(font
					(size 1.016 1.016)
					(thickness 0.1524)
				)
			)
		)
		(duplicate_pad_numbers_are_jumpers no)
		(fp_line
			(start 0.508 0)
			(end -0.508 0)
			(stroke
				(width 0.2032)
				(type default)
			)
			(layer "F.SilkS")
		)
		(fp_rect
			(start -0.5842 1.3335)
			(end 0.5842 -1.3335)
			(stroke
				(width 0)
				(type default)
			)
			(fill no)
			(layer "F.CrtYd")
		)
		(fp_rect
			(start -0.5842 1.3335)
			(end 0.5842 -1.3335)
			(stroke
				(width 0)
				(type default)
			)
			(fill no)
			(layer "F.Fab")
		)
		(pad "1" smd custom
			(at 0 -0.762 180)
			(size 0.2159 0.2159)
			(layers "F.Cu" "F.Mask" "F.Paste")
			(net "P5V_STBY_VCC")
			(options
				(clearance outline)
				(anchor circle)
			)
			(primitives
				(gr_poly
					(pts
						(arc
							(start -0.3302 -0.4318)
							(mid -0.402042 -0.402042)
							(end -0.4318 -0.3302)
						)
						(arc
							(start -0.4318 0.3302)
							(mid -0.402042 0.402042)
							(end -0.3302 0.4318)
						)
						(arc
							(start 0.3302 0.4318)
							(mid 0.402042 0.402042)
							(end 0.4318 0.3302)
						)
						(arc
							(start 0.4318 -0.3302)
							(mid 0.402042 -0.402042)
							(end 0.3302 -0.4318)
						)
					)
					(width 0)
					(fill yes)
				)
			)
		)
		(pad "2" smd custom
			(at 0 0.762 180)
			(size 0.2159 0.2159)
			(layers "F.Cu" "F.Mask" "F.Paste")
			(net "AGND_P5V_STBY")
			(options
				(clearance outline)
				(anchor circle)
			)
			(primitives
				(gr_poly
					(pts
						(arc
							(start -0.3302 -0.4318)
							(mid -0.402042 -0.402042)
							(end -0.4318 -0.3302)
						)
						(arc
							(start -0.4318 0.3302)
							(mid -0.402042 0.402042)
							(end -0.3302 0.4318)
						)
						(arc
							(start 0.3302 0.4318)
							(mid 0.402042 0.402042)
							(end 0.4318 0.3302)
						)
						(arc
							(start 0.4318 -0.3302)
							(mid 0.402042 -0.402042)
							(end 0.3302 -0.4318)
						)
					)
					(width 0)
					(fill yes)
				)
			)
		)
	)
	(footprint ""
		(layer "F.Cu")
		(at 116.713 -70.485 -90)
		(property "Reference" "R5312"
			(at 0 0 270)
			(layer "F.SilkS")
			(hide yes)
			(effects
				(font
					(size 1.27 1.27)
				)
			)
		)
		(property "Value" "0R2J-2-GP"
			(at 0.064008 -3.993896 270)
			(unlocked yes)
			(layer "F.Fab")
			(hide yes)
			(effects
				(font
					(size 1.016 1.016)
					(thickness 0.1524)
				)
			)
		)
		(property "Device Type" "R402H16"
			(at 0.064008 -5.517896 270)
			(unlocked yes)
			(layer "F.Fab")
			(hide yes)
			(effects
				(font
					(size 1.016 1.016)
					(thickness 0.1524)
				)
			)
		)
		(duplicate_pad_numbers_are_jumpers no)
		(fp_line
			(start -0.508 -0.9398)
			(end -0.508 0.9398)
			(stroke
				(width 0.1524)
				(type default)
			)
			(layer "F.SilkS")
		)
		(fp_line
			(start 0.508 -0.9398)
			(end -0.508 -0.9398)
			(stroke
				(width 0.1524)
				(type default)
			)
			(layer "F.SilkS")
		)
		(fp_rect
			(start -0.508 0.9398)
			(end 0.508 -0.9398)
			(stroke
				(width 0)
				(type default)
			)
			(fill no)
			(layer "F.CrtYd")
		)
		(fp_rect
			(start -0.508 0.9398)
			(end 0.508 -0.9398)
			(stroke
				(width 0)
				(type default)
			)
			(fill no)
			(layer "F.Fab")
		)
		(pad "1" smd custom
			(at 0 -0.4445 270)
			(size 0.1397 0.1397)
			(layers "F.Cu" "F.Mask" "F.Paste")
			(net "BMC_I2C_SDA_10")
			(options
				(clearance outline)
				(anchor circle)
			)
			(primitives
				(gr_poly
					(pts
						(arc
							(start -0.1778 -0.2794)
							(mid -0.249642 -0.249642)
							(end -0.2794 -0.1778)
						)
						(arc
							(start -0.2794 0.1778)
							(mid -0.249642 0.249642)
							(end -0.1778 0.2794)
						)
						(arc
							(start 0.1778 0.2794)
							(mid 0.249642 0.249642)
							(end 0.2794 0.1778)
						)
						(arc
							(start 0.2794 -0.1778)
							(mid 0.249642 -0.249642)
							(end 0.1778 -0.2794)
						)
					)
					(width 0)
					(fill yes)
				)
			)
		)
		(pad "2" smd custom
			(at 0 0.4445 270)
			(size 0.1397 0.1397)
			(layers "F.Cu" "F.Mask" "F.Paste")
			(net "TEMP_4_SDA")
			(options
				(clearance outline)
				(anchor circle)
			)
			(primitives
				(gr_poly
					(pts
						(arc
							(start -0.1778 -0.2794)
							(mid -0.249642 -0.249642)
							(end -0.2794 -0.1778)
						)
						(arc
							(start -0.2794 0.1778)
							(mid -0.249642 0.249642)
							(end -0.1778 0.2794)
						)
						(arc
							(start 0.1778 0.2794)
							(mid 0.249642 0.249642)
							(end 0.2794 0.1778)
						)
						(arc
							(start 0.2794 -0.1778)
							(mid 0.249642 -0.249642)
							(end 0.1778 -0.2794)
						)
					)
					(width 0)
					(fill yes)
				)
			)
		)
	)
	(footprint ""
		(layer "F.Cu")
		(at 197.612 -169.672 -90)
		(property "Reference" "R578"
			(at 0 0 270)
			(layer "F.SilkS")
			(hide yes)
			(effects
				(font
					(size 1.27 1.27)
				)
			)
		)
		(property "Value" "4K7R2F-GP"
			(at 0.064008 -3.993896 270)
			(unlocked yes)
			(layer "F.Fab")
			(hide yes)
			(effects
				(font
					(size 1.016 1.016)
					(thickness 0.1524)
				)
			)
		)
		(property "Device Type" "R402H16"
			(at 0.064008 -5.517896 270)
			(unlocked yes)
			(layer "F.Fab")
			(hide yes)
			(effects
				(font
					(size 1.016 1.016)
					(thickness 0.1524)
				)
			)
		)
		(duplicate_pad_numbers_are_jumpers no)
		(fp_line
			(start -0.508 -0.9398)
			(end -0.508 0.9398)
			(stroke
				(width 0.1524)
				(type default)
			)
			(layer "F.SilkS")
		)
		(fp_line
			(start 0.508 -0.9398)
			(end -0.508 -0.9398)
			(stroke
				(width 0.1524)
				(type default)
			)
			(layer "F.SilkS")
		)
		(fp_rect
			(start -0.508 0.9398)
			(end 0.508 -0.9398)
			(stroke
				(width 0)
				(type default)
			)
			(fill no)
			(layer "F.CrtYd")
		)
		(fp_rect
			(start -0.508 0.9398)
			(end 0.508 -0.9398)
			(stroke
				(width 0)
				(type default)
			)
			(fill no)
			(layer "F.Fab")
		)
		(pad "1" smd custom
			(at 0 -0.4445 270)
			(size 0.1397 0.1397)
			(layers "F.Cu" "F.Mask" "F.Paste")
			(net "P3V3_STBY")
			(options
				(clearance outline)
				(anchor circle)
			)
			(primitives
				(gr_poly
					(pts
						(arc
							(start -0.1778 -0.2794)
							(mid -0.249642 -0.249642)
							(end -0.2794 -0.1778)
						)
						(arc
							(start -0.2794 0.1778)
							(mid -0.249642 0.249642)
							(end -0.1778 0.2794)
						)
						(arc
							(start 0.1778 0.2794)
							(mid 0.249642 0.249642)
							(end 0.2794 0.1778)
						)
						(arc
							(start 0.2794 -0.1778)
							(mid 0.249642 -0.249642)
							(end 0.1778 -0.2794)
						)
					)
					(width 0)
					(fill yes)
				)
			)
		)
		(pad "2" smd custom
			(at 0 0.4445 270)
			(size 0.1397 0.1397)
			(layers "F.Cu" "F.Mask" "F.Paste")
			(net "P3V3_STBY_R1")
			(options
				(clearance outline)
				(anchor circle)
			)
			(primitives
				(gr_poly
					(pts
						(arc
							(start -0.1778 -0.2794)
							(mid -0.249642 -0.249642)
							(end -0.2794 -0.1778)
						)
						(arc
							(start -0.2794 0.1778)
							(mid -0.249642 0.249642)
							(end -0.1778 0.2794)
						)
						(arc
							(start 0.1778 0.2794)
							(mid 0.249642 0.249642)
							(end 0.2794 0.1778)
						)
						(arc
							(start 0.2794 -0.1778)
							(mid 0.249642 -0.249642)
							(end 0.1778 -0.2794)
						)
					)
					(width 0)
					(fill yes)
				)
			)
		)
	)
	(footprint ""
		(layer "F.Cu")
		(at 46.99 -230.886)
		(property "Reference" "C299"
			(at 0 0 0)
			(layer "F.SilkS")
			(hide yes)
			(effects
				(font
					(size 1.27 1.27)
				)
			)
		)
		(property "Value" "SC1U25V3KX-GP"
			(at 0 -2.8194 0)
			(unlocked yes)
			(layer "F.Fab")
			(hide yes)
			(effects
				(font
					(size 1.016 1.016)
					(thickness 0.1524)
				)
			)
		)
		(property "Device Type" "C603H36"
			(at 0 -4.3434 0)
			(unlocked yes)
			(layer "F.Fab")
			(hide yes)
			(effects
				(font
					(size 1.016 1.016)
					(thickness 0.1524)
				)
			)
		)
		(duplicate_pad_numbers_are_jumpers no)
		(fp_line
			(start 0.508 0)
			(end -0.508 0)
			(stroke
				(width 0.2032)
				(type default)
			)
			(layer "F.SilkS")
		)
		(fp_rect
			(start -0.5842 1.3335)
			(end 0.5842 -1.3335)
			(stroke
				(width 0)
				(type default)
			)
			(fill no)
			(layer "F.CrtYd")
		)
		(fp_rect
			(start -0.5842 1.3335)
			(end 0.5842 -1.3335)
			(stroke
				(width 0)
				(type default)
			)
			(fill no)
			(layer "F.Fab")
		)
		(pad "1" smd custom
			(at 0 -0.762)
			(size 0.2159 0.2159)
			(layers "F.Cu" "F.Mask" "F.Paste")
			(net "P12V_PCIE")
			(options
				(clearance outline)
				(anchor circle)
			)
			(primitives
				(gr_poly
					(pts
						(arc
							(start -0.3302 -0.4318)
							(mid -0.402042 -0.402042)
							(end -0.4318 -0.3302)
						)
						(arc
							(start -0.4318 0.3302)
							(mid -0.402042 0.402042)
							(end -0.3302 0.4318)
						)
						(arc
							(start 0.3302 0.4318)
							(mid 0.402042 0.402042)
							(end 0.4318 0.3302)
						)
						(arc
							(start 0.4318 -0.3302)
							(mid 0.402042 -0.402042)
							(end 0.3302 -0.4318)
						)
					)
					(width 0)
					(fill yes)
				)
			)
		)
		(pad "2" smd custom
			(at 0 0.762)
			(size 0.2159 0.2159)
			(layers "F.Cu" "F.Mask" "F.Paste")
			(net "GND")
			(options
				(clearance outline)
				(anchor circle)
			)
			(primitives
				(gr_poly
					(pts
						(arc
							(start -0.3302 -0.4318)
							(mid -0.402042 -0.402042)
							(end -0.4318 -0.3302)
						)
						(arc
							(start -0.4318 0.3302)
							(mid -0.402042 0.402042)
							(end -0.3302 0.4318)
						)
						(arc
							(start 0.3302 0.4318)
							(mid 0.402042 0.402042)
							(end 0.4318 0.3302)
						)
						(arc
							(start 0.4318 -0.3302)
							(mid 0.402042 -0.402042)
							(end 0.3302 -0.4318)
						)
					)
					(width 0)
					(fill yes)
				)
			)
		)
	)
	(footprint ""
		(layer "F.Cu")
		(at 109.074966 -64.2366)
		(property "Reference" "STP48"
			(at 0 0 0)
			(layer "F.SilkS")
			(hide yes)
			(effects
				(font
					(size 1.27 1.27)
				)
			)
		)
		(property "Value" "TPAD28"
			(at 0.0127 -1.8034 0)
			(unlocked yes)
			(layer "F.Fab")
			(hide yes)
			(effects
				(font
					(size 1.016 1.016)
					(thickness 0.1524)
				)
			)
		)
		(property "Device Type" "TPAD28"
			(at 0.0127 -3.3274 0)
			(unlocked yes)
			(layer "F.Fab")
			(hide yes)
			(effects
				(font
					(size 1.016 1.016)
					(thickness 0.1524)
				)
			)
		)
		(duplicate_pad_numbers_are_jumpers no)
		(fp_poly
			(pts
				(arc
					(start 0.3556 0)
					(mid -0.3556 0)
					(end 0.3556 0)
				)
			)
			(stroke
				(width 0)
				(type default)
			)
			(fill no)
			(layer "F.CrtYd")
		)
		(fp_poly
			(pts
				(arc
					(start 0.6096 0)
					(mid -0.6096 0)
					(end 0.6096 0)
				)
			)
			(stroke
				(width 0)
				(type default)
			)
			(fill no)
			(layer "F.Fab")
		)
		(pad "1" smd circle
			(at 0 0)
			(size 0.7112 0.7112)
			(layers "F.Cu" "F.Mask" "F.Paste")
			(net "JTAG_IOC_TDI")
		)
	)
	(footprint ""
		(layer "F.Cu")
		(at 90.525092 -134.389876)
		(property "Reference" "SU71"
			(at 0 0 0)
			(layer "F.SilkS")
			(hide yes)
			(effects
				(font
					(size 1.27 1.27)
				)
			)
		)
		(property "Value" "SNLVC8T245DGVR-GP"
			(at 0 -11.1252 0)
			(unlocked yes)
			(layer "F.Fab")
			(hide yes)
			(effects
				(font
					(size 1.016 1.016)
					(thickness 0.1524)
				)
			)
		)
		(property "Device Type" "TVSOP24H48"
			(at 0 -12.6492 0)
			(unlocked yes)
			(layer "F.Fab")
			(hide yes)
			(effects
				(font
					(size 1.016 1.016)
					(thickness 0.1524)
				)
			)
		)
		(duplicate_pad_numbers_are_jumpers no)
		(fp_line
			(start -2.9337 -1.397)
			(end -2.9337 1.397)
			(stroke
				(width 0.1524)
				(type default)
			)
			(layer "F.SilkS")
		)
		(fp_line
			(start -2.9337 -0.3683)
			(end -2.5654 0)
			(stroke
				(width 0.1524)
				(type default)
			)
			(layer "F.SilkS")
		)
		(fp_line
			(start -2.9337 1.397)
			(end 2.2987 1.397)
			(stroke
				(width 0.1524)
				(type default)
			)
			(layer "F.SilkS")
		)
		(fp_line
			(start -2.7559 1.397)
			(end -2.7559 3.8354)
			(stroke
				(width 0.508)
				(type default)
			)
			(layer "F.SilkS")
		)
		(fp_line
			(start -2.5654 0)
			(end -2.9337 0.3683)
			(stroke
				(width 0.1524)
				(type default)
			)
			(layer "F.SilkS")
		)
		(fp_line
			(start 2.2987 -1.397)
			(end -2.9337 -1.397)
			(stroke
				(width 0.1524)
				(type default)
			)
			(layer "F.SilkS")
		)
		(fp_line
			(start 2.2987 1.397)
			(end 2.2987 -1.397)
			(stroke
				(width 0.1524)
				(type default)
			)
			(layer "F.SilkS")
		)
		(fp_rect
			(start -3.0099 4.0894)
			(end 3.0099 -4.0894)
			(stroke
				(width 0)
				(type default)
			)
			(fill no)
			(layer "F.CrtYd")
		)
		(fp_poly
			(pts
				(xy -3.0099 -4.0894) (xy 3.0099 -4.0894) (xy 3.0099 4.0894) (xy -3.0099 4.0894)
			)
			(stroke
				(width 0)
				(type default)
			)
			(fill no)
			(layer "F.Fab")
		)
		(pad "1" smd rect
			(at -2.19964 2.8194)
			(size 0.2032 1.524)
			(layers "F.Cu" "F.Mask" "F.Paste")
			(net "P1V8_E")
		)
		(pad "2" smd rect
			(at -1.79959 2.8194)
			(size 0.2032 1.524)
			(layers "F.Cu" "F.Mask" "F.Paste")
			(net "GND")
		)
		(pad "3" smd rect
			(at -1.39954 2.8194)
			(size 0.2032 1.524)
			(layers "F.Cu" "F.Mask" "F.Paste")
			(net "EXP_GPIO_0")
		)
		(pad "4" smd rect
			(at -0.99949 2.8194)
			(size 0.2032 1.524)
			(layers "F.Cu" "F.Mask" "F.Paste")
			(net "EXP_GPIO_1")
		)
		(pad "5" smd rect
			(at -0.59944 2.8194)
			(size 0.2032 1.524)
			(layers "F.Cu" "F.Mask" "F.Paste")
			(net "EXP_GPIO_2")
		)
		(pad "6" smd rect
			(at -0.19939 2.8194)
			(size 0.2032 1.524)
			(layers "F.Cu" "F.Mask" "F.Paste")
			(net "EXP_GPIO_4")
		)
		(pad "7" smd rect
			(at 0.19939 2.8194)
			(size 0.2032 1.524)
			(layers "F.Cu" "F.Mask" "F.Paste")
			(net "EXP_GPIO_5")
		)
		(pad "8" smd rect
			(at 0.59944 2.8194)
			(size 0.2032 1.524)
			(layers "F.Cu" "F.Mask" "F.Paste")
			(net "EXP_GPIO_6")
		)
		(pad "9" smd rect
			(at 0.99949 2.8194)
			(size 0.2032 1.524)
			(layers "F.Cu" "F.Mask" "F.Paste")
			(net "EXP_GPIO_8")
		)
		(pad "10" smd rect
			(at 1.39954 2.8194)
			(size 0.2032 1.524)
			(layers "F.Cu" "F.Mask" "F.Paste")
			(net "EXP_GPIO_13")
		)
		(pad "11" smd rect
			(at 1.79959 2.8194)
			(size 0.2032 1.524)
			(layers "F.Cu" "F.Mask" "F.Paste")
			(net "GND")
		)
		(pad "12" smd rect
			(at 2.19964 2.8194)
			(size 0.2032 1.524)
			(layers "F.Cu" "F.Mask" "F.Paste")
			(net "GND")
		)
		(pad "13" smd rect
			(at 2.19964 -2.8194)
			(size 0.2032 1.524)
			(layers "F.Cu" "F.Mask" "F.Paste")
			(net "GND")
		)
		(pad "14" smd rect
			(at 1.79959 -2.8194)
			(size 0.2032 1.524)
			(layers "F.Cu" "F.Mask" "F.Paste")
			(net "EXP_HDD_PRE_INT_N")
		)
		(pad "15" smd rect
			(at 1.39954 -2.8194)
			(size 0.2032 1.524)
			(layers "F.Cu" "F.Mask" "F.Paste")
			(net "EXP_TRAY_ID")
		)
		(pad "16" smd rect
			(at 0.99949 -2.8194)
			(size 0.2032 1.524)
			(layers "F.Cu" "F.Mask" "F.Paste")
			(net "PEER_1B_2B_HB")
		)
		(pad "17" smd rect
			(at 0.59944 -2.8194)
			(size 0.2032 1.524)
			(layers "F.Cu" "F.Mask" "F.Paste")
			(net "PEER_1A_2A_HB")
		)
		(pad "18" smd rect
			(at 0.19939 -2.8194)
			(size 0.2032 1.524)
			(layers "F.Cu" "F.Mask" "F.Paste")
			(net "PEER_TRAY_R")
		)
		(pad "19" smd rect
			(at -0.19939 -2.8194)
			(size 0.2032 1.524)
			(layers "F.Cu" "F.Mask" "F.Paste")
			(net "EXP_SELF_TRAY")
		)
		(pad "20" smd rect
			(at -0.59944 -2.8194)
			(size 0.2032 1.524)
			(layers "F.Cu" "F.Mask" "F.Paste")
			(net "DPB_HW_REVISION")
		)
		(pad "21" smd rect
			(at -0.99949 -2.8194)
			(size 0.2032 1.524)
			(layers "F.Cu" "F.Mask" "F.Paste")
			(net "FCB_HW_REVISION")
		)
		(pad "22" smd rect
			(at -1.39954 -2.8194)
			(size 0.2032 1.524)
			(layers "F.Cu" "F.Mask" "F.Paste")
			(net "GND")
		)
		(pad "23" smd rect
			(at -1.79959 -2.8194)
			(size 0.2032 1.524)
			(layers "F.Cu" "F.Mask" "F.Paste")
			(net "P3V3_STBY")
		)
		(pad "24" smd rect
			(at -2.19964 -2.8194)
			(size 0.2032 1.524)
			(layers "F.Cu" "F.Mask" "F.Paste")
			(net "P3V3_STBY")
		)
	)
	(footprint ""
		(layer "F.Cu")
		(at 298.704 -191.897)
		(property "Reference" "R614"
			(at 0 0 0)
			(layer "F.SilkS")
			(hide yes)
			(effects
				(font
					(size 1.27 1.27)
				)
			)
		)
		(property "Value" "0R2J-2-GP"
			(at 0.064008 -3.993896 0)
			(unlocked yes)
			(layer "F.Fab")
			(hide yes)
			(effects
				(font
					(size 1.016 1.016)
					(thickness 0.1524)
				)
			)
		)
		(property "Device Type" "R402H16"
			(at 0.064008 -5.517896 0)
			(unlocked yes)
			(layer "F.Fab")
			(hide yes)
			(effects
				(font
					(size 1.016 1.016)
					(thickness 0.1524)
				)
			)
		)
		(duplicate_pad_numbers_are_jumpers no)
		(fp_line
			(start -0.508 -0.9398)
			(end -0.508 0.9398)
			(stroke
				(width 0.1524)
				(type default)
			)
			(layer "F.SilkS")
		)
		(fp_line
			(start 0.508 -0.9398)
			(end -0.508 -0.9398)
			(stroke
				(width 0.1524)
				(type default)
			)
			(layer "F.SilkS")
		)
		(fp_rect
			(start -0.508 0.9398)
			(end 0.508 -0.9398)
			(stroke
				(width 0)
				(type default)
			)
			(fill no)
			(layer "F.CrtYd")
		)
		(fp_rect
			(start -0.508 0.9398)
			(end 0.508 -0.9398)
			(stroke
				(width 0)
				(type default)
			)
			(fill no)
			(layer "F.Fab")
		)
		(pad "1" smd custom
			(at 0 -0.4445)
			(size 0.1397 0.1397)
			(layers "F.Cu" "F.Mask" "F.Paste")
			(net "SVR_ID0")
			(options
				(clearance outline)
				(anchor circle)
			)
			(primitives
				(gr_poly
					(pts
						(arc
							(start -0.1778 -0.2794)
							(mid -0.249642 -0.249642)
							(end -0.2794 -0.1778)
						)
						(arc
							(start -0.2794 0.1778)
							(mid -0.249642 0.249642)
							(end -0.1778 0.2794)
						)
						(arc
							(start 0.1778 0.2794)
							(mid 0.249642 0.249642)
							(end 0.2794 0.1778)
						)
						(arc
							(start 0.2794 -0.1778)
							(mid 0.249642 -0.249642)
							(end 0.1778 -0.2794)
						)
					)
					(width 0)
					(fill yes)
				)
			)
		)
		(pad "2" smd custom
			(at 0 0.4445)
			(size 0.1397 0.1397)
			(layers "F.Cu" "F.Mask" "F.Paste")
			(net "BMC0_TACH14")
			(options
				(clearance outline)
				(anchor circle)
			)
			(primitives
				(gr_poly
					(pts
						(arc
							(start -0.1778 -0.2794)
							(mid -0.249642 -0.249642)
							(end -0.2794 -0.1778)
						)
						(arc
							(start -0.2794 0.1778)
							(mid -0.249642 0.249642)
							(end -0.1778 0.2794)
						)
						(arc
							(start 0.1778 0.2794)
							(mid 0.249642 0.249642)
							(end 0.2794 0.1778)
						)
						(arc
							(start 0.2794 -0.1778)
							(mid 0.249642 -0.249642)
							(end 0.1778 -0.2794)
						)
					)
					(width 0)
					(fill yes)
				)
			)
		)
	)
	(footprint ""
		(layer "F.Cu")
		(at 62.23 -212.217 -90)
		(property "Reference" "R2099"
			(at 0 0 270)
			(layer "F.SilkS")
			(hide yes)
			(effects
				(font
					(size 1.27 1.27)
				)
			)
		)
		(property "Value" "39K2R2F-L-GP"
			(at 0.064008 -3.993896 270)
			(unlocked yes)
			(layer "F.Fab")
			(hide yes)
			(effects
				(font
					(size 1.016 1.016)
					(thickness 0.1524)
				)
			)
		)
		(property "Device Type" "R402H16"
			(at 0.064008 -5.517896 270)
			(unlocked yes)
			(layer "F.Fab")
			(hide yes)
			(effects
				(font
					(size 1.016 1.016)
					(thickness 0.1524)
				)
			)
		)
		(duplicate_pad_numbers_are_jumpers no)
		(fp_line
			(start -0.508 -0.9398)
			(end -0.508 0.9398)
			(stroke
				(width 0.1524)
				(type default)
			)
			(layer "F.SilkS")
		)
		(fp_line
			(start 0.508 -0.9398)
			(end -0.508 -0.9398)
			(stroke
				(width 0.1524)
				(type default)
			)
			(layer "F.SilkS")
		)
		(fp_rect
			(start -0.508 0.9398)
			(end 0.508 -0.9398)
			(stroke
				(width 0)
				(type default)
			)
			(fill no)
			(layer "F.CrtYd")
		)
		(fp_rect
			(start -0.508 0.9398)
			(end 0.508 -0.9398)
			(stroke
				(width 0)
				(type default)
			)
			(fill no)
			(layer "F.Fab")
		)
		(pad "1" smd custom
			(at 0 -0.4445 270)
			(size 0.1397 0.1397)
			(layers "F.Cu" "F.Mask" "F.Paste")
			(net "P12V")
			(options
				(clearance outline)
				(anchor circle)
			)
			(primitives
				(gr_poly
					(pts
						(arc
							(start -0.1778 -0.2794)
							(mid -0.249642 -0.249642)
							(end -0.2794 -0.1778)
						)
						(arc
							(start -0.2794 0.1778)
							(mid -0.249642 0.249642)
							(end -0.1778 0.2794)
						)
						(arc
							(start 0.1778 0.2794)
							(mid 0.249642 0.249642)
							(end 0.2794 0.1778)
						)
						(arc
							(start 0.2794 -0.1778)
							(mid 0.249642 -0.249642)
							(end 0.1778 -0.2794)
						)
					)
					(width 0)
					(fill yes)
				)
			)
		)
		(pad "2" smd custom
			(at 0 0.4445 270)
			(size 0.1397 0.1397)
			(layers "F.Cu" "F.Mask" "F.Paste")
			(net "MB0_P12V_PWRGOOD")
			(options
				(clearance outline)
				(anchor circle)
			)
			(primitives
				(gr_poly
					(pts
						(arc
							(start -0.1778 -0.2794)
							(mid -0.249642 -0.249642)
							(end -0.2794 -0.1778)
						)
						(arc
							(start -0.2794 0.1778)
							(mid -0.249642 0.249642)
							(end -0.1778 0.2794)
						)
						(arc
							(start 0.1778 0.2794)
							(mid 0.249642 0.249642)
							(end 0.2794 0.1778)
						)
						(arc
							(start 0.2794 -0.1778)
							(mid 0.249642 -0.249642)
							(end 0.1778 -0.2794)
						)
					)
					(width 0)
					(fill yes)
				)
			)
		)
	)
	(footprint ""
		(layer "F.Cu")
		(at 266.500864 -232.401872 90)
		(property "Reference" "PC92"
			(at 0 0 90)
			(layer "F.SilkS")
			(hide yes)
			(effects
				(font
					(size 1.27 1.27)
				)
			)
		)
		(property "Value" "SC10U6D3V5KX-1GP"
			(at -0.0762 -6.1214 90)
			(unlocked yes)
			(layer "F.Fab")
			(hide yes)
			(effects
				(font
					(size 1.016 1.016)
					(thickness 0.1524)
				)
			)
		)
		(property "Device Type" "C805H54"
			(at -0.0762 -8.1534 90)
			(unlocked yes)
			(layer "F.Fab")
			(hide yes)
			(effects
				(font
					(size 1.016 1.016)
					(thickness 0.1524)
				)
			)
		)
		(duplicate_pad_numbers_are_jumpers no)
		(fp_line
			(start 0.635 0)
			(end -0.635 0)
			(stroke
				(width 0.508)
				(type default)
			)
			(layer "F.SilkS")
		)
		(fp_rect
			(start -0.9652 1.778)
			(end 0.9652 -1.778)
			(stroke
				(width 0)
				(type default)
			)
			(fill no)
			(layer "F.CrtYd")
		)
		(fp_poly
			(pts
				(xy -0.9652 -1.778) (xy 0.9652 -1.778) (xy 0.9652 1.778) (xy -0.9652 1.778)
			)
			(stroke
				(width 0)
				(type default)
			)
			(fill no)
			(layer "F.Fab")
		)
		(pad "1" smd rect
			(at 0 -0.9652 90)
			(size 1.397 1.143)
			(layers "F.Cu" "F.Mask" "F.Paste")
			(net "TPS74801_P1V26_STBY_IN")
		)
		(pad "2" smd rect
			(at 0 0.9652 90)
			(size 1.397 1.143)
			(layers "F.Cu" "F.Mask" "F.Paste")
			(net "GND")
		)
	)
	(footprint ""
		(layer "F.Cu")
		(at 280.554684 -208.303876)
		(property "Reference" "U25"
			(at 0 0 0)
			(layer "F.SilkS")
			(hide yes)
			(effects
				(font
					(size 1.27 1.27)
				)
			)
		)
		(property "Value" "SN74LVC1G07DCKRG4-2-GP"
			(at -2.3368 -8.6868 0)
			(unlocked yes)
			(layer "F.Fab")
			(hide yes)
			(effects
				(font
					(size 1.016 1.016)
					(thickness 0.1524)
				)
			)
		)
		(property "Device Type" "SC70-5H44"
			(at -2.3114 -10.414 0)
			(unlocked yes)
			(layer "F.Fab")
			(hide yes)
			(effects
				(font
					(size 1.016 1.016)
					(thickness 0.1524)
				)
			)
		)
		(duplicate_pad_numbers_are_jumpers no)
		(fp_line
			(start -1.27 -1.7018)
			(end 1.27 -1.7018)
			(stroke
				(width 0.1524)
				(type default)
			)
			(layer "F.SilkS")
		)
		(fp_line
			(start -1.27 1.7018)
			(end -1.27 -1.7018)
			(stroke
				(width 0.1524)
				(type default)
			)
			(layer "F.SilkS")
		)
		(fp_line
			(start 0.6604 -1.8034)
			(end 1.3843 -1.8034)
			(stroke
				(width 0.3302)
				(type default)
			)
			(layer "F.SilkS")
		)
		(fp_line
			(start 1.27 -1.7018)
			(end 1.27 1.7018)
			(stroke
				(width 0.1524)
				(type default)
			)
			(layer "F.SilkS")
		)
		(fp_line
			(start 1.27 1.7018)
			(end -1.27 1.7018)
			(stroke
				(width 0.1524)
				(type default)
			)
			(layer "F.SilkS")
		)
		(fp_line
			(start 1.3843 -1.8034)
			(end 1.3843 -1.1176)
			(stroke
				(width 0.3302)
				(type default)
			)
			(layer "F.SilkS")
		)
		(fp_rect
			(start -1.524 1.9558)
			(end 1.524 -1.9558)
			(stroke
				(width 0)
				(type default)
			)
			(fill no)
			(layer "F.CrtYd")
		)
		(fp_poly
			(pts
				(xy -1.524 -1.9558) (xy 1.524 -1.9558) (xy 1.524 1.9558) (xy -1.524 1.9558)
			)
			(stroke
				(width 0)
				(type default)
			)
			(fill no)
			(layer "F.Fab")
		)
		(pad "1" smd rect
			(at 0.65024 -0.8255)
			(size 0.4064 1.2192)
			(layers "F.Cu" "F.Mask" "F.Paste")
			(net "Net_1371")
		)
		(pad "2" smd rect
			(at 0 -0.8255)
			(size 0.4064 1.2192)
			(layers "F.Cu" "F.Mask" "F.Paste")
			(net "FM_BMC_RESET_N")
		)
		(pad "3" smd rect
			(at -0.65024 -0.8255)
			(size 0.4064 1.2192)
			(layers "F.Cu" "F.Mask" "F.Paste")
			(net "GND")
		)
		(pad "4" smd rect
			(at -0.65024 0.8255)
			(size 0.4064 1.2192)
			(layers "F.Cu" "F.Mask" "F.Paste")
			(net "RST_BMC_DDR3_R_N")
		)
		(pad "5" smd rect
			(at 0.65024 0.8255)
			(size 0.4064 1.2192)
			(layers "F.Cu" "F.Mask" "F.Paste")
			(net "P3V3_STBY")
		)
	)
	(footprint ""
		(layer "F.Cu")
		(at 328.667872 -167.966136)
		(property "Reference" "R323"
			(at 0 0 0)
			(layer "F.SilkS")
			(hide yes)
			(effects
				(font
					(size 1.27 1.27)
				)
			)
		)
		(property "Value" "0R2J-2-GP"
			(at 0.064008 -3.993896 0)
			(unlocked yes)
			(layer "F.Fab")
			(hide yes)
			(effects
				(font
					(size 1.016 1.016)
					(thickness 0.1524)
				)
			)
		)
		(property "Device Type" "R402H16"
			(at 0.064008 -5.517896 0)
			(unlocked yes)
			(layer "F.Fab")
			(hide yes)
			(effects
				(font
					(size 1.016 1.016)
					(thickness 0.1524)
				)
			)
		)
		(duplicate_pad_numbers_are_jumpers no)
		(fp_line
			(start -0.508 -0.9398)
			(end -0.508 0.9398)
			(stroke
				(width 0.1524)
				(type default)
			)
			(layer "F.SilkS")
		)
		(fp_line
			(start 0.508 -0.9398)
			(end -0.508 -0.9398)
			(stroke
				(width 0.1524)
				(type default)
			)
			(layer "F.SilkS")
		)
		(fp_rect
			(start -0.508 0.9398)
			(end 0.508 -0.9398)
			(stroke
				(width 0)
				(type default)
			)
			(fill no)
			(layer "F.CrtYd")
		)
		(fp_rect
			(start -0.508 0.9398)
			(end 0.508 -0.9398)
			(stroke
				(width 0)
				(type default)
			)
			(fill no)
			(layer "F.Fab")
		)
		(pad "1" smd custom
			(at 0 -0.4445)
			(size 0.1397 0.1397)
			(layers "F.Cu" "F.Mask" "F.Paste")
			(net "CPU_S_RXD")
			(options
				(clearance outline)
				(anchor circle)
			)
			(primitives
				(gr_poly
					(pts
						(arc
							(start -0.1778 -0.2794)
							(mid -0.249642 -0.249642)
							(end -0.2794 -0.1778)
						)
						(arc
							(start -0.2794 0.1778)
							(mid -0.249642 0.249642)
							(end -0.1778 0.2794)
						)
						(arc
							(start 0.1778 0.2794)
							(mid 0.249642 0.249642)
							(end 0.2794 0.1778)
						)
						(arc
							(start 0.2794 -0.1778)
							(mid 0.249642 -0.249642)
							(end 0.1778 -0.2794)
						)
					)
					(width 0)
					(fill yes)
				)
			)
		)
		(pad "2" smd custom
			(at 0 0.4445)
			(size 0.1397 0.1397)
			(layers "F.Cu" "F.Mask" "F.Paste")
			(net "CPU_UART_RX_R")
			(options
				(clearance outline)
				(anchor circle)
			)
			(primitives
				(gr_poly
					(pts
						(arc
							(start -0.1778 -0.2794)
							(mid -0.249642 -0.249642)
							(end -0.2794 -0.1778)
						)
						(arc
							(start -0.2794 0.1778)
							(mid -0.249642 0.249642)
							(end -0.1778 0.2794)
						)
						(arc
							(start 0.1778 0.2794)
							(mid 0.249642 0.249642)
							(end 0.2794 0.1778)
						)
						(arc
							(start 0.2794 -0.1778)
							(mid 0.249642 -0.249642)
							(end 0.1778 -0.2794)
						)
					)
					(width 0)
					(fill yes)
				)
			)
		)
	)
	(footprint ""
		(layer "F.Cu")
		(at 316.484 -193.548 -90)
		(property "Reference" "R799"
			(at 0 0 270)
			(layer "F.SilkS")
			(hide yes)
			(effects
				(font
					(size 1.27 1.27)
				)
			)
		)
		(property "Value" "4K7R2F-GP"
			(at 0.064008 -3.993896 270)
			(unlocked yes)
			(layer "F.Fab")
			(hide yes)
			(effects
				(font
					(size 1.016 1.016)
					(thickness 0.1524)
				)
			)
		)
		(property "Device Type" "R402H16"
			(at 0.064008 -5.517896 270)
			(unlocked yes)
			(layer "F.Fab")
			(hide yes)
			(effects
				(font
					(size 1.016 1.016)
					(thickness 0.1524)
				)
			)
		)
		(duplicate_pad_numbers_are_jumpers no)
		(fp_line
			(start -0.508 -0.9398)
			(end -0.508 0.9398)
			(stroke
				(width 0.1524)
				(type default)
			)
			(layer "F.SilkS")
		)
		(fp_line
			(start 0.508 -0.9398)
			(end -0.508 -0.9398)
			(stroke
				(width 0.1524)
				(type default)
			)
			(layer "F.SilkS")
		)
		(fp_rect
			(start -0.508 0.9398)
			(end 0.508 -0.9398)
			(stroke
				(width 0)
				(type default)
			)
			(fill no)
			(layer "F.CrtYd")
		)
		(fp_rect
			(start -0.508 0.9398)
			(end 0.508 -0.9398)
			(stroke
				(width 0)
				(type default)
			)
			(fill no)
			(layer "F.Fab")
		)
		(pad "1" smd custom
			(at 0 -0.4445 270)
			(size 0.1397 0.1397)
			(layers "F.Cu" "F.Mask" "F.Paste")
			(net "P3V3_STBY")
			(options
				(clearance outline)
				(anchor circle)
			)
			(primitives
				(gr_poly
					(pts
						(arc
							(start -0.1778 -0.2794)
							(mid -0.249642 -0.249642)
							(end -0.2794 -0.1778)
						)
						(arc
							(start -0.2794 0.1778)
							(mid -0.249642 0.249642)
							(end -0.1778 0.2794)
						)
						(arc
							(start 0.1778 0.2794)
							(mid 0.249642 0.249642)
							(end 0.2794 0.1778)
						)
						(arc
							(start 0.2794 -0.1778)
							(mid 0.249642 -0.249642)
							(end 0.1778 -0.2794)
						)
					)
					(width 0)
					(fill yes)
				)
			)
		)
		(pad "2" smd custom
			(at 0 0.4445 270)
			(size 0.1397 0.1397)
			(layers "F.Cu" "F.Mask" "F.Paste")
			(net "JTAG_BMC_TDO")
			(options
				(clearance outline)
				(anchor circle)
			)
			(primitives
				(gr_poly
					(pts
						(arc
							(start -0.1778 -0.2794)
							(mid -0.249642 -0.249642)
							(end -0.2794 -0.1778)
						)
						(arc
							(start -0.2794 0.1778)
							(mid -0.249642 0.249642)
							(end -0.1778 0.2794)
						)
						(arc
							(start 0.1778 0.2794)
							(mid 0.249642 0.249642)
							(end 0.2794 0.1778)
						)
						(arc
							(start 0.2794 -0.1778)
							(mid 0.249642 -0.249642)
							(end 0.1778 -0.2794)
						)
					)
					(width 0)
					(fill yes)
				)
			)
		)
	)
	(footprint ""
		(layer "F.Cu")
		(at 209.042 -221.742 -90)
		(property "Reference" "R686"
			(at 0 0 270)
			(layer "F.SilkS")
			(hide yes)
			(effects
				(font
					(size 1.27 1.27)
				)
			)
		)
		(property "Value" "0R2J-2-GP"
			(at 0.064008 -3.993896 270)
			(unlocked yes)
			(layer "F.Fab")
			(hide yes)
			(effects
				(font
					(size 1.016 1.016)
					(thickness 0.1524)
				)
			)
		)
		(property "Device Type" "R402H16"
			(at 0.064008 -5.517896 270)
			(unlocked yes)
			(layer "F.Fab")
			(hide yes)
			(effects
				(font
					(size 1.016 1.016)
					(thickness 0.1524)
				)
			)
		)
		(duplicate_pad_numbers_are_jumpers no)
		(fp_line
			(start -0.508 -0.9398)
			(end -0.508 0.9398)
			(stroke
				(width 0.1524)
				(type default)
			)
			(layer "F.SilkS")
		)
		(fp_line
			(start 0.508 -0.9398)
			(end -0.508 -0.9398)
			(stroke
				(width 0.1524)
				(type default)
			)
			(layer "F.SilkS")
		)
		(fp_rect
			(start -0.508 0.9398)
			(end 0.508 -0.9398)
			(stroke
				(width 0)
				(type default)
			)
			(fill no)
			(layer "F.CrtYd")
		)
		(fp_rect
			(start -0.508 0.9398)
			(end 0.508 -0.9398)
			(stroke
				(width 0)
				(type default)
			)
			(fill no)
			(layer "F.Fab")
		)
		(pad "1" smd custom
			(at 0 -0.4445 270)
			(size 0.1397 0.1397)
			(layers "F.Cu" "F.Mask" "F.Paste")
			(net "OE_BMC_RSET")
			(options
				(clearance outline)
				(anchor circle)
			)
			(primitives
				(gr_poly
					(pts
						(arc
							(start -0.1778 -0.2794)
							(mid -0.249642 -0.249642)
							(end -0.2794 -0.1778)
						)
						(arc
							(start -0.2794 0.1778)
							(mid -0.249642 0.249642)
							(end -0.1778 0.2794)
						)
						(arc
							(start 0.1778 0.2794)
							(mid 0.249642 0.249642)
							(end 0.2794 0.1778)
						)
						(arc
							(start 0.2794 -0.1778)
							(mid 0.249642 -0.249642)
							(end 0.1778 -0.2794)
						)
					)
					(width 0)
					(fill yes)
				)
			)
		)
		(pad "2" smd custom
			(at 0 0.4445 270)
			(size 0.1397 0.1397)
			(layers "F.Cu" "F.Mask" "F.Paste")
			(net "BMC_EN_CPU_RESET_CONTROL")
			(options
				(clearance outline)
				(anchor circle)
			)
			(primitives
				(gr_poly
					(pts
						(arc
							(start -0.1778 -0.2794)
							(mid -0.249642 -0.249642)
							(end -0.2794 -0.1778)
						)
						(arc
							(start -0.2794 0.1778)
							(mid -0.249642 0.249642)
							(end -0.1778 0.2794)
						)
						(arc
							(start 0.1778 0.2794)
							(mid 0.249642 0.249642)
							(end 0.2794 0.1778)
						)
						(arc
							(start 0.2794 -0.1778)
							(mid 0.249642 -0.249642)
							(end 0.1778 -0.2794)
						)
					)
					(width 0)
					(fill yes)
				)
			)
		)
	)
	(footprint ""
		(layer "F.Cu")
		(at 300.736 -191.897)
		(property "Reference" "R584"
			(at 0 0 0)
			(layer "F.SilkS")
			(hide yes)
			(effects
				(font
					(size 1.27 1.27)
				)
			)
		)
		(property "Value" "0R2J-2-GP"
			(at 0.064008 -3.993896 0)
			(unlocked yes)
			(layer "F.Fab")
			(hide yes)
			(effects
				(font
					(size 1.016 1.016)
					(thickness 0.1524)
				)
			)
		)
		(property "Device Type" "R402H16"
			(at 0.064008 -5.517896 0)
			(unlocked yes)
			(layer "F.Fab")
			(hide yes)
			(effects
				(font
					(size 1.016 1.016)
					(thickness 0.1524)
				)
			)
		)
		(duplicate_pad_numbers_are_jumpers no)
		(fp_line
			(start -0.508 -0.9398)
			(end -0.508 0.9398)
			(stroke
				(width 0.1524)
				(type default)
			)
			(layer "F.SilkS")
		)
		(fp_line
			(start 0.508 -0.9398)
			(end -0.508 -0.9398)
			(stroke
				(width 0.1524)
				(type default)
			)
			(layer "F.SilkS")
		)
		(fp_rect
			(start -0.508 0.9398)
			(end 0.508 -0.9398)
			(stroke
				(width 0)
				(type default)
			)
			(fill no)
			(layer "F.CrtYd")
		)
		(fp_rect
			(start -0.508 0.9398)
			(end 0.508 -0.9398)
			(stroke
				(width 0)
				(type default)
			)
			(fill no)
			(layer "F.Fab")
		)
		(pad "1" smd custom
			(at 0 -0.4445)
			(size 0.1397 0.1397)
			(layers "F.Cu" "F.Mask" "F.Paste")
			(net "UART COUNT")
			(options
				(clearance outline)
				(anchor circle)
			)
			(primitives
				(gr_poly
					(pts
						(arc
							(start -0.1778 -0.2794)
							(mid -0.249642 -0.249642)
							(end -0.2794 -0.1778)
						)
						(arc
							(start -0.2794 0.1778)
							(mid -0.249642 0.249642)
							(end -0.1778 0.2794)
						)
						(arc
							(start 0.1778 0.2794)
							(mid 0.249642 0.249642)
							(end 0.2794 0.1778)
						)
						(arc
							(start 0.2794 -0.1778)
							(mid 0.249642 -0.249642)
							(end 0.1778 -0.2794)
						)
					)
					(width 0)
					(fill yes)
				)
			)
		)
		(pad "2" smd custom
			(at 0 0.4445)
			(size 0.1397 0.1397)
			(layers "F.Cu" "F.Mask" "F.Paste")
			(net "BMC0_TACH13")
			(options
				(clearance outline)
				(anchor circle)
			)
			(primitives
				(gr_poly
					(pts
						(arc
							(start -0.1778 -0.2794)
							(mid -0.249642 -0.249642)
							(end -0.2794 -0.1778)
						)
						(arc
							(start -0.2794 0.1778)
							(mid -0.249642 0.249642)
							(end -0.1778 0.2794)
						)
						(arc
							(start 0.1778 0.2794)
							(mid 0.249642 0.249642)
							(end 0.2794 0.1778)
						)
						(arc
							(start 0.2794 -0.1778)
							(mid 0.249642 -0.249642)
							(end 0.1778 -0.2794)
						)
					)
					(width 0)
					(fill yes)
				)
			)
		)
	)
	(footprint ""
		(layer "F.Cu")
		(at 301.371 -152.146 180)
		(property "Reference" "R528"
			(at 0 0 180)
			(layer "F.SilkS")
			(hide yes)
			(effects
				(font
					(size 1.27 1.27)
				)
			)
		)
		(property "Value" "33R2J-2-GP"
			(at 0.064008 -3.993896 180)
			(unlocked yes)
			(layer "F.Fab")
			(hide yes)
			(effects
				(font
					(size 1.016 1.016)
					(thickness 0.1524)
				)
			)
		)
		(property "Device Type" "R402H16"
			(at 0.064008 -5.517896 180)
			(unlocked yes)
			(layer "F.Fab")
			(hide yes)
			(effects
				(font
					(size 1.016 1.016)
					(thickness 0.1524)
				)
			)
		)
		(duplicate_pad_numbers_are_jumpers no)
		(fp_line
			(start 0.508 -0.9398)
			(end -0.508 -0.9398)
			(stroke
				(width 0.1524)
				(type default)
			)
			(layer "F.SilkS")
		)
		(fp_line
			(start -0.508 -0.9398)
			(end -0.508 0.9398)
			(stroke
				(width 0.1524)
				(type default)
			)
			(layer "F.SilkS")
		)
		(fp_rect
			(start -0.508 0.9398)
			(end 0.508 -0.9398)
			(stroke
				(width 0)
				(type default)
			)
			(fill no)
			(layer "F.CrtYd")
		)
		(fp_rect
			(start -0.508 0.9398)
			(end 0.508 -0.9398)
			(stroke
				(width 0)
				(type default)
			)
			(fill no)
			(layer "F.Fab")
		)
		(pad "1" smd custom
			(at 0 -0.4445 180)
			(size 0.1397 0.1397)
			(layers "F.Cu" "F.Mask" "F.Paste")
			(net "50M_CLK_OUT")
			(options
				(clearance outline)
				(anchor circle)
			)
			(primitives
				(gr_poly
					(pts
						(arc
							(start -0.1778 -0.2794)
							(mid -0.249642 -0.249642)
							(end -0.2794 -0.1778)
						)
						(arc
							(start -0.2794 0.1778)
							(mid -0.249642 0.249642)
							(end -0.1778 0.2794)
						)
						(arc
							(start 0.1778 0.2794)
							(mid 0.249642 0.249642)
							(end 0.2794 0.1778)
						)
						(arc
							(start 0.2794 -0.1778)
							(mid 0.249642 -0.249642)
							(end 0.1778 -0.2794)
						)
					)
					(width 0)
					(fill yes)
				)
			)
		)
		(pad "2" smd custom
			(at 0 0.4445 180)
			(size 0.1397 0.1397)
			(layers "F.Cu" "F.Mask" "F.Paste")
			(net "50M_CLK_OUT_R")
			(options
				(clearance outline)
				(anchor circle)
			)
			(primitives
				(gr_poly
					(pts
						(arc
							(start -0.1778 -0.2794)
							(mid -0.249642 -0.249642)
							(end -0.2794 -0.1778)
						)
						(arc
							(start -0.2794 0.1778)
							(mid -0.249642 0.249642)
							(end -0.1778 0.2794)
						)
						(arc
							(start 0.1778 0.2794)
							(mid 0.249642 0.249642)
							(end 0.2794 0.1778)
						)
						(arc
							(start 0.2794 -0.1778)
							(mid 0.249642 -0.249642)
							(end 0.1778 -0.2794)
						)
					)
					(width 0)
					(fill yes)
				)
			)
		)
	)
	(footprint ""
		(layer "F.Cu")
		(at 52.08397 -137.795 90)
		(property "Reference" "SU80"
			(at 0 0 90)
			(layer "F.SilkS")
			(hide yes)
			(effects
				(font
					(size 1.27 1.27)
				)
			)
		)
		(property "Value" "SN74LVC1G08DCKR-GP"
			(at -2.3368 -8.6868 90)
			(unlocked yes)
			(layer "F.Fab")
			(hide yes)
			(effects
				(font
					(size 1.016 1.016)
					(thickness 0.1524)
				)
			)
		)
		(property "Device Type" "SC70-5H44"
			(at -2.3114 -10.414 90)
			(unlocked yes)
			(layer "F.Fab")
			(hide yes)
			(effects
				(font
					(size 1.016 1.016)
					(thickness 0.1524)
				)
			)
		)
		(duplicate_pad_numbers_are_jumpers no)
		(fp_line
			(start 1.3843 -1.8034)
			(end 1.3843 -1.1176)
			(stroke
				(width 0.3302)
				(type default)
			)
			(layer "F.SilkS")
		)
		(fp_line
			(start 0.6604 -1.8034)
			(end 1.3843 -1.8034)
			(stroke
				(width 0.3302)
				(type default)
			)
			(layer "F.SilkS")
		)
		(fp_line
			(start 1.27 -1.7018)
			(end 1.27 1.7018)
			(stroke
				(width 0.1524)
				(type default)
			)
			(layer "F.SilkS")
		)
		(fp_line
			(start -1.27 -1.7018)
			(end 1.27 -1.7018)
			(stroke
				(width 0.1524)
				(type default)
			)
			(layer "F.SilkS")
		)
		(fp_line
			(start 1.27 1.7018)
			(end -1.27 1.7018)
			(stroke
				(width 0.1524)
				(type default)
			)
			(layer "F.SilkS")
		)
		(fp_line
			(start -1.27 1.7018)
			(end -1.27 -1.7018)
			(stroke
				(width 0.1524)
				(type default)
			)
			(layer "F.SilkS")
		)
		(fp_rect
			(start -1.524 1.9558)
			(end 1.524 -1.9558)
			(stroke
				(width 0)
				(type default)
			)
			(fill no)
			(layer "F.CrtYd")
		)
		(fp_poly
			(pts
				(xy -1.524 -1.9558) (xy 1.524 -1.9558) (xy 1.524 1.9558) (xy -1.524 1.9558)
			)
			(stroke
				(width 0)
				(type default)
			)
			(fill no)
			(layer "F.Fab")
		)
		(pad "1" smd rect
			(at 0.65024 -0.8255 90)
			(size 0.4064 1.2192)
			(layers "F.Cu" "F.Mask" "F.Paste")
			(net "EXP_RST_1")
		)
		(pad "2" smd rect
			(at 0 -0.8255 90)
			(size 0.4064 1.2192)
			(layers "F.Cu" "F.Mask" "F.Paste")
			(net "EXP_RST_2")
		)
		(pad "3" smd rect
			(at -0.65024 -0.8255 90)
			(size 0.4064 1.2192)
			(layers "F.Cu" "F.Mask" "F.Paste")
			(net "GND")
		)
		(pad "4" smd rect
			(at -0.65024 0.8255 90)
			(size 0.4064 1.2192)
			(layers "F.Cu" "F.Mask" "F.Paste")
			(net "RESET_N")
		)
		(pad "5" smd rect
			(at 0.65024 0.8255 90)
			(size 0.4064 1.2192)
			(layers "F.Cu" "F.Mask" "F.Paste")
			(net "P1V8_E")
		)
	)
	(footprint ""
		(layer "F.Cu")
		(at 163.417504 -24.184356 180)
		(property "Reference" "R418"
			(at 0 0 180)
			(layer "F.SilkS")
			(hide yes)
			(effects
				(font
					(size 1.27 1.27)
				)
			)
		)
		(property "Value" "0R2J-2-GP"
			(at 0.064008 -3.993896 180)
			(unlocked yes)
			(layer "F.Fab")
			(hide yes)
			(effects
				(font
					(size 1.016 1.016)
					(thickness 0.1524)
				)
			)
		)
		(property "Device Type" "R402H16"
			(at 0.064008 -5.517896 180)
			(unlocked yes)
			(layer "F.Fab")
			(hide yes)
			(effects
				(font
					(size 1.016 1.016)
					(thickness 0.1524)
				)
			)
		)
		(duplicate_pad_numbers_are_jumpers no)
		(fp_line
			(start 0.508 -0.9398)
			(end -0.508 -0.9398)
			(stroke
				(width 0.1524)
				(type default)
			)
			(layer "F.SilkS")
		)
		(fp_line
			(start -0.508 -0.9398)
			(end -0.508 0.9398)
			(stroke
				(width 0.1524)
				(type default)
			)
			(layer "F.SilkS")
		)
		(fp_rect
			(start -0.508 0.9398)
			(end 0.508 -0.9398)
			(stroke
				(width 0)
				(type default)
			)
			(fill no)
			(layer "F.CrtYd")
		)
		(fp_rect
			(start -0.508 0.9398)
			(end 0.508 -0.9398)
			(stroke
				(width 0)
				(type default)
			)
			(fill no)
			(layer "F.Fab")
		)
		(pad "1" smd custom
			(at 0 -0.4445 180)
			(size 0.1397 0.1397)
			(layers "F.Cu" "F.Mask" "F.Paste")
			(net "TP_LAN_6")
			(options
				(clearance outline)
				(anchor circle)
			)
			(primitives
				(gr_poly
					(pts
						(arc
							(start -0.1778 -0.2794)
							(mid -0.249642 -0.249642)
							(end -0.2794 -0.1778)
						)
						(arc
							(start -0.2794 0.1778)
							(mid -0.249642 0.249642)
							(end -0.1778 0.2794)
						)
						(arc
							(start 0.1778 0.2794)
							(mid 0.249642 0.249642)
							(end 0.2794 0.1778)
						)
						(arc
							(start 0.2794 -0.1778)
							(mid 0.249642 -0.249642)
							(end 0.1778 -0.2794)
						)
					)
					(width 0)
					(fill yes)
				)
			)
		)
		(pad "2" smd custom
			(at 0 0.4445 180)
			(size 0.1397 0.1397)
			(layers "F.Cu" "F.Mask" "F.Paste")
			(net "GND")
			(options
				(clearance outline)
				(anchor circle)
			)
			(primitives
				(gr_poly
					(pts
						(arc
							(start -0.1778 -0.2794)
							(mid -0.249642 -0.249642)
							(end -0.2794 -0.1778)
						)
						(arc
							(start -0.2794 0.1778)
							(mid -0.249642 0.249642)
							(end -0.1778 0.2794)
						)
						(arc
							(start 0.1778 0.2794)
							(mid 0.249642 0.249642)
							(end 0.2794 0.1778)
						)
						(arc
							(start 0.2794 -0.1778)
							(mid 0.249642 -0.249642)
							(end 0.1778 -0.2794)
						)
					)
					(width 0)
					(fill yes)
				)
			)
		)
	)
	(footprint ""
		(layer "F.Cu")
		(at 175.90897 -67.945)
		(property "Reference" "TP157"
			(at 0 0 0)
			(layer "F.SilkS")
			(hide yes)
			(effects
				(font
					(size 1.27 1.27)
				)
			)
		)
		(property "Value" "TPAD28"
			(at 0.0127 -1.8034 0)
			(unlocked yes)
			(layer "F.Fab")
			(hide yes)
			(effects
				(font
					(size 1.016 1.016)
					(thickness 0.1524)
				)
			)
		)
		(property "Device Type" "TPAD28"
			(at 0.0127 -3.3274 0)
			(unlocked yes)
			(layer "F.Fab")
			(hide yes)
			(effects
				(font
					(size 1.016 1.016)
					(thickness 0.1524)
				)
			)
		)
		(duplicate_pad_numbers_are_jumpers no)
		(fp_poly
			(pts
				(arc
					(start 0.3556 0)
					(mid -0.3556 0)
					(end 0.3556 0)
				)
			)
			(stroke
				(width 0)
				(type default)
			)
			(fill no)
			(layer "F.CrtYd")
		)
		(fp_poly
			(pts
				(arc
					(start 0.6096 0)
					(mid -0.6096 0)
					(end 0.6096 0)
				)
			)
			(stroke
				(width 0)
				(type default)
			)
			(fill no)
			(layer "F.Fab")
		)
		(pad "1" smd circle
			(at 0 0)
			(size 0.7112 0.7112)
			(layers "F.Cu" "F.Mask" "F.Paste")
			(net "TP_MSB_B40")
		)
	)
	(footprint ""
		(layer "F.Cu")
		(at 289.56 -208.915 90)
		(property "Reference" "C177"
			(at 0 0 90)
			(layer "F.SilkS")
			(hide yes)
			(effects
				(font
					(size 1.27 1.27)
				)
			)
		)
		(property "Value" "SCD01U25V2KX-3GP"
			(at 1.1811 -2.7051 90)
			(unlocked yes)
			(layer "F.Fab")
			(hide yes)
			(effects
				(font
					(size 1.016 1.016)
					(thickness 0.1524)
				)
			)
		)
		(property "Device Type" "C402H22"
			(at 1.1811 -4.2291 90)
			(unlocked yes)
			(layer "F.Fab")
			(hide yes)
			(effects
				(font
					(size 1.016 1.016)
					(thickness 0.1524)
				)
			)
		)
		(duplicate_pad_numbers_are_jumpers no)
		(fp_rect
			(start -0.4318 0.9525)
			(end 0.4318 -0.9525)
			(stroke
				(width 0)
				(type default)
			)
			(fill no)
			(layer "F.CrtYd")
		)
		(fp_rect
			(start -0.4318 0.9525)
			(end 0.4318 -0.9525)
			(stroke
				(width 0)
				(type default)
			)
			(fill no)
			(layer "F.Fab")
		)
		(pad "1" smd custom
			(at 0 -0.4445 90)
			(size 0.1524 0.1524)
			(layers "F.Cu" "F.Mask" "F.Paste")
			(net "P1V53_STBY")
			(options
				(clearance outline)
				(anchor circle)
			)
			(primitives
				(gr_poly
					(pts
						(arc
							(start 0.3048 -0.2032)
							(mid 0.275042 -0.275042)
							(end 0.2032 -0.3048)
						)
						(arc
							(start -0.2032 -0.3048)
							(mid -0.275042 -0.275042)
							(end -0.3048 -0.2032)
						)
						(arc
							(start -0.3048 0.2032)
							(mid -0.275042 0.275042)
							(end -0.2032 0.3048)
						)
						(arc
							(start 0.2032 0.3048)
							(mid 0.275042 0.275042)
							(end 0.3048 0.2032)
						)
					)
					(width 0)
					(fill yes)
				)
			)
		)
		(pad "2" smd custom
			(at 0 0.4445 90)
			(size 0.1524 0.1524)
			(layers "F.Cu" "F.Mask" "F.Paste")
			(net "DDR_VREF")
			(options
				(clearance outline)
				(anchor circle)
			)
			(primitives
				(gr_poly
					(pts
						(arc
							(start 0.3048 -0.2032)
							(mid 0.275042 -0.275042)
							(end 0.2032 -0.3048)
						)
						(arc
							(start -0.2032 -0.3048)
							(mid -0.275042 -0.275042)
							(end -0.3048 -0.2032)
						)
						(arc
							(start -0.3048 0.2032)
							(mid -0.275042 0.275042)
							(end -0.2032 0.3048)
						)
						(arc
							(start 0.2032 0.3048)
							(mid 0.275042 0.275042)
							(end 0.3048 0.2032)
						)
					)
					(width 0)
					(fill yes)
				)
			)
		)
	)
	(footprint ""
		(layer "F.Cu")
		(at 144.907 -100.076 90)
		(property "Reference" "SC1158"
			(at 0 0 90)
			(layer "F.SilkS")
			(hide yes)
			(effects
				(font
					(size 1.27 1.27)
				)
			)
		)
		(property "Value" "SC100U6D3V0MX-2GP"
			(at -0.00254 -4.78536 90)
			(unlocked yes)
			(layer "F.Fab")
			(hide yes)
			(effects
				(font
					(size 1.016 1.016)
					(thickness 0.1524)
				)
			)
		)
		(property "Device Type" "C1210H107"
			(at -0.00254 -6.38048 90)
			(unlocked yes)
			(layer "F.Fab")
			(hide yes)
			(effects
				(font
					(size 1.016 1.016)
					(thickness 0.1524)
				)
			)
		)
		(duplicate_pad_numbers_are_jumpers no)
		(fp_line
			(start 1.5748 -2.3368)
			(end -1.5748 -2.3368)
			(stroke
				(width 0.1524)
				(type default)
			)
			(layer "F.SilkS")
		)
		(fp_line
			(start -1.5748 -2.3368)
			(end -1.5748 -0.762)
			(stroke
				(width 0.1524)
				(type default)
			)
			(layer "F.SilkS")
		)
		(fp_line
			(start 1.5748 -0.762)
			(end 1.5748 -2.3368)
			(stroke
				(width 0.1524)
				(type default)
			)
			(layer "F.SilkS")
		)
		(fp_line
			(start -1.5748 0.762)
			(end -1.5748 2.3368)
			(stroke
				(width 0.1524)
				(type default)
			)
			(layer "F.SilkS")
		)
		(fp_line
			(start 1.5748 2.3368)
			(end 1.5748 0.762)
			(stroke
				(width 0.1524)
				(type default)
			)
			(layer "F.SilkS")
		)
		(fp_line
			(start -1.5748 2.3368)
			(end 1.5748 2.3368)
			(stroke
				(width 0.1524)
				(type default)
			)
			(layer "F.SilkS")
		)
		(fp_rect
			(start -1.651 2.413)
			(end 1.651 -2.413)
			(stroke
				(width 0)
				(type default)
			)
			(fill no)
			(layer "F.CrtYd")
		)
		(fp_poly
			(pts
				(xy 1.651 2.413) (xy 1.651 -2.413) (xy -1.651 -2.413) (xy -1.651 2.413)
			)
			(stroke
				(width 0)
				(type default)
			)
			(fill no)
			(layer "F.Fab")
		)
		(pad "1" smd rect
			(at 0 -1.4732 90)
			(size 2.794 1.397)
			(layers "F.Cu" "F.Mask" "F.Paste")
			(net "GND")
		)
		(pad "2" smd rect
			(at 0 1.4732 90)
			(size 2.794 1.397)
			(layers "F.Cu" "F.Mask" "F.Paste")
			(net "GB_VDDA")
		)
	)
	(footprint ""
		(layer "F.Cu")
		(at 144.653 -109.601 -90)
		(property "Reference" "SC1171"
			(at 0 0 270)
			(layer "F.SilkS")
			(hide yes)
			(effects
				(font
					(size 1.27 1.27)
				)
			)
		)
		(property "Value" "SC22U6D3V5MX-2GP"
			(at -0.0762 -6.1214 270)
			(unlocked yes)
			(layer "F.Fab")
			(hide yes)
			(effects
				(font
					(size 1.016 1.016)
					(thickness 0.1524)
				)
			)
		)
		(property "Device Type" "C805H58"
			(at -0.0762 -8.1534 270)
			(unlocked yes)
			(layer "F.Fab")
			(hide yes)
			(effects
				(font
					(size 1.016 1.016)
					(thickness 0.1524)
				)
			)
		)
		(duplicate_pad_numbers_are_jumpers no)
		(fp_line
			(start 0.635 0)
			(end -0.635 0)
			(stroke
				(width 0.508)
				(type default)
			)
			(layer "F.SilkS")
		)
		(fp_rect
			(start -0.9652 1.778)
			(end 0.9652 -1.778)
			(stroke
				(width 0)
				(type default)
			)
			(fill no)
			(layer "F.CrtYd")
		)
		(fp_poly
			(pts
				(xy -0.9652 -1.778) (xy 0.9652 -1.778) (xy 0.9652 1.778) (xy -0.9652 1.778)
			)
			(stroke
				(width 0)
				(type default)
			)
			(fill no)
			(layer "F.Fab")
		)
		(pad "1" smd rect
			(at 0 -0.9652 270)
			(size 1.397 1.143)
			(layers "F.Cu" "F.Mask" "F.Paste")
			(net "GB_VDDA")
		)
		(pad "2" smd rect
			(at 0 0.9652 270)
			(size 1.397 1.143)
			(layers "F.Cu" "F.Mask" "F.Paste")
			(net "GND")
		)
	)
	(footprint ""
		(layer "F.Cu")
		(at 99.70897 -78.613)
		(property "Reference" "STP97"
			(at 0 0 0)
			(layer "F.SilkS")
			(hide yes)
			(effects
				(font
					(size 1.27 1.27)
				)
			)
		)
		(property "Value" "TPAD28"
			(at 0.0127 -1.8034 0)
			(unlocked yes)
			(layer "F.Fab")
			(hide yes)
			(effects
				(font
					(size 1.016 1.016)
					(thickness 0.1524)
				)
			)
		)
		(property "Device Type" "TPAD28"
			(at 0.0127 -3.3274 0)
			(unlocked yes)
			(layer "F.Fab")
			(hide yes)
			(effects
				(font
					(size 1.016 1.016)
					(thickness 0.1524)
				)
			)
		)
		(duplicate_pad_numbers_are_jumpers no)
		(fp_poly
			(pts
				(arc
					(start 0.3556 0)
					(mid -0.3556 0)
					(end 0.3556 0)
				)
			)
			(stroke
				(width 0)
				(type default)
			)
			(fill no)
			(layer "F.CrtYd")
		)
		(fp_poly
			(pts
				(arc
					(start 0.6096 0)
					(mid -0.6096 0)
					(end 0.6096 0)
				)
			)
			(stroke
				(width 0)
				(type default)
			)
			(fill no)
			(layer "F.Fab")
		)
		(pad "1" smd circle
			(at 0 0)
			(size 0.7112 0.7112)
			(layers "F.Cu" "F.Mask" "F.Paste")
			(net "EXP_IDDT")
		)
	)
	(footprint ""
		(layer "F.Cu")
		(at 119.64797 -77.597 -90)
		(property "Reference" "SC1124"
			(at 0 0 270)
			(layer "F.SilkS")
			(hide yes)
			(effects
				(font
					(size 1.27 1.27)
				)
			)
		)
		(property "Value" "SC12P50V2JN-3GP"
			(at 1.1811 -2.7051 270)
			(unlocked yes)
			(layer "F.Fab")
			(hide yes)
			(effects
				(font
					(size 1.016 1.016)
					(thickness 0.1524)
				)
			)
		)
		(property "Device Type" "C402H24"
			(at 1.1811 -4.2291 270)
			(unlocked yes)
			(layer "F.Fab")
			(hide yes)
			(effects
				(font
					(size 1.016 1.016)
					(thickness 0.1524)
				)
			)
		)
		(duplicate_pad_numbers_are_jumpers no)
		(fp_rect
			(start -0.4318 0.9525)
			(end 0.4318 -0.9525)
			(stroke
				(width 0)
				(type default)
			)
			(fill no)
			(layer "F.CrtYd")
		)
		(fp_rect
			(start -0.4318 0.9525)
			(end 0.4318 -0.9525)
			(stroke
				(width 0)
				(type default)
			)
			(fill no)
			(layer "F.Fab")
		)
		(pad "1" smd custom
			(at 0 -0.4445 270)
			(size 0.1524 0.1524)
			(layers "F.Cu" "F.Mask" "F.Paste")
			(net "EXP_REF_CLK_P")
			(options
				(clearance outline)
				(anchor circle)
			)
			(primitives
				(gr_poly
					(pts
						(arc
							(start 0.3048 -0.2032)
							(mid 0.275042 -0.275042)
							(end 0.2032 -0.3048)
						)
						(arc
							(start -0.2032 -0.3048)
							(mid -0.275042 -0.275042)
							(end -0.3048 -0.2032)
						)
						(arc
							(start -0.3048 0.2032)
							(mid -0.275042 0.275042)
							(end -0.2032 0.3048)
						)
						(arc
							(start 0.2032 0.3048)
							(mid 0.275042 0.275042)
							(end 0.3048 0.2032)
						)
					)
					(width 0)
					(fill yes)
				)
			)
		)
		(pad "2" smd custom
			(at 0 0.4445 270)
			(size 0.1524 0.1524)
			(layers "F.Cu" "F.Mask" "F.Paste")
			(net "GND")
			(options
				(clearance outline)
				(anchor circle)
			)
			(primitives
				(gr_poly
					(pts
						(arc
							(start 0.3048 -0.2032)
							(mid 0.275042 -0.275042)
							(end 0.2032 -0.3048)
						)
						(arc
							(start -0.2032 -0.3048)
							(mid -0.275042 -0.275042)
							(end -0.3048 -0.2032)
						)
						(arc
							(start -0.3048 0.2032)
							(mid -0.275042 0.275042)
							(end -0.2032 0.3048)
						)
						(arc
							(start 0.2032 0.3048)
							(mid 0.275042 0.275042)
							(end 0.3048 0.2032)
						)
					)
					(width 0)
					(fill yes)
				)
			)
		)
	)
	(footprint ""
		(layer "F.Cu")
		(at 164.560504 -24.184356 180)
		(property "Reference" "R417"
			(at 0 0 180)
			(layer "F.SilkS")
			(hide yes)
			(effects
				(font
					(size 1.27 1.27)
				)
			)
		)
		(property "Value" "0R2J-2-GP"
			(at 0.064008 -3.993896 180)
			(unlocked yes)
			(layer "F.Fab")
			(hide yes)
			(effects
				(font
					(size 1.016 1.016)
					(thickness 0.1524)
				)
			)
		)
		(property "Device Type" "R402H16"
			(at 0.064008 -5.517896 180)
			(unlocked yes)
			(layer "F.Fab")
			(hide yes)
			(effects
				(font
					(size 1.016 1.016)
					(thickness 0.1524)
				)
			)
		)
		(duplicate_pad_numbers_are_jumpers no)
		(fp_line
			(start 0.508 -0.9398)
			(end -0.508 -0.9398)
			(stroke
				(width 0.1524)
				(type default)
			)
			(layer "F.SilkS")
		)
		(fp_line
			(start -0.508 -0.9398)
			(end -0.508 0.9398)
			(stroke
				(width 0.1524)
				(type default)
			)
			(layer "F.SilkS")
		)
		(fp_rect
			(start -0.508 0.9398)
			(end 0.508 -0.9398)
			(stroke
				(width 0)
				(type default)
			)
			(fill no)
			(layer "F.CrtYd")
		)
		(fp_rect
			(start -0.508 0.9398)
			(end 0.508 -0.9398)
			(stroke
				(width 0)
				(type default)
			)
			(fill no)
			(layer "F.Fab")
		)
		(pad "1" smd custom
			(at 0 -0.4445 180)
			(size 0.1397 0.1397)
			(layers "F.Cu" "F.Mask" "F.Paste")
			(net "TP_LAN_5")
			(options
				(clearance outline)
				(anchor circle)
			)
			(primitives
				(gr_poly
					(pts
						(arc
							(start -0.1778 -0.2794)
							(mid -0.249642 -0.249642)
							(end -0.2794 -0.1778)
						)
						(arc
							(start -0.2794 0.1778)
							(mid -0.249642 0.249642)
							(end -0.1778 0.2794)
						)
						(arc
							(start 0.1778 0.2794)
							(mid 0.249642 0.249642)
							(end 0.2794 0.1778)
						)
						(arc
							(start 0.2794 -0.1778)
							(mid 0.249642 -0.249642)
							(end 0.1778 -0.2794)
						)
					)
					(width 0)
					(fill yes)
				)
			)
		)
		(pad "2" smd custom
			(at 0 0.4445 180)
			(size 0.1397 0.1397)
			(layers "F.Cu" "F.Mask" "F.Paste")
			(net "GND")
			(options
				(clearance outline)
				(anchor circle)
			)
			(primitives
				(gr_poly
					(pts
						(arc
							(start -0.1778 -0.2794)
							(mid -0.249642 -0.249642)
							(end -0.2794 -0.1778)
						)
						(arc
							(start -0.2794 0.1778)
							(mid -0.249642 0.249642)
							(end -0.1778 0.2794)
						)
						(arc
							(start 0.1778 0.2794)
							(mid 0.249642 0.249642)
							(end 0.2794 0.1778)
						)
						(arc
							(start 0.2794 -0.1778)
							(mid 0.249642 -0.249642)
							(end 0.1778 -0.2794)
						)
					)
					(width 0)
					(fill yes)
				)
			)
		)
	)
	(footprint ""
		(layer "F.Cu")
		(at 45.72 -230.886)
		(property "Reference" "C302"
			(at 0 0 0)
			(layer "F.SilkS")
			(hide yes)
			(effects
				(font
					(size 1.27 1.27)
				)
			)
		)
		(property "Value" "SC1U25V3KX-GP"
			(at 0 -2.8194 0)
			(unlocked yes)
			(layer "F.Fab")
			(hide yes)
			(effects
				(font
					(size 1.016 1.016)
					(thickness 0.1524)
				)
			)
		)
		(property "Device Type" "C603H36"
			(at 0 -4.3434 0)
			(unlocked yes)
			(layer "F.Fab")
			(hide yes)
			(effects
				(font
					(size 1.016 1.016)
					(thickness 0.1524)
				)
			)
		)
		(duplicate_pad_numbers_are_jumpers no)
		(fp_line
			(start 0.508 0)
			(end -0.508 0)
			(stroke
				(width 0.2032)
				(type default)
			)
			(layer "F.SilkS")
		)
		(fp_rect
			(start -0.5842 1.3335)
			(end 0.5842 -1.3335)
			(stroke
				(width 0)
				(type default)
			)
			(fill no)
			(layer "F.CrtYd")
		)
		(fp_rect
			(start -0.5842 1.3335)
			(end 0.5842 -1.3335)
			(stroke
				(width 0)
				(type default)
			)
			(fill no)
			(layer "F.Fab")
		)
		(pad "1" smd custom
			(at 0 -0.762)
			(size 0.2159 0.2159)
			(layers "F.Cu" "F.Mask" "F.Paste")
			(net "P12V_PCIE")
			(options
				(clearance outline)
				(anchor circle)
			)
			(primitives
				(gr_poly
					(pts
						(arc
							(start -0.3302 -0.4318)
							(mid -0.402042 -0.402042)
							(end -0.4318 -0.3302)
						)
						(arc
							(start -0.4318 0.3302)
							(mid -0.402042 0.402042)
							(end -0.3302 0.4318)
						)
						(arc
							(start 0.3302 0.4318)
							(mid 0.402042 0.402042)
							(end 0.4318 0.3302)
						)
						(arc
							(start 0.4318 -0.3302)
							(mid 0.402042 -0.402042)
							(end 0.3302 -0.4318)
						)
					)
					(width 0)
					(fill yes)
				)
			)
		)
		(pad "2" smd custom
			(at 0 0.762)
			(size 0.2159 0.2159)
			(layers "F.Cu" "F.Mask" "F.Paste")
			(net "GND")
			(options
				(clearance outline)
				(anchor circle)
			)
			(primitives
				(gr_poly
					(pts
						(arc
							(start -0.3302 -0.4318)
							(mid -0.402042 -0.402042)
							(end -0.4318 -0.3302)
						)
						(arc
							(start -0.4318 0.3302)
							(mid -0.402042 0.402042)
							(end -0.3302 0.4318)
						)
						(arc
							(start 0.3302 0.4318)
							(mid 0.402042 0.402042)
							(end 0.4318 0.3302)
						)
						(arc
							(start 0.4318 -0.3302)
							(mid 0.402042 -0.402042)
							(end 0.3302 -0.4318)
						)
					)
					(width 0)
					(fill yes)
				)
			)
		)
	)
	(footprint ""
		(layer "F.Cu")
		(at 82.92719 -57.879488 90)
		(property "Reference" "SC920"
			(at 0 0 90)
			(layer "F.SilkS")
			(hide yes)
			(effects
				(font
					(size 1.27 1.27)
				)
			)
		)
		(property "Value" "SC10U6D3V5KX-4GP"
			(at -0.0762 -6.1214 90)
			(unlocked yes)
			(layer "F.Fab")
			(hide yes)
			(effects
				(font
					(size 1.016 1.016)
					(thickness 0.1524)
				)
			)
		)
		(property "Device Type" "C805H58"
			(at -0.0762 -8.1534 90)
			(unlocked yes)
			(layer "F.Fab")
			(hide yes)
			(effects
				(font
					(size 1.016 1.016)
					(thickness 0.1524)
				)
			)
		)
		(duplicate_pad_numbers_are_jumpers no)
		(fp_line
			(start 0.635 0)
			(end -0.635 0)
			(stroke
				(width 0.508)
				(type default)
			)
			(layer "F.SilkS")
		)
		(fp_rect
			(start -0.9652 1.778)
			(end 0.9652 -1.778)
			(stroke
				(width 0)
				(type default)
			)
			(fill no)
			(layer "F.CrtYd")
		)
		(fp_poly
			(pts
				(xy -0.9652 -1.778) (xy 0.9652 -1.778) (xy 0.9652 1.778) (xy -0.9652 1.778)
			)
			(stroke
				(width 0)
				(type default)
			)
			(fill no)
			(layer "F.Fab")
		)
		(pad "1" smd rect
			(at 0 -0.9652 90)
			(size 1.397 1.143)
			(layers "F.Cu" "F.Mask" "F.Paste")
			(net "SYS_PLL_VDD")
		)
		(pad "2" smd rect
			(at 0 0.9652 90)
			(size 1.397 1.143)
			(layers "F.Cu" "F.Mask" "F.Paste")
			(net "GND")
		)
	)
	(footprint ""
		(layer "F.Cu")
		(at 116.59997 -114.3 180)
		(property "Reference" "SC1073"
			(at 0 0 180)
			(layer "F.SilkS")
			(hide yes)
			(effects
				(font
					(size 1.27 1.27)
				)
			)
		)
		(property "Value" "SCD01U10V1KX-GP"
			(at -2.8321 -1.7399 180)
			(unlocked yes)
			(layer "F.Fab")
			(hide yes)
			(effects
				(font
					(size 1.016 1.016)
					(thickness 0.1524)
				)
			)
		)
		(property "Device Type" "C0201H13"
			(at -2.8321 -3.2639 180)
			(unlocked yes)
			(layer "F.Fab")
			(hide yes)
			(effects
				(font
					(size 1.016 1.016)
					(thickness 0.1524)
				)
			)
		)
		(duplicate_pad_numbers_are_jumpers no)
		(fp_rect
			(start -0.2794 0.6477)
			(end 0.2794 -0.6477)
			(stroke
				(width 0)
				(type default)
			)
			(fill no)
			(layer "F.CrtYd")
		)
		(fp_rect
			(start -0.2794 0.6477)
			(end 0.2794 -0.6477)
			(stroke
				(width 0)
				(type default)
			)
			(fill no)
			(layer "F.Fab")
		)
		(pad "1" smd custom
			(at 0 -0.2794 180)
			(size 0.0762 0.0762)
			(layers "F.Cu" "F.Mask" "F.Paste")
			(net "SAS_HDD_TX3_P")
			(options
				(clearance outline)
				(anchor circle)
			)
			(primitives
				(gr_poly
					(pts
						(arc
							(start 0.1524 -0.127)
							(mid 0.137521 -0.162921)
							(end 0.1016 -0.1778)
						)
						(arc
							(start -0.1016 -0.1778)
							(mid -0.137521 -0.162921)
							(end -0.1524 -0.127)
						)
						(arc
							(start -0.1524 0.127)
							(mid -0.137521 0.162921)
							(end -0.1016 0.1778)
						)
						(arc
							(start 0.1016 0.1778)
							(mid 0.137521 0.162921)
							(end 0.1524 0.127)
						)
					)
					(width 0)
					(fill yes)
				)
			)
		)
		(pad "2" smd custom
			(at 0 0.2794 180)
			(size 0.0762 0.0762)
			(layers "F.Cu" "F.Mask" "F.Paste")
			(net "SAS_HDD_REDV_TX7_P")
			(options
				(clearance outline)
				(anchor circle)
			)
			(primitives
				(gr_poly
					(pts
						(arc
							(start 0.1524 -0.127)
							(mid 0.137521 -0.162921)
							(end 0.1016 -0.1778)
						)
						(arc
							(start -0.1016 -0.1778)
							(mid -0.137521 -0.162921)
							(end -0.1524 -0.127)
						)
						(arc
							(start -0.1524 0.127)
							(mid -0.137521 0.162921)
							(end -0.1016 0.1778)
						)
						(arc
							(start 0.1016 0.1778)
							(mid 0.137521 0.162921)
							(end 0.1524 0.127)
						)
					)
					(width 0)
					(fill yes)
				)
			)
		)
	)
	(footprint ""
		(layer "F.Cu")
		(at 54.991 -109.982 180)
		(property "Reference" "SC1306"
			(at 0 0 180)
			(layer "F.SilkS")
			(hide yes)
			(effects
				(font
					(size 1.27 1.27)
				)
			)
		)
		(property "Value" "SCD1U16V2KX-3GP"
			(at 1.1811 -2.7051 180)
			(unlocked yes)
			(layer "F.Fab")
			(hide yes)
			(effects
				(font
					(size 1.016 1.016)
					(thickness 0.1524)
				)
			)
		)
		(property "Device Type" "C402H22"
			(at 1.1811 -4.2291 180)
			(unlocked yes)
			(layer "F.Fab")
			(hide yes)
			(effects
				(font
					(size 1.016 1.016)
					(thickness 0.1524)
				)
			)
		)
		(duplicate_pad_numbers_are_jumpers no)
		(fp_rect
			(start -0.4318 0.9525)
			(end 0.4318 -0.9525)
			(stroke
				(width 0)
				(type default)
			)
			(fill no)
			(layer "F.CrtYd")
		)
		(fp_rect
			(start -0.4318 0.9525)
			(end 0.4318 -0.9525)
			(stroke
				(width 0)
				(type default)
			)
			(fill no)
			(layer "F.Fab")
		)
		(pad "1" smd custom
			(at 0 -0.4445 180)
			(size 0.1524 0.1524)
			(layers "F.Cu" "F.Mask" "F.Paste")
			(net "P5V_STBY")
			(options
				(clearance outline)
				(anchor circle)
			)
			(primitives
				(gr_poly
					(pts
						(arc
							(start 0.3048 -0.2032)
							(mid 0.275042 -0.275042)
							(end 0.2032 -0.3048)
						)
						(arc
							(start -0.2032 -0.3048)
							(mid -0.275042 -0.275042)
							(end -0.3048 -0.2032)
						)
						(arc
							(start -0.3048 0.2032)
							(mid -0.275042 0.275042)
							(end -0.2032 0.3048)
						)
						(arc
							(start 0.2032 0.3048)
							(mid 0.275042 0.275042)
							(end 0.3048 0.2032)
						)
					)
					(width 0)
					(fill yes)
				)
			)
		)
		(pad "2" smd custom
			(at 0 0.4445 180)
			(size 0.1524 0.1524)
			(layers "F.Cu" "F.Mask" "F.Paste")
			(net "GND")
			(options
				(clearance outline)
				(anchor circle)
			)
			(primitives
				(gr_poly
					(pts
						(arc
							(start 0.3048 -0.2032)
							(mid 0.275042 -0.275042)
							(end 0.2032 -0.3048)
						)
						(arc
							(start -0.2032 -0.3048)
							(mid -0.275042 -0.275042)
							(end -0.3048 -0.2032)
						)
						(arc
							(start -0.3048 0.2032)
							(mid -0.275042 0.275042)
							(end -0.2032 0.3048)
						)
						(arc
							(start 0.2032 0.3048)
							(mid 0.275042 0.275042)
							(end 0.3048 0.2032)
						)
					)
					(width 0)
					(fill yes)
				)
			)
		)
	)
	(footprint ""
		(layer "F.Cu")
		(at 317.754 -113.03 90)
		(property "Reference" "PG3"
			(at 0 0 90)
			(layer "F.SilkS")
			(hide yes)
			(effects
				(font
					(size 1.27 1.27)
				)
			)
		)
		(property "Value" "COPPER-CLOSE-GP-U"
			(at 0.0762 -2.8702 90)
			(unlocked yes)
			(layer "F.Fab")
			(hide yes)
			(effects
				(font
					(size 1.016 1.016)
					(thickness 0.1524)
				)
			)
		)
		(property "Device Type" "CON2C-U"
			(at 0.0762 -4.3942 90)
			(unlocked yes)
			(layer "F.Fab")
			(hide yes)
			(effects
				(font
					(size 1.016 1.016)
					(thickness 0.1524)
				)
			)
		)
		(duplicate_pad_numbers_are_jumpers no)
		(fp_rect
			(start -0.9398 0.9652)
			(end 0.9398 -0.9652)
			(stroke
				(width 0)
				(type default)
			)
			(fill no)
			(layer "F.CrtYd")
		)
		(fp_rect
			(start -0.9398 0.9652)
			(end 0.9398 -0.9652)
			(stroke
				(width 0)
				(type default)
			)
			(fill no)
			(layer "F.Fab")
		)
		(pad "1" smd custom
			(at 0 -0.5334 90)
			(size 0.17145 0.17145)
			(layers "F.Cu" "F.Mask" "F.Paste")
			(net "AGND_P3V3_STBY")
			(options
				(clearance outline)
				(anchor circle)
			)
			(primitives
				(gr_poly
					(pts
						(xy -0.127 0.3429) (xy -0.127 0.1651) (xy -0.635 -0.3429) (xy 0.635 -0.3429) (xy 0.127 0.1651)
						(xy 0.127 0.3429)
					)
					(width 0)
					(fill yes)
				)
			)
		)
		(pad "2" smd custom
			(at 0 0.5334 90)
			(size 0.17145 0.17145)
			(layers "F.Cu" "F.Mask" "F.Paste")
			(net "GND")
			(options
				(clearance outline)
				(anchor circle)
			)
			(primitives
				(gr_poly
					(pts
						(xy -0.635 0.3429) (xy -0.127 -0.1651) (xy -0.127 -0.3429) (xy 0.127 -0.3429) (xy 0.127 -0.1651)
						(xy 0.635 0.3429)
					)
					(width 0)
					(fill yes)
				)
			)
		)
	)
	(footprint ""
		(layer "F.Cu")
		(at 303.701958 -58.928 180)
		(property "Reference" "C286"
			(at 0 0 180)
			(layer "F.SilkS")
			(hide yes)
			(effects
				(font
					(size 1.27 1.27)
				)
			)
		)
		(property "Value" "SCD1U25V2KX-2-GP"
			(at 1.1811 -2.7051 180)
			(unlocked yes)
			(layer "F.Fab")
			(hide yes)
			(effects
				(font
					(size 1.016 1.016)
					(thickness 0.1524)
				)
			)
		)
		(property "Device Type" "C402H22"
			(at 1.1811 -4.2291 180)
			(unlocked yes)
			(layer "F.Fab")
			(hide yes)
			(effects
				(font
					(size 1.016 1.016)
					(thickness 0.1524)
				)
			)
		)
		(duplicate_pad_numbers_are_jumpers no)
		(fp_rect
			(start -0.4318 0.9525)
			(end 0.4318 -0.9525)
			(stroke
				(width 0)
				(type default)
			)
			(fill no)
			(layer "F.CrtYd")
		)
		(fp_rect
			(start -0.4318 0.9525)
			(end 0.4318 -0.9525)
			(stroke
				(width 0)
				(type default)
			)
			(fill no)
			(layer "F.Fab")
		)
		(pad "1" smd custom
			(at 0 -0.4445 180)
			(size 0.1524 0.1524)
			(layers "F.Cu" "F.Mask" "F.Paste")
			(net "P3V3")
			(options
				(clearance outline)
				(anchor circle)
			)
			(primitives
				(gr_poly
					(pts
						(arc
							(start 0.3048 -0.2032)
							(mid 0.275042 -0.275042)
							(end 0.2032 -0.3048)
						)
						(arc
							(start -0.2032 -0.3048)
							(mid -0.275042 -0.275042)
							(end -0.3048 -0.2032)
						)
						(arc
							(start -0.3048 0.2032)
							(mid -0.275042 0.275042)
							(end -0.2032 0.3048)
						)
						(arc
							(start 0.2032 0.3048)
							(mid 0.275042 0.275042)
							(end 0.3048 0.2032)
						)
					)
					(width 0)
					(fill yes)
				)
			)
		)
		(pad "2" smd custom
			(at 0 0.4445 180)
			(size 0.1524 0.1524)
			(layers "F.Cu" "F.Mask" "F.Paste")
			(net "GND")
			(options
				(clearance outline)
				(anchor circle)
			)
			(primitives
				(gr_poly
					(pts
						(arc
							(start 0.3048 -0.2032)
							(mid 0.275042 -0.275042)
							(end 0.2032 -0.3048)
						)
						(arc
							(start -0.2032 -0.3048)
							(mid -0.275042 -0.275042)
							(end -0.3048 -0.2032)
						)
						(arc
							(start -0.3048 0.2032)
							(mid -0.275042 0.275042)
							(end -0.2032 0.3048)
						)
						(arc
							(start 0.2032 0.3048)
							(mid 0.275042 0.275042)
							(end 0.3048 0.2032)
						)
					)
					(width 0)
					(fill yes)
				)
			)
		)
	)
	(footprint ""
		(layer "F.Cu")
		(at 111.322612 -204.978)
		(property "Reference" "SR881"
			(at 0 0 0)
			(layer "F.SilkS")
			(hide yes)
			(effects
				(font
					(size 1.27 1.27)
				)
			)
		)
		(property "Value" "0R2J-2-GP"
			(at 0.064008 -3.993896 0)
			(unlocked yes)
			(layer "F.Fab")
			(hide yes)
			(effects
				(font
					(size 1.016 1.016)
					(thickness 0.1524)
				)
			)
		)
		(property "Device Type" "R402H16"
			(at 0.064008 -5.517896 0)
			(unlocked yes)
			(layer "F.Fab")
			(hide yes)
			(effects
				(font
					(size 1.016 1.016)
					(thickness 0.1524)
				)
			)
		)
		(duplicate_pad_numbers_are_jumpers no)
		(fp_line
			(start -0.508 -0.9398)
			(end -0.508 0.9398)
			(stroke
				(width 0.1524)
				(type default)
			)
			(layer "F.SilkS")
		)
		(fp_line
			(start 0.508 -0.9398)
			(end -0.508 -0.9398)
			(stroke
				(width 0.1524)
				(type default)
			)
			(layer "F.SilkS")
		)
		(fp_rect
			(start -0.508 0.9398)
			(end 0.508 -0.9398)
			(stroke
				(width 0)
				(type default)
			)
			(fill no)
			(layer "F.CrtYd")
		)
		(fp_rect
			(start -0.508 0.9398)
			(end 0.508 -0.9398)
			(stroke
				(width 0)
				(type default)
			)
			(fill no)
			(layer "F.Fab")
		)
		(pad "1" smd custom
			(at 0 -0.4445)
			(size 0.1397 0.1397)
			(layers "F.Cu" "F.Mask" "F.Paste")
			(net "SAS_HDD_REDV_TX8_N")
			(options
				(clearance outline)
				(anchor circle)
			)
			(primitives
				(gr_poly
					(pts
						(arc
							(start -0.1778 -0.2794)
							(mid -0.249642 -0.249642)
							(end -0.2794 -0.1778)
						)
						(arc
							(start -0.2794 0.1778)
							(mid -0.249642 0.249642)
							(end -0.1778 0.2794)
						)
						(arc
							(start 0.1778 0.2794)
							(mid 0.249642 0.249642)
							(end 0.2794 0.1778)
						)
						(arc
							(start 0.2794 -0.1778)
							(mid 0.249642 -0.249642)
							(end 0.1778 -0.2794)
						)
					)
					(width 0)
					(fill yes)
				)
			)
		)
		(pad "2" smd custom
			(at 0 0.4445)
			(size 0.1397 0.1397)
			(layers "F.Cu" "F.Mask" "F.Paste")
			(net "SAS_HDD_REDV_SER_TX8_N")
			(options
				(clearance outline)
				(anchor circle)
			)
			(primitives
				(gr_poly
					(pts
						(arc
							(start -0.1778 -0.2794)
							(mid -0.249642 -0.249642)
							(end -0.2794 -0.1778)
						)
						(arc
							(start -0.2794 0.1778)
							(mid -0.249642 0.249642)
							(end -0.1778 0.2794)
						)
						(arc
							(start 0.1778 0.2794)
							(mid 0.249642 0.249642)
							(end 0.2794 0.1778)
						)
						(arc
							(start 0.2794 -0.1778)
							(mid 0.249642 -0.249642)
							(end 0.1778 -0.2794)
						)
					)
					(width 0)
					(fill yes)
				)
			)
		)
	)
	(footprint ""
		(layer "F.Cu")
		(at 330.581 -102.616)
		(property "Reference" "PL3"
			(at 0 0 0)
			(layer "F.SilkS")
			(hide yes)
			(effects
				(font
					(size 1.27 1.27)
				)
			)
		)
		(property "Value" "COIL-3D3UH-36-GP"
			(at -5.6134 -2.4892 0)
			(unlocked yes)
			(layer "F.Fab")
			(hide yes)
			(effects
				(font
					(size 1.016 1.016)
					(thickness 0.1524)
				)
			)
		)
		(property "Device Type" "L7166-1830-UH197"
			(at -5.6134 -4.0132 0)
			(unlocked yes)
			(layer "F.Fab")
			(hide yes)
			(effects
				(font
					(size 1.016 1.016)
					(thickness 0.1524)
				)
			)
		)
		(duplicate_pad_numbers_are_jumpers no)
		(fp_line
			(start -3.556 -4.5466)
			(end 3.556 -4.5466)
			(stroke
				(width 0.1524)
				(type default)
			)
			(layer "F.SilkS")
		)
		(fp_line
			(start -3.556 4.5466)
			(end -3.556 -4.5466)
			(stroke
				(width 0.1524)
				(type default)
			)
			(layer "F.SilkS")
		)
		(fp_line
			(start 3.556 -4.5466)
			(end 3.556 4.5466)
			(stroke
				(width 0.1524)
				(type default)
			)
			(layer "F.SilkS")
		)
		(fp_line
			(start 3.556 4.5466)
			(end -3.556 4.5466)
			(stroke
				(width 0.1524)
				(type default)
			)
			(layer "F.SilkS")
		)
		(fp_rect
			(start -3.302 3.5306)
			(end 3.302 -3.5306)
			(stroke
				(width 0)
				(type default)
			)
			(fill no)
			(layer "F.CrtYd")
		)
		(fp_poly
			(pts
				(xy -3.81 4.6228) (xy -3.81 -2.3241) (xy -3.302 -2.3241) (xy -3.302 3.5306) (xy 3.302 3.5306) (xy 3.302 -3.5306)
				(xy -3.302 -3.5306) (xy -3.302 -2.3368) (xy -3.81 -2.3368) (xy -3.81 -4.6228) (xy 3.81 -4.6228)
				(xy 3.81 4.6228)
			)
			(stroke
				(width 0)
				(type default)
			)
			(fill no)
			(layer "F.CrtYd")
		)
		(fp_rect
			(start -3.81 4.6228)
			(end 3.81 -4.6228)
			(stroke
				(width 0)
				(type default)
			)
			(fill no)
			(layer "F.Fab")
		)
		(pad "1" smd rect
			(at 0 -2.804922)
			(size 3.5052 2.9718)
			(layers "F.Cu" "F.Mask" "F.Paste")
			(net "P3V3_STBY_LL")
		)
		(pad "2" smd rect
			(at 0 2.804922)
			(size 3.5052 2.9718)
			(layers "F.Cu" "F.Mask" "F.Paste")
			(net "P3V3_STBY")
		)
	)
	(footprint ""
		(layer "F.Cu")
		(at 51.308 -201.422 -90)
		(property "Reference" "Q94"
			(at 0 0 270)
			(layer "F.SilkS")
			(hide yes)
			(effects
				(font
					(size 1.27 1.27)
				)
			)
		)
		(property "Value" "2N7002A-7-GP"
			(at 0.127 -8.9662 270)
			(unlocked yes)
			(layer "F.Fab")
			(hide yes)
			(effects
				(font
					(size 1.016 1.016)
					(thickness 0.1524)
				)
			)
		)
		(property "Device Type" "SOT23DGS2D4H48"
			(at 0.127 -10.4902 270)
			(unlocked yes)
			(layer "F.Fab")
			(hide yes)
			(effects
				(font
					(size 1.016 1.016)
					(thickness 0.1524)
				)
			)
		)
		(duplicate_pad_numbers_are_jumpers no)
		(fp_line
			(start -1.651 1.778)
			(end 1.651 1.778)
			(stroke
				(width 0.1524)
				(type default)
			)
			(layer "F.SilkS")
		)
		(fp_line
			(start 1.651 1.778)
			(end 1.651 -1.778)
			(stroke
				(width 0.1524)
				(type default)
			)
			(layer "F.SilkS")
		)
		(fp_line
			(start -1.651 -1.778)
			(end -1.651 1.778)
			(stroke
				(width 0.1524)
				(type default)
			)
			(layer "F.SilkS")
		)
		(fp_line
			(start 1.651 -1.778)
			(end -1.651 -1.778)
			(stroke
				(width 0.1524)
				(type default)
			)
			(layer "F.SilkS")
		)
		(fp_poly
			(pts
				(xy -1.778 1.8796) (xy -1.778 -1.8796) (xy 1.778 -1.8796) (xy 1.778 1.8796)
			)
			(stroke
				(width 0)
				(type default)
			)
			(fill no)
			(layer "F.CrtYd")
		)
		(fp_poly
			(pts
				(xy -1.778 1.8796) (xy -1.778 -1.8796) (xy 1.778 -1.8796) (xy 1.778 1.8796)
			)
			(stroke
				(width 0)
				(type default)
			)
			(fill no)
			(layer "F.Fab")
		)
		(pad "D" smd custom
			(at 0 -0.9525 270)
			(size 0.1905 0.1905)
			(layers "F.Cu" "F.Mask" "F.Paste")
			(net "MATED_P12V_EN")
			(options
				(clearance outline)
				(anchor circle)
			)
			(primitives
				(gr_poly
					(pts
						(arc
							(start -0.1778 0.5715)
							(mid -0.321484 0.511984)
							(end -0.381 0.3683)
						)
						(arc
							(start -0.381 -0.3683)
							(mid -0.321484 -0.511984)
							(end -0.1778 -0.5715)
						)
						(arc
							(start 0.1778 -0.5715)
							(mid 0.321484 -0.511984)
							(end 0.381 -0.3683)
						)
						(arc
							(start 0.381 0.3683)
							(mid 0.321484 0.511984)
							(end 0.1778 0.5715)
						)
					)
					(width 0)
					(fill yes)
				)
			)
		)
		(pad "G" smd custom
			(at -0.98425 0.9525 270)
			(size 0.1905 0.1905)
			(layers "F.Cu" "F.Mask" "F.Paste")
			(net "PCIE_MATED#_A")
			(options
				(clearance outline)
				(anchor circle)
			)
			(primitives
				(gr_poly
					(pts
						(arc
							(start -0.1778 0.5715)
							(mid -0.321484 0.511984)
							(end -0.381 0.3683)
						)
						(arc
							(start -0.381 -0.3683)
							(mid -0.321484 -0.511984)
							(end -0.1778 -0.5715)
						)
						(arc
							(start 0.1778 -0.5715)
							(mid 0.321484 -0.511984)
							(end 0.381 -0.3683)
						)
						(arc
							(start 0.381 0.3683)
							(mid 0.321484 0.511984)
							(end 0.1778 0.5715)
						)
					)
					(width 0)
					(fill yes)
				)
			)
		)
		(pad "S" smd custom
			(at 0.98425 0.9525 270)
			(size 0.1905 0.1905)
			(layers "F.Cu" "F.Mask" "F.Paste")
			(net "GND")
			(options
				(clearance outline)
				(anchor circle)
			)
			(primitives
				(gr_poly
					(pts
						(arc
							(start -0.1778 0.5715)
							(mid -0.321484 0.511984)
							(end -0.381 0.3683)
						)
						(arc
							(start -0.381 -0.3683)
							(mid -0.321484 -0.511984)
							(end -0.1778 -0.5715)
						)
						(arc
							(start 0.1778 -0.5715)
							(mid 0.321484 -0.511984)
							(end 0.381 -0.3683)
						)
						(arc
							(start 0.381 0.3683)
							(mid 0.321484 0.511984)
							(end 0.1778 0.5715)
						)
					)
					(width 0)
					(fill yes)
				)
			)
		)
	)
	(footprint ""
		(layer "F.Cu")
		(at 7.570216 -226.62388 180)
		(property "Reference" "R156"
			(at 0 0 180)
			(layer "F.SilkS")
			(hide yes)
			(effects
				(font
					(size 1.27 1.27)
				)
			)
		)
		(property "Value" "0R2J-2-GP"
			(at 0.064008 -3.993896 180)
			(unlocked yes)
			(layer "F.Fab")
			(hide yes)
			(effects
				(font
					(size 1.016 1.016)
					(thickness 0.1524)
				)
			)
		)
		(property "Device Type" "R402H16"
			(at 0.064008 -5.517896 180)
			(unlocked yes)
			(layer "F.Fab")
			(hide yes)
			(effects
				(font
					(size 1.016 1.016)
					(thickness 0.1524)
				)
			)
		)
		(duplicate_pad_numbers_are_jumpers no)
		(fp_line
			(start 0.508 -0.9398)
			(end -0.508 -0.9398)
			(stroke
				(width 0.1524)
				(type default)
			)
			(layer "F.SilkS")
		)
		(fp_line
			(start -0.508 -0.9398)
			(end -0.508 0.9398)
			(stroke
				(width 0.1524)
				(type default)
			)
			(layer "F.SilkS")
		)
		(fp_rect
			(start -0.508 0.9398)
			(end 0.508 -0.9398)
			(stroke
				(width 0)
				(type default)
			)
			(fill no)
			(layer "F.CrtYd")
		)
		(fp_rect
			(start -0.508 0.9398)
			(end 0.508 -0.9398)
			(stroke
				(width 0)
				(type default)
			)
			(fill no)
			(layer "F.Fab")
		)
		(pad "1" smd custom
			(at 0 -0.4445 180)
			(size 0.1397 0.1397)
			(layers "F.Cu" "F.Mask" "F.Paste")
			(net "PEER_TRAY_R")
			(options
				(clearance outline)
				(anchor circle)
			)
			(primitives
				(gr_poly
					(pts
						(arc
							(start -0.1778 -0.2794)
							(mid -0.249642 -0.249642)
							(end -0.2794 -0.1778)
						)
						(arc
							(start -0.2794 0.1778)
							(mid -0.249642 0.249642)
							(end -0.1778 0.2794)
						)
						(arc
							(start 0.1778 0.2794)
							(mid 0.249642 0.249642)
							(end 0.2794 0.1778)
						)
						(arc
							(start 0.2794 -0.1778)
							(mid 0.249642 -0.249642)
							(end 0.1778 -0.2794)
						)
					)
					(width 0)
					(fill yes)
				)
			)
		)
		(pad "2" smd custom
			(at 0 0.4445 180)
			(size 0.1397 0.1397)
			(layers "F.Cu" "F.Mask" "F.Paste")
			(net "PEER_TRAY")
			(options
				(clearance outline)
				(anchor circle)
			)
			(primitives
				(gr_poly
					(pts
						(arc
							(start -0.1778 -0.2794)
							(mid -0.249642 -0.249642)
							(end -0.2794 -0.1778)
						)
						(arc
							(start -0.2794 0.1778)
							(mid -0.249642 0.249642)
							(end -0.1778 0.2794)
						)
						(arc
							(start 0.1778 0.2794)
							(mid 0.249642 0.249642)
							(end 0.2794 0.1778)
						)
						(arc
							(start 0.2794 -0.1778)
							(mid 0.249642 -0.249642)
							(end 0.1778 -0.2794)
						)
					)
					(width 0)
					(fill yes)
				)
			)
		)
	)
	(footprint ""
		(layer "F.Cu")
		(at 104.775 -67.818)
		(property "Reference" "SR659"
			(at 0 0 0)
			(layer "F.SilkS")
			(hide yes)
			(effects
				(font
					(size 1.27 1.27)
				)
			)
		)
		(property "Value" "10KR2F-2-GP"
			(at 0.064008 -3.993896 0)
			(unlocked yes)
			(layer "F.Fab")
			(hide yes)
			(effects
				(font
					(size 1.016 1.016)
					(thickness 0.1524)
				)
			)
		)
		(property "Device Type" "R402H16"
			(at 0.064008 -5.517896 0)
			(unlocked yes)
			(layer "F.Fab")
			(hide yes)
			(effects
				(font
					(size 1.016 1.016)
					(thickness 0.1524)
				)
			)
		)
		(duplicate_pad_numbers_are_jumpers no)
		(fp_line
			(start -0.508 -0.9398)
			(end -0.508 0.9398)
			(stroke
				(width 0.1524)
				(type default)
			)
			(layer "F.SilkS")
		)
		(fp_line
			(start 0.508 -0.9398)
			(end -0.508 -0.9398)
			(stroke
				(width 0.1524)
				(type default)
			)
			(layer "F.SilkS")
		)
		(fp_rect
			(start -0.508 0.9398)
			(end 0.508 -0.9398)
			(stroke
				(width 0)
				(type default)
			)
			(fill no)
			(layer "F.CrtYd")
		)
		(fp_rect
			(start -0.508 0.9398)
			(end 0.508 -0.9398)
			(stroke
				(width 0)
				(type default)
			)
			(fill no)
			(layer "F.Fab")
		)
		(pad "1" smd custom
			(at 0 -0.4445)
			(size 0.1397 0.1397)
			(layers "F.Cu" "F.Mask" "F.Paste")
			(net "P1V8_C")
			(options
				(clearance outline)
				(anchor circle)
			)
			(primitives
				(gr_poly
					(pts
						(arc
							(start -0.1778 -0.2794)
							(mid -0.249642 -0.249642)
							(end -0.2794 -0.1778)
						)
						(arc
							(start -0.2794 0.1778)
							(mid -0.249642 0.249642)
							(end -0.1778 0.2794)
						)
						(arc
							(start 0.1778 0.2794)
							(mid 0.249642 0.249642)
							(end 0.2794 0.1778)
						)
						(arc
							(start 0.2794 -0.1778)
							(mid 0.249642 -0.249642)
							(end 0.1778 -0.2794)
						)
					)
					(width 0)
					(fill yes)
				)
			)
		)
		(pad "2" smd custom
			(at 0 0.4445)
			(size 0.1397 0.1397)
			(layers "F.Cu" "F.Mask" "F.Paste")
			(net "LSI_TN")
			(options
				(clearance outline)
				(anchor circle)
			)
			(primitives
				(gr_poly
					(pts
						(arc
							(start -0.1778 -0.2794)
							(mid -0.249642 -0.249642)
							(end -0.2794 -0.1778)
						)
						(arc
							(start -0.2794 0.1778)
							(mid -0.249642 0.249642)
							(end -0.1778 0.2794)
						)
						(arc
							(start 0.1778 0.2794)
							(mid 0.249642 0.249642)
							(end 0.2794 0.1778)
						)
						(arc
							(start 0.2794 -0.1778)
							(mid 0.249642 -0.249642)
							(end 0.1778 -0.2794)
						)
					)
					(width 0)
					(fill yes)
				)
			)
		)
	)
	(footprint ""
		(layer "F.Cu")
		(at 92.28201 -101.727 -90)
		(property "Reference" "SR820"
			(at 0 0 270)
			(layer "F.SilkS")
			(hide yes)
			(effects
				(font
					(size 1.27 1.27)
				)
			)
		)
		(property "Value" "1KR2F-3-GP"
			(at 0.064008 -3.993896 270)
			(unlocked yes)
			(layer "F.Fab")
			(hide yes)
			(effects
				(font
					(size 1.016 1.016)
					(thickness 0.1524)
				)
			)
		)
		(property "Device Type" "R402H16"
			(at 0.064008 -5.517896 270)
			(unlocked yes)
			(layer "F.Fab")
			(hide yes)
			(effects
				(font
					(size 1.016 1.016)
					(thickness 0.1524)
				)
			)
		)
		(duplicate_pad_numbers_are_jumpers no)
		(fp_line
			(start -0.508 -0.9398)
			(end -0.508 0.9398)
			(stroke
				(width 0.1524)
				(type default)
			)
			(layer "F.SilkS")
		)
		(fp_line
			(start 0.508 -0.9398)
			(end -0.508 -0.9398)
			(stroke
				(width 0.1524)
				(type default)
			)
			(layer "F.SilkS")
		)
		(fp_rect
			(start -0.508 0.9398)
			(end 0.508 -0.9398)
			(stroke
				(width 0)
				(type default)
			)
			(fill no)
			(layer "F.CrtYd")
		)
		(fp_rect
			(start -0.508 0.9398)
			(end 0.508 -0.9398)
			(stroke
				(width 0)
				(type default)
			)
			(fill no)
			(layer "F.Fab")
		)
		(pad "1" smd custom
			(at 0 -0.4445 270)
			(size 0.1397 0.1397)
			(layers "F.Cu" "F.Mask" "F.Paste")
			(net "UART_CTS")
			(options
				(clearance outline)
				(anchor circle)
			)
			(primitives
				(gr_poly
					(pts
						(arc
							(start -0.1778 -0.2794)
							(mid -0.249642 -0.249642)
							(end -0.2794 -0.1778)
						)
						(arc
							(start -0.2794 0.1778)
							(mid -0.249642 0.249642)
							(end -0.1778 0.2794)
						)
						(arc
							(start 0.1778 0.2794)
							(mid 0.249642 0.249642)
							(end 0.2794 0.1778)
						)
						(arc
							(start 0.2794 -0.1778)
							(mid 0.249642 -0.249642)
							(end 0.1778 -0.2794)
						)
					)
					(width 0)
					(fill yes)
				)
			)
		)
		(pad "2" smd custom
			(at 0 0.4445 270)
			(size 0.1397 0.1397)
			(layers "F.Cu" "F.Mask" "F.Paste")
			(net "P1V8_E")
			(options
				(clearance outline)
				(anchor circle)
			)
			(primitives
				(gr_poly
					(pts
						(arc
							(start -0.1778 -0.2794)
							(mid -0.249642 -0.249642)
							(end -0.2794 -0.1778)
						)
						(arc
							(start -0.2794 0.1778)
							(mid -0.249642 0.249642)
							(end -0.1778 0.2794)
						)
						(arc
							(start 0.1778 0.2794)
							(mid 0.249642 0.249642)
							(end 0.2794 0.1778)
						)
						(arc
							(start 0.2794 -0.1778)
							(mid 0.249642 -0.249642)
							(end 0.1778 -0.2794)
						)
					)
					(width 0)
					(fill yes)
				)
			)
		)
	)
	(footprint ""
		(layer "F.Cu")
		(at 256.667 -115.189)
		(property "Reference" "R7901"
			(at 0 0 0)
			(layer "F.SilkS")
			(hide yes)
			(effects
				(font
					(size 1.27 1.27)
				)
			)
		)
		(property "Value" "0R2J-2-GP"
			(at 0.064008 -3.993896 0)
			(unlocked yes)
			(layer "F.Fab")
			(hide yes)
			(effects
				(font
					(size 1.016 1.016)
					(thickness 0.1524)
				)
			)
		)
		(property "Device Type" "R402H16"
			(at 0.064008 -5.517896 0)
			(unlocked yes)
			(layer "F.Fab")
			(hide yes)
			(effects
				(font
					(size 1.016 1.016)
					(thickness 0.1524)
				)
			)
		)
		(duplicate_pad_numbers_are_jumpers no)
		(fp_line
			(start -0.508 -0.9398)
			(end -0.508 0.9398)
			(stroke
				(width 0.1524)
				(type default)
			)
			(layer "F.SilkS")
		)
		(fp_line
			(start 0.508 -0.9398)
			(end -0.508 -0.9398)
			(stroke
				(width 0.1524)
				(type default)
			)
			(layer "F.SilkS")
		)
		(fp_rect
			(start -0.508 0.9398)
			(end 0.508 -0.9398)
			(stroke
				(width 0)
				(type default)
			)
			(fill no)
			(layer "F.CrtYd")
		)
		(fp_rect
			(start -0.508 0.9398)
			(end 0.508 -0.9398)
			(stroke
				(width 0)
				(type default)
			)
			(fill no)
			(layer "F.Fab")
		)
		(pad "1" smd custom
			(at 0 -0.4445)
			(size 0.1397 0.1397)
			(layers "F.Cu" "F.Mask" "F.Paste")
			(net "CPU_RXD_R")
			(options
				(clearance outline)
				(anchor circle)
			)
			(primitives
				(gr_poly
					(pts
						(arc
							(start -0.1778 -0.2794)
							(mid -0.249642 -0.249642)
							(end -0.2794 -0.1778)
						)
						(arc
							(start -0.2794 0.1778)
							(mid -0.249642 0.249642)
							(end -0.1778 0.2794)
						)
						(arc
							(start 0.1778 0.2794)
							(mid 0.249642 0.249642)
							(end 0.2794 0.1778)
						)
						(arc
							(start 0.2794 -0.1778)
							(mid 0.249642 -0.249642)
							(end 0.1778 -0.2794)
						)
					)
					(width 0)
					(fill yes)
				)
			)
		)
		(pad "2" smd custom
			(at 0 0.4445)
			(size 0.1397 0.1397)
			(layers "F.Cu" "F.Mask" "F.Paste")
			(net "CPU_RXD")
			(options
				(clearance outline)
				(anchor circle)
			)
			(primitives
				(gr_poly
					(pts
						(arc
							(start -0.1778 -0.2794)
							(mid -0.249642 -0.249642)
							(end -0.2794 -0.1778)
						)
						(arc
							(start -0.2794 0.1778)
							(mid -0.249642 0.249642)
							(end -0.1778 0.2794)
						)
						(arc
							(start 0.1778 0.2794)
							(mid 0.249642 0.249642)
							(end 0.2794 0.1778)
						)
						(arc
							(start 0.2794 -0.1778)
							(mid 0.249642 -0.249642)
							(end 0.1778 -0.2794)
						)
					)
					(width 0)
					(fill yes)
				)
			)
		)
	)
	(footprint ""
		(layer "F.Cu")
		(at 337.058 -83.947)
		(property "Reference" "R264"
			(at 0 0 0)
			(layer "F.SilkS")
			(hide yes)
			(effects
				(font
					(size 1.27 1.27)
				)
			)
		)
		(property "Value" "2K2R2J-2-GP"
			(at 0.064008 -3.993896 0)
			(unlocked yes)
			(layer "F.Fab")
			(hide yes)
			(effects
				(font
					(size 1.016 1.016)
					(thickness 0.1524)
				)
			)
		)
		(property "Device Type" "R402H16"
			(at 0.064008 -5.517896 0)
			(unlocked yes)
			(layer "F.Fab")
			(hide yes)
			(effects
				(font
					(size 1.016 1.016)
					(thickness 0.1524)
				)
			)
		)
		(duplicate_pad_numbers_are_jumpers no)
		(fp_line
			(start -0.508 -0.9398)
			(end -0.508 0.9398)
			(stroke
				(width 0.1524)
				(type default)
			)
			(layer "F.SilkS")
		)
		(fp_line
			(start 0.508 -0.9398)
			(end -0.508 -0.9398)
			(stroke
				(width 0.1524)
				(type default)
			)
			(layer "F.SilkS")
		)
		(fp_rect
			(start -0.508 0.9398)
			(end 0.508 -0.9398)
			(stroke
				(width 0)
				(type default)
			)
			(fill no)
			(layer "F.CrtYd")
		)
		(fp_rect
			(start -0.508 0.9398)
			(end 0.508 -0.9398)
			(stroke
				(width 0)
				(type default)
			)
			(fill no)
			(layer "F.Fab")
		)
		(pad "1" smd custom
			(at 0 -0.4445)
			(size 0.1397 0.1397)
			(layers "F.Cu" "F.Mask" "F.Paste")
			(net "P3V3_STBY")
			(options
				(clearance outline)
				(anchor circle)
			)
			(primitives
				(gr_poly
					(pts
						(arc
							(start -0.1778 -0.2794)
							(mid -0.249642 -0.249642)
							(end -0.2794 -0.1778)
						)
						(arc
							(start -0.2794 0.1778)
							(mid -0.249642 0.249642)
							(end -0.1778 0.2794)
						)
						(arc
							(start 0.1778 0.2794)
							(mid 0.249642 0.249642)
							(end 0.2794 0.1778)
						)
						(arc
							(start 0.2794 -0.1778)
							(mid 0.249642 -0.249642)
							(end 0.1778 -0.2794)
						)
					)
					(width 0)
					(fill yes)
				)
			)
		)
		(pad "2" smd custom
			(at 0 0.4445)
			(size 0.1397 0.1397)
			(layers "F.Cu" "F.Mask" "F.Paste")
			(net "FLA_CS_R")
			(options
				(clearance outline)
				(anchor circle)
			)
			(primitives
				(gr_poly
					(pts
						(arc
							(start -0.1778 -0.2794)
							(mid -0.249642 -0.249642)
							(end -0.2794 -0.1778)
						)
						(arc
							(start -0.2794 0.1778)
							(mid -0.249642 0.249642)
							(end -0.1778 0.2794)
						)
						(arc
							(start 0.1778 0.2794)
							(mid 0.249642 0.249642)
							(end 0.2794 0.1778)
						)
						(arc
							(start 0.2794 -0.1778)
							(mid 0.249642 -0.249642)
							(end 0.1778 -0.2794)
						)
					)
					(width 0)
					(fill yes)
				)
			)
		)
	)
	(footprint ""
		(layer "F.Cu")
		(at 164.211 -112.903 -90)
		(property "Reference" "PR152"
			(at 0 0 270)
			(layer "F.SilkS")
			(hide yes)
			(effects
				(font
					(size 1.27 1.27)
				)
			)
		)
		(property "Value" "0R2J-2-GP"
			(at 0.064008 -3.993896 270)
			(unlocked yes)
			(layer "F.Fab")
			(hide yes)
			(effects
				(font
					(size 1.016 1.016)
					(thickness 0.1524)
				)
			)
		)
		(property "Device Type" "R402H16"
			(at 0.064008 -5.517896 270)
			(unlocked yes)
			(layer "F.Fab")
			(hide yes)
			(effects
				(font
					(size 1.016 1.016)
					(thickness 0.1524)
				)
			)
		)
		(duplicate_pad_numbers_are_jumpers no)
		(fp_line
			(start -0.508 -0.9398)
			(end -0.508 0.9398)
			(stroke
				(width 0.1524)
				(type default)
			)
			(layer "F.SilkS")
		)
		(fp_line
			(start 0.508 -0.9398)
			(end -0.508 -0.9398)
			(stroke
				(width 0.1524)
				(type default)
			)
			(layer "F.SilkS")
		)
		(fp_rect
			(start -0.508 0.9398)
			(end 0.508 -0.9398)
			(stroke
				(width 0)
				(type default)
			)
			(fill no)
			(layer "F.CrtYd")
		)
		(fp_rect
			(start -0.508 0.9398)
			(end 0.508 -0.9398)
			(stroke
				(width 0)
				(type default)
			)
			(fill no)
			(layer "F.Fab")
		)
		(pad "1" smd custom
			(at 0 -0.4445 270)
			(size 0.1397 0.1397)
			(layers "F.Cu" "F.Mask" "F.Paste")
			(net "P0V9_E_EN")
			(options
				(clearance outline)
				(anchor circle)
			)
			(primitives
				(gr_poly
					(pts
						(arc
							(start -0.1778 -0.2794)
							(mid -0.249642 -0.249642)
							(end -0.2794 -0.1778)
						)
						(arc
							(start -0.2794 0.1778)
							(mid -0.249642 0.249642)
							(end -0.1778 0.2794)
						)
						(arc
							(start 0.1778 0.2794)
							(mid 0.249642 0.249642)
							(end 0.2794 0.1778)
						)
						(arc
							(start 0.2794 -0.1778)
							(mid 0.249642 -0.249642)
							(end 0.1778 -0.2794)
						)
					)
					(width 0)
					(fill yes)
				)
			)
		)
		(pad "2" smd custom
			(at 0 0.4445 270)
			(size 0.1397 0.1397)
			(layers "F.Cu" "F.Mask" "F.Paste")
			(net "P1V5_E_PG")
			(options
				(clearance outline)
				(anchor circle)
			)
			(primitives
				(gr_poly
					(pts
						(arc
							(start -0.1778 -0.2794)
							(mid -0.249642 -0.249642)
							(end -0.2794 -0.1778)
						)
						(arc
							(start -0.2794 0.1778)
							(mid -0.249642 0.249642)
							(end -0.1778 0.2794)
						)
						(arc
							(start 0.1778 0.2794)
							(mid 0.249642 0.249642)
							(end 0.2794 0.1778)
						)
						(arc
							(start 0.2794 -0.1778)
							(mid 0.249642 -0.249642)
							(end 0.1778 -0.2794)
						)
					)
					(width 0)
					(fill yes)
				)
			)
		)
	)
	(footprint ""
		(layer "F.Cu")
		(at 291.592 -151.638 90)
		(property "Reference" "R400"
			(at 0 0 90)
			(layer "F.SilkS")
			(hide yes)
			(effects
				(font
					(size 1.27 1.27)
				)
			)
		)
		(property "Value" "10KR2F-2-GP"
			(at 0.064008 -3.993896 90)
			(unlocked yes)
			(layer "F.Fab")
			(hide yes)
			(effects
				(font
					(size 1.016 1.016)
					(thickness 0.1524)
				)
			)
		)
		(property "Device Type" "R402H16"
			(at 0.064008 -5.517896 90)
			(unlocked yes)
			(layer "F.Fab")
			(hide yes)
			(effects
				(font
					(size 1.016 1.016)
					(thickness 0.1524)
				)
			)
		)
		(duplicate_pad_numbers_are_jumpers no)
		(fp_line
			(start 0.508 -0.9398)
			(end -0.508 -0.9398)
			(stroke
				(width 0.1524)
				(type default)
			)
			(layer "F.SilkS")
		)
		(fp_line
			(start -0.508 -0.9398)
			(end -0.508 0.9398)
			(stroke
				(width 0.1524)
				(type default)
			)
			(layer "F.SilkS")
		)
		(fp_rect
			(start -0.508 0.9398)
			(end 0.508 -0.9398)
			(stroke
				(width 0)
				(type default)
			)
			(fill no)
			(layer "F.CrtYd")
		)
		(fp_rect
			(start -0.508 0.9398)
			(end 0.508 -0.9398)
			(stroke
				(width 0)
				(type default)
			)
			(fill no)
			(layer "F.Fab")
		)
		(pad "1" smd custom
			(at 0 -0.4445 90)
			(size 0.1397 0.1397)
			(layers "F.Cu" "F.Mask" "F.Paste")
			(net "P3V3_STBY")
			(options
				(clearance outline)
				(anchor circle)
			)
			(primitives
				(gr_poly
					(pts
						(arc
							(start -0.1778 -0.2794)
							(mid -0.249642 -0.249642)
							(end -0.2794 -0.1778)
						)
						(arc
							(start -0.2794 0.1778)
							(mid -0.249642 0.249642)
							(end -0.1778 0.2794)
						)
						(arc
							(start 0.1778 0.2794)
							(mid 0.249642 0.249642)
							(end 0.2794 0.1778)
						)
						(arc
							(start 0.2794 -0.1778)
							(mid 0.249642 -0.249642)
							(end 0.1778 -0.2794)
						)
					)
					(width 0)
					(fill yes)
				)
			)
		)
		(pad "2" smd custom
			(at 0 0.4445 90)
			(size 0.1397 0.1397)
			(layers "F.Cu" "F.Mask" "F.Paste")
			(net "50M_CLK_OE")
			(options
				(clearance outline)
				(anchor circle)
			)
			(primitives
				(gr_poly
					(pts
						(arc
							(start -0.1778 -0.2794)
							(mid -0.249642 -0.249642)
							(end -0.2794 -0.1778)
						)
						(arc
							(start -0.2794 0.1778)
							(mid -0.249642 0.249642)
							(end -0.1778 0.2794)
						)
						(arc
							(start 0.1778 0.2794)
							(mid 0.249642 0.249642)
							(end 0.2794 0.1778)
						)
						(arc
							(start 0.2794 -0.1778)
							(mid 0.249642 -0.249642)
							(end 0.1778 -0.2794)
						)
					)
					(width 0)
					(fill yes)
				)
			)
		)
	)
	(footprint ""
		(layer "F.Cu")
		(at 304.038 -216.789 180)
		(property "Reference" "R647"
			(at 0 0 180)
			(layer "F.SilkS")
			(hide yes)
			(effects
				(font
					(size 1.27 1.27)
				)
			)
		)
		(property "Value" "4K7R2F-GP"
			(at 0.064008 -3.993896 180)
			(unlocked yes)
			(layer "F.Fab")
			(hide yes)
			(effects
				(font
					(size 1.016 1.016)
					(thickness 0.1524)
				)
			)
		)
		(property "Device Type" "R402H16"
			(at 0.064008 -5.517896 180)
			(unlocked yes)
			(layer "F.Fab")
			(hide yes)
			(effects
				(font
					(size 1.016 1.016)
					(thickness 0.1524)
				)
			)
		)
		(duplicate_pad_numbers_are_jumpers no)
		(fp_line
			(start 0.508 -0.9398)
			(end -0.508 -0.9398)
			(stroke
				(width 0.1524)
				(type default)
			)
			(layer "F.SilkS")
		)
		(fp_line
			(start -0.508 -0.9398)
			(end -0.508 0.9398)
			(stroke
				(width 0.1524)
				(type default)
			)
			(layer "F.SilkS")
		)
		(fp_rect
			(start -0.508 0.9398)
			(end 0.508 -0.9398)
			(stroke
				(width 0)
				(type default)
			)
			(fill no)
			(layer "F.CrtYd")
		)
		(fp_rect
			(start -0.508 0.9398)
			(end 0.508 -0.9398)
			(stroke
				(width 0)
				(type default)
			)
			(fill no)
			(layer "F.Fab")
		)
		(pad "1" smd custom
			(at 0 -0.4445 180)
			(size 0.1397 0.1397)
			(layers "F.Cu" "F.Mask" "F.Paste")
			(net "P3V3_STBY")
			(options
				(clearance outline)
				(anchor circle)
			)
			(primitives
				(gr_poly
					(pts
						(arc
							(start -0.1778 -0.2794)
							(mid -0.249642 -0.249642)
							(end -0.2794 -0.1778)
						)
						(arc
							(start -0.2794 0.1778)
							(mid -0.249642 0.249642)
							(end -0.1778 0.2794)
						)
						(arc
							(start 0.1778 0.2794)
							(mid 0.249642 0.249642)
							(end 0.2794 0.1778)
						)
						(arc
							(start 0.2794 -0.1778)
							(mid 0.249642 -0.249642)
							(end 0.1778 -0.2794)
						)
					)
					(width 0)
					(fill yes)
				)
			)
		)
		(pad "2" smd custom
			(at 0 0.4445 180)
			(size 0.1397 0.1397)
			(layers "F.Cu" "F.Mask" "F.Paste")
			(net "BMC_DEBUG_OE_1_N")
			(options
				(clearance outline)
				(anchor circle)
			)
			(primitives
				(gr_poly
					(pts
						(arc
							(start -0.1778 -0.2794)
							(mid -0.249642 -0.249642)
							(end -0.2794 -0.1778)
						)
						(arc
							(start -0.2794 0.1778)
							(mid -0.249642 0.249642)
							(end -0.1778 0.2794)
						)
						(arc
							(start 0.1778 0.2794)
							(mid 0.249642 0.249642)
							(end 0.2794 0.1778)
						)
						(arc
							(start 0.2794 -0.1778)
							(mid 0.249642 -0.249642)
							(end 0.1778 -0.2794)
						)
					)
					(width 0)
					(fill yes)
				)
			)
		)
	)
	(footprint ""
		(layer "F.Cu")
		(at 17.385538 -172.926756)
		(property "Reference" "SU70"
			(at 0 0 0)
			(layer "F.SilkS")
			(hide yes)
			(effects
				(font
					(size 1.27 1.27)
				)
			)
		)
		(property "Value" "SNLVC8T245DGVR-GP"
			(at 0 -11.1252 0)
			(unlocked yes)
			(layer "F.Fab")
			(hide yes)
			(effects
				(font
					(size 1.016 1.016)
					(thickness 0.1524)
				)
			)
		)
		(property "Device Type" "TVSOP24H48"
			(at 0 -12.6492 0)
			(unlocked yes)
			(layer "F.Fab")
			(hide yes)
			(effects
				(font
					(size 1.016 1.016)
					(thickness 0.1524)
				)
			)
		)
		(duplicate_pad_numbers_are_jumpers no)
		(fp_line
			(start -2.9337 -1.397)
			(end -2.9337 1.397)
			(stroke
				(width 0.1524)
				(type default)
			)
			(layer "F.SilkS")
		)
		(fp_line
			(start -2.9337 -0.3683)
			(end -2.5654 0)
			(stroke
				(width 0.1524)
				(type default)
			)
			(layer "F.SilkS")
		)
		(fp_line
			(start -2.9337 1.397)
			(end 2.2987 1.397)
			(stroke
				(width 0.1524)
				(type default)
			)
			(layer "F.SilkS")
		)
		(fp_line
			(start -2.7559 1.397)
			(end -2.7559 3.8354)
			(stroke
				(width 0.508)
				(type default)
			)
			(layer "F.SilkS")
		)
		(fp_line
			(start -2.5654 0)
			(end -2.9337 0.3683)
			(stroke
				(width 0.1524)
				(type default)
			)
			(layer "F.SilkS")
		)
		(fp_line
			(start 2.2987 -1.397)
			(end -2.9337 -1.397)
			(stroke
				(width 0.1524)
				(type default)
			)
			(layer "F.SilkS")
		)
		(fp_line
			(start 2.2987 1.397)
			(end 2.2987 -1.397)
			(stroke
				(width 0.1524)
				(type default)
			)
			(layer "F.SilkS")
		)
		(fp_rect
			(start -3.0099 4.0894)
			(end 3.0099 -4.0894)
			(stroke
				(width 0)
				(type default)
			)
			(fill no)
			(layer "F.CrtYd")
		)
		(fp_poly
			(pts
				(xy -3.0099 -4.0894) (xy 3.0099 -4.0894) (xy 3.0099 4.0894) (xy -3.0099 4.0894)
			)
			(stroke
				(width 0)
				(type default)
			)
			(fill no)
			(layer "F.Fab")
		)
		(pad "1" smd rect
			(at -2.19964 2.8194)
			(size 0.2032 1.524)
			(layers "F.Cu" "F.Mask" "F.Paste")
			(net "P1V8_E")
		)
		(pad "2" smd rect
			(at -1.79959 2.8194)
			(size 0.2032 1.524)
			(layers "F.Cu" "F.Mask" "F.Paste")
			(net "GND")
		)
		(pad "3" smd rect
			(at -1.39954 2.8194)
			(size 0.2032 1.524)
			(layers "F.Cu" "F.Mask" "F.Paste")
			(net "SAS_HDD_LED4")
		)
		(pad "4" smd rect
			(at -0.99949 2.8194)
			(size 0.2032 1.524)
			(layers "F.Cu" "F.Mask" "F.Paste")
			(net "SAS_HDD_LED5")
		)
		(pad "5" smd rect
			(at -0.59944 2.8194)
			(size 0.2032 1.524)
			(layers "F.Cu" "F.Mask" "F.Paste")
			(net "SAS_HDD_LED6")
		)
		(pad "6" smd rect
			(at -0.19939 2.8194)
			(size 0.2032 1.524)
			(layers "F.Cu" "F.Mask" "F.Paste")
			(net "SAS_HDD_LED7")
		)
		(pad "7" smd rect
			(at 0.19939 2.8194)
			(size 0.2032 1.524)
			(layers "F.Cu" "F.Mask" "F.Paste")
			(net "SAS_HDD_LED8")
		)
		(pad "8" smd rect
			(at 0.59944 2.8194)
			(size 0.2032 1.524)
			(layers "F.Cu" "F.Mask" "F.Paste")
			(net "SAS_HDD_LED9")
		)
		(pad "9" smd rect
			(at 0.99949 2.8194)
			(size 0.2032 1.524)
			(layers "F.Cu" "F.Mask" "F.Paste")
			(net "SAS_HDD_LED10")
		)
		(pad "10" smd rect
			(at 1.39954 2.8194)
			(size 0.2032 1.524)
			(layers "F.Cu" "F.Mask" "F.Paste")
			(net "SAS_HDD_LED11")
		)
		(pad "11" smd rect
			(at 1.79959 2.8194)
			(size 0.2032 1.524)
			(layers "F.Cu" "F.Mask" "F.Paste")
			(net "GND")
		)
		(pad "12" smd rect
			(at 2.19964 2.8194)
			(size 0.2032 1.524)
			(layers "F.Cu" "F.Mask" "F.Paste")
			(net "GND")
		)
		(pad "13" smd rect
			(at 2.19964 -2.8194)
			(size 0.2032 1.524)
			(layers "F.Cu" "F.Mask" "F.Paste")
			(net "GND")
		)
		(pad "14" smd rect
			(at 1.79959 -2.8194)
			(size 0.2032 1.524)
			(layers "F.Cu" "F.Mask" "F.Paste")
			(net "SAS_HDD_PRE15")
		)
		(pad "15" smd rect
			(at 1.39954 -2.8194)
			(size 0.2032 1.524)
			(layers "F.Cu" "F.Mask" "F.Paste")
			(net "SAS_HDD_PRE14")
		)
		(pad "16" smd rect
			(at 0.99949 -2.8194)
			(size 0.2032 1.524)
			(layers "F.Cu" "F.Mask" "F.Paste")
			(net "SAS_HDD_PRE13")
		)
		(pad "17" smd rect
			(at 0.59944 -2.8194)
			(size 0.2032 1.524)
			(layers "F.Cu" "F.Mask" "F.Paste")
			(net "SAS_HDD_PRE12")
		)
		(pad "18" smd rect
			(at 0.19939 -2.8194)
			(size 0.2032 1.524)
			(layers "F.Cu" "F.Mask" "F.Paste")
			(net "SAS_HDD_PRE11")
		)
		(pad "19" smd rect
			(at -0.19939 -2.8194)
			(size 0.2032 1.524)
			(layers "F.Cu" "F.Mask" "F.Paste")
			(net "SAS_HDD_PRE10")
		)
		(pad "20" smd rect
			(at -0.59944 -2.8194)
			(size 0.2032 1.524)
			(layers "F.Cu" "F.Mask" "F.Paste")
			(net "SAS_HDD_PRE9")
		)
		(pad "21" smd rect
			(at -0.99949 -2.8194)
			(size 0.2032 1.524)
			(layers "F.Cu" "F.Mask" "F.Paste")
			(net "SAS_HDD_PRE8")
		)
		(pad "22" smd rect
			(at -1.39954 -2.8194)
			(size 0.2032 1.524)
			(layers "F.Cu" "F.Mask" "F.Paste")
			(net "GND")
		)
		(pad "23" smd rect
			(at -1.79959 -2.8194)
			(size 0.2032 1.524)
			(layers "F.Cu" "F.Mask" "F.Paste")
			(net "P3V3_STBY")
		)
		(pad "24" smd rect
			(at -2.19964 -2.8194)
			(size 0.2032 1.524)
			(layers "F.Cu" "F.Mask" "F.Paste")
			(net "P3V3_STBY")
		)
	)
	(footprint ""
		(layer "F.Cu")
		(at 220.844872 -178.634136)
		(property "Reference" "R499"
			(at 0 0 0)
			(layer "F.SilkS")
			(hide yes)
			(effects
				(font
					(size 1.27 1.27)
				)
			)
		)
		(property "Value" "0R2J-2-GP"
			(at 0.064008 -3.993896 0)
			(unlocked yes)
			(layer "F.Fab")
			(hide yes)
			(effects
				(font
					(size 1.016 1.016)
					(thickness 0.1524)
				)
			)
		)
		(property "Device Type" "R402H16"
			(at 0.064008 -5.517896 0)
			(unlocked yes)
			(layer "F.Fab")
			(hide yes)
			(effects
				(font
					(size 1.016 1.016)
					(thickness 0.1524)
				)
			)
		)
		(duplicate_pad_numbers_are_jumpers no)
		(fp_line
			(start -0.508 -0.9398)
			(end -0.508 0.9398)
			(stroke
				(width 0.1524)
				(type default)
			)
			(layer "F.SilkS")
		)
		(fp_line
			(start 0.508 -0.9398)
			(end -0.508 -0.9398)
			(stroke
				(width 0.1524)
				(type default)
			)
			(layer "F.SilkS")
		)
		(fp_rect
			(start -0.508 0.9398)
			(end 0.508 -0.9398)
			(stroke
				(width 0)
				(type default)
			)
			(fill no)
			(layer "F.CrtYd")
		)
		(fp_rect
			(start -0.508 0.9398)
			(end 0.508 -0.9398)
			(stroke
				(width 0)
				(type default)
			)
			(fill no)
			(layer "F.Fab")
		)
		(pad "1" smd custom
			(at 0 -0.4445)
			(size 0.1397 0.1397)
			(layers "F.Cu" "F.Mask" "F.Paste")
			(net "HB_A_OUT_EXP")
			(options
				(clearance outline)
				(anchor circle)
			)
			(primitives
				(gr_poly
					(pts
						(arc
							(start -0.1778 -0.2794)
							(mid -0.249642 -0.249642)
							(end -0.2794 -0.1778)
						)
						(arc
							(start -0.2794 0.1778)
							(mid -0.249642 0.249642)
							(end -0.1778 0.2794)
						)
						(arc
							(start 0.1778 0.2794)
							(mid 0.249642 0.249642)
							(end 0.2794 0.1778)
						)
						(arc
							(start 0.2794 -0.1778)
							(mid 0.249642 -0.249642)
							(end 0.1778 -0.2794)
						)
					)
					(width 0)
					(fill yes)
				)
			)
		)
		(pad "2" smd custom
			(at 0 0.4445)
			(size 0.1397 0.1397)
			(layers "F.Cu" "F.Mask" "F.Paste")
			(net "HB_EXP_TO_BMC")
			(options
				(clearance outline)
				(anchor circle)
			)
			(primitives
				(gr_poly
					(pts
						(arc
							(start -0.1778 -0.2794)
							(mid -0.249642 -0.249642)
							(end -0.2794 -0.1778)
						)
						(arc
							(start -0.2794 0.1778)
							(mid -0.249642 0.249642)
							(end -0.1778 0.2794)
						)
						(arc
							(start 0.1778 0.2794)
							(mid 0.249642 0.249642)
							(end 0.2794 0.1778)
						)
						(arc
							(start 0.2794 -0.1778)
							(mid 0.249642 -0.249642)
							(end 0.1778 -0.2794)
						)
					)
					(width 0)
					(fill yes)
				)
			)
		)
	)
	(footprint ""
		(layer "F.Cu")
		(at 215.519 -184.531 -90)
		(property "Reference" "SC1309"
			(at 0 0 270)
			(layer "F.SilkS")
			(hide yes)
			(effects
				(font
					(size 1.27 1.27)
				)
			)
		)
		(property "Value" "SC10U6D3V5KX-4GP"
			(at -0.0762 -6.1214 270)
			(unlocked yes)
			(layer "F.Fab")
			(hide yes)
			(effects
				(font
					(size 1.016 1.016)
					(thickness 0.1524)
				)
			)
		)
		(property "Device Type" "C805H58"
			(at -0.0762 -8.1534 270)
			(unlocked yes)
			(layer "F.Fab")
			(hide yes)
			(effects
				(font
					(size 1.016 1.016)
					(thickness 0.1524)
				)
			)
		)
		(duplicate_pad_numbers_are_jumpers no)
		(fp_line
			(start 0.635 0)
			(end -0.635 0)
			(stroke
				(width 0.508)
				(type default)
			)
			(layer "F.SilkS")
		)
		(fp_rect
			(start -0.9652 1.778)
			(end 0.9652 -1.778)
			(stroke
				(width 0)
				(type default)
			)
			(fill no)
			(layer "F.CrtYd")
		)
		(fp_poly
			(pts
				(xy -0.9652 -1.778) (xy 0.9652 -1.778) (xy 0.9652 1.778) (xy -0.9652 1.778)
			)
			(stroke
				(width 0)
				(type default)
			)
			(fill no)
			(layer "F.Fab")
		)
		(pad "1" smd rect
			(at 0 -0.9652 270)
			(size 1.397 1.143)
			(layers "F.Cu" "F.Mask" "F.Paste")
			(net "HB_A_IN_EXP")
		)
		(pad "2" smd rect
			(at 0 0.9652 270)
			(size 1.397 1.143)
			(layers "F.Cu" "F.Mask" "F.Paste")
			(net "GND")
		)
	)
	(footprint ""
		(layer "F.Cu")
		(at 261.562596 -54.375812 -90)
		(property "Reference" "SR717"
			(at 0 0 270)
			(layer "F.SilkS")
			(hide yes)
			(effects
				(font
					(size 1.27 1.27)
				)
			)
		)
		(property "Value" "4K7R2F-GP"
			(at 0.064008 -3.993896 270)
			(unlocked yes)
			(layer "F.Fab")
			(hide yes)
			(effects
				(font
					(size 1.016 1.016)
					(thickness 0.1524)
				)
			)
		)
		(property "Device Type" "R402H16"
			(at 0.064008 -5.517896 270)
			(unlocked yes)
			(layer "F.Fab")
			(hide yes)
			(effects
				(font
					(size 1.016 1.016)
					(thickness 0.1524)
				)
			)
		)
		(duplicate_pad_numbers_are_jumpers no)
		(fp_line
			(start -0.508 -0.9398)
			(end -0.508 0.9398)
			(stroke
				(width 0.1524)
				(type default)
			)
			(layer "F.SilkS")
		)
		(fp_line
			(start 0.508 -0.9398)
			(end -0.508 -0.9398)
			(stroke
				(width 0.1524)
				(type default)
			)
			(layer "F.SilkS")
		)
		(fp_rect
			(start -0.508 0.9398)
			(end 0.508 -0.9398)
			(stroke
				(width 0)
				(type default)
			)
			(fill no)
			(layer "F.CrtYd")
		)
		(fp_rect
			(start -0.508 0.9398)
			(end 0.508 -0.9398)
			(stroke
				(width 0)
				(type default)
			)
			(fill no)
			(layer "F.Fab")
		)
		(pad "1" smd custom
			(at 0 -0.4445 270)
			(size 0.1397 0.1397)
			(layers "F.Cu" "F.Mask" "F.Paste")
			(net "P1V8_C")
			(options
				(clearance outline)
				(anchor circle)
			)
			(primitives
				(gr_poly
					(pts
						(arc
							(start -0.1778 -0.2794)
							(mid -0.249642 -0.249642)
							(end -0.2794 -0.1778)
						)
						(arc
							(start -0.2794 0.1778)
							(mid -0.249642 0.249642)
							(end -0.1778 0.2794)
						)
						(arc
							(start 0.1778 0.2794)
							(mid 0.249642 0.249642)
							(end 0.2794 0.1778)
						)
						(arc
							(start 0.2794 -0.1778)
							(mid 0.249642 -0.249642)
							(end 0.1778 -0.2794)
						)
					)
					(width 0)
					(fill yes)
				)
			)
		)
		(pad "2" smd custom
			(at 0 0.4445 270)
			(size 0.1397 0.1397)
			(layers "F.Cu" "F.Mask" "F.Paste")
			(net "IOC_EEPROM_A2")
			(options
				(clearance outline)
				(anchor circle)
			)
			(primitives
				(gr_poly
					(pts
						(arc
							(start -0.1778 -0.2794)
							(mid -0.249642 -0.249642)
							(end -0.2794 -0.1778)
						)
						(arc
							(start -0.2794 0.1778)
							(mid -0.249642 0.249642)
							(end -0.1778 0.2794)
						)
						(arc
							(start 0.1778 0.2794)
							(mid 0.249642 0.249642)
							(end 0.2794 0.1778)
						)
						(arc
							(start 0.2794 -0.1778)
							(mid 0.249642 -0.249642)
							(end 0.1778 -0.2794)
						)
					)
					(width 0)
					(fill yes)
				)
			)
		)
	)
	(footprint ""
		(layer "F.Cu")
		(at 174.117 -131.953 90)
		(property "Reference" "PC175"
			(at 0 0 90)
			(layer "F.SilkS")
			(hide yes)
			(effects
				(font
					(size 1.27 1.27)
				)
			)
		)
		(property "Value" "SC22U25V5MX-GP"
			(at -0.0762 -6.1214 90)
			(unlocked yes)
			(layer "F.Fab")
			(hide yes)
			(effects
				(font
					(size 1.016 1.016)
					(thickness 0.1524)
				)
			)
		)
		(property "Device Type" "C805H58"
			(at -0.0762 -8.1534 90)
			(unlocked yes)
			(layer "F.Fab")
			(hide yes)
			(effects
				(font
					(size 1.016 1.016)
					(thickness 0.1524)
				)
			)
		)
		(duplicate_pad_numbers_are_jumpers no)
		(fp_line
			(start 0.635 0)
			(end -0.635 0)
			(stroke
				(width 0.508)
				(type default)
			)
			(layer "F.SilkS")
		)
		(fp_rect
			(start -0.9652 1.778)
			(end 0.9652 -1.778)
			(stroke
				(width 0)
				(type default)
			)
			(fill no)
			(layer "F.CrtYd")
		)
		(fp_poly
			(pts
				(xy -0.9652 -1.778) (xy 0.9652 -1.778) (xy 0.9652 1.778) (xy -0.9652 1.778)
			)
			(stroke
				(width 0)
				(type default)
			)
			(fill no)
			(layer "F.Fab")
		)
		(pad "1" smd rect
			(at 0 -0.9652 90)
			(size 1.397 1.143)
			(layers "F.Cu" "F.Mask" "F.Paste")
			(net "P0V9_E_VIN")
		)
		(pad "2" smd rect
			(at 0 0.9652 90)
			(size 1.397 1.143)
			(layers "F.Cu" "F.Mask" "F.Paste")
			(net "GND")
		)
	)
	(footprint ""
		(layer "F.Cu")
		(at 14.682216 -221.67088 -90)
		(property "Reference" "SR296"
			(at 0 0 270)
			(layer "F.SilkS")
			(hide yes)
			(effects
				(font
					(size 1.27 1.27)
				)
			)
		)
		(property "Value" "0R2J-2-GP"
			(at 0.064008 -3.993896 270)
			(unlocked yes)
			(layer "F.Fab")
			(hide yes)
			(effects
				(font
					(size 1.016 1.016)
					(thickness 0.1524)
				)
			)
		)
		(property "Device Type" "R402H16"
			(at 0.064008 -5.517896 270)
			(unlocked yes)
			(layer "F.Fab")
			(hide yes)
			(effects
				(font
					(size 1.016 1.016)
					(thickness 0.1524)
				)
			)
		)
		(duplicate_pad_numbers_are_jumpers no)
		(fp_line
			(start -0.508 -0.9398)
			(end -0.508 0.9398)
			(stroke
				(width 0.1524)
				(type default)
			)
			(layer "F.SilkS")
		)
		(fp_line
			(start 0.508 -0.9398)
			(end -0.508 -0.9398)
			(stroke
				(width 0.1524)
				(type default)
			)
			(layer "F.SilkS")
		)
		(fp_rect
			(start -0.508 0.9398)
			(end 0.508 -0.9398)
			(stroke
				(width 0)
				(type default)
			)
			(fill no)
			(layer "F.CrtYd")
		)
		(fp_rect
			(start -0.508 0.9398)
			(end 0.508 -0.9398)
			(stroke
				(width 0)
				(type default)
			)
			(fill no)
			(layer "F.Fab")
		)
		(pad "1" smd custom
			(at 0 -0.4445 270)
			(size 0.1397 0.1397)
			(layers "F.Cu" "F.Mask" "F.Paste")
			(net "PWR_SCL")
			(options
				(clearance outline)
				(anchor circle)
			)
			(primitives
				(gr_poly
					(pts
						(arc
							(start -0.1778 -0.2794)
							(mid -0.249642 -0.249642)
							(end -0.2794 -0.1778)
						)
						(arc
							(start -0.2794 0.1778)
							(mid -0.249642 0.249642)
							(end -0.1778 0.2794)
						)
						(arc
							(start 0.1778 0.2794)
							(mid 0.249642 0.249642)
							(end 0.2794 0.1778)
						)
						(arc
							(start 0.2794 -0.1778)
							(mid 0.249642 -0.249642)
							(end 0.1778 -0.2794)
						)
					)
					(width 0)
					(fill yes)
				)
			)
		)
		(pad "2" smd custom
			(at 0 0.4445 270)
			(size 0.1397 0.1397)
			(layers "F.Cu" "F.Mask" "F.Paste")
			(net "BMC_IOEXP_SCL_10")
			(options
				(clearance outline)
				(anchor circle)
			)
			(primitives
				(gr_poly
					(pts
						(arc
							(start -0.1778 -0.2794)
							(mid -0.249642 -0.249642)
							(end -0.2794 -0.1778)
						)
						(arc
							(start -0.2794 0.1778)
							(mid -0.249642 0.249642)
							(end -0.1778 0.2794)
						)
						(arc
							(start 0.1778 0.2794)
							(mid 0.249642 0.249642)
							(end 0.2794 0.1778)
						)
						(arc
							(start 0.2794 -0.1778)
							(mid 0.249642 -0.249642)
							(end 0.1778 -0.2794)
						)
					)
					(width 0)
					(fill yes)
				)
			)
		)
	)
	(footprint ""
		(layer "F.Cu")
		(at 307.20538 -144.02054)
		(property "Reference" "C7788"
			(at 0 0 0)
			(layer "F.SilkS")
			(hide yes)
			(effects
				(font
					(size 1.27 1.27)
				)
			)
		)
		(property "Value" "SCD1U16V2KX-3GP"
			(at 1.1811 -2.7051 0)
			(unlocked yes)
			(layer "F.Fab")
			(hide yes)
			(effects
				(font
					(size 1.016 1.016)
					(thickness 0.1524)
				)
			)
		)
		(property "Device Type" "C402H22"
			(at 1.1811 -4.2291 0)
			(unlocked yes)
			(layer "F.Fab")
			(hide yes)
			(effects
				(font
					(size 1.016 1.016)
					(thickness 0.1524)
				)
			)
		)
		(duplicate_pad_numbers_are_jumpers no)
		(fp_rect
			(start -0.4318 0.9525)
			(end 0.4318 -0.9525)
			(stroke
				(width 0)
				(type default)
			)
			(fill no)
			(layer "F.CrtYd")
		)
		(fp_rect
			(start -0.4318 0.9525)
			(end 0.4318 -0.9525)
			(stroke
				(width 0)
				(type default)
			)
			(fill no)
			(layer "F.Fab")
		)
		(pad "1" smd custom
			(at 0 -0.4445)
			(size 0.1524 0.1524)
			(layers "F.Cu" "F.Mask" "F.Paste")
			(net "P3V3_STBY")
			(options
				(clearance outline)
				(anchor circle)
			)
			(primitives
				(gr_poly
					(pts
						(arc
							(start 0.3048 -0.2032)
							(mid 0.275042 -0.275042)
							(end 0.2032 -0.3048)
						)
						(arc
							(start -0.2032 -0.3048)
							(mid -0.275042 -0.275042)
							(end -0.3048 -0.2032)
						)
						(arc
							(start -0.3048 0.2032)
							(mid -0.275042 0.275042)
							(end -0.2032 0.3048)
						)
						(arc
							(start 0.2032 0.3048)
							(mid 0.275042 0.275042)
							(end 0.3048 0.2032)
						)
					)
					(width 0)
					(fill yes)
				)
			)
		)
		(pad "2" smd custom
			(at 0 0.4445)
			(size 0.1524 0.1524)
			(layers "F.Cu" "F.Mask" "F.Paste")
			(net "GND")
			(options
				(clearance outline)
				(anchor circle)
			)
			(primitives
				(gr_poly
					(pts
						(arc
							(start 0.3048 -0.2032)
							(mid 0.275042 -0.275042)
							(end 0.2032 -0.3048)
						)
						(arc
							(start -0.2032 -0.3048)
							(mid -0.275042 -0.275042)
							(end -0.3048 -0.2032)
						)
						(arc
							(start -0.3048 0.2032)
							(mid -0.275042 0.275042)
							(end -0.2032 0.3048)
						)
						(arc
							(start 0.2032 0.3048)
							(mid 0.275042 0.275042)
							(end 0.3048 0.2032)
						)
					)
					(width 0)
					(fill yes)
				)
			)
		)
	)
	(footprint ""
		(layer "F.Cu")
		(at 348.390718 -155.298648 -90)
		(property "Reference" "R533"
			(at 0 0 270)
			(layer "F.SilkS")
			(hide yes)
			(effects
				(font
					(size 1.27 1.27)
				)
			)
		)
		(property "Value" "0R2J-2-GP"
			(at 0.064008 -3.993896 270)
			(unlocked yes)
			(layer "F.Fab")
			(hide yes)
			(effects
				(font
					(size 1.016 1.016)
					(thickness 0.1524)
				)
			)
		)
		(property "Device Type" "R402H16"
			(at 0.064008 -5.517896 270)
			(unlocked yes)
			(layer "F.Fab")
			(hide yes)
			(effects
				(font
					(size 1.016 1.016)
					(thickness 0.1524)
				)
			)
		)
		(duplicate_pad_numbers_are_jumpers no)
		(fp_line
			(start -0.508 -0.9398)
			(end -0.508 0.9398)
			(stroke
				(width 0.1524)
				(type default)
			)
			(layer "F.SilkS")
		)
		(fp_line
			(start 0.508 -0.9398)
			(end -0.508 -0.9398)
			(stroke
				(width 0.1524)
				(type default)
			)
			(layer "F.SilkS")
		)
		(fp_rect
			(start -0.508 0.9398)
			(end 0.508 -0.9398)
			(stroke
				(width 0)
				(type default)
			)
			(fill no)
			(layer "F.CrtYd")
		)
		(fp_rect
			(start -0.508 0.9398)
			(end 0.508 -0.9398)
			(stroke
				(width 0)
				(type default)
			)
			(fill no)
			(layer "F.Fab")
		)
		(pad "1" smd custom
			(at 0 -0.4445 270)
			(size 0.1397 0.1397)
			(layers "F.Cu" "F.Mask" "F.Paste")
			(net "BMC_USB1_HDP2")
			(options
				(clearance outline)
				(anchor circle)
			)
			(primitives
				(gr_poly
					(pts
						(arc
							(start -0.1778 -0.2794)
							(mid -0.249642 -0.249642)
							(end -0.2794 -0.1778)
						)
						(arc
							(start -0.2794 0.1778)
							(mid -0.249642 0.249642)
							(end -0.1778 0.2794)
						)
						(arc
							(start 0.1778 0.2794)
							(mid 0.249642 0.249642)
							(end 0.2794 0.1778)
						)
						(arc
							(start 0.2794 -0.1778)
							(mid 0.249642 -0.249642)
							(end 0.1778 -0.2794)
						)
					)
					(width 0)
					(fill yes)
				)
			)
		)
		(pad "2" smd custom
			(at 0 0.4445 270)
			(size 0.1397 0.1397)
			(layers "F.Cu" "F.Mask" "F.Paste")
			(net "USB_P4_DP")
			(options
				(clearance outline)
				(anchor circle)
			)
			(primitives
				(gr_poly
					(pts
						(arc
							(start -0.1778 -0.2794)
							(mid -0.249642 -0.249642)
							(end -0.2794 -0.1778)
						)
						(arc
							(start -0.2794 0.1778)
							(mid -0.249642 0.249642)
							(end -0.1778 0.2794)
						)
						(arc
							(start 0.1778 0.2794)
							(mid 0.249642 0.249642)
							(end 0.2794 0.1778)
						)
						(arc
							(start 0.2794 -0.1778)
							(mid 0.249642 -0.249642)
							(end 0.1778 -0.2794)
						)
					)
					(width 0)
					(fill yes)
				)
			)
		)
	)
	(footprint ""
		(layer "F.Cu")
		(at 117.964966 -42.037 -90)
		(property "Reference" "SR666"
			(at 0 0 270)
			(layer "F.SilkS")
			(hide yes)
			(effects
				(font
					(size 1.27 1.27)
				)
			)
		)
		(property "Value" "10KR2F-2-GP"
			(at 0.064008 -3.993896 270)
			(unlocked yes)
			(layer "F.Fab")
			(hide yes)
			(effects
				(font
					(size 1.016 1.016)
					(thickness 0.1524)
				)
			)
		)
		(property "Device Type" "R402H16"
			(at 0.064008 -5.517896 270)
			(unlocked yes)
			(layer "F.Fab")
			(hide yes)
			(effects
				(font
					(size 1.016 1.016)
					(thickness 0.1524)
				)
			)
		)
		(duplicate_pad_numbers_are_jumpers no)
		(fp_line
			(start -0.508 -0.9398)
			(end -0.508 0.9398)
			(stroke
				(width 0.1524)
				(type default)
			)
			(layer "F.SilkS")
		)
		(fp_line
			(start 0.508 -0.9398)
			(end -0.508 -0.9398)
			(stroke
				(width 0.1524)
				(type default)
			)
			(layer "F.SilkS")
		)
		(fp_rect
			(start -0.508 0.9398)
			(end 0.508 -0.9398)
			(stroke
				(width 0)
				(type default)
			)
			(fill no)
			(layer "F.CrtYd")
		)
		(fp_rect
			(start -0.508 0.9398)
			(end 0.508 -0.9398)
			(stroke
				(width 0)
				(type default)
			)
			(fill no)
			(layer "F.Fab")
		)
		(pad "1" smd custom
			(at 0 -0.4445 270)
			(size 0.1397 0.1397)
			(layers "F.Cu" "F.Mask" "F.Paste")
			(net "P1V8_C")
			(options
				(clearance outline)
				(anchor circle)
			)
			(primitives
				(gr_poly
					(pts
						(arc
							(start -0.1778 -0.2794)
							(mid -0.249642 -0.249642)
							(end -0.2794 -0.1778)
						)
						(arc
							(start -0.2794 0.1778)
							(mid -0.249642 0.249642)
							(end -0.1778 0.2794)
						)
						(arc
							(start 0.1778 0.2794)
							(mid 0.249642 0.249642)
							(end 0.2794 0.1778)
						)
						(arc
							(start 0.2794 -0.1778)
							(mid 0.249642 -0.249642)
							(end 0.1778 -0.2794)
						)
					)
					(width 0)
					(fill yes)
				)
			)
		)
		(pad "2" smd custom
			(at 0 0.4445 270)
			(size 0.1397 0.1397)
			(layers "F.Cu" "F.Mask" "F.Paste")
			(net "CP_DONE")
			(options
				(clearance outline)
				(anchor circle)
			)
			(primitives
				(gr_poly
					(pts
						(arc
							(start -0.1778 -0.2794)
							(mid -0.249642 -0.249642)
							(end -0.2794 -0.1778)
						)
						(arc
							(start -0.2794 0.1778)
							(mid -0.249642 0.249642)
							(end -0.1778 0.2794)
						)
						(arc
							(start 0.1778 0.2794)
							(mid 0.249642 0.249642)
							(end 0.2794 0.1778)
						)
						(arc
							(start 0.2794 -0.1778)
							(mid 0.249642 -0.249642)
							(end 0.1778 -0.2794)
						)
					)
					(width 0)
					(fill yes)
				)
			)
		)
	)
	(footprint ""
		(layer "F.Cu")
		(at 66.715386 -108.122212 -90)
		(property "Reference" "PR169"
			(at 0 0 270)
			(layer "F.SilkS")
			(hide yes)
			(effects
				(font
					(size 1.27 1.27)
				)
			)
		)
		(property "Value" "0R2J-2-GP"
			(at 0.064008 -3.993896 270)
			(unlocked yes)
			(layer "F.Fab")
			(hide yes)
			(effects
				(font
					(size 1.016 1.016)
					(thickness 0.1524)
				)
			)
		)
		(property "Device Type" "R402H16"
			(at 0.064008 -5.517896 270)
			(unlocked yes)
			(layer "F.Fab")
			(hide yes)
			(effects
				(font
					(size 1.016 1.016)
					(thickness 0.1524)
				)
			)
		)
		(duplicate_pad_numbers_are_jumpers no)
		(fp_line
			(start -0.508 -0.9398)
			(end -0.508 0.9398)
			(stroke
				(width 0.1524)
				(type default)
			)
			(layer "F.SilkS")
		)
		(fp_line
			(start 0.508 -0.9398)
			(end -0.508 -0.9398)
			(stroke
				(width 0.1524)
				(type default)
			)
			(layer "F.SilkS")
		)
		(fp_rect
			(start -0.508 0.9398)
			(end 0.508 -0.9398)
			(stroke
				(width 0)
				(type default)
			)
			(fill no)
			(layer "F.CrtYd")
		)
		(fp_rect
			(start -0.508 0.9398)
			(end 0.508 -0.9398)
			(stroke
				(width 0)
				(type default)
			)
			(fill no)
			(layer "F.Fab")
		)
		(pad "1" smd custom
			(at 0 -0.4445 270)
			(size 0.1397 0.1397)
			(layers "F.Cu" "F.Mask" "F.Paste")
			(net "P1V8_EN_S")
			(options
				(clearance outline)
				(anchor circle)
			)
			(primitives
				(gr_poly
					(pts
						(arc
							(start -0.1778 -0.2794)
							(mid -0.249642 -0.249642)
							(end -0.2794 -0.1778)
						)
						(arc
							(start -0.2794 0.1778)
							(mid -0.249642 0.249642)
							(end -0.1778 0.2794)
						)
						(arc
							(start 0.1778 0.2794)
							(mid 0.249642 0.249642)
							(end 0.2794 0.1778)
						)
						(arc
							(start 0.2794 -0.1778)
							(mid 0.249642 -0.249642)
							(end 0.1778 -0.2794)
						)
					)
					(width 0)
					(fill yes)
				)
			)
		)
		(pad "2" smd custom
			(at 0 0.4445 270)
			(size 0.1397 0.1397)
			(layers "F.Cu" "F.Mask" "F.Paste")
			(net "P1V26_STBY_PG")
			(options
				(clearance outline)
				(anchor circle)
			)
			(primitives
				(gr_poly
					(pts
						(arc
							(start -0.1778 -0.2794)
							(mid -0.249642 -0.249642)
							(end -0.2794 -0.1778)
						)
						(arc
							(start -0.2794 0.1778)
							(mid -0.249642 0.249642)
							(end -0.1778 0.2794)
						)
						(arc
							(start 0.1778 0.2794)
							(mid 0.249642 0.249642)
							(end 0.2794 0.1778)
						)
						(arc
							(start 0.2794 -0.1778)
							(mid 0.249642 -0.249642)
							(end 0.1778 -0.2794)
						)
					)
					(width 0)
					(fill yes)
				)
			)
		)
	)
	(footprint ""
		(layer "F.Cu")
		(at 166.624 -154.1526 90)
		(property "Reference" "SR730"
			(at 0 0 90)
			(layer "F.SilkS")
			(hide yes)
			(effects
				(font
					(size 1.27 1.27)
				)
			)
		)
		(property "Value" "0R2J-2-GP"
			(at 0.064008 -3.993896 90)
			(unlocked yes)
			(layer "F.Fab")
			(hide yes)
			(effects
				(font
					(size 1.016 1.016)
					(thickness 0.1524)
				)
			)
		)
		(property "Device Type" "R402H16"
			(at 0.064008 -5.517896 90)
			(unlocked yes)
			(layer "F.Fab")
			(hide yes)
			(effects
				(font
					(size 1.016 1.016)
					(thickness 0.1524)
				)
			)
		)
		(duplicate_pad_numbers_are_jumpers no)
		(fp_line
			(start 0.508 -0.9398)
			(end -0.508 -0.9398)
			(stroke
				(width 0.1524)
				(type default)
			)
			(layer "F.SilkS")
		)
		(fp_line
			(start -0.508 -0.9398)
			(end -0.508 0.9398)
			(stroke
				(width 0.1524)
				(type default)
			)
			(layer "F.SilkS")
		)
		(fp_rect
			(start -0.508 0.9398)
			(end 0.508 -0.9398)
			(stroke
				(width 0)
				(type default)
			)
			(fill no)
			(layer "F.CrtYd")
		)
		(fp_rect
			(start -0.508 0.9398)
			(end 0.508 -0.9398)
			(stroke
				(width 0)
				(type default)
			)
			(fill no)
			(layer "F.Fab")
		)
		(pad "1" smd custom
			(at 0 -0.4445 90)
			(size 0.1397 0.1397)
			(layers "F.Cu" "F.Mask" "F.Paste")
			(net "IOC_P3V3_R_SDA_14")
			(options
				(clearance outline)
				(anchor circle)
			)
			(primitives
				(gr_poly
					(pts
						(arc
							(start -0.1778 -0.2794)
							(mid -0.249642 -0.249642)
							(end -0.2794 -0.1778)
						)
						(arc
							(start -0.2794 0.1778)
							(mid -0.249642 0.249642)
							(end -0.1778 0.2794)
						)
						(arc
							(start 0.1778 0.2794)
							(mid 0.249642 0.249642)
							(end 0.2794 0.1778)
						)
						(arc
							(start 0.2794 -0.1778)
							(mid 0.249642 -0.249642)
							(end 0.1778 -0.2794)
						)
					)
					(width 0)
					(fill yes)
				)
			)
		)
		(pad "2" smd custom
			(at 0 0.4445 90)
			(size 0.1397 0.1397)
			(layers "F.Cu" "F.Mask" "F.Paste")
			(net "IOC_P3V3_SDA_14")
			(options
				(clearance outline)
				(anchor circle)
			)
			(primitives
				(gr_poly
					(pts
						(arc
							(start -0.1778 -0.2794)
							(mid -0.249642 -0.249642)
							(end -0.2794 -0.1778)
						)
						(arc
							(start -0.2794 0.1778)
							(mid -0.249642 0.249642)
							(end -0.1778 0.2794)
						)
						(arc
							(start 0.1778 0.2794)
							(mid 0.249642 0.249642)
							(end 0.2794 0.1778)
						)
						(arc
							(start 0.2794 -0.1778)
							(mid 0.249642 -0.249642)
							(end 0.1778 -0.2794)
						)
					)
					(width 0)
					(fill yes)
				)
			)
		)
	)
	(footprint ""
		(layer "F.Cu")
		(at 108.966 -240.157 90)
		(property "Reference" "SR949"
			(at 0 0 90)
			(layer "F.SilkS")
			(hide yes)
			(effects
				(font
					(size 1.27 1.27)
				)
			)
		)
		(property "Value" "4K7R2F-GP"
			(at 0.064008 -3.993896 90)
			(unlocked yes)
			(layer "F.Fab")
			(hide yes)
			(effects
				(font
					(size 1.016 1.016)
					(thickness 0.1524)
				)
			)
		)
		(property "Device Type" "R402H16"
			(at 0.064008 -5.517896 90)
			(unlocked yes)
			(layer "F.Fab")
			(hide yes)
			(effects
				(font
					(size 1.016 1.016)
					(thickness 0.1524)
				)
			)
		)
		(duplicate_pad_numbers_are_jumpers no)
		(fp_line
			(start 0.508 -0.9398)
			(end -0.508 -0.9398)
			(stroke
				(width 0.1524)
				(type default)
			)
			(layer "F.SilkS")
		)
		(fp_line
			(start -0.508 -0.9398)
			(end -0.508 0.9398)
			(stroke
				(width 0.1524)
				(type default)
			)
			(layer "F.SilkS")
		)
		(fp_rect
			(start -0.508 0.9398)
			(end 0.508 -0.9398)
			(stroke
				(width 0)
				(type default)
			)
			(fill no)
			(layer "F.CrtYd")
		)
		(fp_rect
			(start -0.508 0.9398)
			(end 0.508 -0.9398)
			(stroke
				(width 0)
				(type default)
			)
			(fill no)
			(layer "F.Fab")
		)
		(pad "1" smd custom
			(at 0 -0.4445 90)
			(size 0.1397 0.1397)
			(layers "F.Cu" "F.Mask" "F.Paste")
			(net "SAS_FAULT_LED8")
			(options
				(clearance outline)
				(anchor circle)
			)
			(primitives
				(gr_poly
					(pts
						(arc
							(start -0.1778 -0.2794)
							(mid -0.249642 -0.249642)
							(end -0.2794 -0.1778)
						)
						(arc
							(start -0.2794 0.1778)
							(mid -0.249642 0.249642)
							(end -0.1778 0.2794)
						)
						(arc
							(start 0.1778 0.2794)
							(mid 0.249642 0.249642)
							(end 0.2794 0.1778)
						)
						(arc
							(start 0.2794 -0.1778)
							(mid 0.249642 -0.249642)
							(end 0.1778 -0.2794)
						)
					)
					(width 0)
					(fill yes)
				)
			)
		)
		(pad "2" smd custom
			(at 0 0.4445 90)
			(size 0.1397 0.1397)
			(layers "F.Cu" "F.Mask" "F.Paste")
			(net "P3V3_STBY")
			(options
				(clearance outline)
				(anchor circle)
			)
			(primitives
				(gr_poly
					(pts
						(arc
							(start -0.1778 -0.2794)
							(mid -0.249642 -0.249642)
							(end -0.2794 -0.1778)
						)
						(arc
							(start -0.2794 0.1778)
							(mid -0.249642 0.249642)
							(end -0.1778 0.2794)
						)
						(arc
							(start 0.1778 0.2794)
							(mid 0.249642 0.249642)
							(end 0.2794 0.1778)
						)
						(arc
							(start 0.2794 -0.1778)
							(mid 0.249642 -0.249642)
							(end 0.1778 -0.2794)
						)
					)
					(width 0)
					(fill yes)
				)
			)
		)
	)
	(footprint ""
		(layer "F.Cu")
		(at 291.973 -208.915 90)
		(property "Reference" "C179"
			(at 0 0 90)
			(layer "F.SilkS")
			(hide yes)
			(effects
				(font
					(size 1.27 1.27)
				)
			)
		)
		(property "Value" "SCD01U25V2KX-3GP"
			(at 1.1811 -2.7051 90)
			(unlocked yes)
			(layer "F.Fab")
			(hide yes)
			(effects
				(font
					(size 1.016 1.016)
					(thickness 0.1524)
				)
			)
		)
		(property "Device Type" "C402H22"
			(at 1.1811 -4.2291 90)
			(unlocked yes)
			(layer "F.Fab")
			(hide yes)
			(effects
				(font
					(size 1.016 1.016)
					(thickness 0.1524)
				)
			)
		)
		(duplicate_pad_numbers_are_jumpers no)
		(fp_rect
			(start -0.4318 0.9525)
			(end 0.4318 -0.9525)
			(stroke
				(width 0)
				(type default)
			)
			(fill no)
			(layer "F.CrtYd")
		)
		(fp_rect
			(start -0.4318 0.9525)
			(end 0.4318 -0.9525)
			(stroke
				(width 0)
				(type default)
			)
			(fill no)
			(layer "F.Fab")
		)
		(pad "1" smd custom
			(at 0 -0.4445 90)
			(size 0.1524 0.1524)
			(layers "F.Cu" "F.Mask" "F.Paste")
			(net "DDR_VREF")
			(options
				(clearance outline)
				(anchor circle)
			)
			(primitives
				(gr_poly
					(pts
						(arc
							(start 0.3048 -0.2032)
							(mid 0.275042 -0.275042)
							(end 0.2032 -0.3048)
						)
						(arc
							(start -0.2032 -0.3048)
							(mid -0.275042 -0.275042)
							(end -0.3048 -0.2032)
						)
						(arc
							(start -0.3048 0.2032)
							(mid -0.275042 0.275042)
							(end -0.2032 0.3048)
						)
						(arc
							(start 0.2032 0.3048)
							(mid 0.275042 0.275042)
							(end 0.3048 0.2032)
						)
					)
					(width 0)
					(fill yes)
				)
			)
		)
		(pad "2" smd custom
			(at 0 0.4445 90)
			(size 0.1524 0.1524)
			(layers "F.Cu" "F.Mask" "F.Paste")
			(net "GND")
			(options
				(clearance outline)
				(anchor circle)
			)
			(primitives
				(gr_poly
					(pts
						(arc
							(start 0.3048 -0.2032)
							(mid 0.275042 -0.275042)
							(end 0.2032 -0.3048)
						)
						(arc
							(start -0.2032 -0.3048)
							(mid -0.275042 -0.275042)
							(end -0.3048 -0.2032)
						)
						(arc
							(start -0.3048 0.2032)
							(mid -0.275042 0.275042)
							(end -0.2032 0.3048)
						)
						(arc
							(start 0.2032 0.3048)
							(mid 0.275042 0.275042)
							(end 0.3048 0.2032)
						)
					)
					(width 0)
					(fill yes)
				)
			)
		)
	)
	(footprint ""
		(layer "F.Cu")
		(at 89.643966 -69.342 180)
		(property "Reference" "SC1000"
			(at 0 0 180)
			(layer "F.SilkS")
			(hide yes)
			(effects
				(font
					(size 1.27 1.27)
				)
			)
		)
		(property "Value" "SCD1U16V2KX-3GP"
			(at 1.1811 -2.7051 180)
			(unlocked yes)
			(layer "F.Fab")
			(hide yes)
			(effects
				(font
					(size 1.016 1.016)
					(thickness 0.1524)
				)
			)
		)
		(property "Device Type" "C402H22"
			(at 1.1811 -4.2291 180)
			(unlocked yes)
			(layer "F.Fab")
			(hide yes)
			(effects
				(font
					(size 1.016 1.016)
					(thickness 0.1524)
				)
			)
		)
		(duplicate_pad_numbers_are_jumpers no)
		(fp_rect
			(start -0.4318 0.9525)
			(end 0.4318 -0.9525)
			(stroke
				(width 0)
				(type default)
			)
			(fill no)
			(layer "F.CrtYd")
		)
		(fp_rect
			(start -0.4318 0.9525)
			(end 0.4318 -0.9525)
			(stroke
				(width 0)
				(type default)
			)
			(fill no)
			(layer "F.Fab")
		)
		(pad "1" smd custom
			(at 0 -0.4445 180)
			(size 0.1524 0.1524)
			(layers "F.Cu" "F.Mask" "F.Paste")
			(net "P1V8_C")
			(options
				(clearance outline)
				(anchor circle)
			)
			(primitives
				(gr_poly
					(pts
						(arc
							(start 0.3048 -0.2032)
							(mid 0.275042 -0.275042)
							(end 0.2032 -0.3048)
						)
						(arc
							(start -0.2032 -0.3048)
							(mid -0.275042 -0.275042)
							(end -0.3048 -0.2032)
						)
						(arc
							(start -0.3048 0.2032)
							(mid -0.275042 0.275042)
							(end -0.2032 0.3048)
						)
						(arc
							(start 0.2032 0.3048)
							(mid 0.275042 0.275042)
							(end 0.3048 0.2032)
						)
					)
					(width 0)
					(fill yes)
				)
			)
		)
		(pad "2" smd custom
			(at 0 0.4445 180)
			(size 0.1524 0.1524)
			(layers "F.Cu" "F.Mask" "F.Paste")
			(net "GND")
			(options
				(clearance outline)
				(anchor circle)
			)
			(primitives
				(gr_poly
					(pts
						(arc
							(start 0.3048 -0.2032)
							(mid 0.275042 -0.275042)
							(end 0.2032 -0.3048)
						)
						(arc
							(start -0.2032 -0.3048)
							(mid -0.275042 -0.275042)
							(end -0.3048 -0.2032)
						)
						(arc
							(start -0.3048 0.2032)
							(mid -0.275042 0.275042)
							(end -0.2032 0.3048)
						)
						(arc
							(start 0.2032 0.3048)
							(mid 0.275042 0.275042)
							(end 0.3048 0.2032)
						)
					)
					(width 0)
					(fill yes)
				)
			)
		)
	)
	(footprint ""
		(layer "F.Cu")
		(at 48.4632 -119.0752)
		(property "Reference" "SC1298"
			(at 0 0 0)
			(layer "F.SilkS")
			(hide yes)
			(effects
				(font
					(size 1.27 1.27)
				)
			)
		)
		(property "Value" "SCD1U16V2KX-3GP"
			(at 1.1811 -2.7051 0)
			(unlocked yes)
			(layer "F.Fab")
			(hide yes)
			(effects
				(font
					(size 1.016 1.016)
					(thickness 0.1524)
				)
			)
		)
		(property "Device Type" "C402H22"
			(at 1.1811 -4.2291 0)
			(unlocked yes)
			(layer "F.Fab")
			(hide yes)
			(effects
				(font
					(size 1.016 1.016)
					(thickness 0.1524)
				)
			)
		)
		(duplicate_pad_numbers_are_jumpers no)
		(fp_rect
			(start -0.4318 0.9525)
			(end 0.4318 -0.9525)
			(stroke
				(width 0)
				(type default)
			)
			(fill no)
			(layer "F.CrtYd")
		)
		(fp_rect
			(start -0.4318 0.9525)
			(end 0.4318 -0.9525)
			(stroke
				(width 0)
				(type default)
			)
			(fill no)
			(layer "F.Fab")
		)
		(pad "1" smd custom
			(at 0 -0.4445)
			(size 0.1524 0.1524)
			(layers "F.Cu" "F.Mask" "F.Paste")
			(net "P1V8_E")
			(options
				(clearance outline)
				(anchor circle)
			)
			(primitives
				(gr_poly
					(pts
						(arc
							(start 0.3048 -0.2032)
							(mid 0.275042 -0.275042)
							(end 0.2032 -0.3048)
						)
						(arc
							(start -0.2032 -0.3048)
							(mid -0.275042 -0.275042)
							(end -0.3048 -0.2032)
						)
						(arc
							(start -0.3048 0.2032)
							(mid -0.275042 0.275042)
							(end -0.2032 0.3048)
						)
						(arc
							(start 0.2032 0.3048)
							(mid 0.275042 0.275042)
							(end 0.3048 0.2032)
						)
					)
					(width 0)
					(fill yes)
				)
			)
		)
		(pad "2" smd custom
			(at 0 0.4445)
			(size 0.1524 0.1524)
			(layers "F.Cu" "F.Mask" "F.Paste")
			(net "GND")
			(options
				(clearance outline)
				(anchor circle)
			)
			(primitives
				(gr_poly
					(pts
						(arc
							(start 0.3048 -0.2032)
							(mid 0.275042 -0.275042)
							(end 0.2032 -0.3048)
						)
						(arc
							(start -0.2032 -0.3048)
							(mid -0.275042 -0.275042)
							(end -0.3048 -0.2032)
						)
						(arc
							(start -0.3048 0.2032)
							(mid -0.275042 0.275042)
							(end -0.2032 0.3048)
						)
						(arc
							(start 0.2032 0.3048)
							(mid 0.275042 0.275042)
							(end 0.3048 0.2032)
						)
					)
					(width 0)
					(fill yes)
				)
			)
		)
	)
	(footprint ""
		(layer "F.Cu")
		(at 161.925 -115.062 -90)
		(property "Reference" "PR156"
			(at 0 0 270)
			(layer "F.SilkS")
			(hide yes)
			(effects
				(font
					(size 1.27 1.27)
				)
			)
		)
		(property "Value" "10D7R2F-GP"
			(at 0.064008 -3.993896 270)
			(unlocked yes)
			(layer "F.Fab")
			(hide yes)
			(effects
				(font
					(size 1.016 1.016)
					(thickness 0.1524)
				)
			)
		)
		(property "Device Type" "R402H16"
			(at 0.064008 -5.517896 270)
			(unlocked yes)
			(layer "F.Fab")
			(hide yes)
			(effects
				(font
					(size 1.016 1.016)
					(thickness 0.1524)
				)
			)
		)
		(duplicate_pad_numbers_are_jumpers no)
		(fp_line
			(start -0.508 -0.9398)
			(end -0.508 0.9398)
			(stroke
				(width 0.1524)
				(type default)
			)
			(layer "F.SilkS")
		)
		(fp_line
			(start 0.508 -0.9398)
			(end -0.508 -0.9398)
			(stroke
				(width 0.1524)
				(type default)
			)
			(layer "F.SilkS")
		)
		(fp_rect
			(start -0.508 0.9398)
			(end 0.508 -0.9398)
			(stroke
				(width 0)
				(type default)
			)
			(fill no)
			(layer "F.CrtYd")
		)
		(fp_rect
			(start -0.508 0.9398)
			(end 0.508 -0.9398)
			(stroke
				(width 0)
				(type default)
			)
			(fill no)
			(layer "F.Fab")
		)
		(pad "1" smd custom
			(at 0 -0.4445 270)
			(size 0.1397 0.1397)
			(layers "F.Cu" "F.Mask" "F.Paste")
			(net "P0V9_E_VFB_R")
			(options
				(clearance outline)
				(anchor circle)
			)
			(primitives
				(gr_poly
					(pts
						(arc
							(start -0.1778 -0.2794)
							(mid -0.249642 -0.249642)
							(end -0.2794 -0.1778)
						)
						(arc
							(start -0.2794 0.1778)
							(mid -0.249642 0.249642)
							(end -0.1778 0.2794)
						)
						(arc
							(start 0.1778 0.2794)
							(mid 0.249642 0.249642)
							(end 0.2794 0.1778)
						)
						(arc
							(start 0.2794 -0.1778)
							(mid 0.249642 -0.249642)
							(end 0.1778 -0.2794)
						)
					)
					(width 0)
					(fill yes)
				)
			)
		)
		(pad "2" smd custom
			(at 0 0.4445 270)
			(size 0.1397 0.1397)
			(layers "F.Cu" "F.Mask" "F.Paste")
			(net "P0V9_E")
			(options
				(clearance outline)
				(anchor circle)
			)
			(primitives
				(gr_poly
					(pts
						(arc
							(start -0.1778 -0.2794)
							(mid -0.249642 -0.249642)
							(end -0.2794 -0.1778)
						)
						(arc
							(start -0.2794 0.1778)
							(mid -0.249642 0.249642)
							(end -0.1778 0.2794)
						)
						(arc
							(start 0.1778 0.2794)
							(mid 0.249642 0.249642)
							(end 0.2794 0.1778)
						)
						(arc
							(start 0.2794 -0.1778)
							(mid 0.249642 -0.249642)
							(end 0.1778 -0.2794)
						)
					)
					(width 0)
					(fill yes)
				)
			)
		)
	)
	(footprint ""
		(layer "F.Cu")
		(at 191.389 -117.221 -90)
		(property "Reference" "PQ6"
			(at 0 0 270)
			(layer "F.SilkS")
			(hide yes)
			(effects
				(font
					(size 1.27 1.27)
				)
			)
		)
		(property "Value" "2N7002A-7-GP"
			(at 0.127 -8.9662 270)
			(unlocked yes)
			(layer "F.Fab")
			(hide yes)
			(effects
				(font
					(size 1.016 1.016)
					(thickness 0.1524)
				)
			)
		)
		(property "Device Type" "SOT23DGS2D4H48"
			(at 0.127 -10.4902 270)
			(unlocked yes)
			(layer "F.Fab")
			(hide yes)
			(effects
				(font
					(size 1.016 1.016)
					(thickness 0.1524)
				)
			)
		)
		(duplicate_pad_numbers_are_jumpers no)
		(fp_line
			(start -1.651 1.778)
			(end 1.651 1.778)
			(stroke
				(width 0.1524)
				(type default)
			)
			(layer "F.SilkS")
		)
		(fp_line
			(start 1.651 1.778)
			(end 1.651 -1.778)
			(stroke
				(width 0.1524)
				(type default)
			)
			(layer "F.SilkS")
		)
		(fp_line
			(start -1.651 -1.778)
			(end -1.651 1.778)
			(stroke
				(width 0.1524)
				(type default)
			)
			(layer "F.SilkS")
		)
		(fp_line
			(start 1.651 -1.778)
			(end -1.651 -1.778)
			(stroke
				(width 0.1524)
				(type default)
			)
			(layer "F.SilkS")
		)
		(fp_poly
			(pts
				(xy -1.778 1.8796) (xy -1.778 -1.8796) (xy 1.778 -1.8796) (xy 1.778 1.8796)
			)
			(stroke
				(width 0)
				(type default)
			)
			(fill no)
			(layer "F.CrtYd")
		)
		(fp_poly
			(pts
				(xy -1.778 1.8796) (xy -1.778 -1.8796) (xy 1.778 -1.8796) (xy 1.778 1.8796)
			)
			(stroke
				(width 0)
				(type default)
			)
			(fill no)
			(layer "F.Fab")
		)
		(pad "D" smd custom
			(at 0 -0.9525 270)
			(size 0.1905 0.1905)
			(layers "F.Cu" "F.Mask" "F.Paste")
			(net "P1V8_PG_R_1")
			(options
				(clearance outline)
				(anchor circle)
			)
			(primitives
				(gr_poly
					(pts
						(arc
							(start -0.1778 0.5715)
							(mid -0.321484 0.511984)
							(end -0.381 0.3683)
						)
						(arc
							(start -0.381 -0.3683)
							(mid -0.321484 -0.511984)
							(end -0.1778 -0.5715)
						)
						(arc
							(start 0.1778 -0.5715)
							(mid 0.321484 -0.511984)
							(end 0.381 -0.3683)
						)
						(arc
							(start 0.381 0.3683)
							(mid 0.321484 0.511984)
							(end 0.1778 0.5715)
						)
					)
					(width 0)
					(fill yes)
				)
			)
		)
		(pad "G" smd custom
			(at -0.98425 0.9525 270)
			(size 0.1905 0.1905)
			(layers "F.Cu" "F.Mask" "F.Paste")
			(net "P3V3_STBY_B2")
			(options
				(clearance outline)
				(anchor circle)
			)
			(primitives
				(gr_poly
					(pts
						(arc
							(start -0.1778 0.5715)
							(mid -0.321484 0.511984)
							(end -0.381 0.3683)
						)
						(arc
							(start -0.381 -0.3683)
							(mid -0.321484 -0.511984)
							(end -0.1778 -0.5715)
						)
						(arc
							(start 0.1778 -0.5715)
							(mid 0.321484 -0.511984)
							(end 0.381 -0.3683)
						)
						(arc
							(start 0.381 0.3683)
							(mid 0.321484 0.511984)
							(end 0.1778 0.5715)
						)
					)
					(width 0)
					(fill yes)
				)
			)
		)
		(pad "S" smd custom
			(at 0.98425 0.9525 270)
			(size 0.1905 0.1905)
			(layers "F.Cu" "F.Mask" "F.Paste")
			(net "GND")
			(options
				(clearance outline)
				(anchor circle)
			)
			(primitives
				(gr_poly
					(pts
						(arc
							(start -0.1778 0.5715)
							(mid -0.321484 0.511984)
							(end -0.381 0.3683)
						)
						(arc
							(start -0.381 -0.3683)
							(mid -0.321484 -0.511984)
							(end -0.1778 -0.5715)
						)
						(arc
							(start 0.1778 -0.5715)
							(mid 0.321484 -0.511984)
							(end 0.381 -0.3683)
						)
						(arc
							(start 0.381 0.3683)
							(mid 0.321484 0.511984)
							(end 0.1778 0.5715)
						)
					)
					(width 0)
					(fill yes)
				)
			)
		)
	)
	(footprint ""
		(layer "F.Cu")
		(at 318.008 -170.434 90)
		(property "Reference" "R336"
			(at 0 0 90)
			(layer "F.SilkS")
			(hide yes)
			(effects
				(font
					(size 1.27 1.27)
				)
			)
		)
		(property "Value" "0R2J-2-GP"
			(at 0.064008 -3.993896 90)
			(unlocked yes)
			(layer "F.Fab")
			(hide yes)
			(effects
				(font
					(size 1.016 1.016)
					(thickness 0.1524)
				)
			)
		)
		(property "Device Type" "R402H16"
			(at 0.064008 -5.517896 90)
			(unlocked yes)
			(layer "F.Fab")
			(hide yes)
			(effects
				(font
					(size 1.016 1.016)
					(thickness 0.1524)
				)
			)
		)
		(duplicate_pad_numbers_are_jumpers no)
		(fp_line
			(start 0.508 -0.9398)
			(end -0.508 -0.9398)
			(stroke
				(width 0.1524)
				(type default)
			)
			(layer "F.SilkS")
		)
		(fp_line
			(start -0.508 -0.9398)
			(end -0.508 0.9398)
			(stroke
				(width 0.1524)
				(type default)
			)
			(layer "F.SilkS")
		)
		(fp_rect
			(start -0.508 0.9398)
			(end 0.508 -0.9398)
			(stroke
				(width 0)
				(type default)
			)
			(fill no)
			(layer "F.CrtYd")
		)
		(fp_rect
			(start -0.508 0.9398)
			(end 0.508 -0.9398)
			(stroke
				(width 0)
				(type default)
			)
			(fill no)
			(layer "F.Fab")
		)
		(pad "1" smd custom
			(at 0 -0.4445 90)
			(size 0.1397 0.1397)
			(layers "F.Cu" "F.Mask" "F.Paste")
			(net "JTAG_BMC_TRST_N")
			(options
				(clearance outline)
				(anchor circle)
			)
			(primitives
				(gr_poly
					(pts
						(arc
							(start -0.1778 -0.2794)
							(mid -0.249642 -0.249642)
							(end -0.2794 -0.1778)
						)
						(arc
							(start -0.2794 0.1778)
							(mid -0.249642 0.249642)
							(end -0.1778 0.2794)
						)
						(arc
							(start 0.1778 0.2794)
							(mid 0.249642 0.249642)
							(end 0.2794 0.1778)
						)
						(arc
							(start 0.2794 -0.1778)
							(mid 0.249642 -0.249642)
							(end 0.1778 -0.2794)
						)
					)
					(width 0)
					(fill yes)
				)
			)
		)
		(pad "2" smd custom
			(at 0 0.4445 90)
			(size 0.1397 0.1397)
			(layers "F.Cu" "F.Mask" "F.Paste")
			(net "GND")
			(options
				(clearance outline)
				(anchor circle)
			)
			(primitives
				(gr_poly
					(pts
						(arc
							(start -0.1778 -0.2794)
							(mid -0.249642 -0.249642)
							(end -0.2794 -0.1778)
						)
						(arc
							(start -0.2794 0.1778)
							(mid -0.249642 0.249642)
							(end -0.1778 0.2794)
						)
						(arc
							(start 0.1778 0.2794)
							(mid 0.249642 0.249642)
							(end 0.2794 0.1778)
						)
						(arc
							(start 0.2794 -0.1778)
							(mid 0.249642 -0.249642)
							(end 0.1778 -0.2794)
						)
					)
					(width 0)
					(fill yes)
				)
			)
		)
	)
	(footprint ""
		(layer "F.Cu")
		(at 173.981872 -205.100936 90)
		(property "Reference" "R424"
			(at 0 0 90)
			(layer "F.SilkS")
			(hide yes)
			(effects
				(font
					(size 1.27 1.27)
				)
			)
		)
		(property "Value" "10KR2F-2-GP"
			(at 0.064008 -3.993896 90)
			(unlocked yes)
			(layer "F.Fab")
			(hide yes)
			(effects
				(font
					(size 1.016 1.016)
					(thickness 0.1524)
				)
			)
		)
		(property "Device Type" "R402H16"
			(at 0.064008 -5.517896 90)
			(unlocked yes)
			(layer "F.Fab")
			(hide yes)
			(effects
				(font
					(size 1.016 1.016)
					(thickness 0.1524)
				)
			)
		)
		(duplicate_pad_numbers_are_jumpers no)
		(fp_line
			(start 0.508 -0.9398)
			(end -0.508 -0.9398)
			(stroke
				(width 0.1524)
				(type default)
			)
			(layer "F.SilkS")
		)
		(fp_line
			(start -0.508 -0.9398)
			(end -0.508 0.9398)
			(stroke
				(width 0.1524)
				(type default)
			)
			(layer "F.SilkS")
		)
		(fp_rect
			(start -0.508 0.9398)
			(end 0.508 -0.9398)
			(stroke
				(width 0)
				(type default)
			)
			(fill no)
			(layer "F.CrtYd")
		)
		(fp_rect
			(start -0.508 0.9398)
			(end 0.508 -0.9398)
			(stroke
				(width 0)
				(type default)
			)
			(fill no)
			(layer "F.Fab")
		)
		(pad "1" smd custom
			(at 0 -0.4445 90)
			(size 0.1397 0.1397)
			(layers "F.Cu" "F.Mask" "F.Paste")
			(net "P3V3_STBY")
			(options
				(clearance outline)
				(anchor circle)
			)
			(primitives
				(gr_poly
					(pts
						(arc
							(start -0.1778 -0.2794)
							(mid -0.249642 -0.249642)
							(end -0.2794 -0.1778)
						)
						(arc
							(start -0.2794 0.1778)
							(mid -0.249642 0.249642)
							(end -0.1778 0.2794)
						)
						(arc
							(start 0.1778 0.2794)
							(mid 0.249642 0.249642)
							(end 0.2794 0.1778)
						)
						(arc
							(start 0.2794 -0.1778)
							(mid 0.249642 -0.249642)
							(end 0.1778 -0.2794)
						)
					)
					(width 0)
					(fill yes)
				)
			)
		)
		(pad "2" smd custom
			(at 0 0.4445 90)
			(size 0.1397 0.1397)
			(layers "F.Cu" "F.Mask" "F.Paste")
			(net "I2C_B_BUFF_EN")
			(options
				(clearance outline)
				(anchor circle)
			)
			(primitives
				(gr_poly
					(pts
						(arc
							(start -0.1778 -0.2794)
							(mid -0.249642 -0.249642)
							(end -0.2794 -0.1778)
						)
						(arc
							(start -0.2794 0.1778)
							(mid -0.249642 0.249642)
							(end -0.1778 0.2794)
						)
						(arc
							(start 0.1778 0.2794)
							(mid 0.249642 0.249642)
							(end 0.2794 0.1778)
						)
						(arc
							(start 0.2794 -0.1778)
							(mid 0.249642 -0.249642)
							(end 0.1778 -0.2794)
						)
					)
					(width 0)
					(fill yes)
				)
			)
		)
	)
	(footprint ""
		(layer "F.Cu")
		(at 86.976966 -91.44 180)
		(property "Reference" "SC1201"
			(at 0 0 180)
			(layer "F.SilkS")
			(hide yes)
			(effects
				(font
					(size 1.27 1.27)
				)
			)
		)
		(property "Value" "SCD1U6D3V1KX-GP"
			(at -2.8321 -1.7399 180)
			(unlocked yes)
			(layer "F.Fab")
			(hide yes)
			(effects
				(font
					(size 1.016 1.016)
					(thickness 0.1524)
				)
			)
		)
		(property "Device Type" "C0201H13"
			(at -2.8321 -3.2639 180)
			(unlocked yes)
			(layer "F.Fab")
			(hide yes)
			(effects
				(font
					(size 1.016 1.016)
					(thickness 0.1524)
				)
			)
		)
		(duplicate_pad_numbers_are_jumpers no)
		(fp_rect
			(start -0.2794 0.6477)
			(end 0.2794 -0.6477)
			(stroke
				(width 0)
				(type default)
			)
			(fill no)
			(layer "F.CrtYd")
		)
		(fp_rect
			(start -0.2794 0.6477)
			(end 0.2794 -0.6477)
			(stroke
				(width 0)
				(type default)
			)
			(fill no)
			(layer "F.Fab")
		)
		(pad "1" smd custom
			(at 0 -0.2794 180)
			(size 0.0762 0.0762)
			(layers "F.Cu" "F.Mask" "F.Paste")
			(net "SYSPLL_VDDA09")
			(options
				(clearance outline)
				(anchor circle)
			)
			(primitives
				(gr_poly
					(pts
						(arc
							(start 0.1524 -0.127)
							(mid 0.137521 -0.162921)
							(end 0.1016 -0.1778)
						)
						(arc
							(start -0.1016 -0.1778)
							(mid -0.137521 -0.162921)
							(end -0.1524 -0.127)
						)
						(arc
							(start -0.1524 0.127)
							(mid -0.137521 0.162921)
							(end -0.1016 0.1778)
						)
						(arc
							(start 0.1016 0.1778)
							(mid 0.137521 0.162921)
							(end 0.1524 0.127)
						)
					)
					(width 0)
					(fill yes)
				)
			)
		)
		(pad "2" smd custom
			(at 0 0.2794 180)
			(size 0.0762 0.0762)
			(layers "F.Cu" "F.Mask" "F.Paste")
			(net "GND")
			(options
				(clearance outline)
				(anchor circle)
			)
			(primitives
				(gr_poly
					(pts
						(arc
							(start 0.1524 -0.127)
							(mid 0.137521 -0.162921)
							(end 0.1016 -0.1778)
						)
						(arc
							(start -0.1016 -0.1778)
							(mid -0.137521 -0.162921)
							(end -0.1524 -0.127)
						)
						(arc
							(start -0.1524 0.127)
							(mid -0.137521 0.162921)
							(end -0.1016 0.1778)
						)
						(arc
							(start 0.1016 0.1778)
							(mid 0.137521 0.162921)
							(end 0.1524 0.127)
						)
					)
					(width 0)
					(fill yes)
				)
			)
		)
	)
	(footprint ""
		(layer "F.Cu")
		(at 113.04397 -114.3 180)
		(property "Reference" "SC1077"
			(at 0 0 180)
			(layer "F.SilkS")
			(hide yes)
			(effects
				(font
					(size 1.27 1.27)
				)
			)
		)
		(property "Value" "SCD01U10V1KX-GP"
			(at -2.8321 -1.7399 180)
			(unlocked yes)
			(layer "F.Fab")
			(hide yes)
			(effects
				(font
					(size 1.016 1.016)
					(thickness 0.1524)
				)
			)
		)
		(property "Device Type" "C0201H13"
			(at -2.8321 -3.2639 180)
			(unlocked yes)
			(layer "F.Fab")
			(hide yes)
			(effects
				(font
					(size 1.016 1.016)
					(thickness 0.1524)
				)
			)
		)
		(duplicate_pad_numbers_are_jumpers no)
		(fp_rect
			(start -0.2794 0.6477)
			(end 0.2794 -0.6477)
			(stroke
				(width 0)
				(type default)
			)
			(fill no)
			(layer "F.CrtYd")
		)
		(fp_rect
			(start -0.2794 0.6477)
			(end 0.2794 -0.6477)
			(stroke
				(width 0)
				(type default)
			)
			(fill no)
			(layer "F.Fab")
		)
		(pad "1" smd custom
			(at 0 -0.2794 180)
			(size 0.0762 0.0762)
			(layers "F.Cu" "F.Mask" "F.Paste")
			(net "SAS_HDD_TX5_P")
			(options
				(clearance outline)
				(anchor circle)
			)
			(primitives
				(gr_poly
					(pts
						(arc
							(start 0.1524 -0.127)
							(mid 0.137521 -0.162921)
							(end 0.1016 -0.1778)
						)
						(arc
							(start -0.1016 -0.1778)
							(mid -0.137521 -0.162921)
							(end -0.1524 -0.127)
						)
						(arc
							(start -0.1524 0.127)
							(mid -0.137521 0.162921)
							(end -0.1016 0.1778)
						)
						(arc
							(start 0.1016 0.1778)
							(mid 0.137521 0.162921)
							(end 0.1524 0.127)
						)
					)
					(width 0)
					(fill yes)
				)
			)
		)
		(pad "2" smd custom
			(at 0 0.2794 180)
			(size 0.0762 0.0762)
			(layers "F.Cu" "F.Mask" "F.Paste")
			(net "SAS_EXP_GF_TX_DP9")
			(options
				(clearance outline)
				(anchor circle)
			)
			(primitives
				(gr_poly
					(pts
						(arc
							(start 0.1524 -0.127)
							(mid 0.137521 -0.162921)
							(end 0.1016 -0.1778)
						)
						(arc
							(start -0.1016 -0.1778)
							(mid -0.137521 -0.162921)
							(end -0.1524 -0.127)
						)
						(arc
							(start -0.1524 0.127)
							(mid -0.137521 0.162921)
							(end -0.1016 0.1778)
						)
						(arc
							(start 0.1016 0.1778)
							(mid 0.137521 0.162921)
							(end 0.1524 0.127)
						)
					)
					(width 0)
					(fill yes)
				)
			)
		)
	)
	(footprint ""
		(layer "F.Cu")
		(at 90.937842 -117.800882 90)
		(property "Reference" "SR743"
			(at 0 0 90)
			(layer "F.SilkS")
			(hide yes)
			(effects
				(font
					(size 1.27 1.27)
				)
			)
		)
		(property "Value" "2K2R2F-GP"
			(at 0.064008 -3.993896 90)
			(unlocked yes)
			(layer "F.Fab")
			(hide yes)
			(effects
				(font
					(size 1.016 1.016)
					(thickness 0.1524)
				)
			)
		)
		(property "Device Type" "R402H16"
			(at 0.064008 -5.517896 90)
			(unlocked yes)
			(layer "F.Fab")
			(hide yes)
			(effects
				(font
					(size 1.016 1.016)
					(thickness 0.1524)
				)
			)
		)
		(duplicate_pad_numbers_are_jumpers no)
		(fp_line
			(start 0.508 -0.9398)
			(end -0.508 -0.9398)
			(stroke
				(width 0.1524)
				(type default)
			)
			(layer "F.SilkS")
		)
		(fp_line
			(start -0.508 -0.9398)
			(end -0.508 0.9398)
			(stroke
				(width 0.1524)
				(type default)
			)
			(layer "F.SilkS")
		)
		(fp_rect
			(start -0.508 0.9398)
			(end 0.508 -0.9398)
			(stroke
				(width 0)
				(type default)
			)
			(fill no)
			(layer "F.CrtYd")
		)
		(fp_rect
			(start -0.508 0.9398)
			(end 0.508 -0.9398)
			(stroke
				(width 0)
				(type default)
			)
			(fill no)
			(layer "F.Fab")
		)
		(pad "1" smd custom
			(at 0 -0.4445 90)
			(size 0.1397 0.1397)
			(layers "F.Cu" "F.Mask" "F.Paste")
			(net "EXP_I2C_SDA_1")
			(options
				(clearance outline)
				(anchor circle)
			)
			(primitives
				(gr_poly
					(pts
						(arc
							(start -0.1778 -0.2794)
							(mid -0.249642 -0.249642)
							(end -0.2794 -0.1778)
						)
						(arc
							(start -0.2794 0.1778)
							(mid -0.249642 0.249642)
							(end -0.1778 0.2794)
						)
						(arc
							(start 0.1778 0.2794)
							(mid 0.249642 0.249642)
							(end 0.2794 0.1778)
						)
						(arc
							(start 0.2794 -0.1778)
							(mid 0.249642 -0.249642)
							(end 0.1778 -0.2794)
						)
					)
					(width 0)
					(fill yes)
				)
			)
		)
		(pad "2" smd custom
			(at 0 0.4445 90)
			(size 0.1397 0.1397)
			(layers "F.Cu" "F.Mask" "F.Paste")
			(net "P1V8_E")
			(options
				(clearance outline)
				(anchor circle)
			)
			(primitives
				(gr_poly
					(pts
						(arc
							(start -0.1778 -0.2794)
							(mid -0.249642 -0.249642)
							(end -0.2794 -0.1778)
						)
						(arc
							(start -0.2794 0.1778)
							(mid -0.249642 0.249642)
							(end -0.1778 0.2794)
						)
						(arc
							(start 0.1778 0.2794)
							(mid 0.249642 0.249642)
							(end 0.2794 0.1778)
						)
						(arc
							(start 0.2794 -0.1778)
							(mid 0.249642 -0.249642)
							(end 0.1778 -0.2794)
						)
					)
					(width 0)
					(fill yes)
				)
			)
		)
	)
	(footprint ""
		(layer "F.Cu")
		(at 249.555 -100.965)
		(property "Reference" "TP165"
			(at 0 0 0)
			(layer "F.SilkS")
			(hide yes)
			(effects
				(font
					(size 1.27 1.27)
				)
			)
		)
		(property "Value" "TPAD28"
			(at 0.0127 -1.8034 0)
			(unlocked yes)
			(layer "F.Fab")
			(hide yes)
			(effects
				(font
					(size 1.016 1.016)
					(thickness 0.1524)
				)
			)
		)
		(property "Device Type" "TPAD28"
			(at 0.0127 -3.3274 0)
			(unlocked yes)
			(layer "F.Fab")
			(hide yes)
			(effects
				(font
					(size 1.016 1.016)
					(thickness 0.1524)
				)
			)
		)
		(duplicate_pad_numbers_are_jumpers no)
		(fp_poly
			(pts
				(arc
					(start 0.3556 0)
					(mid -0.3556 0)
					(end 0.3556 0)
				)
			)
			(stroke
				(width 0)
				(type default)
			)
			(fill no)
			(layer "F.CrtYd")
		)
		(fp_poly
			(pts
				(arc
					(start 0.6096 0)
					(mid -0.6096 0)
					(end 0.6096 0)
				)
			)
			(stroke
				(width 0)
				(type default)
			)
			(fill no)
			(layer "F.Fab")
		)
		(pad "1" smd circle
			(at 0 0)
			(size 0.7112 0.7112)
			(layers "F.Cu" "F.Mask" "F.Paste")
			(net "BMC_JTAG_L_EN")
		)
	)
	(footprint ""
		(layer "F.Cu")
		(at 54.991 -180.086 180)
		(property "Reference" "SR811"
			(at 0 0 180)
			(layer "F.SilkS")
			(hide yes)
			(effects
				(font
					(size 1.27 1.27)
				)
			)
		)
		(property "Value" "4K75R2F-1-GP"
			(at 0.064008 -3.993896 180)
			(unlocked yes)
			(layer "F.Fab")
			(hide yes)
			(effects
				(font
					(size 1.016 1.016)
					(thickness 0.1524)
				)
			)
		)
		(property "Device Type" "R402H16"
			(at 0.064008 -5.517896 180)
			(unlocked yes)
			(layer "F.Fab")
			(hide yes)
			(effects
				(font
					(size 1.016 1.016)
					(thickness 0.1524)
				)
			)
		)
		(duplicate_pad_numbers_are_jumpers no)
		(fp_line
			(start 0.508 -0.9398)
			(end -0.508 -0.9398)
			(stroke
				(width 0.1524)
				(type default)
			)
			(layer "F.SilkS")
		)
		(fp_line
			(start -0.508 -0.9398)
			(end -0.508 0.9398)
			(stroke
				(width 0.1524)
				(type default)
			)
			(layer "F.SilkS")
		)
		(fp_rect
			(start -0.508 0.9398)
			(end 0.508 -0.9398)
			(stroke
				(width 0)
				(type default)
			)
			(fill no)
			(layer "F.CrtYd")
		)
		(fp_rect
			(start -0.508 0.9398)
			(end 0.508 -0.9398)
			(stroke
				(width 0)
				(type default)
			)
			(fill no)
			(layer "F.Fab")
		)
		(pad "1" smd custom
			(at 0 -0.4445 180)
			(size 0.1397 0.1397)
			(layers "F.Cu" "F.Mask" "F.Paste")
			(net "P1V8_E")
			(options
				(clearance outline)
				(anchor circle)
			)
			(primitives
				(gr_poly
					(pts
						(arc
							(start -0.1778 -0.2794)
							(mid -0.249642 -0.249642)
							(end -0.2794 -0.1778)
						)
						(arc
							(start -0.2794 0.1778)
							(mid -0.249642 0.249642)
							(end -0.1778 0.2794)
						)
						(arc
							(start 0.1778 0.2794)
							(mid 0.249642 0.249642)
							(end 0.2794 0.1778)
						)
						(arc
							(start 0.2794 -0.1778)
							(mid 0.249642 -0.249642)
							(end 0.1778 -0.2794)
						)
					)
					(width 0)
					(fill yes)
				)
			)
		)
		(pad "2" smd custom
			(at 0 0.4445 180)
			(size 0.1397 0.1397)
			(layers "F.Cu" "F.Mask" "F.Paste")
			(net "ICE_TMS")
			(options
				(clearance outline)
				(anchor circle)
			)
			(primitives
				(gr_poly
					(pts
						(arc
							(start -0.1778 -0.2794)
							(mid -0.249642 -0.249642)
							(end -0.2794 -0.1778)
						)
						(arc
							(start -0.2794 0.1778)
							(mid -0.249642 0.249642)
							(end -0.1778 0.2794)
						)
						(arc
							(start 0.1778 0.2794)
							(mid 0.249642 0.249642)
							(end 0.2794 0.1778)
						)
						(arc
							(start 0.2794 -0.1778)
							(mid 0.249642 -0.249642)
							(end 0.1778 -0.2794)
						)
					)
					(width 0)
					(fill yes)
				)
			)
		)
	)
	(footprint ""
		(layer "F.Cu")
		(at 80.51927 -81.191608 -90)
		(property "Reference" "SL21"
			(at 0 0 270)
			(layer "F.SilkS")
			(hide yes)
			(effects
				(font
					(size 1.27 1.27)
				)
			)
		)
		(property "Value" "MPZ2012S601AT-GP"
			(at 0 -4.2418 270)
			(unlocked yes)
			(layer "F.Fab")
			(hide yes)
			(effects
				(font
					(size 1.016 1.016)
					(thickness 0.1524)
				)
			)
		)
		(property "Device Type" "L805H42"
			(at 0 -5.7912 270)
			(unlocked yes)
			(layer "F.Fab")
			(hide yes)
			(effects
				(font
					(size 1.016 1.016)
					(thickness 0.1524)
				)
			)
		)
		(duplicate_pad_numbers_are_jumpers no)
		(fp_line
			(start -0.889 1.7018)
			(end -0.889 -1.7018)
			(stroke
				(width 0.1524)
				(type default)
			)
			(layer "F.SilkS")
		)
		(fp_line
			(start 0.889 1.7018)
			(end -0.889 1.7018)
			(stroke
				(width 0.1524)
				(type default)
			)
			(layer "F.SilkS")
		)
		(fp_line
			(start -0.889 -1.7018)
			(end 0.889 -1.7018)
			(stroke
				(width 0.1524)
				(type default)
			)
			(layer "F.SilkS")
		)
		(fp_line
			(start 0.889 -1.7018)
			(end 0.889 1.7018)
			(stroke
				(width 0.1524)
				(type default)
			)
			(layer "F.SilkS")
		)
		(fp_rect
			(start -0.9652 1.778)
			(end 0.9652 -1.778)
			(stroke
				(width 0)
				(type default)
			)
			(fill no)
			(layer "F.CrtYd")
		)
		(fp_rect
			(start -0.9652 1.778)
			(end 0.9652 -1.778)
			(stroke
				(width 0)
				(type default)
			)
			(fill no)
			(layer "F.Fab")
		)
		(pad "1" smd rect
			(at 0 -0.9652 270)
			(size 1.397 1.143)
			(layers "F.Cu" "F.Mask" "F.Paste")
			(net "XTAL_VDDA09")
		)
		(pad "2" smd rect
			(at 0 0.9652 270)
			(size 1.397 1.143)
			(layers "F.Cu" "F.Mask" "F.Paste")
			(net "P0V9_E")
		)
	)
	(footprint ""
		(layer "F.Cu")
		(at 262.001 -34.798 -90)
		(property "Reference" "PC51"
			(at 0 0 270)
			(layer "F.SilkS")
			(hide yes)
			(effects
				(font
					(size 1.27 1.27)
				)
			)
		)
		(property "Value" "SC1KP50V2KX-1GP"
			(at 1.1811 -2.7051 270)
			(unlocked yes)
			(layer "F.Fab")
			(hide yes)
			(effects
				(font
					(size 1.016 1.016)
					(thickness 0.1524)
				)
			)
		)
		(property "Device Type" "C402H22"
			(at 1.1811 -4.2291 270)
			(unlocked yes)
			(layer "F.Fab")
			(hide yes)
			(effects
				(font
					(size 1.016 1.016)
					(thickness 0.1524)
				)
			)
		)
		(duplicate_pad_numbers_are_jumpers no)
		(fp_rect
			(start -0.4318 0.9525)
			(end 0.4318 -0.9525)
			(stroke
				(width 0)
				(type default)
			)
			(fill no)
			(layer "F.CrtYd")
		)
		(fp_rect
			(start -0.4318 0.9525)
			(end 0.4318 -0.9525)
			(stroke
				(width 0)
				(type default)
			)
			(fill no)
			(layer "F.Fab")
		)
		(pad "1" smd custom
			(at 0 -0.4445 270)
			(size 0.1524 0.1524)
			(layers "F.Cu" "F.Mask" "F.Paste")
			(net "P1V8_STBY_LL_R")
			(options
				(clearance outline)
				(anchor circle)
			)
			(primitives
				(gr_poly
					(pts
						(arc
							(start 0.3048 -0.2032)
							(mid 0.275042 -0.275042)
							(end 0.2032 -0.3048)
						)
						(arc
							(start -0.2032 -0.3048)
							(mid -0.275042 -0.275042)
							(end -0.3048 -0.2032)
						)
						(arc
							(start -0.3048 0.2032)
							(mid -0.275042 0.275042)
							(end -0.2032 0.3048)
						)
						(arc
							(start 0.2032 0.3048)
							(mid 0.275042 0.275042)
							(end 0.3048 0.2032)
						)
					)
					(width 0)
					(fill yes)
				)
			)
		)
		(pad "2" smd custom
			(at 0 0.4445 270)
			(size 0.1524 0.1524)
			(layers "F.Cu" "F.Mask" "F.Paste")
			(net "P1V8_STBY_VFB")
			(options
				(clearance outline)
				(anchor circle)
			)
			(primitives
				(gr_poly
					(pts
						(arc
							(start 0.3048 -0.2032)
							(mid 0.275042 -0.275042)
							(end 0.2032 -0.3048)
						)
						(arc
							(start -0.2032 -0.3048)
							(mid -0.275042 -0.275042)
							(end -0.3048 -0.2032)
						)
						(arc
							(start -0.3048 0.2032)
							(mid -0.275042 0.275042)
							(end -0.2032 0.3048)
						)
						(arc
							(start 0.2032 0.3048)
							(mid 0.275042 0.275042)
							(end 0.3048 0.2032)
						)
					)
					(width 0)
					(fill yes)
				)
			)
		)
	)
	(footprint ""
		(layer "F.Cu")
		(at 23.056088 -195.708016 90)
		(property "Reference" "SR309"
			(at 0 0 90)
			(layer "F.SilkS")
			(hide yes)
			(effects
				(font
					(size 1.27 1.27)
				)
			)
		)
		(property "Value" "0R2J-2-GP"
			(at 0.064008 -3.993896 90)
			(unlocked yes)
			(layer "F.Fab")
			(hide yes)
			(effects
				(font
					(size 1.016 1.016)
					(thickness 0.1524)
				)
			)
		)
		(property "Device Type" "R402H16"
			(at 0.064008 -5.517896 90)
			(unlocked yes)
			(layer "F.Fab")
			(hide yes)
			(effects
				(font
					(size 1.016 1.016)
					(thickness 0.1524)
				)
			)
		)
		(duplicate_pad_numbers_are_jumpers no)
		(fp_line
			(start 0.508 -0.9398)
			(end -0.508 -0.9398)
			(stroke
				(width 0.1524)
				(type default)
			)
			(layer "F.SilkS")
		)
		(fp_line
			(start -0.508 -0.9398)
			(end -0.508 0.9398)
			(stroke
				(width 0.1524)
				(type default)
			)
			(layer "F.SilkS")
		)
		(fp_rect
			(start -0.508 0.9398)
			(end 0.508 -0.9398)
			(stroke
				(width 0)
				(type default)
			)
			(fill no)
			(layer "F.CrtYd")
		)
		(fp_rect
			(start -0.508 0.9398)
			(end 0.508 -0.9398)
			(stroke
				(width 0)
				(type default)
			)
			(fill no)
			(layer "F.Fab")
		)
		(pad "1" smd custom
			(at 0 -0.4445 90)
			(size 0.1397 0.1397)
			(layers "F.Cu" "F.Mask" "F.Paste")
			(net "I2C_IO_EXP_RESET#")
			(options
				(clearance outline)
				(anchor circle)
			)
			(primitives
				(gr_poly
					(pts
						(arc
							(start -0.1778 -0.2794)
							(mid -0.249642 -0.249642)
							(end -0.2794 -0.1778)
						)
						(arc
							(start -0.2794 0.1778)
							(mid -0.249642 0.249642)
							(end -0.1778 0.2794)
						)
						(arc
							(start 0.1778 0.2794)
							(mid 0.249642 0.249642)
							(end 0.2794 0.1778)
						)
						(arc
							(start 0.2794 -0.1778)
							(mid 0.249642 -0.249642)
							(end 0.1778 -0.2794)
						)
					)
					(width 0)
					(fill yes)
				)
			)
		)
		(pad "2" smd custom
			(at 0 0.4445 90)
			(size 0.1397 0.1397)
			(layers "F.Cu" "F.Mask" "F.Paste")
			(net "I2C_IO_EXP_RESET#_PRST")
			(options
				(clearance outline)
				(anchor circle)
			)
			(primitives
				(gr_poly
					(pts
						(arc
							(start -0.1778 -0.2794)
							(mid -0.249642 -0.249642)
							(end -0.2794 -0.1778)
						)
						(arc
							(start -0.2794 0.1778)
							(mid -0.249642 0.249642)
							(end -0.1778 0.2794)
						)
						(arc
							(start 0.1778 0.2794)
							(mid 0.249642 0.249642)
							(end 0.2794 0.1778)
						)
						(arc
							(start 0.2794 -0.1778)
							(mid 0.249642 -0.249642)
							(end 0.1778 -0.2794)
						)
					)
					(width 0)
					(fill yes)
				)
			)
		)
	)
	(footprint ""
		(layer "F.Cu")
		(at 177.927 -219.329 -90)
		(property "Reference" "R1579"
			(at 0 0 270)
			(layer "F.SilkS")
			(hide yes)
			(effects
				(font
					(size 1.27 1.27)
				)
			)
		)
		(property "Value" "4K7R2F-GP"
			(at 0.064008 -3.993896 270)
			(unlocked yes)
			(layer "F.Fab")
			(hide yes)
			(effects
				(font
					(size 1.016 1.016)
					(thickness 0.1524)
				)
			)
		)
		(property "Device Type" "R402H16"
			(at 0.064008 -5.517896 270)
			(unlocked yes)
			(layer "F.Fab")
			(hide yes)
			(effects
				(font
					(size 1.016 1.016)
					(thickness 0.1524)
				)
			)
		)
		(duplicate_pad_numbers_are_jumpers no)
		(fp_line
			(start -0.508 -0.9398)
			(end -0.508 0.9398)
			(stroke
				(width 0.1524)
				(type default)
			)
			(layer "F.SilkS")
		)
		(fp_line
			(start 0.508 -0.9398)
			(end -0.508 -0.9398)
			(stroke
				(width 0.1524)
				(type default)
			)
			(layer "F.SilkS")
		)
		(fp_rect
			(start -0.508 0.9398)
			(end 0.508 -0.9398)
			(stroke
				(width 0)
				(type default)
			)
			(fill no)
			(layer "F.CrtYd")
		)
		(fp_rect
			(start -0.508 0.9398)
			(end 0.508 -0.9398)
			(stroke
				(width 0)
				(type default)
			)
			(fill no)
			(layer "F.Fab")
		)
		(pad "1" smd custom
			(at 0 -0.4445 270)
			(size 0.1397 0.1397)
			(layers "F.Cu" "F.Mask" "F.Paste")
			(net "P3V3_STBY")
			(options
				(clearance outline)
				(anchor circle)
			)
			(primitives
				(gr_poly
					(pts
						(arc
							(start -0.1778 -0.2794)
							(mid -0.249642 -0.249642)
							(end -0.2794 -0.1778)
						)
						(arc
							(start -0.2794 0.1778)
							(mid -0.249642 0.249642)
							(end -0.1778 0.2794)
						)
						(arc
							(start 0.1778 0.2794)
							(mid 0.249642 0.249642)
							(end 0.2794 0.1778)
						)
						(arc
							(start 0.2794 -0.1778)
							(mid 0.249642 -0.249642)
							(end 0.1778 -0.2794)
						)
					)
					(width 0)
					(fill yes)
				)
			)
		)
		(pad "2" smd custom
			(at 0 0.4445 270)
			(size 0.1397 0.1397)
			(layers "F.Cu" "F.Mask" "F.Paste")
			(net "PMU_PWRBTN_N")
			(options
				(clearance outline)
				(anchor circle)
			)
			(primitives
				(gr_poly
					(pts
						(arc
							(start -0.1778 -0.2794)
							(mid -0.249642 -0.249642)
							(end -0.2794 -0.1778)
						)
						(arc
							(start -0.2794 0.1778)
							(mid -0.249642 0.249642)
							(end -0.1778 0.2794)
						)
						(arc
							(start 0.1778 0.2794)
							(mid 0.249642 0.249642)
							(end 0.2794 0.1778)
						)
						(arc
							(start 0.2794 -0.1778)
							(mid 0.249642 -0.249642)
							(end 0.1778 -0.2794)
						)
					)
					(width 0)
					(fill yes)
				)
			)
		)
	)
	(footprint ""
		(layer "F.Cu")
		(at 133.25729 -53.895752)
		(property "Reference" "STP117"
			(at 0 0 0)
			(layer "F.SilkS")
			(hide yes)
			(effects
				(font
					(size 1.27 1.27)
				)
			)
		)
		(property "Value" "TPAD28"
			(at 0.0127 -1.8034 0)
			(unlocked yes)
			(layer "F.Fab")
			(hide yes)
			(effects
				(font
					(size 1.016 1.016)
					(thickness 0.1524)
				)
			)
		)
		(property "Device Type" "TPAD28"
			(at 0.0127 -3.3274 0)
			(unlocked yes)
			(layer "F.Fab")
			(hide yes)
			(effects
				(font
					(size 1.016 1.016)
					(thickness 0.1524)
				)
			)
		)
		(duplicate_pad_numbers_are_jumpers no)
		(fp_poly
			(pts
				(arc
					(start 0.3556 0)
					(mid -0.3556 0)
					(end 0.3556 0)
				)
			)
			(stroke
				(width 0)
				(type default)
			)
			(fill no)
			(layer "F.CrtYd")
		)
		(fp_poly
			(pts
				(arc
					(start 0.6096 0)
					(mid -0.6096 0)
					(end 0.6096 0)
				)
			)
			(stroke
				(width 0)
				(type default)
			)
			(fill no)
			(layer "F.Fab")
		)
		(pad "1" smd circle
			(at 0 0)
			(size 0.7112 0.7112)
			(layers "F.Cu" "F.Mask" "F.Paste")
			(net "XM_ADDR_17")
		)
	)
	(footprint ""
		(layer "F.Cu")
		(at 96.144842 -98.496882 -90)
		(property "Reference" "SR804"
			(at 0 0 270)
			(layer "F.SilkS")
			(hide yes)
			(effects
				(font
					(size 1.27 1.27)
				)
			)
		)
		(property "Value" "4K75R2F-1-GP"
			(at 0.064008 -3.993896 270)
			(unlocked yes)
			(layer "F.Fab")
			(hide yes)
			(effects
				(font
					(size 1.016 1.016)
					(thickness 0.1524)
				)
			)
		)
		(property "Device Type" "R402H16"
			(at 0.064008 -5.517896 270)
			(unlocked yes)
			(layer "F.Fab")
			(hide yes)
			(effects
				(font
					(size 1.016 1.016)
					(thickness 0.1524)
				)
			)
		)
		(duplicate_pad_numbers_are_jumpers no)
		(fp_line
			(start -0.508 -0.9398)
			(end -0.508 0.9398)
			(stroke
				(width 0.1524)
				(type default)
			)
			(layer "F.SilkS")
		)
		(fp_line
			(start 0.508 -0.9398)
			(end -0.508 -0.9398)
			(stroke
				(width 0.1524)
				(type default)
			)
			(layer "F.SilkS")
		)
		(fp_rect
			(start -0.508 0.9398)
			(end 0.508 -0.9398)
			(stroke
				(width 0)
				(type default)
			)
			(fill no)
			(layer "F.CrtYd")
		)
		(fp_rect
			(start -0.508 0.9398)
			(end 0.508 -0.9398)
			(stroke
				(width 0)
				(type default)
			)
			(fill no)
			(layer "F.Fab")
		)
		(pad "1" smd custom
			(at 0 -0.4445 270)
			(size 0.1397 0.1397)
			(layers "F.Cu" "F.Mask" "F.Paste")
			(net "LSI_EFUSE")
			(options
				(clearance outline)
				(anchor circle)
			)
			(primitives
				(gr_poly
					(pts
						(arc
							(start -0.1778 -0.2794)
							(mid -0.249642 -0.249642)
							(end -0.2794 -0.1778)
						)
						(arc
							(start -0.2794 0.1778)
							(mid -0.249642 0.249642)
							(end -0.1778 0.2794)
						)
						(arc
							(start 0.1778 0.2794)
							(mid 0.249642 0.249642)
							(end 0.2794 0.1778)
						)
						(arc
							(start 0.2794 -0.1778)
							(mid 0.249642 -0.249642)
							(end 0.1778 -0.2794)
						)
					)
					(width 0)
					(fill yes)
				)
			)
		)
		(pad "2" smd custom
			(at 0 0.4445 270)
			(size 0.1397 0.1397)
			(layers "F.Cu" "F.Mask" "F.Paste")
			(net "GND")
			(options
				(clearance outline)
				(anchor circle)
			)
			(primitives
				(gr_poly
					(pts
						(arc
							(start -0.1778 -0.2794)
							(mid -0.249642 -0.249642)
							(end -0.2794 -0.1778)
						)
						(arc
							(start -0.2794 0.1778)
							(mid -0.249642 0.249642)
							(end -0.1778 0.2794)
						)
						(arc
							(start 0.1778 0.2794)
							(mid 0.249642 0.249642)
							(end 0.2794 0.1778)
						)
						(arc
							(start 0.2794 -0.1778)
							(mid 0.249642 -0.249642)
							(end 0.1778 -0.2794)
						)
					)
					(width 0)
					(fill yes)
				)
			)
		)
	)
	(footprint ""
		(layer "F.Cu")
		(at 333.912718 -144.503648 90)
		(property "Reference" "R558"
			(at 0 0 90)
			(layer "F.SilkS")
			(hide yes)
			(effects
				(font
					(size 1.27 1.27)
				)
			)
		)
		(property "Value" "0R2J-2-GP"
			(at 0.064008 -3.993896 90)
			(unlocked yes)
			(layer "F.Fab")
			(hide yes)
			(effects
				(font
					(size 1.016 1.016)
					(thickness 0.1524)
				)
			)
		)
		(property "Device Type" "R402H16"
			(at 0.064008 -5.517896 90)
			(unlocked yes)
			(layer "F.Fab")
			(hide yes)
			(effects
				(font
					(size 1.016 1.016)
					(thickness 0.1524)
				)
			)
		)
		(duplicate_pad_numbers_are_jumpers no)
		(fp_line
			(start 0.508 -0.9398)
			(end -0.508 -0.9398)
			(stroke
				(width 0.1524)
				(type default)
			)
			(layer "F.SilkS")
		)
		(fp_line
			(start -0.508 -0.9398)
			(end -0.508 0.9398)
			(stroke
				(width 0.1524)
				(type default)
			)
			(layer "F.SilkS")
		)
		(fp_rect
			(start -0.508 0.9398)
			(end 0.508 -0.9398)
			(stroke
				(width 0)
				(type default)
			)
			(fill no)
			(layer "F.CrtYd")
		)
		(fp_rect
			(start -0.508 0.9398)
			(end 0.508 -0.9398)
			(stroke
				(width 0)
				(type default)
			)
			(fill no)
			(layer "F.Fab")
		)
		(pad "1" smd custom
			(at 0 -0.4445 90)
			(size 0.1397 0.1397)
			(layers "F.Cu" "F.Mask" "F.Paste")
			(net "PMU_PLTRST_N")
			(options
				(clearance outline)
				(anchor circle)
			)
			(primitives
				(gr_poly
					(pts
						(arc
							(start -0.1778 -0.2794)
							(mid -0.249642 -0.249642)
							(end -0.2794 -0.1778)
						)
						(arc
							(start -0.2794 0.1778)
							(mid -0.249642 0.249642)
							(end -0.1778 0.2794)
						)
						(arc
							(start 0.1778 0.2794)
							(mid 0.249642 0.249642)
							(end 0.2794 0.1778)
						)
						(arc
							(start 0.2794 -0.1778)
							(mid 0.249642 -0.249642)
							(end 0.1778 -0.2794)
						)
					)
					(width 0)
					(fill yes)
				)
			)
		)
		(pad "2" smd custom
			(at 0 0.4445 90)
			(size 0.1397 0.1397)
			(layers "F.Cu" "F.Mask" "F.Paste")
			(net "USB_RESET_N")
			(options
				(clearance outline)
				(anchor circle)
			)
			(primitives
				(gr_poly
					(pts
						(arc
							(start -0.1778 -0.2794)
							(mid -0.249642 -0.249642)
							(end -0.2794 -0.1778)
						)
						(arc
							(start -0.2794 0.1778)
							(mid -0.249642 0.249642)
							(end -0.1778 0.2794)
						)
						(arc
							(start 0.1778 0.2794)
							(mid 0.249642 0.249642)
							(end 0.2794 0.1778)
						)
						(arc
							(start 0.2794 -0.1778)
							(mid 0.249642 -0.249642)
							(end 0.1778 -0.2794)
						)
					)
					(width 0)
					(fill yes)
				)
			)
		)
	)
	(footprint ""
		(layer "F.Cu")
		(at 339.979 -116.332)
		(property "Reference" "PR13"
			(at 0 0 0)
			(layer "F.SilkS")
			(hide yes)
			(effects
				(font
					(size 1.27 1.27)
				)
			)
		)
		(property "Value" "10KR2F-2-GP"
			(at 0.064008 -3.993896 0)
			(unlocked yes)
			(layer "F.Fab")
			(hide yes)
			(effects
				(font
					(size 1.016 1.016)
					(thickness 0.1524)
				)
			)
		)
		(property "Device Type" "R402H16"
			(at 0.064008 -5.517896 0)
			(unlocked yes)
			(layer "F.Fab")
			(hide yes)
			(effects
				(font
					(size 1.016 1.016)
					(thickness 0.1524)
				)
			)
		)
		(duplicate_pad_numbers_are_jumpers no)
		(fp_line
			(start -0.508 -0.9398)
			(end -0.508 0.9398)
			(stroke
				(width 0.1524)
				(type default)
			)
			(layer "F.SilkS")
		)
		(fp_line
			(start 0.508 -0.9398)
			(end -0.508 -0.9398)
			(stroke
				(width 0.1524)
				(type default)
			)
			(layer "F.SilkS")
		)
		(fp_rect
			(start -0.508 0.9398)
			(end 0.508 -0.9398)
			(stroke
				(width 0)
				(type default)
			)
			(fill no)
			(layer "F.CrtYd")
		)
		(fp_rect
			(start -0.508 0.9398)
			(end 0.508 -0.9398)
			(stroke
				(width 0)
				(type default)
			)
			(fill no)
			(layer "F.Fab")
		)
		(pad "1" smd custom
			(at 0 -0.4445)
			(size 0.1397 0.1397)
			(layers "F.Cu" "F.Mask" "F.Paste")
			(net "P5V_STBY_PG")
			(options
				(clearance outline)
				(anchor circle)
			)
			(primitives
				(gr_poly
					(pts
						(arc
							(start -0.1778 -0.2794)
							(mid -0.249642 -0.249642)
							(end -0.2794 -0.1778)
						)
						(arc
							(start -0.2794 0.1778)
							(mid -0.249642 0.249642)
							(end -0.1778 0.2794)
						)
						(arc
							(start 0.1778 0.2794)
							(mid 0.249642 0.249642)
							(end 0.2794 0.1778)
						)
						(arc
							(start 0.2794 -0.1778)
							(mid 0.249642 -0.249642)
							(end 0.1778 -0.2794)
						)
					)
					(width 0)
					(fill yes)
				)
			)
		)
		(pad "2" smd custom
			(at 0 0.4445)
			(size 0.1397 0.1397)
			(layers "F.Cu" "F.Mask" "F.Paste")
			(net "P5V_STBY_VRG5")
			(options
				(clearance outline)
				(anchor circle)
			)
			(primitives
				(gr_poly
					(pts
						(arc
							(start -0.1778 -0.2794)
							(mid -0.249642 -0.249642)
							(end -0.2794 -0.1778)
						)
						(arc
							(start -0.2794 0.1778)
							(mid -0.249642 0.249642)
							(end -0.1778 0.2794)
						)
						(arc
							(start 0.1778 0.2794)
							(mid 0.249642 0.249642)
							(end 0.2794 0.1778)
						)
						(arc
							(start 0.2794 -0.1778)
							(mid 0.249642 -0.249642)
							(end 0.1778 -0.2794)
						)
					)
					(width 0)
					(fill yes)
				)
			)
		)
	)
	(footprint ""
		(layer "F.Cu")
		(at 333.883 -80.772 90)
		(property "Reference" "R682"
			(at 0 0 90)
			(layer "F.SilkS")
			(hide yes)
			(effects
				(font
					(size 1.27 1.27)
				)
			)
		)
		(property "Value" "0R2J-2-GP"
			(at 0.064008 -3.993896 90)
			(unlocked yes)
			(layer "F.Fab")
			(hide yes)
			(effects
				(font
					(size 1.016 1.016)
					(thickness 0.1524)
				)
			)
		)
		(property "Device Type" "R402H16"
			(at 0.064008 -5.517896 90)
			(unlocked yes)
			(layer "F.Fab")
			(hide yes)
			(effects
				(font
					(size 1.016 1.016)
					(thickness 0.1524)
				)
			)
		)
		(duplicate_pad_numbers_are_jumpers no)
		(fp_line
			(start 0.508 -0.9398)
			(end -0.508 -0.9398)
			(stroke
				(width 0.1524)
				(type default)
			)
			(layer "F.SilkS")
		)
		(fp_line
			(start -0.508 -0.9398)
			(end -0.508 0.9398)
			(stroke
				(width 0.1524)
				(type default)
			)
			(layer "F.SilkS")
		)
		(fp_rect
			(start -0.508 0.9398)
			(end 0.508 -0.9398)
			(stroke
				(width 0)
				(type default)
			)
			(fill no)
			(layer "F.CrtYd")
		)
		(fp_rect
			(start -0.508 0.9398)
			(end 0.508 -0.9398)
			(stroke
				(width 0)
				(type default)
			)
			(fill no)
			(layer "F.Fab")
		)
		(pad "1" smd custom
			(at 0 -0.4445 90)
			(size 0.1397 0.1397)
			(layers "F.Cu" "F.Mask" "F.Paste")
			(net "ROMD2_R_R")
			(options
				(clearance outline)
				(anchor circle)
			)
			(primitives
				(gr_poly
					(pts
						(arc
							(start -0.1778 -0.2794)
							(mid -0.249642 -0.249642)
							(end -0.2794 -0.1778)
						)
						(arc
							(start -0.2794 0.1778)
							(mid -0.249642 0.249642)
							(end -0.1778 0.2794)
						)
						(arc
							(start 0.1778 0.2794)
							(mid 0.249642 0.249642)
							(end 0.2794 0.1778)
						)
						(arc
							(start 0.2794 -0.1778)
							(mid 0.249642 -0.249642)
							(end 0.1778 -0.2794)
						)
					)
					(width 0)
					(fill yes)
				)
			)
		)
		(pad "2" smd custom
			(at 0 0.4445 90)
			(size 0.1397 0.1397)
			(layers "F.Cu" "F.Mask" "F.Paste")
			(net "ROMD2_R")
			(options
				(clearance outline)
				(anchor circle)
			)
			(primitives
				(gr_poly
					(pts
						(arc
							(start -0.1778 -0.2794)
							(mid -0.249642 -0.249642)
							(end -0.2794 -0.1778)
						)
						(arc
							(start -0.2794 0.1778)
							(mid -0.249642 0.249642)
							(end -0.1778 0.2794)
						)
						(arc
							(start 0.1778 0.2794)
							(mid 0.249642 0.249642)
							(end 0.2794 0.1778)
						)
						(arc
							(start 0.2794 -0.1778)
							(mid 0.249642 -0.249642)
							(end 0.1778 -0.2794)
						)
					)
					(width 0)
					(fill yes)
				)
			)
		)
	)
	(footprint ""
		(layer "F.Cu")
		(at 343.408 -20.32)
		(property "Reference" "R453"
			(at 0 0 0)
			(layer "F.SilkS")
			(hide yes)
			(effects
				(font
					(size 1.27 1.27)
				)
			)
		)
		(property "Value" "8K2R2J-3-GP"
			(at 0.064008 -3.993896 0)
			(unlocked yes)
			(layer "F.Fab")
			(hide yes)
			(effects
				(font
					(size 1.016 1.016)
					(thickness 0.1524)
				)
			)
		)
		(property "Device Type" "R402H16"
			(at 0.064008 -5.517896 0)
			(unlocked yes)
			(layer "F.Fab")
			(hide yes)
			(effects
				(font
					(size 1.016 1.016)
					(thickness 0.1524)
				)
			)
		)
		(duplicate_pad_numbers_are_jumpers no)
		(fp_line
			(start -0.508 -0.9398)
			(end -0.508 0.9398)
			(stroke
				(width 0.1524)
				(type default)
			)
			(layer "F.SilkS")
		)
		(fp_line
			(start 0.508 -0.9398)
			(end -0.508 -0.9398)
			(stroke
				(width 0.1524)
				(type default)
			)
			(layer "F.SilkS")
		)
		(fp_rect
			(start -0.508 0.9398)
			(end 0.508 -0.9398)
			(stroke
				(width 0)
				(type default)
			)
			(fill no)
			(layer "F.CrtYd")
		)
		(fp_rect
			(start -0.508 0.9398)
			(end 0.508 -0.9398)
			(stroke
				(width 0)
				(type default)
			)
			(fill no)
			(layer "F.Fab")
		)
		(pad "1" smd custom
			(at 0 -0.4445)
			(size 0.1397 0.1397)
			(layers "F.Cu" "F.Mask" "F.Paste")
			(net "P3V3_STBY")
			(options
				(clearance outline)
				(anchor circle)
			)
			(primitives
				(gr_poly
					(pts
						(arc
							(start -0.1778 -0.2794)
							(mid -0.249642 -0.249642)
							(end -0.2794 -0.1778)
						)
						(arc
							(start -0.2794 0.1778)
							(mid -0.249642 0.249642)
							(end -0.1778 0.2794)
						)
						(arc
							(start 0.1778 0.2794)
							(mid 0.249642 0.249642)
							(end 0.2794 0.1778)
						)
						(arc
							(start 0.2794 -0.1778)
							(mid 0.249642 -0.249642)
							(end 0.1778 -0.2794)
						)
					)
					(width 0)
					(fill yes)
				)
			)
		)
		(pad "2" smd custom
			(at 0 0.4445)
			(size 0.1397 0.1397)
			(layers "F.Cu" "F.Mask" "F.Paste")
			(net "CPU_EXP_RST")
			(options
				(clearance outline)
				(anchor circle)
			)
			(primitives
				(gr_poly
					(pts
						(arc
							(start -0.1778 -0.2794)
							(mid -0.249642 -0.249642)
							(end -0.2794 -0.1778)
						)
						(arc
							(start -0.2794 0.1778)
							(mid -0.249642 0.249642)
							(end -0.1778 0.2794)
						)
						(arc
							(start 0.1778 0.2794)
							(mid 0.249642 0.249642)
							(end 0.2794 0.1778)
						)
						(arc
							(start 0.2794 -0.1778)
							(mid 0.249642 -0.249642)
							(end 0.1778 -0.2794)
						)
					)
					(width 0)
					(fill yes)
				)
			)
		)
	)
	(footprint ""
		(layer "F.Cu")
		(at 85.857842 -116.530882 90)
		(property "Reference" "SU66"
			(at 0 0 90)
			(layer "F.SilkS")
			(hide yes)
			(effects
				(font
					(size 1.27 1.27)
				)
			)
		)
		(property "Value" "PCA9306DCTT-GP"
			(at 0 -11.6332 90)
			(unlocked yes)
			(layer "F.Fab")
			(hide yes)
			(effects
				(font
					(size 1.016 1.016)
					(thickness 0.1524)
				)
			)
		)
		(property "Device Type" "SSOIC8H52"
			(at 0 -13.1572 90)
			(unlocked yes)
			(layer "F.Fab")
			(hide yes)
			(effects
				(font
					(size 1.016 1.016)
					(thickness 0.1524)
				)
			)
		)
		(duplicate_pad_numbers_are_jumpers no)
		(fp_line
			(start 1.0668 -0.5842)
			(end 1.0668 0.5842)
			(stroke
				(width 0.1524)
				(type default)
			)
			(layer "F.SilkS")
		)
		(fp_line
			(start -1.7018 -0.5842)
			(end 1.0668 -0.5842)
			(stroke
				(width 0.1524)
				(type default)
			)
			(layer "F.SilkS")
		)
		(fp_line
			(start -1.7018 -0.5842)
			(end -1.7018 2.286)
			(stroke
				(width 0.1524)
				(type default)
			)
			(layer "F.SilkS")
		)
		(fp_line
			(start -1.397 0)
			(end -1.7018 -0.3048)
			(stroke
				(width 0.1524)
				(type default)
			)
			(layer "F.SilkS")
		)
		(fp_line
			(start -1.397 0)
			(end -1.7018 0.3048)
			(stroke
				(width 0.1524)
				(type default)
			)
			(layer "F.SilkS")
		)
		(fp_line
			(start 1.0668 0.5842)
			(end -1.524 0.5842)
			(stroke
				(width 0.1524)
				(type default)
			)
			(layer "F.SilkS")
		)
		(fp_line
			(start -1.524 0.5842)
			(end -1.524 2.286)
			(stroke
				(width 0.508)
				(type default)
			)
			(layer "F.SilkS")
		)
		(fp_poly
			(pts
				(xy -1.1684 -0.5842) (xy 1.0668 -0.5842) (xy 1.0668 0.5842) (xy -1.1684 0.5842)
			)
			(stroke
				(width 0)
				(type default)
			)
			(fill yes)
			(layer "F.SilkS")
		)
		(fp_poly
			(pts
				(xy -1.778 2.54) (xy 1.778 2.54) (xy 1.778 -2.54) (xy -1.778 -2.54)
			)
			(stroke
				(width 0)
				(type default)
			)
			(fill no)
			(layer "F.CrtYd")
		)
		(fp_poly
			(pts
				(xy -1.778 -2.54) (xy 1.778 -2.54) (xy 1.778 2.54) (xy -1.778 2.54)
			)
			(stroke
				(width 0)
				(type default)
			)
			(fill no)
			(layer "F.Fab")
		)
		(pad "1" smd rect
			(at -0.97536 1.6256 90)
			(size 0.3556 1.524)
			(layers "F.Cu" "F.Mask" "F.Paste")
			(net "GND")
		)
		(pad "2" smd rect
			(at -0.32512 1.6256 90)
			(size 0.3556 1.524)
			(layers "F.Cu" "F.Mask" "F.Paste")
			(net "P1V8_E")
		)
		(pad "3" smd rect
			(at 0.32512 1.6256 90)
			(size 0.3556 1.524)
			(layers "F.Cu" "F.Mask" "F.Paste")
			(net "EXP_I2C_SCL_2")
		)
		(pad "4" smd rect
			(at 0.97536 1.6256 90)
			(size 0.3556 1.524)
			(layers "F.Cu" "F.Mask" "F.Paste")
			(net "EXP_I2C_SDA_2")
		)
		(pad "5" smd rect
			(at 0.97536 -1.6256 90)
			(size 0.3556 1.524)
			(layers "F.Cu" "F.Mask" "F.Paste")
			(net "EXP_IOC_BMC_SDA_14")
		)
		(pad "6" smd rect
			(at 0.32512 -1.6256 90)
			(size 0.3556 1.524)
			(layers "F.Cu" "F.Mask" "F.Paste")
			(net "EXP_IOC_BMC_SCL_14")
		)
		(pad "7" smd rect
			(at -0.32512 -1.6256 90)
			(size 0.3556 1.524)
			(layers "F.Cu" "F.Mask" "F.Paste")
			(net "EXP_I2C_VREF_1")
		)
		(pad "8" smd rect
			(at -0.97536 -1.6256 90)
			(size 0.3556 1.524)
			(layers "F.Cu" "F.Mask" "F.Paste")
			(net "EXP_I2C_VREF_1")
		)
	)
	(footprint ""
		(layer "F.Cu")
		(at 270.374872 -57.730136 -90)
		(property "Reference" "PR114"
			(at 0 0 270)
			(layer "F.SilkS")
			(hide yes)
			(effects
				(font
					(size 1.27 1.27)
				)
			)
		)
		(property "Value" "4K02R2F-GP"
			(at 0.064008 -3.993896 270)
			(unlocked yes)
			(layer "F.Fab")
			(hide yes)
			(effects
				(font
					(size 1.016 1.016)
					(thickness 0.1524)
				)
			)
		)
		(property "Device Type" "R402H16"
			(at 0.064008 -5.517896 270)
			(unlocked yes)
			(layer "F.Fab")
			(hide yes)
			(effects
				(font
					(size 1.016 1.016)
					(thickness 0.1524)
				)
			)
		)
		(duplicate_pad_numbers_are_jumpers no)
		(fp_line
			(start -0.508 -0.9398)
			(end -0.508 0.9398)
			(stroke
				(width 0.1524)
				(type default)
			)
			(layer "F.SilkS")
		)
		(fp_line
			(start 0.508 -0.9398)
			(end -0.508 -0.9398)
			(stroke
				(width 0.1524)
				(type default)
			)
			(layer "F.SilkS")
		)
		(fp_rect
			(start -0.508 0.9398)
			(end 0.508 -0.9398)
			(stroke
				(width 0)
				(type default)
			)
			(fill no)
			(layer "F.CrtYd")
		)
		(fp_rect
			(start -0.508 0.9398)
			(end 0.508 -0.9398)
			(stroke
				(width 0)
				(type default)
			)
			(fill no)
			(layer "F.Fab")
		)
		(pad "1" smd custom
			(at 0 -0.4445 270)
			(size 0.1397 0.1397)
			(layers "F.Cu" "F.Mask" "F.Paste")
			(net "P3V3_EN_G")
			(options
				(clearance outline)
				(anchor circle)
			)
			(primitives
				(gr_poly
					(pts
						(arc
							(start -0.1778 -0.2794)
							(mid -0.249642 -0.249642)
							(end -0.2794 -0.1778)
						)
						(arc
							(start -0.2794 0.1778)
							(mid -0.249642 0.249642)
							(end -0.1778 0.2794)
						)
						(arc
							(start 0.1778 0.2794)
							(mid 0.249642 0.249642)
							(end 0.2794 0.1778)
						)
						(arc
							(start 0.2794 -0.1778)
							(mid 0.249642 -0.249642)
							(end 0.1778 -0.2794)
						)
					)
					(width 0)
					(fill yes)
				)
			)
		)
		(pad "2" smd custom
			(at 0 0.4445 270)
			(size 0.1397 0.1397)
			(layers "F.Cu" "F.Mask" "F.Paste")
			(net "P3V3_STBY")
			(options
				(clearance outline)
				(anchor circle)
			)
			(primitives
				(gr_poly
					(pts
						(arc
							(start -0.1778 -0.2794)
							(mid -0.249642 -0.249642)
							(end -0.2794 -0.1778)
						)
						(arc
							(start -0.2794 0.1778)
							(mid -0.249642 0.249642)
							(end -0.1778 0.2794)
						)
						(arc
							(start 0.1778 0.2794)
							(mid 0.249642 0.249642)
							(end 0.2794 0.1778)
						)
						(arc
							(start 0.2794 -0.1778)
							(mid 0.249642 -0.249642)
							(end 0.1778 -0.2794)
						)
					)
					(width 0)
					(fill yes)
				)
			)
		)
	)
	(footprint ""
		(layer "F.Cu")
		(at 289.678872 -71.700136 90)
		(property "Reference" "C266"
			(at 0 0 90)
			(layer "F.SilkS")
			(hide yes)
			(effects
				(font
					(size 1.27 1.27)
				)
			)
		)
		(property "Value" "SC2200P50V2KX-2GP"
			(at 1.1811 -2.7051 90)
			(unlocked yes)
			(layer "F.Fab")
			(hide yes)
			(effects
				(font
					(size 1.016 1.016)
					(thickness 0.1524)
				)
			)
		)
		(property "Device Type" "C402H22"
			(at 1.1811 -4.2291 90)
			(unlocked yes)
			(layer "F.Fab")
			(hide yes)
			(effects
				(font
					(size 1.016 1.016)
					(thickness 0.1524)
				)
			)
		)
		(duplicate_pad_numbers_are_jumpers no)
		(fp_rect
			(start -0.4318 0.9525)
			(end 0.4318 -0.9525)
			(stroke
				(width 0)
				(type default)
			)
			(fill no)
			(layer "F.CrtYd")
		)
		(fp_rect
			(start -0.4318 0.9525)
			(end 0.4318 -0.9525)
			(stroke
				(width 0)
				(type default)
			)
			(fill no)
			(layer "F.Fab")
		)
		(pad "1" smd custom
			(at 0 -0.4445 90)
			(size 0.1524 0.1524)
			(layers "F.Cu" "F.Mask" "F.Paste")
			(net "VR_HSC_GATE_MSB")
			(options
				(clearance outline)
				(anchor circle)
			)
			(primitives
				(gr_poly
					(pts
						(arc
							(start 0.3048 -0.2032)
							(mid 0.275042 -0.275042)
							(end 0.2032 -0.3048)
						)
						(arc
							(start -0.2032 -0.3048)
							(mid -0.275042 -0.275042)
							(end -0.3048 -0.2032)
						)
						(arc
							(start -0.3048 0.2032)
							(mid -0.275042 0.275042)
							(end -0.2032 0.3048)
						)
						(arc
							(start 0.2032 0.3048)
							(mid 0.275042 0.275042)
							(end 0.3048 0.2032)
						)
					)
					(width 0)
					(fill yes)
				)
			)
		)
		(pad "2" smd custom
			(at 0 0.4445 90)
			(size 0.1524 0.1524)
			(layers "F.Cu" "F.Mask" "F.Paste")
			(net "GND")
			(options
				(clearance outline)
				(anchor circle)
			)
			(primitives
				(gr_poly
					(pts
						(arc
							(start 0.3048 -0.2032)
							(mid 0.275042 -0.275042)
							(end 0.2032 -0.3048)
						)
						(arc
							(start -0.2032 -0.3048)
							(mid -0.275042 -0.275042)
							(end -0.3048 -0.2032)
						)
						(arc
							(start -0.3048 0.2032)
							(mid -0.275042 0.275042)
							(end -0.2032 0.3048)
						)
						(arc
							(start 0.2032 0.3048)
							(mid 0.275042 0.275042)
							(end 0.3048 0.2032)
						)
					)
					(width 0)
					(fill yes)
				)
			)
		)
	)
	(footprint ""
		(layer "F.Cu")
		(at 281.051 -182.3974)
		(property "Reference" "TP143"
			(at 0 0 0)
			(layer "F.SilkS")
			(hide yes)
			(effects
				(font
					(size 1.27 1.27)
				)
			)
		)
		(property "Value" "TPAD28"
			(at 0.0127 -1.8034 0)
			(unlocked yes)
			(layer "F.Fab")
			(hide yes)
			(effects
				(font
					(size 1.016 1.016)
					(thickness 0.1524)
				)
			)
		)
		(property "Device Type" "TPAD28"
			(at 0.0127 -3.3274 0)
			(unlocked yes)
			(layer "F.Fab")
			(hide yes)
			(effects
				(font
					(size 1.016 1.016)
					(thickness 0.1524)
				)
			)
		)
		(duplicate_pad_numbers_are_jumpers no)
		(fp_poly
			(pts
				(arc
					(start 0.3556 0)
					(mid -0.3556 0)
					(end 0.3556 0)
				)
			)
			(stroke
				(width 0)
				(type default)
			)
			(fill no)
			(layer "F.CrtYd")
		)
		(fp_poly
			(pts
				(arc
					(start 0.6096 0)
					(mid -0.6096 0)
					(end 0.6096 0)
				)
			)
			(stroke
				(width 0)
				(type default)
			)
			(fill no)
			(layer "F.Fab")
		)
		(pad "1" smd circle
			(at 0 0)
			(size 0.7112 0.7112)
			(layers "F.Cu" "F.Mask" "F.Paste")
			(net "TP_BMC_GPIOR1")
		)
	)
	(footprint ""
		(layer "F.Cu")
		(at 15.944088 -206.884016 180)
		(property "Reference" "SU52"
			(at 0 0 180)
			(layer "F.SilkS")
			(hide yes)
			(effects
				(font
					(size 1.27 1.27)
				)
			)
		)
		(property "Value" "PCA9306DCTT-GP"
			(at 0 -11.6332 180)
			(unlocked yes)
			(layer "F.Fab")
			(hide yes)
			(effects
				(font
					(size 1.016 1.016)
					(thickness 0.1524)
				)
			)
		)
		(property "Device Type" "SSOIC8H52"
			(at 0 -13.1572 180)
			(unlocked yes)
			(layer "F.Fab")
			(hide yes)
			(effects
				(font
					(size 1.016 1.016)
					(thickness 0.1524)
				)
			)
		)
		(duplicate_pad_numbers_are_jumpers no)
		(fp_line
			(start 1.0668 0.5842)
			(end -1.524 0.5842)
			(stroke
				(width 0.1524)
				(type default)
			)
			(layer "F.SilkS")
		)
		(fp_line
			(start 1.0668 -0.5842)
			(end 1.0668 0.5842)
			(stroke
				(width 0.1524)
				(type default)
			)
			(layer "F.SilkS")
		)
		(fp_line
			(start -1.397 0)
			(end -1.7018 0.3048)
			(stroke
				(width 0.1524)
				(type default)
			)
			(layer "F.SilkS")
		)
		(fp_line
			(start -1.397 0)
			(end -1.7018 -0.3048)
			(stroke
				(width 0.1524)
				(type default)
			)
			(layer "F.SilkS")
		)
		(fp_line
			(start -1.524 0.5842)
			(end -1.524 2.286)
			(stroke
				(width 0.508)
				(type default)
			)
			(layer "F.SilkS")
		)
		(fp_line
			(start -1.7018 -0.5842)
			(end 1.0668 -0.5842)
			(stroke
				(width 0.1524)
				(type default)
			)
			(layer "F.SilkS")
		)
		(fp_line
			(start -1.7018 -0.5842)
			(end -1.7018 2.286)
			(stroke
				(width 0.1524)
				(type default)
			)
			(layer "F.SilkS")
		)
		(fp_poly
			(pts
				(xy -1.1684 -0.5842) (xy 1.0668 -0.5842) (xy 1.0668 0.5842) (xy -1.1684 0.5842)
			)
			(stroke
				(width 0)
				(type default)
			)
			(fill yes)
			(layer "F.SilkS")
		)
		(fp_poly
			(pts
				(xy -1.778 2.54) (xy 1.778 2.54) (xy 1.778 -2.54) (xy -1.778 -2.54)
			)
			(stroke
				(width 0)
				(type default)
			)
			(fill no)
			(layer "F.CrtYd")
		)
		(fp_poly
			(pts
				(xy -1.778 -2.54) (xy 1.778 -2.54) (xy 1.778 2.54) (xy -1.778 2.54)
			)
			(stroke
				(width 0)
				(type default)
			)
			(fill no)
			(layer "F.Fab")
		)
		(pad "1" smd rect
			(at -0.97536 1.6256 180)
			(size 0.3556 1.524)
			(layers "F.Cu" "F.Mask" "F.Paste")
			(net "GND")
		)
		(pad "2" smd rect
			(at -0.32512 1.6256 180)
			(size 0.3556 1.524)
			(layers "F.Cu" "F.Mask" "F.Paste")
			(net "P1V8_E")
		)
		(pad "3" smd rect
			(at 0.32512 1.6256 180)
			(size 0.3556 1.524)
			(layers "F.Cu" "F.Mask" "F.Paste")
			(net "BMC_IOEXP_SCL_10")
		)
		(pad "4" smd rect
			(at 0.97536 1.6256 180)
			(size 0.3556 1.524)
			(layers "F.Cu" "F.Mask" "F.Paste")
			(net "BMC_IOEXP_SDA_10")
		)
		(pad "5" smd rect
			(at 0.97536 -1.6256 180)
			(size 0.3556 1.524)
			(layers "F.Cu" "F.Mask" "F.Paste")
			(net "BMC_I2C_SDA_10")
		)
		(pad "6" smd rect
			(at 0.32512 -1.6256 180)
			(size 0.3556 1.524)
			(layers "F.Cu" "F.Mask" "F.Paste")
			(net "BMC_I2C_SCL_10")
		)
		(pad "7" smd rect
			(at -0.32512 -1.6256 180)
			(size 0.3556 1.524)
			(layers "F.Cu" "F.Mask" "F.Paste")
			(net "BMC_I2C10_EN")
		)
		(pad "8" smd rect
			(at -0.97536 -1.6256 180)
			(size 0.3556 1.524)
			(layers "F.Cu" "F.Mask" "F.Paste")
			(net "BMC_I2C10_EN")
		)
	)
	(footprint ""
		(layer "F.Cu")
		(at 304.546 -102.108 180)
		(property "Reference" "R160"
			(at 0 0 180)
			(layer "F.SilkS")
			(hide yes)
			(effects
				(font
					(size 1.27 1.27)
				)
			)
		)
		(property "Value" "4K7R2F-GP"
			(at 0.064008 -3.993896 180)
			(unlocked yes)
			(layer "F.Fab")
			(hide yes)
			(effects
				(font
					(size 1.016 1.016)
					(thickness 0.1524)
				)
			)
		)
		(property "Device Type" "R402H16"
			(at 0.064008 -5.517896 180)
			(unlocked yes)
			(layer "F.Fab")
			(hide yes)
			(effects
				(font
					(size 1.016 1.016)
					(thickness 0.1524)
				)
			)
		)
		(duplicate_pad_numbers_are_jumpers no)
		(fp_line
			(start 0.508 -0.9398)
			(end -0.508 -0.9398)
			(stroke
				(width 0.1524)
				(type default)
			)
			(layer "F.SilkS")
		)
		(fp_line
			(start -0.508 -0.9398)
			(end -0.508 0.9398)
			(stroke
				(width 0.1524)
				(type default)
			)
			(layer "F.SilkS")
		)
		(fp_rect
			(start -0.508 0.9398)
			(end 0.508 -0.9398)
			(stroke
				(width 0)
				(type default)
			)
			(fill no)
			(layer "F.CrtYd")
		)
		(fp_rect
			(start -0.508 0.9398)
			(end 0.508 -0.9398)
			(stroke
				(width 0)
				(type default)
			)
			(fill no)
			(layer "F.Fab")
		)
		(pad "1" smd custom
			(at 0 -0.4445 180)
			(size 0.1397 0.1397)
			(layers "F.Cu" "F.Mask" "F.Paste")
			(net "TEMP_2_A2")
			(options
				(clearance outline)
				(anchor circle)
			)
			(primitives
				(gr_poly
					(pts
						(arc
							(start -0.1778 -0.2794)
							(mid -0.249642 -0.249642)
							(end -0.2794 -0.1778)
						)
						(arc
							(start -0.2794 0.1778)
							(mid -0.249642 0.249642)
							(end -0.1778 0.2794)
						)
						(arc
							(start 0.1778 0.2794)
							(mid 0.249642 0.249642)
							(end 0.2794 0.1778)
						)
						(arc
							(start 0.2794 -0.1778)
							(mid 0.249642 -0.249642)
							(end 0.1778 -0.2794)
						)
					)
					(width 0)
					(fill yes)
				)
			)
		)
		(pad "2" smd custom
			(at 0 0.4445 180)
			(size 0.1397 0.1397)
			(layers "F.Cu" "F.Mask" "F.Paste")
			(net "GND")
			(options
				(clearance outline)
				(anchor circle)
			)
			(primitives
				(gr_poly
					(pts
						(arc
							(start -0.1778 -0.2794)
							(mid -0.249642 -0.249642)
							(end -0.2794 -0.1778)
						)
						(arc
							(start -0.2794 0.1778)
							(mid -0.249642 0.249642)
							(end -0.1778 0.2794)
						)
						(arc
							(start 0.1778 0.2794)
							(mid 0.249642 0.249642)
							(end 0.2794 0.1778)
						)
						(arc
							(start 0.2794 -0.1778)
							(mid 0.249642 -0.249642)
							(end 0.1778 -0.2794)
						)
					)
					(width 0)
					(fill yes)
				)
			)
		)
	)
	(footprint ""
		(layer "F.Cu")
		(at 98.806 -221.488 180)
		(property "Reference" "R640"
			(at 0 0 180)
			(layer "F.SilkS")
			(hide yes)
			(effects
				(font
					(size 1.27 1.27)
				)
			)
		)
		(property "Value" "4K7R2F-GP"
			(at 0.064008 -3.993896 180)
			(unlocked yes)
			(layer "F.Fab")
			(hide yes)
			(effects
				(font
					(size 1.016 1.016)
					(thickness 0.1524)
				)
			)
		)
		(property "Device Type" "R402H16"
			(at 0.064008 -5.517896 180)
			(unlocked yes)
			(layer "F.Fab")
			(hide yes)
			(effects
				(font
					(size 1.016 1.016)
					(thickness 0.1524)
				)
			)
		)
		(duplicate_pad_numbers_are_jumpers no)
		(fp_line
			(start 0.508 -0.9398)
			(end -0.508 -0.9398)
			(stroke
				(width 0.1524)
				(type default)
			)
			(layer "F.SilkS")
		)
		(fp_line
			(start -0.508 -0.9398)
			(end -0.508 0.9398)
			(stroke
				(width 0.1524)
				(type default)
			)
			(layer "F.SilkS")
		)
		(fp_rect
			(start -0.508 0.9398)
			(end 0.508 -0.9398)
			(stroke
				(width 0)
				(type default)
			)
			(fill no)
			(layer "F.CrtYd")
		)
		(fp_rect
			(start -0.508 0.9398)
			(end 0.508 -0.9398)
			(stroke
				(width 0)
				(type default)
			)
			(fill no)
			(layer "F.Fab")
		)
		(pad "1" smd custom
			(at 0 -0.4445 180)
			(size 0.1397 0.1397)
			(layers "F.Cu" "F.Mask" "F.Paste")
			(net "P3V3_STBY")
			(options
				(clearance outline)
				(anchor circle)
			)
			(primitives
				(gr_poly
					(pts
						(arc
							(start -0.1778 -0.2794)
							(mid -0.249642 -0.249642)
							(end -0.2794 -0.1778)
						)
						(arc
							(start -0.2794 0.1778)
							(mid -0.249642 0.249642)
							(end -0.1778 0.2794)
						)
						(arc
							(start 0.1778 0.2794)
							(mid 0.249642 0.249642)
							(end 0.2794 0.1778)
						)
						(arc
							(start 0.2794 -0.1778)
							(mid 0.249642 -0.249642)
							(end 0.1778 -0.2794)
						)
					)
					(width 0)
					(fill yes)
				)
			)
		)
		(pad "2" smd custom
			(at 0 0.4445 180)
			(size 0.1397 0.1397)
			(layers "F.Cu" "F.Mask" "F.Paste")
			(net "IO_EXP_HDD_FAULT_A0")
			(options
				(clearance outline)
				(anchor circle)
			)
			(primitives
				(gr_poly
					(pts
						(arc
							(start -0.1778 -0.2794)
							(mid -0.249642 -0.249642)
							(end -0.2794 -0.1778)
						)
						(arc
							(start -0.2794 0.1778)
							(mid -0.249642 0.249642)
							(end -0.1778 0.2794)
						)
						(arc
							(start 0.1778 0.2794)
							(mid 0.249642 0.249642)
							(end 0.2794 0.1778)
						)
						(arc
							(start 0.2794 -0.1778)
							(mid 0.249642 -0.249642)
							(end 0.1778 -0.2794)
						)
					)
					(width 0)
					(fill yes)
				)
			)
		)
	)
	(footprint ""
		(layer "F.Cu")
		(at 338.455 -13.335)
		(property "Reference" "SR707"
			(at 0 0 0)
			(layer "F.SilkS")
			(hide yes)
			(effects
				(font
					(size 1.27 1.27)
				)
			)
		)
		(property "Value" "150R2F-1-GP"
			(at 0.064008 -3.993896 0)
			(unlocked yes)
			(layer "F.Fab")
			(hide yes)
			(effects
				(font
					(size 1.016 1.016)
					(thickness 0.1524)
				)
			)
		)
		(property "Device Type" "R402H16"
			(at 0.064008 -5.517896 0)
			(unlocked yes)
			(layer "F.Fab")
			(hide yes)
			(effects
				(font
					(size 1.016 1.016)
					(thickness 0.1524)
				)
			)
		)
		(duplicate_pad_numbers_are_jumpers no)
		(fp_line
			(start -0.508 -0.9398)
			(end -0.508 0.9398)
			(stroke
				(width 0.1524)
				(type default)
			)
			(layer "F.SilkS")
		)
		(fp_line
			(start 0.508 -0.9398)
			(end -0.508 -0.9398)
			(stroke
				(width 0.1524)
				(type default)
			)
			(layer "F.SilkS")
		)
		(fp_rect
			(start -0.508 0.9398)
			(end 0.508 -0.9398)
			(stroke
				(width 0)
				(type default)
			)
			(fill no)
			(layer "F.CrtYd")
		)
		(fp_rect
			(start -0.508 0.9398)
			(end 0.508 -0.9398)
			(stroke
				(width 0)
				(type default)
			)
			(fill no)
			(layer "F.Fab")
		)
		(pad "1" smd custom
			(at 0 -0.4445)
			(size 0.1397 0.1397)
			(layers "F.Cu" "F.Mask" "F.Paste")
			(net "P3V3_STBY")
			(options
				(clearance outline)
				(anchor circle)
			)
			(primitives
				(gr_poly
					(pts
						(arc
							(start -0.1778 -0.2794)
							(mid -0.249642 -0.249642)
							(end -0.2794 -0.1778)
						)
						(arc
							(start -0.2794 0.1778)
							(mid -0.249642 0.249642)
							(end -0.1778 0.2794)
						)
						(arc
							(start 0.1778 0.2794)
							(mid 0.249642 0.249642)
							(end 0.2794 0.1778)
						)
						(arc
							(start 0.2794 -0.1778)
							(mid 0.249642 -0.249642)
							(end 0.1778 -0.2794)
						)
					)
					(width 0)
					(fill yes)
				)
			)
		)
		(pad "2" smd custom
			(at 0 0.4445)
			(size 0.1397 0.1397)
			(layers "F.Cu" "F.Mask" "F.Paste")
			(net "EXP_BMC_HB_LED_R")
			(options
				(clearance outline)
				(anchor circle)
			)
			(primitives
				(gr_poly
					(pts
						(arc
							(start -0.1778 -0.2794)
							(mid -0.249642 -0.249642)
							(end -0.2794 -0.1778)
						)
						(arc
							(start -0.2794 0.1778)
							(mid -0.249642 0.249642)
							(end -0.1778 0.2794)
						)
						(arc
							(start 0.1778 0.2794)
							(mid 0.249642 0.249642)
							(end 0.2794 0.1778)
						)
						(arc
							(start 0.2794 -0.1778)
							(mid 0.249642 -0.249642)
							(end 0.1778 -0.2794)
						)
					)
					(width 0)
					(fill yes)
				)
			)
		)
	)
	(footprint ""
		(layer "F.Cu")
		(at 89.662 -223.139 -90)
		(property "Reference" "SR311"
			(at 0 0 270)
			(layer "F.SilkS")
			(hide yes)
			(effects
				(font
					(size 1.27 1.27)
				)
			)
		)
		(property "Value" "0R2J-2-GP"
			(at 0.064008 -3.993896 270)
			(unlocked yes)
			(layer "F.Fab")
			(hide yes)
			(effects
				(font
					(size 1.016 1.016)
					(thickness 0.1524)
				)
			)
		)
		(property "Device Type" "R402H16"
			(at 0.064008 -5.517896 270)
			(unlocked yes)
			(layer "F.Fab")
			(hide yes)
			(effects
				(font
					(size 1.016 1.016)
					(thickness 0.1524)
				)
			)
		)
		(duplicate_pad_numbers_are_jumpers no)
		(fp_line
			(start -0.508 -0.9398)
			(end -0.508 0.9398)
			(stroke
				(width 0.1524)
				(type default)
			)
			(layer "F.SilkS")
		)
		(fp_line
			(start 0.508 -0.9398)
			(end -0.508 -0.9398)
			(stroke
				(width 0.1524)
				(type default)
			)
			(layer "F.SilkS")
		)
		(fp_rect
			(start -0.508 0.9398)
			(end 0.508 -0.9398)
			(stroke
				(width 0)
				(type default)
			)
			(fill no)
			(layer "F.CrtYd")
		)
		(fp_rect
			(start -0.508 0.9398)
			(end 0.508 -0.9398)
			(stroke
				(width 0)
				(type default)
			)
			(fill no)
			(layer "F.Fab")
		)
		(pad "1" smd custom
			(at 0 -0.4445 270)
			(size 0.1397 0.1397)
			(layers "F.Cu" "F.Mask" "F.Paste")
			(net "FAULT_SDA")
			(options
				(clearance outline)
				(anchor circle)
			)
			(primitives
				(gr_poly
					(pts
						(arc
							(start -0.1778 -0.2794)
							(mid -0.249642 -0.249642)
							(end -0.2794 -0.1778)
						)
						(arc
							(start -0.2794 0.1778)
							(mid -0.249642 0.249642)
							(end -0.1778 0.2794)
						)
						(arc
							(start 0.1778 0.2794)
							(mid 0.249642 0.249642)
							(end 0.2794 0.1778)
						)
						(arc
							(start 0.2794 -0.1778)
							(mid 0.249642 -0.249642)
							(end 0.1778 -0.2794)
						)
					)
					(width 0)
					(fill yes)
				)
			)
		)
		(pad "2" smd custom
			(at 0 0.4445 270)
			(size 0.1397 0.1397)
			(layers "F.Cu" "F.Mask" "F.Paste")
			(net "EXP_SDA_L_0")
			(options
				(clearance outline)
				(anchor circle)
			)
			(primitives
				(gr_poly
					(pts
						(arc
							(start -0.1778 -0.2794)
							(mid -0.249642 -0.249642)
							(end -0.2794 -0.1778)
						)
						(arc
							(start -0.2794 0.1778)
							(mid -0.249642 0.249642)
							(end -0.1778 0.2794)
						)
						(arc
							(start 0.1778 0.2794)
							(mid 0.249642 0.249642)
							(end 0.2794 0.1778)
						)
						(arc
							(start 0.2794 -0.1778)
							(mid 0.249642 -0.249642)
							(end 0.1778 -0.2794)
						)
					)
					(width 0)
					(fill yes)
				)
			)
		)
	)
	(footprint ""
		(layer "F.Cu")
		(at 23.064216 -206.04988 90)
		(property "Reference" "R569"
			(at 0 0 90)
			(layer "F.SilkS")
			(hide yes)
			(effects
				(font
					(size 1.27 1.27)
				)
			)
		)
		(property "Value" "4K7R2F-GP"
			(at 0.064008 -3.993896 90)
			(unlocked yes)
			(layer "F.Fab")
			(hide yes)
			(effects
				(font
					(size 1.016 1.016)
					(thickness 0.1524)
				)
			)
		)
		(property "Device Type" "R402H16"
			(at 0.064008 -5.517896 90)
			(unlocked yes)
			(layer "F.Fab")
			(hide yes)
			(effects
				(font
					(size 1.016 1.016)
					(thickness 0.1524)
				)
			)
		)
		(duplicate_pad_numbers_are_jumpers no)
		(fp_line
			(start 0.508 -0.9398)
			(end -0.508 -0.9398)
			(stroke
				(width 0.1524)
				(type default)
			)
			(layer "F.SilkS")
		)
		(fp_line
			(start -0.508 -0.9398)
			(end -0.508 0.9398)
			(stroke
				(width 0.1524)
				(type default)
			)
			(layer "F.SilkS")
		)
		(fp_rect
			(start -0.508 0.9398)
			(end 0.508 -0.9398)
			(stroke
				(width 0)
				(type default)
			)
			(fill no)
			(layer "F.CrtYd")
		)
		(fp_rect
			(start -0.508 0.9398)
			(end 0.508 -0.9398)
			(stroke
				(width 0)
				(type default)
			)
			(fill no)
			(layer "F.Fab")
		)
		(pad "1" smd custom
			(at 0 -0.4445 90)
			(size 0.1397 0.1397)
			(layers "F.Cu" "F.Mask" "F.Paste")
			(net "P3V3_STBY")
			(options
				(clearance outline)
				(anchor circle)
			)
			(primitives
				(gr_poly
					(pts
						(arc
							(start -0.1778 -0.2794)
							(mid -0.249642 -0.249642)
							(end -0.2794 -0.1778)
						)
						(arc
							(start -0.2794 0.1778)
							(mid -0.249642 0.249642)
							(end -0.1778 0.2794)
						)
						(arc
							(start 0.1778 0.2794)
							(mid 0.249642 0.249642)
							(end 0.2794 0.1778)
						)
						(arc
							(start 0.2794 -0.1778)
							(mid 0.249642 -0.249642)
							(end 0.1778 -0.2794)
						)
					)
					(width 0)
					(fill yes)
				)
			)
		)
		(pad "2" smd custom
			(at 0 0.4445 90)
			(size 0.1397 0.1397)
			(layers "F.Cu" "F.Mask" "F.Paste")
			(net "VOL_SEN_ADDR_U17")
			(options
				(clearance outline)
				(anchor circle)
			)
			(primitives
				(gr_poly
					(pts
						(arc
							(start -0.1778 -0.2794)
							(mid -0.249642 -0.249642)
							(end -0.2794 -0.1778)
						)
						(arc
							(start -0.2794 0.1778)
							(mid -0.249642 0.249642)
							(end -0.1778 0.2794)
						)
						(arc
							(start 0.1778 0.2794)
							(mid 0.249642 0.249642)
							(end 0.2794 0.1778)
						)
						(arc
							(start 0.2794 -0.1778)
							(mid 0.249642 -0.249642)
							(end 0.1778 -0.2794)
						)
					)
					(width 0)
					(fill yes)
				)
			)
		)
	)
	(footprint ""
		(layer "F.Cu")
		(at 62.357 -218.313 90)
		(property "Reference" "R1226"
			(at 0 0 90)
			(layer "F.SilkS")
			(hide yes)
			(effects
				(font
					(size 1.27 1.27)
				)
			)
		)
		(property "Value" "11KR2F-L-GP"
			(at 0.064008 -3.993896 90)
			(unlocked yes)
			(layer "F.Fab")
			(hide yes)
			(effects
				(font
					(size 1.016 1.016)
					(thickness 0.1524)
				)
			)
		)
		(property "Device Type" "R402H16"
			(at 0.064008 -5.517896 90)
			(unlocked yes)
			(layer "F.Fab")
			(hide yes)
			(effects
				(font
					(size 1.016 1.016)
					(thickness 0.1524)
				)
			)
		)
		(duplicate_pad_numbers_are_jumpers no)
		(fp_line
			(start 0.508 -0.9398)
			(end -0.508 -0.9398)
			(stroke
				(width 0.1524)
				(type default)
			)
			(layer "F.SilkS")
		)
		(fp_line
			(start -0.508 -0.9398)
			(end -0.508 0.9398)
			(stroke
				(width 0.1524)
				(type default)
			)
			(layer "F.SilkS")
		)
		(fp_rect
			(start -0.508 0.9398)
			(end 0.508 -0.9398)
			(stroke
				(width 0)
				(type default)
			)
			(fill no)
			(layer "F.CrtYd")
		)
		(fp_rect
			(start -0.508 0.9398)
			(end 0.508 -0.9398)
			(stroke
				(width 0)
				(type default)
			)
			(fill no)
			(layer "F.Fab")
		)
		(pad "1" smd custom
			(at 0 -0.4445 90)
			(size 0.1397 0.1397)
			(layers "F.Cu" "F.Mask" "F.Paste")
			(net "MB0_P12V_PWGIN_R")
			(options
				(clearance outline)
				(anchor circle)
			)
			(primitives
				(gr_poly
					(pts
						(arc
							(start -0.1778 -0.2794)
							(mid -0.249642 -0.249642)
							(end -0.2794 -0.1778)
						)
						(arc
							(start -0.2794 0.1778)
							(mid -0.249642 0.249642)
							(end -0.1778 0.2794)
						)
						(arc
							(start 0.1778 0.2794)
							(mid 0.249642 0.249642)
							(end 0.2794 0.1778)
						)
						(arc
							(start 0.2794 -0.1778)
							(mid 0.249642 -0.249642)
							(end 0.1778 -0.2794)
						)
					)
					(width 0)
					(fill yes)
				)
			)
		)
		(pad "2" smd custom
			(at 0 0.4445 90)
			(size 0.1397 0.1397)
			(layers "F.Cu" "F.Mask" "F.Paste")
			(net "AGND_CURRENT_MON")
			(options
				(clearance outline)
				(anchor circle)
			)
			(primitives
				(gr_poly
					(pts
						(arc
							(start -0.1778 -0.2794)
							(mid -0.249642 -0.249642)
							(end -0.2794 -0.1778)
						)
						(arc
							(start -0.2794 0.1778)
							(mid -0.249642 0.249642)
							(end -0.1778 0.2794)
						)
						(arc
							(start 0.1778 0.2794)
							(mid 0.249642 0.249642)
							(end 0.2794 0.1778)
						)
						(arc
							(start 0.2794 -0.1778)
							(mid 0.249642 -0.249642)
							(end 0.1778 -0.2794)
						)
					)
					(width 0)
					(fill yes)
				)
			)
		)
	)
	(footprint ""
		(layer "F.Cu")
		(at 46.62297 -133.477 90)
		(property "Reference" "SR860"
			(at 0 0 90)
			(layer "F.SilkS")
			(hide yes)
			(effects
				(font
					(size 1.27 1.27)
				)
			)
		)
		(property "Value" "1KR2J-1-GP"
			(at 0.064008 -3.993896 90)
			(unlocked yes)
			(layer "F.Fab")
			(hide yes)
			(effects
				(font
					(size 1.016 1.016)
					(thickness 0.1524)
				)
			)
		)
		(property "Device Type" "R402H16"
			(at 0.064008 -5.517896 90)
			(unlocked yes)
			(layer "F.Fab")
			(hide yes)
			(effects
				(font
					(size 1.016 1.016)
					(thickness 0.1524)
				)
			)
		)
		(duplicate_pad_numbers_are_jumpers no)
		(fp_line
			(start 0.508 -0.9398)
			(end -0.508 -0.9398)
			(stroke
				(width 0.1524)
				(type default)
			)
			(layer "F.SilkS")
		)
		(fp_line
			(start -0.508 -0.9398)
			(end -0.508 0.9398)
			(stroke
				(width 0.1524)
				(type default)
			)
			(layer "F.SilkS")
		)
		(fp_rect
			(start -0.508 0.9398)
			(end 0.508 -0.9398)
			(stroke
				(width 0)
				(type default)
			)
			(fill no)
			(layer "F.CrtYd")
		)
		(fp_rect
			(start -0.508 0.9398)
			(end 0.508 -0.9398)
			(stroke
				(width 0)
				(type default)
			)
			(fill no)
			(layer "F.Fab")
		)
		(pad "1" smd custom
			(at 0 -0.4445 90)
			(size 0.1397 0.1397)
			(layers "F.Cu" "F.Mask" "F.Paste")
			(net "EXP_RST_R")
			(options
				(clearance outline)
				(anchor circle)
			)
			(primitives
				(gr_poly
					(pts
						(arc
							(start -0.1778 -0.2794)
							(mid -0.249642 -0.249642)
							(end -0.2794 -0.1778)
						)
						(arc
							(start -0.2794 0.1778)
							(mid -0.249642 0.249642)
							(end -0.1778 0.2794)
						)
						(arc
							(start 0.1778 0.2794)
							(mid 0.249642 0.249642)
							(end 0.2794 0.1778)
						)
						(arc
							(start 0.2794 -0.1778)
							(mid 0.249642 -0.249642)
							(end 0.1778 -0.2794)
						)
					)
					(width 0)
					(fill yes)
				)
			)
		)
		(pad "2" smd custom
			(at 0 0.4445 90)
			(size 0.1397 0.1397)
			(layers "F.Cu" "F.Mask" "F.Paste")
			(net "P1V8_E")
			(options
				(clearance outline)
				(anchor circle)
			)
			(primitives
				(gr_poly
					(pts
						(arc
							(start -0.1778 -0.2794)
							(mid -0.249642 -0.249642)
							(end -0.2794 -0.1778)
						)
						(arc
							(start -0.2794 0.1778)
							(mid -0.249642 0.249642)
							(end -0.1778 0.2794)
						)
						(arc
							(start 0.1778 0.2794)
							(mid 0.249642 0.249642)
							(end 0.2794 0.1778)
						)
						(arc
							(start 0.2794 -0.1778)
							(mid 0.249642 -0.249642)
							(end 0.1778 -0.2794)
						)
					)
					(width 0)
					(fill yes)
				)
			)
		)
	)
	(footprint ""
		(layer "F.Cu")
		(at 305.181 -216.789)
		(property "Reference" "R656"
			(at 0 0 0)
			(layer "F.SilkS")
			(hide yes)
			(effects
				(font
					(size 1.27 1.27)
				)
			)
		)
		(property "Value" "0R2J-2-GP"
			(at 0.064008 -3.993896 0)
			(unlocked yes)
			(layer "F.Fab")
			(hide yes)
			(effects
				(font
					(size 1.016 1.016)
					(thickness 0.1524)
				)
			)
		)
		(property "Device Type" "R402H16"
			(at 0.064008 -5.517896 0)
			(unlocked yes)
			(layer "F.Fab")
			(hide yes)
			(effects
				(font
					(size 1.016 1.016)
					(thickness 0.1524)
				)
			)
		)
		(duplicate_pad_numbers_are_jumpers no)
		(fp_line
			(start -0.508 -0.9398)
			(end -0.508 0.9398)
			(stroke
				(width 0.1524)
				(type default)
			)
			(layer "F.SilkS")
		)
		(fp_line
			(start 0.508 -0.9398)
			(end -0.508 -0.9398)
			(stroke
				(width 0.1524)
				(type default)
			)
			(layer "F.SilkS")
		)
		(fp_rect
			(start -0.508 0.9398)
			(end 0.508 -0.9398)
			(stroke
				(width 0)
				(type default)
			)
			(fill no)
			(layer "F.CrtYd")
		)
		(fp_rect
			(start -0.508 0.9398)
			(end 0.508 -0.9398)
			(stroke
				(width 0)
				(type default)
			)
			(fill no)
			(layer "F.Fab")
		)
		(pad "1" smd custom
			(at 0 -0.4445)
			(size 0.1397 0.1397)
			(layers "F.Cu" "F.Mask" "F.Paste")
			(net "BMC_DEBUG_OE_1_N")
			(options
				(clearance outline)
				(anchor circle)
			)
			(primitives
				(gr_poly
					(pts
						(arc
							(start -0.1778 -0.2794)
							(mid -0.249642 -0.249642)
							(end -0.2794 -0.1778)
						)
						(arc
							(start -0.2794 0.1778)
							(mid -0.249642 0.249642)
							(end -0.1778 0.2794)
						)
						(arc
							(start 0.1778 0.2794)
							(mid 0.249642 0.249642)
							(end 0.2794 0.1778)
						)
						(arc
							(start 0.2794 -0.1778)
							(mid 0.249642 -0.249642)
							(end 0.1778 -0.2794)
						)
					)
					(width 0)
					(fill yes)
				)
			)
		)
		(pad "2" smd custom
			(at 0 0.4445)
			(size 0.1397 0.1397)
			(layers "F.Cu" "F.Mask" "F.Paste")
			(net "BMC0_TACH9")
			(options
				(clearance outline)
				(anchor circle)
			)
			(primitives
				(gr_poly
					(pts
						(arc
							(start -0.1778 -0.2794)
							(mid -0.249642 -0.249642)
							(end -0.2794 -0.1778)
						)
						(arc
							(start -0.2794 0.1778)
							(mid -0.249642 0.249642)
							(end -0.1778 0.2794)
						)
						(arc
							(start 0.1778 0.2794)
							(mid 0.249642 0.249642)
							(end 0.2794 0.1778)
						)
						(arc
							(start 0.2794 -0.1778)
							(mid 0.249642 -0.249642)
							(end 0.1778 -0.2794)
						)
					)
					(width 0)
					(fill yes)
				)
			)
		)
	)
	(footprint ""
		(layer "F.Cu")
		(at 181.283864 -38.172136 180)
		(property "Reference" "R392"
			(at 0 0 180)
			(layer "F.SilkS")
			(hide yes)
			(effects
				(font
					(size 1.27 1.27)
				)
			)
		)
		(property "Value" "4K75R2F-1-GP"
			(at 0.064008 -3.993896 180)
			(unlocked yes)
			(layer "F.Fab")
			(hide yes)
			(effects
				(font
					(size 1.016 1.016)
					(thickness 0.1524)
				)
			)
		)
		(property "Device Type" "R402H16"
			(at 0.064008 -5.517896 180)
			(unlocked yes)
			(layer "F.Fab")
			(hide yes)
			(effects
				(font
					(size 1.016 1.016)
					(thickness 0.1524)
				)
			)
		)
		(duplicate_pad_numbers_are_jumpers no)
		(fp_line
			(start 0.508 -0.9398)
			(end -0.508 -0.9398)
			(stroke
				(width 0.1524)
				(type default)
			)
			(layer "F.SilkS")
		)
		(fp_line
			(start -0.508 -0.9398)
			(end -0.508 0.9398)
			(stroke
				(width 0.1524)
				(type default)
			)
			(layer "F.SilkS")
		)
		(fp_rect
			(start -0.508 0.9398)
			(end 0.508 -0.9398)
			(stroke
				(width 0)
				(type default)
			)
			(fill no)
			(layer "F.CrtYd")
		)
		(fp_rect
			(start -0.508 0.9398)
			(end 0.508 -0.9398)
			(stroke
				(width 0)
				(type default)
			)
			(fill no)
			(layer "F.Fab")
		)
		(pad "1" smd custom
			(at 0 -0.4445 180)
			(size 0.1397 0.1397)
			(layers "F.Cu" "F.Mask" "F.Paste")
			(net "PHY_AD3")
			(options
				(clearance outline)
				(anchor circle)
			)
			(primitives
				(gr_poly
					(pts
						(arc
							(start -0.1778 -0.2794)
							(mid -0.249642 -0.249642)
							(end -0.2794 -0.1778)
						)
						(arc
							(start -0.2794 0.1778)
							(mid -0.249642 0.249642)
							(end -0.1778 0.2794)
						)
						(arc
							(start 0.1778 0.2794)
							(mid 0.249642 0.249642)
							(end 0.2794 0.1778)
						)
						(arc
							(start 0.2794 -0.1778)
							(mid 0.249642 -0.249642)
							(end 0.1778 -0.2794)
						)
					)
					(width 0)
					(fill yes)
				)
			)
		)
		(pad "2" smd custom
			(at 0 0.4445 180)
			(size 0.1397 0.1397)
			(layers "F.Cu" "F.Mask" "F.Paste")
			(net "GND")
			(options
				(clearance outline)
				(anchor circle)
			)
			(primitives
				(gr_poly
					(pts
						(arc
							(start -0.1778 -0.2794)
							(mid -0.249642 -0.249642)
							(end -0.2794 -0.1778)
						)
						(arc
							(start -0.2794 0.1778)
							(mid -0.249642 0.249642)
							(end -0.1778 0.2794)
						)
						(arc
							(start 0.1778 0.2794)
							(mid 0.249642 0.249642)
							(end 0.2794 0.1778)
						)
						(arc
							(start 0.2794 -0.1778)
							(mid 0.249642 -0.249642)
							(end 0.1778 -0.2794)
						)
					)
					(width 0)
					(fill yes)
				)
			)
		)
	)
	(footprint ""
		(layer "F.Cu")
		(at 92.34297 -112.014 180)
		(property "Reference" "SC1231"
			(at 0 0 180)
			(layer "F.SilkS")
			(hide yes)
			(effects
				(font
					(size 1.27 1.27)
				)
			)
		)
		(property "Value" "SCD1U6D3V1KX-GP"
			(at -2.8321 -1.7399 180)
			(unlocked yes)
			(layer "F.Fab")
			(hide yes)
			(effects
				(font
					(size 1.016 1.016)
					(thickness 0.1524)
				)
			)
		)
		(property "Device Type" "C0201H13"
			(at -2.8321 -3.2639 180)
			(unlocked yes)
			(layer "F.Fab")
			(hide yes)
			(effects
				(font
					(size 1.016 1.016)
					(thickness 0.1524)
				)
			)
		)
		(duplicate_pad_numbers_are_jumpers no)
		(fp_rect
			(start -0.2794 0.6477)
			(end 0.2794 -0.6477)
			(stroke
				(width 0)
				(type default)
			)
			(fill no)
			(layer "F.CrtYd")
		)
		(fp_rect
			(start -0.2794 0.6477)
			(end 0.2794 -0.6477)
			(stroke
				(width 0)
				(type default)
			)
			(fill no)
			(layer "F.Fab")
		)
		(pad "1" smd custom
			(at 0 -0.2794 180)
			(size 0.0762 0.0762)
			(layers "F.Cu" "F.Mask" "F.Paste")
			(net "P1V8_E")
			(options
				(clearance outline)
				(anchor circle)
			)
			(primitives
				(gr_poly
					(pts
						(arc
							(start 0.1524 -0.127)
							(mid 0.137521 -0.162921)
							(end 0.1016 -0.1778)
						)
						(arc
							(start -0.1016 -0.1778)
							(mid -0.137521 -0.162921)
							(end -0.1524 -0.127)
						)
						(arc
							(start -0.1524 0.127)
							(mid -0.137521 0.162921)
							(end -0.1016 0.1778)
						)
						(arc
							(start 0.1016 0.1778)
							(mid 0.137521 0.162921)
							(end 0.1524 0.127)
						)
					)
					(width 0)
					(fill yes)
				)
			)
		)
		(pad "2" smd custom
			(at 0 0.2794 180)
			(size 0.0762 0.0762)
			(layers "F.Cu" "F.Mask" "F.Paste")
			(net "GND")
			(options
				(clearance outline)
				(anchor circle)
			)
			(primitives
				(gr_poly
					(pts
						(arc
							(start 0.1524 -0.127)
							(mid 0.137521 -0.162921)
							(end 0.1016 -0.1778)
						)
						(arc
							(start -0.1016 -0.1778)
							(mid -0.137521 -0.162921)
							(end -0.1524 -0.127)
						)
						(arc
							(start -0.1524 0.127)
							(mid -0.137521 0.162921)
							(end -0.1016 0.1778)
						)
						(arc
							(start 0.1016 0.1778)
							(mid 0.137521 0.162921)
							(end 0.1524 0.127)
						)
					)
					(width 0)
					(fill yes)
				)
			)
		)
	)
	(footprint ""
		(layer "F.Cu")
		(at 307.648864 -205.096872)
		(property "Reference" "R169"
			(at 0 0 0)
			(layer "F.SilkS")
			(hide yes)
			(effects
				(font
					(size 1.27 1.27)
				)
			)
		)
		(property "Value" "0R2J-2-GP"
			(at 0.064008 -3.993896 0)
			(unlocked yes)
			(layer "F.Fab")
			(hide yes)
			(effects
				(font
					(size 1.016 1.016)
					(thickness 0.1524)
				)
			)
		)
		(property "Device Type" "R402H16"
			(at 0.064008 -5.517896 0)
			(unlocked yes)
			(layer "F.Fab")
			(hide yes)
			(effects
				(font
					(size 1.016 1.016)
					(thickness 0.1524)
				)
			)
		)
		(duplicate_pad_numbers_are_jumpers no)
		(fp_line
			(start -0.508 -0.9398)
			(end -0.508 0.9398)
			(stroke
				(width 0.1524)
				(type default)
			)
			(layer "F.SilkS")
		)
		(fp_line
			(start 0.508 -0.9398)
			(end -0.508 -0.9398)
			(stroke
				(width 0.1524)
				(type default)
			)
			(layer "F.SilkS")
		)
		(fp_rect
			(start -0.508 0.9398)
			(end 0.508 -0.9398)
			(stroke
				(width 0)
				(type default)
			)
			(fill no)
			(layer "F.CrtYd")
		)
		(fp_rect
			(start -0.508 0.9398)
			(end 0.508 -0.9398)
			(stroke
				(width 0)
				(type default)
			)
			(fill no)
			(layer "F.Fab")
		)
		(pad "1" smd custom
			(at 0 -0.4445)
			(size 0.1397 0.1397)
			(layers "F.Cu" "F.Mask" "F.Paste")
			(net "BMC_I2C_A_SDA")
			(options
				(clearance outline)
				(anchor circle)
			)
			(primitives
				(gr_poly
					(pts
						(arc
							(start -0.1778 -0.2794)
							(mid -0.249642 -0.249642)
							(end -0.2794 -0.1778)
						)
						(arc
							(start -0.2794 0.1778)
							(mid -0.249642 0.249642)
							(end -0.1778 0.2794)
						)
						(arc
							(start 0.1778 0.2794)
							(mid 0.249642 0.249642)
							(end 0.2794 0.1778)
						)
						(arc
							(start 0.2794 -0.1778)
							(mid 0.249642 -0.249642)
							(end 0.1778 -0.2794)
						)
					)
					(width 0)
					(fill yes)
				)
			)
		)
		(pad "2" smd custom
			(at 0 0.4445)
			(size 0.1397 0.1397)
			(layers "F.Cu" "F.Mask" "F.Paste")
			(net "LED_DR_I2C_SDA")
			(options
				(clearance outline)
				(anchor circle)
			)
			(primitives
				(gr_poly
					(pts
						(arc
							(start -0.1778 -0.2794)
							(mid -0.249642 -0.249642)
							(end -0.2794 -0.1778)
						)
						(arc
							(start -0.2794 0.1778)
							(mid -0.249642 0.249642)
							(end -0.1778 0.2794)
						)
						(arc
							(start 0.1778 0.2794)
							(mid 0.249642 0.249642)
							(end 0.2794 0.1778)
						)
						(arc
							(start 0.2794 -0.1778)
							(mid 0.249642 -0.249642)
							(end 0.1778 -0.2794)
						)
					)
					(width 0)
					(fill yes)
				)
			)
		)
	)
	(footprint ""
		(layer "F.Cu")
		(at 98.43897 -116.7638)
		(property "Reference" "TP261"
			(at 0 0 0)
			(layer "F.SilkS")
			(hide yes)
			(effects
				(font
					(size 1.27 1.27)
				)
			)
		)
		(property "Value" "TPAD28"
			(at 0.0127 -1.8034 0)
			(unlocked yes)
			(layer "F.Fab")
			(hide yes)
			(effects
				(font
					(size 1.016 1.016)
					(thickness 0.1524)
				)
			)
		)
		(property "Device Type" "TPAD28"
			(at 0.0127 -3.3274 0)
			(unlocked yes)
			(layer "F.Fab")
			(hide yes)
			(effects
				(font
					(size 1.016 1.016)
					(thickness 0.1524)
				)
			)
		)
		(duplicate_pad_numbers_are_jumpers no)
		(fp_poly
			(pts
				(arc
					(start 0.3556 0)
					(mid -0.3556 0)
					(end 0.3556 0)
				)
			)
			(stroke
				(width 0)
				(type default)
			)
			(fill no)
			(layer "F.CrtYd")
		)
		(fp_poly
			(pts
				(arc
					(start 0.6096 0)
					(mid -0.6096 0)
					(end 0.6096 0)
				)
			)
			(stroke
				(width 0)
				(type default)
			)
			(fill no)
			(layer "F.Fab")
		)
		(pad "1" smd circle
			(at 0 0)
			(size 0.7112 0.7112)
			(layers "F.Cu" "F.Mask" "F.Paste")
			(net "EXP_SIO_CLK_IN")
		)
	)
	(footprint ""
		(layer "F.Cu")
		(at 95.89897 -90.805 90)
		(property "Reference" "SR796"
			(at 0 0 90)
			(layer "F.SilkS")
			(hide yes)
			(effects
				(font
					(size 1.27 1.27)
				)
			)
		)
		(property "Value" "4K75R2F-1-GP"
			(at 0.064008 -3.993896 90)
			(unlocked yes)
			(layer "F.Fab")
			(hide yes)
			(effects
				(font
					(size 1.016 1.016)
					(thickness 0.1524)
				)
			)
		)
		(property "Device Type" "R402H16"
			(at 0.064008 -5.517896 90)
			(unlocked yes)
			(layer "F.Fab")
			(hide yes)
			(effects
				(font
					(size 1.016 1.016)
					(thickness 0.1524)
				)
			)
		)
		(duplicate_pad_numbers_are_jumpers no)
		(fp_line
			(start 0.508 -0.9398)
			(end -0.508 -0.9398)
			(stroke
				(width 0.1524)
				(type default)
			)
			(layer "F.SilkS")
		)
		(fp_line
			(start -0.508 -0.9398)
			(end -0.508 0.9398)
			(stroke
				(width 0.1524)
				(type default)
			)
			(layer "F.SilkS")
		)
		(fp_rect
			(start -0.508 0.9398)
			(end 0.508 -0.9398)
			(stroke
				(width 0)
				(type default)
			)
			(fill no)
			(layer "F.CrtYd")
		)
		(fp_rect
			(start -0.508 0.9398)
			(end 0.508 -0.9398)
			(stroke
				(width 0)
				(type default)
			)
			(fill no)
			(layer "F.Fab")
		)
		(pad "1" smd custom
			(at 0 -0.4445 90)
			(size 0.1397 0.1397)
			(layers "F.Cu" "F.Mask" "F.Paste")
			(net "P1V8_E")
			(options
				(clearance outline)
				(anchor circle)
			)
			(primitives
				(gr_poly
					(pts
						(arc
							(start -0.1778 -0.2794)
							(mid -0.249642 -0.249642)
							(end -0.2794 -0.1778)
						)
						(arc
							(start -0.2794 0.1778)
							(mid -0.249642 0.249642)
							(end -0.1778 0.2794)
						)
						(arc
							(start 0.1778 0.2794)
							(mid 0.249642 0.249642)
							(end 0.2794 0.1778)
						)
						(arc
							(start 0.2794 -0.1778)
							(mid 0.249642 -0.249642)
							(end 0.1778 -0.2794)
						)
					)
					(width 0)
					(fill yes)
				)
			)
		)
		(pad "2" smd custom
			(at 0 0.4445 90)
			(size 0.1397 0.1397)
			(layers "F.Cu" "F.Mask" "F.Paste")
			(net "EXP_CLK_SEL0")
			(options
				(clearance outline)
				(anchor circle)
			)
			(primitives
				(gr_poly
					(pts
						(arc
							(start -0.1778 -0.2794)
							(mid -0.249642 -0.249642)
							(end -0.2794 -0.1778)
						)
						(arc
							(start -0.2794 0.1778)
							(mid -0.249642 0.249642)
							(end -0.1778 0.2794)
						)
						(arc
							(start 0.1778 0.2794)
							(mid 0.249642 0.249642)
							(end 0.2794 0.1778)
						)
						(arc
							(start 0.2794 -0.1778)
							(mid 0.249642 -0.249642)
							(end 0.1778 -0.2794)
						)
					)
					(width 0)
					(fill yes)
				)
			)
		)
	)
	(footprint ""
		(layer "F.Cu")
		(at 221.733872 -180.285136 -90)
		(property "Reference" "R497"
			(at 0 0 270)
			(layer "F.SilkS")
			(hide yes)
			(effects
				(font
					(size 1.27 1.27)
				)
			)
		)
		(property "Value" "200R3F-GP"
			(at -0.0254 -2.5146 270)
			(unlocked yes)
			(layer "F.Fab")
			(hide yes)
			(effects
				(font
					(size 1.016 1.016)
					(thickness 0.1524)
				)
			)
		)
		(property "Device Type" "R603H22"
			(at -0.0254 -4.0386 270)
			(unlocked yes)
			(layer "F.Fab")
			(hide yes)
			(effects
				(font
					(size 1.016 1.016)
					(thickness 0.1524)
				)
			)
		)
		(duplicate_pad_numbers_are_jumpers no)
		(fp_line
			(start -0.4826 0)
			(end -0.2032 0)
			(stroke
				(width 0.2032)
				(type default)
			)
			(layer "F.SilkS")
		)
		(fp_line
			(start 0.2032 0)
			(end 0.4826 0)
			(stroke
				(width 0.2032)
				(type default)
			)
			(layer "F.SilkS")
		)
		(fp_rect
			(start -0.5842 1.3335)
			(end 0.5842 -1.3335)
			(stroke
				(width 0)
				(type default)
			)
			(fill no)
			(layer "F.CrtYd")
		)
		(fp_rect
			(start -0.5842 1.3335)
			(end 0.5842 -1.3335)
			(stroke
				(width 0)
				(type default)
			)
			(fill no)
			(layer "F.Fab")
		)
		(pad "1" smd custom
			(at 0 -0.762 270)
			(size 0.2159 0.2159)
			(layers "F.Cu" "F.Mask" "F.Paste")
			(net "P3V3_STBY")
			(options
				(clearance outline)
				(anchor circle)
			)
			(primitives
				(gr_poly
					(pts
						(arc
							(start -0.3302 -0.4318)
							(mid -0.402042 -0.402042)
							(end -0.4318 -0.3302)
						)
						(arc
							(start -0.4318 0.3302)
							(mid -0.402042 0.402042)
							(end -0.3302 0.4318)
						)
						(arc
							(start 0.3302 0.4318)
							(mid 0.402042 0.402042)
							(end 0.4318 0.3302)
						)
						(arc
							(start 0.4318 -0.3302)
							(mid 0.402042 -0.402042)
							(end 0.3302 -0.4318)
						)
					)
					(width 0)
					(fill yes)
				)
			)
		)
		(pad "2" smd custom
			(at 0 0.762 270)
			(size 0.2159 0.2159)
			(layers "F.Cu" "F.Mask" "F.Paste")
			(net "HB_A_OUT_EXP")
			(options
				(clearance outline)
				(anchor circle)
			)
			(primitives
				(gr_poly
					(pts
						(arc
							(start -0.3302 -0.4318)
							(mid -0.402042 -0.402042)
							(end -0.4318 -0.3302)
						)
						(arc
							(start -0.4318 0.3302)
							(mid -0.402042 0.402042)
							(end -0.3302 0.4318)
						)
						(arc
							(start 0.3302 0.4318)
							(mid 0.402042 0.402042)
							(end 0.4318 0.3302)
						)
						(arc
							(start 0.4318 -0.3302)
							(mid 0.402042 -0.402042)
							(end 0.3302 -0.4318)
						)
					)
					(width 0)
					(fill yes)
				)
			)
		)
	)
	(footprint ""
		(layer "F.Cu")
		(at 176.012348 -115.687856 -90)
		(property "Reference" "PC188"
			(at 0 0 270)
			(layer "F.SilkS")
			(hide yes)
			(effects
				(font
					(size 1.27 1.27)
				)
			)
		)
		(property "Value" "SC470P50V2KX-3GP"
			(at 1.1811 -2.7051 270)
			(unlocked yes)
			(layer "F.Fab")
			(hide yes)
			(effects
				(font
					(size 1.016 1.016)
					(thickness 0.1524)
				)
			)
		)
		(property "Device Type" "C402H22"
			(at 1.1811 -4.2291 270)
			(unlocked yes)
			(layer "F.Fab")
			(hide yes)
			(effects
				(font
					(size 1.016 1.016)
					(thickness 0.1524)
				)
			)
		)
		(duplicate_pad_numbers_are_jumpers no)
		(fp_rect
			(start -0.4318 0.9525)
			(end 0.4318 -0.9525)
			(stroke
				(width 0)
				(type default)
			)
			(fill no)
			(layer "F.CrtYd")
		)
		(fp_rect
			(start -0.4318 0.9525)
			(end 0.4318 -0.9525)
			(stroke
				(width 0)
				(type default)
			)
			(fill no)
			(layer "F.Fab")
		)
		(pad "1" smd custom
			(at 0 -0.4445 270)
			(size 0.1524 0.1524)
			(layers "F.Cu" "F.Mask" "F.Paste")
			(net "P0V9_E_SNB")
			(options
				(clearance outline)
				(anchor circle)
			)
			(primitives
				(gr_poly
					(pts
						(arc
							(start 0.3048 -0.2032)
							(mid 0.275042 -0.275042)
							(end 0.2032 -0.3048)
						)
						(arc
							(start -0.2032 -0.3048)
							(mid -0.275042 -0.275042)
							(end -0.3048 -0.2032)
						)
						(arc
							(start -0.3048 0.2032)
							(mid -0.275042 0.275042)
							(end -0.2032 0.3048)
						)
						(arc
							(start 0.2032 0.3048)
							(mid 0.275042 0.275042)
							(end 0.3048 0.2032)
						)
					)
					(width 0)
					(fill yes)
				)
			)
		)
		(pad "2" smd custom
			(at 0 0.4445 270)
			(size 0.1524 0.1524)
			(layers "F.Cu" "F.Mask" "F.Paste")
			(net "GND")
			(options
				(clearance outline)
				(anchor circle)
			)
			(primitives
				(gr_poly
					(pts
						(arc
							(start 0.3048 -0.2032)
							(mid 0.275042 -0.275042)
							(end 0.2032 -0.3048)
						)
						(arc
							(start -0.2032 -0.3048)
							(mid -0.275042 -0.275042)
							(end -0.3048 -0.2032)
						)
						(arc
							(start -0.3048 0.2032)
							(mid -0.275042 0.275042)
							(end -0.2032 0.3048)
						)
						(arc
							(start 0.2032 0.3048)
							(mid 0.275042 0.275042)
							(end 0.3048 0.2032)
						)
					)
					(width 0)
					(fill yes)
				)
			)
		)
	)
	(footprint ""
		(layer "F.Cu")
		(at 34.544 -214.122 -90)
		(property "Reference" "SU74"
			(at 0 0 270)
			(layer "F.SilkS")
			(hide yes)
			(effects
				(font
					(size 1.27 1.27)
				)
			)
		)
		(property "Value" "PCA9306DCTT-GP"
			(at 0 -11.6332 270)
			(unlocked yes)
			(layer "F.Fab")
			(hide yes)
			(effects
				(font
					(size 1.016 1.016)
					(thickness 0.1524)
				)
			)
		)
		(property "Device Type" "SSOIC8H52"
			(at 0 -13.1572 270)
			(unlocked yes)
			(layer "F.Fab")
			(hide yes)
			(effects
				(font
					(size 1.016 1.016)
					(thickness 0.1524)
				)
			)
		)
		(duplicate_pad_numbers_are_jumpers no)
		(fp_line
			(start -1.524 0.5842)
			(end -1.524 2.286)
			(stroke
				(width 0.508)
				(type default)
			)
			(layer "F.SilkS")
		)
		(fp_line
			(start 1.0668 0.5842)
			(end -1.524 0.5842)
			(stroke
				(width 0.1524)
				(type default)
			)
			(layer "F.SilkS")
		)
		(fp_line
			(start -1.397 0)
			(end -1.7018 0.3048)
			(stroke
				(width 0.1524)
				(type default)
			)
			(layer "F.SilkS")
		)
		(fp_line
			(start -1.397 0)
			(end -1.7018 -0.3048)
			(stroke
				(width 0.1524)
				(type default)
			)
			(layer "F.SilkS")
		)
		(fp_line
			(start -1.7018 -0.5842)
			(end -1.7018 2.286)
			(stroke
				(width 0.1524)
				(type default)
			)
			(layer "F.SilkS")
		)
		(fp_line
			(start -1.7018 -0.5842)
			(end 1.0668 -0.5842)
			(stroke
				(width 0.1524)
				(type default)
			)
			(layer "F.SilkS")
		)
		(fp_line
			(start 1.0668 -0.5842)
			(end 1.0668 0.5842)
			(stroke
				(width 0.1524)
				(type default)
			)
			(layer "F.SilkS")
		)
		(fp_poly
			(pts
				(xy -1.1684 -0.5842) (xy 1.0668 -0.5842) (xy 1.0668 0.5842) (xy -1.1684 0.5842)
			)
			(stroke
				(width 0)
				(type default)
			)
			(fill yes)
			(layer "F.SilkS")
		)
		(fp_poly
			(pts
				(xy -1.778 2.54) (xy 1.778 2.54) (xy 1.778 -2.54) (xy -1.778 -2.54)
			)
			(stroke
				(width 0)
				(type default)
			)
			(fill no)
			(layer "F.CrtYd")
		)
		(fp_poly
			(pts
				(xy -1.778 -2.54) (xy 1.778 -2.54) (xy 1.778 2.54) (xy -1.778 2.54)
			)
			(stroke
				(width 0)
				(type default)
			)
			(fill no)
			(layer "F.Fab")
		)
		(pad "1" smd rect
			(at -0.97536 1.6256 270)
			(size 0.3556 1.524)
			(layers "F.Cu" "F.Mask" "F.Paste")
			(net "GND")
		)
		(pad "2" smd rect
			(at -0.32512 1.6256 270)
			(size 0.3556 1.524)
			(layers "F.Cu" "F.Mask" "F.Paste")
			(net "P1V8_E")
		)
		(pad "3" smd rect
			(at 0.32512 1.6256 270)
			(size 0.3556 1.524)
			(layers "F.Cu" "F.Mask" "F.Paste")
			(net "EXP_SCL_0")
		)
		(pad "4" smd rect
			(at 0.97536 1.6256 270)
			(size 0.3556 1.524)
			(layers "F.Cu" "F.Mask" "F.Paste")
			(net "EXP_SDA_0")
		)
		(pad "5" smd rect
			(at 0.97536 -1.6256 270)
			(size 0.3556 1.524)
			(layers "F.Cu" "F.Mask" "F.Paste")
			(net "EXP_SDA_L_0")
		)
		(pad "6" smd rect
			(at 0.32512 -1.6256 270)
			(size 0.3556 1.524)
			(layers "F.Cu" "F.Mask" "F.Paste")
			(net "EXP_SCL_L_0")
		)
		(pad "7" smd rect
			(at -0.32512 -1.6256 270)
			(size 0.3556 1.524)
			(layers "F.Cu" "F.Mask" "F.Paste")
			(net "EXP_I2C_VREF_4")
		)
		(pad "8" smd rect
			(at -0.97536 -1.6256 270)
			(size 0.3556 1.524)
			(layers "F.Cu" "F.Mask" "F.Paste")
			(net "EXP_I2C_VREF_4")
		)
	)
	(footprint ""
		(layer "F.Cu")
		(at 311.15 -114.935 90)
		(property "Reference" "PR27"
			(at 0 0 90)
			(layer "F.SilkS")
			(hide yes)
			(effects
				(font
					(size 1.27 1.27)
				)
			)
		)
		(property "Value" "10R3F-GP"
			(at -0.0254 -2.5146 90)
			(unlocked yes)
			(layer "F.Fab")
			(hide yes)
			(effects
				(font
					(size 1.016 1.016)
					(thickness 0.1524)
				)
			)
		)
		(property "Device Type" "R603H22"
			(at -0.0254 -4.0386 90)
			(unlocked yes)
			(layer "F.Fab")
			(hide yes)
			(effects
				(font
					(size 1.016 1.016)
					(thickness 0.1524)
				)
			)
		)
		(duplicate_pad_numbers_are_jumpers no)
		(fp_line
			(start 0.2032 0)
			(end 0.4826 0)
			(stroke
				(width 0.2032)
				(type default)
			)
			(layer "F.SilkS")
		)
		(fp_line
			(start -0.4826 0)
			(end -0.2032 0)
			(stroke
				(width 0.2032)
				(type default)
			)
			(layer "F.SilkS")
		)
		(fp_rect
			(start -0.5842 1.3335)
			(end 0.5842 -1.3335)
			(stroke
				(width 0)
				(type default)
			)
			(fill no)
			(layer "F.CrtYd")
		)
		(fp_rect
			(start -0.5842 1.3335)
			(end 0.5842 -1.3335)
			(stroke
				(width 0)
				(type default)
			)
			(fill no)
			(layer "F.Fab")
		)
		(pad "1" smd custom
			(at 0 -0.762 90)
			(size 0.2159 0.2159)
			(layers "F.Cu" "F.Mask" "F.Paste")
			(net "P3V3_STBY")
			(options
				(clearance outline)
				(anchor circle)
			)
			(primitives
				(gr_poly
					(pts
						(arc
							(start -0.3302 -0.4318)
							(mid -0.402042 -0.402042)
							(end -0.4318 -0.3302)
						)
						(arc
							(start -0.4318 0.3302)
							(mid -0.402042 0.402042)
							(end -0.3302 0.4318)
						)
						(arc
							(start 0.3302 0.4318)
							(mid 0.402042 0.402042)
							(end 0.4318 0.3302)
						)
						(arc
							(start 0.4318 -0.3302)
							(mid 0.402042 -0.402042)
							(end 0.3302 -0.4318)
						)
					)
					(width 0)
					(fill yes)
				)
			)
		)
		(pad "2" smd custom
			(at 0 0.762 90)
			(size 0.2159 0.2159)
			(layers "F.Cu" "F.Mask" "F.Paste")
			(net "P3V3_STBY_VFB_R")
			(options
				(clearance outline)
				(anchor circle)
			)
			(primitives
				(gr_poly
					(pts
						(arc
							(start -0.3302 -0.4318)
							(mid -0.402042 -0.402042)
							(end -0.4318 -0.3302)
						)
						(arc
							(start -0.4318 0.3302)
							(mid -0.402042 0.402042)
							(end -0.3302 0.4318)
						)
						(arc
							(start 0.3302 0.4318)
							(mid 0.402042 0.402042)
							(end 0.4318 0.3302)
						)
						(arc
							(start 0.4318 -0.3302)
							(mid 0.402042 -0.402042)
							(end 0.3302 -0.4318)
						)
					)
					(width 0)
					(fill yes)
				)
			)
		)
	)
	(footprint ""
		(layer "F.Cu")
		(at 66.715386 -109.265212 -90)
		(property "Reference" "PR166"
			(at 0 0 270)
			(layer "F.SilkS")
			(hide yes)
			(effects
				(font
					(size 1.27 1.27)
				)
			)
		)
		(property "Value" "4K02R2F-GP"
			(at 0.064008 -3.993896 270)
			(unlocked yes)
			(layer "F.Fab")
			(hide yes)
			(effects
				(font
					(size 1.016 1.016)
					(thickness 0.1524)
				)
			)
		)
		(property "Device Type" "R402H16"
			(at 0.064008 -5.517896 270)
			(unlocked yes)
			(layer "F.Fab")
			(hide yes)
			(effects
				(font
					(size 1.016 1.016)
					(thickness 0.1524)
				)
			)
		)
		(duplicate_pad_numbers_are_jumpers no)
		(fp_line
			(start -0.508 -0.9398)
			(end -0.508 0.9398)
			(stroke
				(width 0.1524)
				(type default)
			)
			(layer "F.SilkS")
		)
		(fp_line
			(start 0.508 -0.9398)
			(end -0.508 -0.9398)
			(stroke
				(width 0.1524)
				(type default)
			)
			(layer "F.SilkS")
		)
		(fp_rect
			(start -0.508 0.9398)
			(end 0.508 -0.9398)
			(stroke
				(width 0)
				(type default)
			)
			(fill no)
			(layer "F.CrtYd")
		)
		(fp_rect
			(start -0.508 0.9398)
			(end 0.508 -0.9398)
			(stroke
				(width 0)
				(type default)
			)
			(fill no)
			(layer "F.Fab")
		)
		(pad "1" smd custom
			(at 0 -0.4445 270)
			(size 0.1397 0.1397)
			(layers "F.Cu" "F.Mask" "F.Paste")
			(net "P1V8_EN_S")
			(options
				(clearance outline)
				(anchor circle)
			)
			(primitives
				(gr_poly
					(pts
						(arc
							(start -0.1778 -0.2794)
							(mid -0.249642 -0.249642)
							(end -0.2794 -0.1778)
						)
						(arc
							(start -0.2794 0.1778)
							(mid -0.249642 0.249642)
							(end -0.1778 0.2794)
						)
						(arc
							(start 0.1778 0.2794)
							(mid 0.249642 0.249642)
							(end 0.2794 0.1778)
						)
						(arc
							(start 0.2794 -0.1778)
							(mid 0.249642 -0.249642)
							(end 0.1778 -0.2794)
						)
					)
					(width 0)
					(fill yes)
				)
			)
		)
		(pad "2" smd custom
			(at 0 0.4445 270)
			(size 0.1397 0.1397)
			(layers "F.Cu" "F.Mask" "F.Paste")
			(net "P3V3_STBY")
			(options
				(clearance outline)
				(anchor circle)
			)
			(primitives
				(gr_poly
					(pts
						(arc
							(start -0.1778 -0.2794)
							(mid -0.249642 -0.249642)
							(end -0.2794 -0.1778)
						)
						(arc
							(start -0.2794 0.1778)
							(mid -0.249642 0.249642)
							(end -0.1778 0.2794)
						)
						(arc
							(start 0.1778 0.2794)
							(mid 0.249642 0.249642)
							(end 0.2794 0.1778)
						)
						(arc
							(start 0.2794 -0.1778)
							(mid 0.249642 -0.249642)
							(end 0.1778 -0.2794)
						)
					)
					(width 0)
					(fill yes)
				)
			)
		)
	)
	(footprint ""
		(layer "F.Cu")
		(at 270.764 -186.309 -90)
		(property "Reference" "R607"
			(at 0 0 270)
			(layer "F.SilkS")
			(hide yes)
			(effects
				(font
					(size 1.27 1.27)
				)
			)
		)
		(property "Value" "0R2J-2-GP"
			(at 0.064008 -3.993896 270)
			(unlocked yes)
			(layer "F.Fab")
			(hide yes)
			(effects
				(font
					(size 1.016 1.016)
					(thickness 0.1524)
				)
			)
		)
		(property "Device Type" "R402H16"
			(at 0.064008 -5.517896 270)
			(unlocked yes)
			(layer "F.Fab")
			(hide yes)
			(effects
				(font
					(size 1.016 1.016)
					(thickness 0.1524)
				)
			)
		)
		(duplicate_pad_numbers_are_jumpers no)
		(fp_line
			(start -0.508 -0.9398)
			(end -0.508 0.9398)
			(stroke
				(width 0.1524)
				(type default)
			)
			(layer "F.SilkS")
		)
		(fp_line
			(start 0.508 -0.9398)
			(end -0.508 -0.9398)
			(stroke
				(width 0.1524)
				(type default)
			)
			(layer "F.SilkS")
		)
		(fp_rect
			(start -0.508 0.9398)
			(end 0.508 -0.9398)
			(stroke
				(width 0)
				(type default)
			)
			(fill no)
			(layer "F.CrtYd")
		)
		(fp_rect
			(start -0.508 0.9398)
			(end 0.508 -0.9398)
			(stroke
				(width 0)
				(type default)
			)
			(fill no)
			(layer "F.Fab")
		)
		(pad "1" smd custom
			(at 0 -0.4445 270)
			(size 0.1397 0.1397)
			(layers "F.Cu" "F.Mask" "F.Paste")
			(net "DP_RST_N_R")
			(options
				(clearance outline)
				(anchor circle)
			)
			(primitives
				(gr_poly
					(pts
						(arc
							(start -0.1778 -0.2794)
							(mid -0.249642 -0.249642)
							(end -0.2794 -0.1778)
						)
						(arc
							(start -0.2794 0.1778)
							(mid -0.249642 0.249642)
							(end -0.1778 0.2794)
						)
						(arc
							(start 0.1778 0.2794)
							(mid 0.249642 0.249642)
							(end 0.2794 0.1778)
						)
						(arc
							(start 0.2794 -0.1778)
							(mid 0.249642 -0.249642)
							(end 0.1778 -0.2794)
						)
					)
					(width 0)
					(fill yes)
				)
			)
		)
		(pad "2" smd custom
			(at 0 0.4445 270)
			(size 0.1397 0.1397)
			(layers "F.Cu" "F.Mask" "F.Paste")
			(net "DP_RST_N")
			(options
				(clearance outline)
				(anchor circle)
			)
			(primitives
				(gr_poly
					(pts
						(arc
							(start -0.1778 -0.2794)
							(mid -0.249642 -0.249642)
							(end -0.2794 -0.1778)
						)
						(arc
							(start -0.2794 0.1778)
							(mid -0.249642 0.249642)
							(end -0.1778 0.2794)
						)
						(arc
							(start 0.1778 0.2794)
							(mid 0.249642 0.249642)
							(end 0.2794 0.1778)
						)
						(arc
							(start 0.2794 -0.1778)
							(mid 0.249642 -0.249642)
							(end 0.1778 -0.2794)
						)
					)
					(width 0)
					(fill yes)
				)
			)
		)
	)
	(footprint ""
		(layer "F.Cu")
		(at 131.318 -89.154 90)
		(property "Reference" "SC1265"
			(at 0 0 90)
			(layer "F.SilkS")
			(hide yes)
			(effects
				(font
					(size 1.27 1.27)
				)
			)
		)
		(property "Value" "SCD01U10V1KX-GP"
			(at -2.8321 -1.7399 90)
			(unlocked yes)
			(layer "F.Fab")
			(hide yes)
			(effects
				(font
					(size 1.016 1.016)
					(thickness 0.1524)
				)
			)
		)
		(property "Device Type" "C0201H13"
			(at -2.8321 -3.2639 90)
			(unlocked yes)
			(layer "F.Fab")
			(hide yes)
			(effects
				(font
					(size 1.016 1.016)
					(thickness 0.1524)
				)
			)
		)
		(duplicate_pad_numbers_are_jumpers no)
		(fp_rect
			(start -0.2794 0.6477)
			(end 0.2794 -0.6477)
			(stroke
				(width 0)
				(type default)
			)
			(fill no)
			(layer "F.CrtYd")
		)
		(fp_rect
			(start -0.2794 0.6477)
			(end 0.2794 -0.6477)
			(stroke
				(width 0)
				(type default)
			)
			(fill no)
			(layer "F.Fab")
		)
		(pad "1" smd custom
			(at 0 -0.2794 90)
			(size 0.0762 0.0762)
			(layers "F.Cu" "F.Mask" "F.Paste")
			(net "3X24_SAS_TX17_N")
			(options
				(clearance outline)
				(anchor circle)
			)
			(primitives
				(gr_poly
					(pts
						(arc
							(start 0.1524 -0.127)
							(mid 0.137521 -0.162921)
							(end 0.1016 -0.1778)
						)
						(arc
							(start -0.1016 -0.1778)
							(mid -0.137521 -0.162921)
							(end -0.1524 -0.127)
						)
						(arc
							(start -0.1524 0.127)
							(mid -0.137521 0.162921)
							(end -0.1016 0.1778)
						)
						(arc
							(start 0.1016 0.1778)
							(mid 0.137521 0.162921)
							(end 0.1524 0.127)
						)
					)
					(width 0)
					(fill yes)
				)
			)
		)
		(pad "2" smd custom
			(at 0 0.2794 90)
			(size 0.0762 0.0762)
			(layers "F.Cu" "F.Mask" "F.Paste")
			(net "SAS_EXP2CONN_TX_N_21")
			(options
				(clearance outline)
				(anchor circle)
			)
			(primitives
				(gr_poly
					(pts
						(arc
							(start 0.1524 -0.127)
							(mid 0.137521 -0.162921)
							(end 0.1016 -0.1778)
						)
						(arc
							(start -0.1016 -0.1778)
							(mid -0.137521 -0.162921)
							(end -0.1524 -0.127)
						)
						(arc
							(start -0.1524 0.127)
							(mid -0.137521 0.162921)
							(end -0.1016 0.1778)
						)
						(arc
							(start 0.1016 0.1778)
							(mid 0.137521 0.162921)
							(end 0.1524 0.127)
						)
					)
					(width 0)
					(fill yes)
				)
			)
		)
	)
	(footprint ""
		(layer "F.Cu")
		(at 288.408872 -218.512136)
		(property "Reference" "PR80"
			(at 0 0 0)
			(layer "F.SilkS")
			(hide yes)
			(effects
				(font
					(size 1.27 1.27)
				)
			)
		)
		(property "Value" "4K75R2F-1-GP"
			(at 0.064008 -3.993896 0)
			(unlocked yes)
			(layer "F.Fab")
			(hide yes)
			(effects
				(font
					(size 1.016 1.016)
					(thickness 0.1524)
				)
			)
		)
		(property "Device Type" "R402H16"
			(at 0.064008 -5.517896 0)
			(unlocked yes)
			(layer "F.Fab")
			(hide yes)
			(effects
				(font
					(size 1.016 1.016)
					(thickness 0.1524)
				)
			)
		)
		(duplicate_pad_numbers_are_jumpers no)
		(fp_line
			(start -0.508 -0.9398)
			(end -0.508 0.9398)
			(stroke
				(width 0.1524)
				(type default)
			)
			(layer "F.SilkS")
		)
		(fp_line
			(start 0.508 -0.9398)
			(end -0.508 -0.9398)
			(stroke
				(width 0.1524)
				(type default)
			)
			(layer "F.SilkS")
		)
		(fp_rect
			(start -0.508 0.9398)
			(end 0.508 -0.9398)
			(stroke
				(width 0)
				(type default)
			)
			(fill no)
			(layer "F.CrtYd")
		)
		(fp_rect
			(start -0.508 0.9398)
			(end 0.508 -0.9398)
			(stroke
				(width 0)
				(type default)
			)
			(fill no)
			(layer "F.Fab")
		)
		(pad "1" smd custom
			(at 0 -0.4445)
			(size 0.1397 0.1397)
			(layers "F.Cu" "F.Mask" "F.Paste")
			(net "TPS74801_1V53_STBY_FB")
			(options
				(clearance outline)
				(anchor circle)
			)
			(primitives
				(gr_poly
					(pts
						(arc
							(start -0.1778 -0.2794)
							(mid -0.249642 -0.249642)
							(end -0.2794 -0.1778)
						)
						(arc
							(start -0.2794 0.1778)
							(mid -0.249642 0.249642)
							(end -0.1778 0.2794)
						)
						(arc
							(start 0.1778 0.2794)
							(mid 0.249642 0.249642)
							(end 0.2794 0.1778)
						)
						(arc
							(start 0.2794 -0.1778)
							(mid 0.249642 -0.249642)
							(end 0.1778 -0.2794)
						)
					)
					(width 0)
					(fill yes)
				)
			)
		)
		(pad "2" smd custom
			(at 0 0.4445)
			(size 0.1397 0.1397)
			(layers "F.Cu" "F.Mask" "F.Paste")
			(net "GND")
			(options
				(clearance outline)
				(anchor circle)
			)
			(primitives
				(gr_poly
					(pts
						(arc
							(start -0.1778 -0.2794)
							(mid -0.249642 -0.249642)
							(end -0.2794 -0.1778)
						)
						(arc
							(start -0.2794 0.1778)
							(mid -0.249642 0.249642)
							(end -0.1778 0.2794)
						)
						(arc
							(start 0.1778 0.2794)
							(mid 0.249642 0.249642)
							(end 0.2794 0.1778)
						)
						(arc
							(start 0.2794 -0.1778)
							(mid 0.249642 -0.249642)
							(end 0.1778 -0.2794)
						)
					)
					(width 0)
					(fill yes)
				)
			)
		)
	)
	(footprint ""
		(layer "F.Cu")
		(at 117.856 -46.99 90)
		(property "Reference" "SR921"
			(at 0 0 90)
			(layer "F.SilkS")
			(hide yes)
			(effects
				(font
					(size 1.27 1.27)
				)
			)
		)
		(property "Value" "10KR2F-2-GP"
			(at 0.064008 -3.993896 90)
			(unlocked yes)
			(layer "F.Fab")
			(hide yes)
			(effects
				(font
					(size 1.016 1.016)
					(thickness 0.1524)
				)
			)
		)
		(property "Device Type" "R402H16"
			(at 0.064008 -5.517896 90)
			(unlocked yes)
			(layer "F.Fab")
			(hide yes)
			(effects
				(font
					(size 1.016 1.016)
					(thickness 0.1524)
				)
			)
		)
		(duplicate_pad_numbers_are_jumpers no)
		(fp_line
			(start 0.508 -0.9398)
			(end -0.508 -0.9398)
			(stroke
				(width 0.1524)
				(type default)
			)
			(layer "F.SilkS")
		)
		(fp_line
			(start -0.508 -0.9398)
			(end -0.508 0.9398)
			(stroke
				(width 0.1524)
				(type default)
			)
			(layer "F.SilkS")
		)
		(fp_rect
			(start -0.508 0.9398)
			(end 0.508 -0.9398)
			(stroke
				(width 0)
				(type default)
			)
			(fill no)
			(layer "F.CrtYd")
		)
		(fp_rect
			(start -0.508 0.9398)
			(end 0.508 -0.9398)
			(stroke
				(width 0)
				(type default)
			)
			(fill no)
			(layer "F.Fab")
		)
		(pad "1" smd custom
			(at 0 -0.4445 90)
			(size 0.1397 0.1397)
			(layers "F.Cu" "F.Mask" "F.Paste")
			(net "GND")
			(options
				(clearance outline)
				(anchor circle)
			)
			(primitives
				(gr_poly
					(pts
						(arc
							(start -0.1778 -0.2794)
							(mid -0.249642 -0.249642)
							(end -0.2794 -0.1778)
						)
						(arc
							(start -0.2794 0.1778)
							(mid -0.249642 0.249642)
							(end -0.1778 0.2794)
						)
						(arc
							(start 0.1778 0.2794)
							(mid 0.249642 0.249642)
							(end 0.2794 0.1778)
						)
						(arc
							(start 0.2794 -0.1778)
							(mid 0.249642 -0.249642)
							(end 0.1778 -0.2794)
						)
					)
					(width 0)
					(fill yes)
				)
			)
		)
		(pad "2" smd custom
			(at 0 0.4445 90)
			(size 0.1397 0.1397)
			(layers "F.Cu" "F.Mask" "F.Paste")
			(net "IOC_CLK_SEL0")
			(options
				(clearance outline)
				(anchor circle)
			)
			(primitives
				(gr_poly
					(pts
						(arc
							(start -0.1778 -0.2794)
							(mid -0.249642 -0.249642)
							(end -0.2794 -0.1778)
						)
						(arc
							(start -0.2794 0.1778)
							(mid -0.249642 0.249642)
							(end -0.1778 0.2794)
						)
						(arc
							(start 0.1778 0.2794)
							(mid 0.249642 0.249642)
							(end 0.2794 0.1778)
						)
						(arc
							(start 0.2794 -0.1778)
							(mid 0.249642 -0.249642)
							(end 0.1778 -0.2794)
						)
					)
					(width 0)
					(fill yes)
				)
			)
		)
	)
	(footprint ""
		(layer "F.Cu")
		(at 185.355992 -46.355)
		(property "Reference" "C271"
			(at 0 0 0)
			(layer "F.SilkS")
			(hide yes)
			(effects
				(font
					(size 1.27 1.27)
				)
			)
		)
		(property "Value" "SCD1U25V2KX-2-GP"
			(at 1.1811 -2.7051 0)
			(unlocked yes)
			(layer "F.Fab")
			(hide yes)
			(effects
				(font
					(size 1.016 1.016)
					(thickness 0.1524)
				)
			)
		)
		(property "Device Type" "C402H22"
			(at 1.1811 -4.2291 0)
			(unlocked yes)
			(layer "F.Fab")
			(hide yes)
			(effects
				(font
					(size 1.016 1.016)
					(thickness 0.1524)
				)
			)
		)
		(duplicate_pad_numbers_are_jumpers no)
		(fp_rect
			(start -0.4318 0.9525)
			(end 0.4318 -0.9525)
			(stroke
				(width 0)
				(type default)
			)
			(fill no)
			(layer "F.CrtYd")
		)
		(fp_rect
			(start -0.4318 0.9525)
			(end 0.4318 -0.9525)
			(stroke
				(width 0)
				(type default)
			)
			(fill no)
			(layer "F.Fab")
		)
		(pad "1" smd custom
			(at 0 -0.4445)
			(size 0.1524 0.1524)
			(layers "F.Cu" "F.Mask" "F.Paste")
			(net "P3V3_STBY")
			(options
				(clearance outline)
				(anchor circle)
			)
			(primitives
				(gr_poly
					(pts
						(arc
							(start 0.3048 -0.2032)
							(mid 0.275042 -0.275042)
							(end 0.2032 -0.3048)
						)
						(arc
							(start -0.2032 -0.3048)
							(mid -0.275042 -0.275042)
							(end -0.3048 -0.2032)
						)
						(arc
							(start -0.3048 0.2032)
							(mid -0.275042 0.275042)
							(end -0.2032 0.3048)
						)
						(arc
							(start 0.2032 0.3048)
							(mid 0.275042 0.275042)
							(end 0.3048 0.2032)
						)
					)
					(width 0)
					(fill yes)
				)
			)
		)
		(pad "2" smd custom
			(at 0 0.4445)
			(size 0.1524 0.1524)
			(layers "F.Cu" "F.Mask" "F.Paste")
			(net "GND")
			(options
				(clearance outline)
				(anchor circle)
			)
			(primitives
				(gr_poly
					(pts
						(arc
							(start 0.3048 -0.2032)
							(mid 0.275042 -0.275042)
							(end 0.2032 -0.3048)
						)
						(arc
							(start -0.2032 -0.3048)
							(mid -0.275042 -0.275042)
							(end -0.3048 -0.2032)
						)
						(arc
							(start -0.3048 0.2032)
							(mid -0.275042 0.275042)
							(end -0.2032 0.3048)
						)
						(arc
							(start 0.2032 0.3048)
							(mid 0.275042 0.275042)
							(end 0.3048 0.2032)
						)
					)
					(width 0)
					(fill yes)
				)
			)
		)
	)
	(footprint ""
		(layer "F.Cu")
		(at 90.31097 -112.014 180)
		(property "Reference" "SC1239"
			(at 0 0 180)
			(layer "F.SilkS")
			(hide yes)
			(effects
				(font
					(size 1.27 1.27)
				)
			)
		)
		(property "Value" "SCD1U6D3V1KX-GP"
			(at -2.8321 -1.7399 180)
			(unlocked yes)
			(layer "F.Fab")
			(hide yes)
			(effects
				(font
					(size 1.016 1.016)
					(thickness 0.1524)
				)
			)
		)
		(property "Device Type" "C0201H13"
			(at -2.8321 -3.2639 180)
			(unlocked yes)
			(layer "F.Fab")
			(hide yes)
			(effects
				(font
					(size 1.016 1.016)
					(thickness 0.1524)
				)
			)
		)
		(duplicate_pad_numbers_are_jumpers no)
		(fp_rect
			(start -0.2794 0.6477)
			(end 0.2794 -0.6477)
			(stroke
				(width 0)
				(type default)
			)
			(fill no)
			(layer "F.CrtYd")
		)
		(fp_rect
			(start -0.2794 0.6477)
			(end 0.2794 -0.6477)
			(stroke
				(width 0)
				(type default)
			)
			(fill no)
			(layer "F.Fab")
		)
		(pad "1" smd custom
			(at 0 -0.2794 180)
			(size 0.0762 0.0762)
			(layers "F.Cu" "F.Mask" "F.Paste")
			(net "P1V8_E")
			(options
				(clearance outline)
				(anchor circle)
			)
			(primitives
				(gr_poly
					(pts
						(arc
							(start 0.1524 -0.127)
							(mid 0.137521 -0.162921)
							(end 0.1016 -0.1778)
						)
						(arc
							(start -0.1016 -0.1778)
							(mid -0.137521 -0.162921)
							(end -0.1524 -0.127)
						)
						(arc
							(start -0.1524 0.127)
							(mid -0.137521 0.162921)
							(end -0.1016 0.1778)
						)
						(arc
							(start 0.1016 0.1778)
							(mid 0.137521 0.162921)
							(end 0.1524 0.127)
						)
					)
					(width 0)
					(fill yes)
				)
			)
		)
		(pad "2" smd custom
			(at 0 0.2794 180)
			(size 0.0762 0.0762)
			(layers "F.Cu" "F.Mask" "F.Paste")
			(net "GND")
			(options
				(clearance outline)
				(anchor circle)
			)
			(primitives
				(gr_poly
					(pts
						(arc
							(start 0.1524 -0.127)
							(mid 0.137521 -0.162921)
							(end 0.1016 -0.1778)
						)
						(arc
							(start -0.1016 -0.1778)
							(mid -0.137521 -0.162921)
							(end -0.1524 -0.127)
						)
						(arc
							(start -0.1524 0.127)
							(mid -0.137521 0.162921)
							(end -0.1016 0.1778)
						)
						(arc
							(start 0.1016 0.1778)
							(mid 0.137521 0.162921)
							(end 0.1524 0.127)
						)
					)
					(width 0)
					(fill yes)
				)
			)
		)
	)
	(footprint ""
		(layer "F.Cu")
		(at 102.616 -223.647 -90)
		(property "Reference" "R644"
			(at 0 0 270)
			(layer "F.SilkS")
			(hide yes)
			(effects
				(font
					(size 1.27 1.27)
				)
			)
		)
		(property "Value" "4K7R2F-GP"
			(at 0.064008 -3.993896 270)
			(unlocked yes)
			(layer "F.Fab")
			(hide yes)
			(effects
				(font
					(size 1.016 1.016)
					(thickness 0.1524)
				)
			)
		)
		(property "Device Type" "R402H16"
			(at 0.064008 -5.517896 270)
			(unlocked yes)
			(layer "F.Fab")
			(hide yes)
			(effects
				(font
					(size 1.016 1.016)
					(thickness 0.1524)
				)
			)
		)
		(duplicate_pad_numbers_are_jumpers no)
		(fp_line
			(start -0.508 -0.9398)
			(end -0.508 0.9398)
			(stroke
				(width 0.1524)
				(type default)
			)
			(layer "F.SilkS")
		)
		(fp_line
			(start 0.508 -0.9398)
			(end -0.508 -0.9398)
			(stroke
				(width 0.1524)
				(type default)
			)
			(layer "F.SilkS")
		)
		(fp_rect
			(start -0.508 0.9398)
			(end 0.508 -0.9398)
			(stroke
				(width 0)
				(type default)
			)
			(fill no)
			(layer "F.CrtYd")
		)
		(fp_rect
			(start -0.508 0.9398)
			(end 0.508 -0.9398)
			(stroke
				(width 0)
				(type default)
			)
			(fill no)
			(layer "F.Fab")
		)
		(pad "1" smd custom
			(at 0 -0.4445 270)
			(size 0.1397 0.1397)
			(layers "F.Cu" "F.Mask" "F.Paste")
			(net "P3V3_STBY")
			(options
				(clearance outline)
				(anchor circle)
			)
			(primitives
				(gr_poly
					(pts
						(arc
							(start -0.1778 -0.2794)
							(mid -0.249642 -0.249642)
							(end -0.2794 -0.1778)
						)
						(arc
							(start -0.2794 0.1778)
							(mid -0.249642 0.249642)
							(end -0.1778 0.2794)
						)
						(arc
							(start 0.1778 0.2794)
							(mid 0.249642 0.249642)
							(end 0.2794 0.1778)
						)
						(arc
							(start 0.2794 -0.1778)
							(mid 0.249642 -0.249642)
							(end 0.1778 -0.2794)
						)
					)
					(width 0)
					(fill yes)
				)
			)
		)
		(pad "2" smd custom
			(at 0 0.4445 270)
			(size 0.1397 0.1397)
			(layers "F.Cu" "F.Mask" "F.Paste")
			(net "IO_EXP_HDD_FAULT_A2")
			(options
				(clearance outline)
				(anchor circle)
			)
			(primitives
				(gr_poly
					(pts
						(arc
							(start -0.1778 -0.2794)
							(mid -0.249642 -0.249642)
							(end -0.2794 -0.1778)
						)
						(arc
							(start -0.2794 0.1778)
							(mid -0.249642 0.249642)
							(end -0.1778 0.2794)
						)
						(arc
							(start 0.1778 0.2794)
							(mid 0.249642 0.249642)
							(end 0.2794 0.1778)
						)
						(arc
							(start 0.2794 -0.1778)
							(mid 0.249642 -0.249642)
							(end 0.1778 -0.2794)
						)
					)
					(width 0)
					(fill yes)
				)
			)
		)
	)
	(footprint ""
		(layer "F.Cu")
		(at 307.8734 -149.05736 90)
		(property "Reference" "X10"
			(at 0 0 90)
			(layer "F.SilkS")
			(hide yes)
			(effects
				(font
					(size 1.27 1.27)
				)
			)
		)
		(property "Value" "OSC-125MHZ-3-GP"
			(at 0 -10.6172 90)
			(unlocked yes)
			(layer "F.Fab")
			(hide yes)
			(effects
				(font
					(size 1.016 1.016)
					(thickness 0.1524)
				)
			)
		)
		(property "Device Type" "SMD-OSC5H56"
			(at 0 -12.6492 90)
			(unlocked yes)
			(layer "F.Fab")
			(hide yes)
			(effects
				(font
					(size 1.016 1.016)
					(thickness 0.1524)
				)
			)
		)
		(duplicate_pad_numbers_are_jumpers no)
		(fp_line
			(start 3.7592 -3.3528)
			(end 3.7592 3.3528)
			(stroke
				(width 0.1524)
				(type default)
			)
			(layer "F.SilkS")
		)
		(fp_line
			(start -3.7592 -3.3528)
			(end 3.7592 -3.3528)
			(stroke
				(width 0.1524)
				(type default)
			)
			(layer "F.SilkS")
		)
		(fp_line
			(start 3.7592 3.3528)
			(end -3.7592 3.3528)
			(stroke
				(width 0.1524)
				(type default)
			)
			(layer "F.SilkS")
		)
		(fp_line
			(start -3.7592 3.3528)
			(end -3.7592 -3.3528)
			(stroke
				(width 0.1524)
				(type default)
			)
			(layer "F.SilkS")
		)
		(fp_line
			(start -2.416556 3.453638)
			(end -3.844544 3.453638)
			(stroke
				(width 0.3302)
				(type default)
			)
			(layer "F.SilkS")
		)
		(fp_line
			(start -3.844544 3.453638)
			(end -3.844544 1.789176)
			(stroke
				(width 0.3302)
				(type default)
			)
			(layer "F.SilkS")
		)
		(fp_poly
			(pts
				(xy -3.0734 3.9624) (xy -2.0066 3.9624) (xy -2.54 3.429)
			)
			(stroke
				(width 0)
				(type default)
			)
			(fill yes)
			(layer "F.SilkS")
		)
		(fp_rect
			(start -4.0132 3.6068)
			(end 4.0132 -3.6068)
			(stroke
				(width 0)
				(type default)
			)
			(fill no)
			(layer "F.CrtYd")
		)
		(fp_rect
			(start -4.0132 3.6068)
			(end 4.0132 -3.6068)
			(stroke
				(width 0)
				(type default)
			)
			(fill no)
			(layer "F.Fab")
		)
		(pad "1" smd rect
			(at -2.54 2.10058 90)
			(size 1.8034 2.0066)
			(layers "F.Cu" "F.Mask" "F.Paste")
			(net "OSC_OE")
		)
		(pad "2" smd rect
			(at 2.54 2.10058 90)
			(size 1.8034 2.0066)
			(layers "F.Cu" "F.Mask" "F.Paste")
			(net "GND")
		)
		(pad "3" smd rect
			(at 2.54 -2.10058 90)
			(size 1.8034 2.0066)
			(layers "F.Cu" "F.Mask" "F.Paste")
			(net "125_GTX")
		)
		(pad "4" smd rect
			(at -2.54 -2.10058 90)
			(size 1.8034 2.0066)
			(layers "F.Cu" "F.Mask" "F.Paste")
			(net "P3V3_STBY")
		)
		(zone
			(layer "F.Cu")
			(hatch none 0.5)
			(connect_pads
				(clearance 0)
			)
			(min_thickness 0.25)
			(keepout
				(tracks not_allowed)
				(vias allowed)
				(pads allowed)
				(copperpour not_allowed)
				(footprints allowed)
			)
			(placement
				(enabled no)
				(sheetname "")
			)
			(fill
				(thermal_gap 0.5)
				(thermal_bridge_width 0.5)
				(island_removal_mode 0)
			)
			(polygon
				(pts
					(xy 307.099462 -150.372318) (xy 308.647338 -150.372318) (xy 308.647338 -147.742402) (xy 307.099462 -147.742402)
				)
			)
		)
		(zone
			(layer "F.Cu")
			(hatch none 0.5)
			(connect_pads
				(clearance 0)
			)
			(min_thickness 0.25)
			(keepout
				(tracks allowed)
				(vias not_allowed)
				(pads allowed)
				(copperpour not_allowed)
				(footprints allowed)
			)
			(placement
				(enabled no)
				(sheetname "")
			)
			(fill
				(thermal_gap 0.5)
				(thermal_bridge_width 0.5)
				(island_removal_mode 0)
			)
			(polygon
				(pts
					(xy 310.97728 -147.41906) (xy 308.97068 -147.41906) (xy 308.97068 -145.61566) (xy 306.77612 -145.61566)
					(xy 306.77612 -147.41906) (xy 304.76952 -147.41906) (xy 304.76952 -150.69566) (xy 306.77612 -150.69566)
					(xy 306.77612 -152.49906) (xy 308.97068 -152.49906) (xy 308.97068 -150.69566) (xy 310.97728 -150.69566)
				)
			)
		)
	)
	(footprint ""
		(layer "F.Cu")
		(at 29.160216 -202.87488 -90)
		(property "Reference" "U17"
			(at 0 0 270)
			(layer "F.SilkS")
			(hide yes)
			(effects
				(font
					(size 1.27 1.27)
				)
			)
		)
		(property "Value" "ADS1015IDGSR-GP"
			(at 0 -11.1252 270)
			(unlocked yes)
			(layer "F.Fab")
			(hide yes)
			(effects
				(font
					(size 1.016 1.016)
					(thickness 0.1524)
				)
			)
		)
		(property "Device Type" "MSOP10H44"
			(at 0 -12.6492 270)
			(unlocked yes)
			(layer "F.Fab")
			(hide yes)
			(effects
				(font
					(size 1.016 1.016)
					(thickness 0.1524)
				)
			)
		)
		(duplicate_pad_numbers_are_jumpers no)
		(fp_line
			(start -2.0066 1.016)
			(end -2.0066 -1.016)
			(stroke
				(width 0.1524)
				(type default)
			)
			(layer "F.SilkS")
		)
		(fp_line
			(start -1.8288 1.016)
			(end -1.8288 3.048)
			(stroke
				(width 0.508)
				(type default)
			)
			(layer "F.SilkS")
		)
		(fp_line
			(start 1.143 1.016)
			(end -2.0066 1.016)
			(stroke
				(width 0.1524)
				(type default)
			)
			(layer "F.SilkS")
		)
		(fp_line
			(start -1.5748 0)
			(end -1.9558 0.381)
			(stroke
				(width 0.1524)
				(type default)
			)
			(layer "F.SilkS")
		)
		(fp_line
			(start -1.5748 0)
			(end -1.9558 -0.381)
			(stroke
				(width 0.1524)
				(type default)
			)
			(layer "F.SilkS")
		)
		(fp_line
			(start -2.0066 -1.016)
			(end 1.143 -1.016)
			(stroke
				(width 0.1524)
				(type default)
			)
			(layer "F.SilkS")
		)
		(fp_line
			(start 1.143 -1.016)
			(end 1.143 1.016)
			(stroke
				(width 0.1524)
				(type default)
			)
			(layer "F.SilkS")
		)
		(fp_poly
			(pts
				(xy -2.0828 3.3401) (xy 2.0828 3.3401) (xy 2.0828 -3.3401) (xy -2.0828 -3.3401)
			)
			(stroke
				(width 0)
				(type default)
			)
			(fill no)
			(layer "F.CrtYd")
		)
		(fp_poly
			(pts
				(xy -2.0828 3.3401) (xy 2.0828 3.3401) (xy 2.0828 -3.3401) (xy -2.0828 -3.3401)
			)
			(stroke
				(width 0)
				(type default)
			)
			(fill no)
			(layer "F.Fab")
		)
		(pad "1" smd rect
			(at -0.99949 2.0701 270)
			(size 0.3048 1.524)
			(layers "F.Cu" "F.Mask" "F.Paste")
			(net "VOL_SEN_ADDR_U17")
		)
		(pad "2" smd rect
			(at -0.50038 2.0701 270)
			(size 0.3048 1.524)
			(layers "F.Cu" "F.Mask" "F.Paste")
			(net "VOL_SEN_ALERT_U17")
		)
		(pad "3" smd rect
			(at 0 2.0701 270)
			(size 0.3048 1.524)
			(layers "F.Cu" "F.Mask" "F.Paste")
			(net "GND")
		)
		(pad "4" smd rect
			(at 0.50038 2.0701 270)
			(size 0.3048 1.524)
			(layers "F.Cu" "F.Mask" "F.Paste")
			(net "P0V9_E_SENSE")
		)
		(pad "5" smd rect
			(at 0.99949 2.0701 270)
			(size 0.3048 1.524)
			(layers "F.Cu" "F.Mask" "F.Paste")
			(net "P0V955_C_SENSE")
		)
		(pad "6" smd rect
			(at 0.99949 -2.0701 270)
			(size 0.3048 1.524)
			(layers "F.Cu" "F.Mask" "F.Paste")
			(net "P1V5_E_SENSE")
		)
		(pad "7" smd rect
			(at 0.50038 -2.0701 270)
			(size 0.3048 1.524)
			(layers "F.Cu" "F.Mask" "F.Paste")
			(net "P1V5_C_SENSE")
		)
		(pad "8" smd rect
			(at 0 -2.0701 270)
			(size 0.3048 1.524)
			(layers "F.Cu" "F.Mask" "F.Paste")
			(net "P3V3_STBY")
		)
		(pad "9" smd rect
			(at -0.50038 -2.0701 270)
			(size 0.3048 1.524)
			(layers "F.Cu" "F.Mask" "F.Paste")
			(net "VOL_SEN_SDA_U17")
		)
		(pad "10" smd rect
			(at -0.99949 -2.0701 270)
			(size 0.3048 1.524)
			(layers "F.Cu" "F.Mask" "F.Paste")
			(net "VOL_SEN_SCL_U17")
		)
	)
	(footprint ""
		(layer "F.Cu")
		(at 152.019 -50.927 90)
		(property "Reference" "SR697"
			(at 0 0 90)
			(layer "F.SilkS")
			(hide yes)
			(effects
				(font
					(size 1.27 1.27)
				)
			)
		)
		(property "Value" "10KR2F-2-GP"
			(at 0.064008 -3.993896 90)
			(unlocked yes)
			(layer "F.Fab")
			(hide yes)
			(effects
				(font
					(size 1.016 1.016)
					(thickness 0.1524)
				)
			)
		)
		(property "Device Type" "R402H16"
			(at 0.064008 -5.517896 90)
			(unlocked yes)
			(layer "F.Fab")
			(hide yes)
			(effects
				(font
					(size 1.016 1.016)
					(thickness 0.1524)
				)
			)
		)
		(duplicate_pad_numbers_are_jumpers no)
		(fp_line
			(start 0.508 -0.9398)
			(end -0.508 -0.9398)
			(stroke
				(width 0.1524)
				(type default)
			)
			(layer "F.SilkS")
		)
		(fp_line
			(start -0.508 -0.9398)
			(end -0.508 0.9398)
			(stroke
				(width 0.1524)
				(type default)
			)
			(layer "F.SilkS")
		)
		(fp_rect
			(start -0.508 0.9398)
			(end 0.508 -0.9398)
			(stroke
				(width 0)
				(type default)
			)
			(fill no)
			(layer "F.CrtYd")
		)
		(fp_rect
			(start -0.508 0.9398)
			(end 0.508 -0.9398)
			(stroke
				(width 0)
				(type default)
			)
			(fill no)
			(layer "F.Fab")
		)
		(pad "1" smd custom
			(at 0 -0.4445 90)
			(size 0.1397 0.1397)
			(layers "F.Cu" "F.Mask" "F.Paste")
			(net "XM_ADDR_2")
			(options
				(clearance outline)
				(anchor circle)
			)
			(primitives
				(gr_poly
					(pts
						(arc
							(start -0.1778 -0.2794)
							(mid -0.249642 -0.249642)
							(end -0.2794 -0.1778)
						)
						(arc
							(start -0.2794 0.1778)
							(mid -0.249642 0.249642)
							(end -0.1778 0.2794)
						)
						(arc
							(start 0.1778 0.2794)
							(mid 0.249642 0.249642)
							(end 0.2794 0.1778)
						)
						(arc
							(start 0.2794 -0.1778)
							(mid 0.249642 -0.249642)
							(end 0.1778 -0.2794)
						)
					)
					(width 0)
					(fill yes)
				)
			)
		)
		(pad "2" smd custom
			(at 0 0.4445 90)
			(size 0.1397 0.1397)
			(layers "F.Cu" "F.Mask" "F.Paste")
			(net "GND")
			(options
				(clearance outline)
				(anchor circle)
			)
			(primitives
				(gr_poly
					(pts
						(arc
							(start -0.1778 -0.2794)
							(mid -0.249642 -0.249642)
							(end -0.2794 -0.1778)
						)
						(arc
							(start -0.2794 0.1778)
							(mid -0.249642 0.249642)
							(end -0.1778 0.2794)
						)
						(arc
							(start 0.1778 0.2794)
							(mid 0.249642 0.249642)
							(end 0.2794 0.1778)
						)
						(arc
							(start 0.2794 -0.1778)
							(mid 0.249642 -0.249642)
							(end 0.1778 -0.2794)
						)
					)
					(width 0)
					(fill yes)
				)
			)
		)
	)
	(footprint ""
		(layer "F.Cu")
		(at 140.88237 -88.411812 180)
		(property "Reference" "U135"
			(at 0 0 180)
			(layer "F.SilkS")
			(hide yes)
			(effects
				(font
					(size 1.27 1.27)
				)
			)
		)
		(property "Value" "TMP75AIDGKR-GP"
			(at -0.1143 -9.1948 180)
			(unlocked yes)
			(layer "F.Fab")
			(hide yes)
			(effects
				(font
					(size 1.016 1.016)
					(thickness 0.1524)
				)
			)
		)
		(property "Device Type" "MSOP8-1H44"
			(at -0.1143 -10.795 180)
			(unlocked yes)
			(layer "F.Fab")
			(hide yes)
			(effects
				(font
					(size 1.016 1.016)
					(thickness 0.1524)
				)
			)
		)
		(duplicate_pad_numbers_are_jumpers no)
		(fp_line
			(start 1.0795 1.016)
			(end 1.0795 -1.016)
			(stroke
				(width 0.1524)
				(type default)
			)
			(layer "F.SilkS")
		)
		(fp_line
			(start 1.0795 -1.016)
			(end -1.9558 -1.016)
			(stroke
				(width 0.1524)
				(type default)
			)
			(layer "F.SilkS")
		)
		(fp_line
			(start -1.4478 -0.0381)
			(end -1.9558 0.4699)
			(stroke
				(width 0.1524)
				(type default)
			)
			(layer "F.SilkS")
		)
		(fp_line
			(start -1.778 1.0922)
			(end -1.778 3.048)
			(stroke
				(width 0.508)
				(type default)
			)
			(layer "F.SilkS")
		)
		(fp_line
			(start -1.9558 1.016)
			(end 1.0795 1.016)
			(stroke
				(width 0.1524)
				(type default)
			)
			(layer "F.SilkS")
		)
		(fp_line
			(start -1.9558 -0.5461)
			(end -1.4478 -0.0381)
			(stroke
				(width 0.1524)
				(type default)
			)
			(layer "F.SilkS")
		)
		(fp_line
			(start -1.9558 -1.016)
			(end -1.9558 1.016)
			(stroke
				(width 0.1524)
				(type default)
			)
			(layer "F.SilkS")
		)
		(fp_poly
			(pts
				(xy -1.1557 -1.016) (xy -1.1557 1.016) (xy 1.1557 1.016) (xy 1.1557 -1.016)
			)
			(stroke
				(width 0)
				(type default)
			)
			(fill yes)
			(layer "F.SilkS")
		)
		(fp_rect
			(start -1.4986 2.4511)
			(end 1.4986 -2.4511)
			(stroke
				(width 0)
				(type default)
			)
			(fill no)
			(layer "F.CrtYd")
		)
		(fp_poly
			(pts
				(xy -2.032 3.302) (xy -2.032 -3.302) (xy 2.032 -3.302) (xy 2.032 -2.1209) (xy 1.4986 -2.1209) (xy 1.4986 -2.4511)
				(xy -1.4986 -2.4511) (xy -1.4986 2.4511) (xy 1.4986 2.4511) (xy 1.4986 -2.1082) (xy 2.032 -2.1082)
				(xy 2.032 3.302)
			)
			(stroke
				(width 0)
				(type default)
			)
			(fill no)
			(layer "F.CrtYd")
		)
		(fp_rect
			(start -2.032 3.302)
			(end 2.032 -3.302)
			(stroke
				(width 0)
				(type default)
			)
			(fill no)
			(layer "F.Fab")
		)
		(pad "1" smd rect
			(at -0.97536 2.05486 180)
			(size 0.3556 1.524)
			(layers "F.Cu" "F.Mask" "F.Paste")
			(net "TEMP_3_SDA")
		)
		(pad "2" smd rect
			(at -0.32512 2.05486 180)
			(size 0.3556 1.524)
			(layers "F.Cu" "F.Mask" "F.Paste")
			(net "TEMP_3_SCL")
		)
		(pad "3" smd rect
			(at 0.32512 2.05486 180)
			(size 0.3556 1.524)
			(layers "F.Cu" "F.Mask" "F.Paste")
			(net "TEMP_3_ALERT")
		)
		(pad "4" smd rect
			(at 0.97536 2.05486 180)
			(size 0.3556 1.524)
			(layers "F.Cu" "F.Mask" "F.Paste")
			(net "GND")
		)
		(pad "5" smd rect
			(at 0.97536 -2.05486 180)
			(size 0.3556 1.524)
			(layers "F.Cu" "F.Mask" "F.Paste")
			(net "TEMP_3_A2")
		)
		(pad "6" smd rect
			(at 0.32512 -2.05486 180)
			(size 0.3556 1.524)
			(layers "F.Cu" "F.Mask" "F.Paste")
			(net "TEMP_3_A1")
		)
		(pad "7" smd rect
			(at -0.32512 -2.05486 180)
			(size 0.3556 1.524)
			(layers "F.Cu" "F.Mask" "F.Paste")
			(net "TEMP_3_A0")
		)
		(pad "8" smd rect
			(at -0.97536 -2.05486 180)
			(size 0.3556 1.524)
			(layers "F.Cu" "F.Mask" "F.Paste")
			(net "P3V3_STBY")
		)
	)
	(footprint ""
		(layer "F.Cu")
		(at 309.871872 -200.859136 90)
		(property "Reference" "TP83"
			(at 0 0 90)
			(layer "F.SilkS")
			(hide yes)
			(effects
				(font
					(size 1.27 1.27)
				)
			)
		)
		(property "Value" "TPAD32-GP"
			(at 0 -3.166364 90)
			(unlocked yes)
			(layer "F.Fab")
			(hide yes)
			(effects
				(font
					(size 1.016 1.016)
					(thickness 0.1524)
				)
			)
		)
		(property "Device Type" "TPAD32"
			(at 0 -4.690618 90)
			(unlocked yes)
			(layer "F.Fab")
			(hide yes)
			(effects
				(font
					(size 1.016 1.016)
					(thickness 0.1524)
				)
			)
		)
		(duplicate_pad_numbers_are_jumpers no)
		(fp_poly
			(pts
				(arc
					(start 0 0.4064)
					(mid 0 -0.4064)
					(end 0 0.4064)
				)
			)
			(stroke
				(width 0)
				(type default)
			)
			(fill no)
			(layer "F.CrtYd")
		)
		(fp_poly
			(pts
				(arc
					(start 0 0.7112)
					(mid 0 -0.7112)
					(end 0 0.7112)
				)
			)
			(stroke
				(width 0)
				(type default)
			)
			(fill no)
			(layer "F.Fab")
		)
		(pad "1" smd circle
			(at 0 0 90)
			(size 0.8128 0.8128)
			(layers "F.Cu" "F.Mask" "F.Paste")
			(net "LED_DR_RESET#")
		)
	)
	(footprint ""
		(layer "F.Cu")
		(at 300.228 -91.948 180)
		(property "Reference" "R5308"
			(at 0 0 180)
			(layer "F.SilkS")
			(hide yes)
			(effects
				(font
					(size 1.27 1.27)
				)
			)
		)
		(property "Value" "0R2J-2-GP"
			(at 0.064008 -3.993896 180)
			(unlocked yes)
			(layer "F.Fab")
			(hide yes)
			(effects
				(font
					(size 1.016 1.016)
					(thickness 0.1524)
				)
			)
		)
		(property "Device Type" "R402H16"
			(at 0.064008 -5.517896 180)
			(unlocked yes)
			(layer "F.Fab")
			(hide yes)
			(effects
				(font
					(size 1.016 1.016)
					(thickness 0.1524)
				)
			)
		)
		(duplicate_pad_numbers_are_jumpers no)
		(fp_line
			(start 0.508 -0.9398)
			(end -0.508 -0.9398)
			(stroke
				(width 0.1524)
				(type default)
			)
			(layer "F.SilkS")
		)
		(fp_line
			(start -0.508 -0.9398)
			(end -0.508 0.9398)
			(stroke
				(width 0.1524)
				(type default)
			)
			(layer "F.SilkS")
		)
		(fp_rect
			(start -0.508 0.9398)
			(end 0.508 -0.9398)
			(stroke
				(width 0)
				(type default)
			)
			(fill no)
			(layer "F.CrtYd")
		)
		(fp_rect
			(start -0.508 0.9398)
			(end 0.508 -0.9398)
			(stroke
				(width 0)
				(type default)
			)
			(fill no)
			(layer "F.Fab")
		)
		(pad "1" smd custom
			(at 0 -0.4445 180)
			(size 0.1397 0.1397)
			(layers "F.Cu" "F.Mask" "F.Paste")
			(net "BMC_I2C_SDA_10")
			(options
				(clearance outline)
				(anchor circle)
			)
			(primitives
				(gr_poly
					(pts
						(arc
							(start -0.1778 -0.2794)
							(mid -0.249642 -0.249642)
							(end -0.2794 -0.1778)
						)
						(arc
							(start -0.2794 0.1778)
							(mid -0.249642 0.249642)
							(end -0.1778 0.2794)
						)
						(arc
							(start 0.1778 0.2794)
							(mid 0.249642 0.249642)
							(end 0.2794 0.1778)
						)
						(arc
							(start 0.2794 -0.1778)
							(mid 0.249642 -0.249642)
							(end 0.1778 -0.2794)
						)
					)
					(width 0)
					(fill yes)
				)
			)
		)
		(pad "2" smd custom
			(at 0 0.4445 180)
			(size 0.1397 0.1397)
			(layers "F.Cu" "F.Mask" "F.Paste")
			(net "TEMP_2_SDA")
			(options
				(clearance outline)
				(anchor circle)
			)
			(primitives
				(gr_poly
					(pts
						(arc
							(start -0.1778 -0.2794)
							(mid -0.249642 -0.249642)
							(end -0.2794 -0.1778)
						)
						(arc
							(start -0.2794 0.1778)
							(mid -0.249642 0.249642)
							(end -0.1778 0.2794)
						)
						(arc
							(start 0.1778 0.2794)
							(mid 0.249642 0.249642)
							(end 0.2794 0.1778)
						)
						(arc
							(start 0.2794 -0.1778)
							(mid 0.249642 -0.249642)
							(end 0.1778 -0.2794)
						)
					)
					(width 0)
					(fill yes)
				)
			)
		)
	)
	(footprint ""
		(layer "F.Cu")
		(at 95.70847 -107.188 -90)
		(property "Reference" "SR736"
			(at 0 0 270)
			(layer "F.SilkS")
			(hide yes)
			(effects
				(font
					(size 1.27 1.27)
				)
			)
		)
		(property "Value" "2K2R2F-GP"
			(at 0.064008 -3.993896 270)
			(unlocked yes)
			(layer "F.Fab")
			(hide yes)
			(effects
				(font
					(size 1.016 1.016)
					(thickness 0.1524)
				)
			)
		)
		(property "Device Type" "R402H16"
			(at 0.064008 -5.517896 270)
			(unlocked yes)
			(layer "F.Fab")
			(hide yes)
			(effects
				(font
					(size 1.016 1.016)
					(thickness 0.1524)
				)
			)
		)
		(duplicate_pad_numbers_are_jumpers no)
		(fp_line
			(start -0.508 -0.9398)
			(end -0.508 0.9398)
			(stroke
				(width 0.1524)
				(type default)
			)
			(layer "F.SilkS")
		)
		(fp_line
			(start 0.508 -0.9398)
			(end -0.508 -0.9398)
			(stroke
				(width 0.1524)
				(type default)
			)
			(layer "F.SilkS")
		)
		(fp_rect
			(start -0.508 0.9398)
			(end 0.508 -0.9398)
			(stroke
				(width 0)
				(type default)
			)
			(fill no)
			(layer "F.CrtYd")
		)
		(fp_rect
			(start -0.508 0.9398)
			(end 0.508 -0.9398)
			(stroke
				(width 0)
				(type default)
			)
			(fill no)
			(layer "F.Fab")
		)
		(pad "1" smd custom
			(at 0 -0.4445 270)
			(size 0.1397 0.1397)
			(layers "F.Cu" "F.Mask" "F.Paste")
			(net "EXP_I2C_SCL_4")
			(options
				(clearance outline)
				(anchor circle)
			)
			(primitives
				(gr_poly
					(pts
						(arc
							(start -0.1778 -0.2794)
							(mid -0.249642 -0.249642)
							(end -0.2794 -0.1778)
						)
						(arc
							(start -0.2794 0.1778)
							(mid -0.249642 0.249642)
							(end -0.1778 0.2794)
						)
						(arc
							(start 0.1778 0.2794)
							(mid 0.249642 0.249642)
							(end 0.2794 0.1778)
						)
						(arc
							(start 0.2794 -0.1778)
							(mid 0.249642 -0.249642)
							(end 0.1778 -0.2794)
						)
					)
					(width 0)
					(fill yes)
				)
			)
		)
		(pad "2" smd custom
			(at 0 0.4445 270)
			(size 0.1397 0.1397)
			(layers "F.Cu" "F.Mask" "F.Paste")
			(net "P1V8_E")
			(options
				(clearance outline)
				(anchor circle)
			)
			(primitives
				(gr_poly
					(pts
						(arc
							(start -0.1778 -0.2794)
							(mid -0.249642 -0.249642)
							(end -0.2794 -0.1778)
						)
						(arc
							(start -0.2794 0.1778)
							(mid -0.249642 0.249642)
							(end -0.1778 0.2794)
						)
						(arc
							(start 0.1778 0.2794)
							(mid 0.249642 0.249642)
							(end 0.2794 0.1778)
						)
						(arc
							(start 0.2794 -0.1778)
							(mid 0.249642 -0.249642)
							(end 0.1778 -0.2794)
						)
					)
					(width 0)
					(fill yes)
				)
			)
		)
	)
	(footprint ""
		(layer "F.Cu")
		(at 266.065 -176.022 90)
		(property "Reference" "R447"
			(at 0 0 90)
			(layer "F.SilkS")
			(hide yes)
			(effects
				(font
					(size 1.27 1.27)
				)
			)
		)
		(property "Value" "10KR2F-2-GP"
			(at 0.064008 -3.993896 90)
			(unlocked yes)
			(layer "F.Fab")
			(hide yes)
			(effects
				(font
					(size 1.016 1.016)
					(thickness 0.1524)
				)
			)
		)
		(property "Device Type" "R402H16"
			(at 0.064008 -5.517896 90)
			(unlocked yes)
			(layer "F.Fab")
			(hide yes)
			(effects
				(font
					(size 1.016 1.016)
					(thickness 0.1524)
				)
			)
		)
		(duplicate_pad_numbers_are_jumpers no)
		(fp_line
			(start 0.508 -0.9398)
			(end -0.508 -0.9398)
			(stroke
				(width 0.1524)
				(type default)
			)
			(layer "F.SilkS")
		)
		(fp_line
			(start -0.508 -0.9398)
			(end -0.508 0.9398)
			(stroke
				(width 0.1524)
				(type default)
			)
			(layer "F.SilkS")
		)
		(fp_rect
			(start -0.508 0.9398)
			(end 0.508 -0.9398)
			(stroke
				(width 0)
				(type default)
			)
			(fill no)
			(layer "F.CrtYd")
		)
		(fp_rect
			(start -0.508 0.9398)
			(end 0.508 -0.9398)
			(stroke
				(width 0)
				(type default)
			)
			(fill no)
			(layer "F.Fab")
		)
		(pad "1" smd custom
			(at 0 -0.4445 90)
			(size 0.1397 0.1397)
			(layers "F.Cu" "F.Mask" "F.Paste")
			(net "P3V3_STBY")
			(options
				(clearance outline)
				(anchor circle)
			)
			(primitives
				(gr_poly
					(pts
						(arc
							(start -0.1778 -0.2794)
							(mid -0.249642 -0.249642)
							(end -0.2794 -0.1778)
						)
						(arc
							(start -0.2794 0.1778)
							(mid -0.249642 0.249642)
							(end -0.1778 0.2794)
						)
						(arc
							(start 0.1778 0.2794)
							(mid 0.249642 0.249642)
							(end 0.2794 0.1778)
						)
						(arc
							(start 0.2794 -0.1778)
							(mid 0.249642 -0.249642)
							(end 0.1778 -0.2794)
						)
					)
					(width 0)
					(fill yes)
				)
			)
		)
		(pad "2" smd custom
			(at 0 0.4445 90)
			(size 0.1397 0.1397)
			(layers "F.Cu" "F.Mask" "F.Paste")
			(net "BMC_SALT3")
			(options
				(clearance outline)
				(anchor circle)
			)
			(primitives
				(gr_poly
					(pts
						(arc
							(start -0.1778 -0.2794)
							(mid -0.249642 -0.249642)
							(end -0.2794 -0.1778)
						)
						(arc
							(start -0.2794 0.1778)
							(mid -0.249642 0.249642)
							(end -0.1778 0.2794)
						)
						(arc
							(start 0.1778 0.2794)
							(mid 0.249642 0.249642)
							(end 0.2794 0.1778)
						)
						(arc
							(start 0.2794 -0.1778)
							(mid 0.249642 -0.249642)
							(end 0.1778 -0.2794)
						)
					)
					(width 0)
					(fill yes)
				)
			)
		)
	)
	(footprint ""
		(layer "F.Cu")
		(at 123.703842 -76.906882)
		(property "Reference" "SX2"
			(at 0 0 0)
			(layer "F.SilkS")
			(hide yes)
			(effects
				(font
					(size 1.27 1.27)
				)
			)
		)
		(property "Value" "XTAL-25MHZ-105-GP"
			(at 0.1016 -10.5918 0)
			(unlocked yes)
			(layer "F.Fab")
			(hide yes)
			(effects
				(font
					(size 1.016 1.016)
					(thickness 0.1524)
				)
			)
		)
		(property "Device Type" "SG8002CAPC-4H40"
			(at 0.1016 -12.6238 0)
			(unlocked yes)
			(layer "F.Fab")
			(hide yes)
			(effects
				(font
					(size 1.016 1.016)
					(thickness 0.1524)
				)
			)
		)
		(duplicate_pad_numbers_are_jumpers no)
		(fp_line
			(start -2.8575 -1.9558)
			(end 2.8575 -1.9558)
			(stroke
				(width 0.1524)
				(type default)
			)
			(layer "F.SilkS")
		)
		(fp_line
			(start -2.8575 1.9558)
			(end -2.8575 -1.9558)
			(stroke
				(width 0.1524)
				(type default)
			)
			(layer "F.SilkS")
		)
		(fp_line
			(start 2.8575 -1.9558)
			(end 2.8575 1.9558)
			(stroke
				(width 0.1524)
				(type default)
			)
			(layer "F.SilkS")
		)
		(fp_line
			(start 2.8575 1.9558)
			(end -2.8575 1.9558)
			(stroke
				(width 0.1524)
				(type default)
			)
			(layer "F.SilkS")
		)
		(fp_poly
			(pts
				(xy -2.3114 2.3876) (xy -1.9558 2.032) (xy -1.6002 2.3876)
			)
			(stroke
				(width 0)
				(type default)
			)
			(fill yes)
			(layer "F.SilkS")
		)
		(fp_rect
			(start -2.99974 2.10058)
			(end 2.99974 -2.09931)
			(stroke
				(width 0)
				(type default)
			)
			(fill no)
			(layer "F.CrtYd")
		)
		(fp_rect
			(start -2.3114 2.3876)
			(end -1.6002 2.10058)
			(stroke
				(width 0)
				(type default)
			)
			(fill no)
			(layer "F.CrtYd")
		)
		(fp_poly
			(pts
				(xy -2.3114 2.3876) (xy -2.3114 2.10058) (xy -2.99974 2.10058) (xy -2.99974 -2.09931) (xy 2.99974 -2.09931)
				(xy 2.99974 2.09931) (xy -1.6002 2.09931) (xy -1.6002 2.3876)
			)
			(stroke
				(width 0)
				(type default)
			)
			(fill no)
			(layer "F.Fab")
		)
		(pad "1" smd rect
			(at -1.8034 1.0414)
			(size 1.6002 1.3462)
			(layers "F.Cu" "F.Mask" "F.Paste")
			(net "EXP_REF_CLK_N_R")
		)
		(pad "2" smd rect
			(at 1.8034 1.0414)
			(size 1.6002 1.3462)
			(layers "F.Cu" "F.Mask" "F.Paste")
			(net "GND")
		)
		(pad "3" smd rect
			(at 1.8034 -1.0414)
			(size 1.6002 1.3462)
			(layers "F.Cu" "F.Mask" "F.Paste")
			(net "EXP_REF_CLK_P")
		)
		(pad "4" smd rect
			(at -1.8034 -1.0414)
			(size 1.6002 1.3462)
			(layers "F.Cu" "F.Mask" "F.Paste")
			(net "GND")
		)
		(zone
			(layer "F.Cu")
			(hatch none 0.5)
			(connect_pads
				(clearance 0)
			)
			(min_thickness 0.25)
			(keepout
				(tracks not_allowed)
				(vias allowed)
				(pads allowed)
				(copperpour not_allowed)
				(footprints allowed)
			)
			(placement
				(enabled no)
				(sheetname "")
			)
			(fill
				(thermal_gap 0.5)
				(thermal_bridge_width 0.5)
				(island_removal_mode 0)
			)
			(polygon
				(pts
					(xy 123.195842 -77.287882) (xy 124.211842 -77.287882) (xy 124.211842 -76.525882) (xy 123.195842 -76.525882)
				)
			)
		)
		(zone
			(layer "F.Cu")
			(hatch none 0.5)
			(connect_pads
				(clearance 0)
			)
			(min_thickness 0.25)
			(keepout
				(tracks allowed)
				(vias not_allowed)
				(pads allowed)
				(copperpour not_allowed)
				(footprints allowed)
			)
			(placement
				(enabled no)
				(sheetname "")
			)
			(fill
				(thermal_gap 0.5)
				(thermal_bridge_width 0.5)
				(island_removal_mode 0)
			)
			(polygon
				(pts
					(xy 122.687842 -78.557882) (xy 124.719842 -78.557882) (xy 124.719842 -77.160882) (xy 126.243842 -77.160882)
					(xy 126.243842 -76.652882) (xy 124.719842 -76.652882) (xy 124.719842 -75.255882) (xy 122.687842 -75.255882)
					(xy 122.687842 -76.652882) (xy 121.163842 -76.652882) (xy 121.163842 -77.160882) (xy 122.687842 -77.160882)
				)
			)
		)
	)
	(footprint ""
		(layer "F.Cu")
		(at 36.449 -171.958)
		(property "Reference" "SQ17"
			(at 0 0 0)
			(layer "F.SilkS")
			(hide yes)
			(effects
				(font
					(size 1.27 1.27)
				)
			)
		)
		(property "Value" "2N7002A-7-GP"
			(at 0.127 -8.9662 0)
			(unlocked yes)
			(layer "F.Fab")
			(hide yes)
			(effects
				(font
					(size 1.016 1.016)
					(thickness 0.1524)
				)
			)
		)
		(property "Device Type" "SOT23DGS2D4H48"
			(at 0.127 -10.4902 0)
			(unlocked yes)
			(layer "F.Fab")
			(hide yes)
			(effects
				(font
					(size 1.016 1.016)
					(thickness 0.1524)
				)
			)
		)
		(duplicate_pad_numbers_are_jumpers no)
		(fp_line
			(start -1.651 -1.778)
			(end -1.651 1.778)
			(stroke
				(width 0.1524)
				(type default)
			)
			(layer "F.SilkS")
		)
		(fp_line
			(start -1.651 1.778)
			(end 1.651 1.778)
			(stroke
				(width 0.1524)
				(type default)
			)
			(layer "F.SilkS")
		)
		(fp_line
			(start 1.651 -1.778)
			(end -1.651 -1.778)
			(stroke
				(width 0.1524)
				(type default)
			)
			(layer "F.SilkS")
		)
		(fp_line
			(start 1.651 1.778)
			(end 1.651 -1.778)
			(stroke
				(width 0.1524)
				(type default)
			)
			(layer "F.SilkS")
		)
		(fp_poly
			(pts
				(xy -1.778 1.8796) (xy -1.778 -1.8796) (xy 1.778 -1.8796) (xy 1.778 1.8796)
			)
			(stroke
				(width 0)
				(type default)
			)
			(fill no)
			(layer "F.CrtYd")
		)
		(fp_poly
			(pts
				(xy -1.778 1.8796) (xy -1.778 -1.8796) (xy 1.778 -1.8796) (xy 1.778 1.8796)
			)
			(stroke
				(width 0)
				(type default)
			)
			(fill no)
			(layer "F.Fab")
		)
		(pad "D" smd custom
			(at 0 -0.9525)
			(size 0.1905 0.1905)
			(layers "F.Cu" "F.Mask" "F.Paste")
			(net "P3V3_STBY_R8")
			(options
				(clearance outline)
				(anchor circle)
			)
			(primitives
				(gr_poly
					(pts
						(arc
							(start -0.1778 0.5715)
							(mid -0.321484 0.511984)
							(end -0.381 0.3683)
						)
						(arc
							(start -0.381 -0.3683)
							(mid -0.321484 -0.511984)
							(end -0.1778 -0.5715)
						)
						(arc
							(start 0.1778 -0.5715)
							(mid 0.321484 -0.511984)
							(end 0.381 -0.3683)
						)
						(arc
							(start 0.381 0.3683)
							(mid 0.321484 0.511984)
							(end 0.1778 0.5715)
						)
					)
					(width 0)
					(fill yes)
				)
			)
		)
		(pad "G" smd custom
			(at -0.98425 0.9525)
			(size 0.1905 0.1905)
			(layers "F.Cu" "F.Mask" "F.Paste")
			(net "DP_BMC_EXP_RST_N")
			(options
				(clearance outline)
				(anchor circle)
			)
			(primitives
				(gr_poly
					(pts
						(arc
							(start -0.1778 0.5715)
							(mid -0.321484 0.511984)
							(end -0.381 0.3683)
						)
						(arc
							(start -0.381 -0.3683)
							(mid -0.321484 -0.511984)
							(end -0.1778 -0.5715)
						)
						(arc
							(start 0.1778 -0.5715)
							(mid 0.321484 -0.511984)
							(end 0.381 -0.3683)
						)
						(arc
							(start 0.381 0.3683)
							(mid 0.321484 0.511984)
							(end 0.1778 0.5715)
						)
					)
					(width 0)
					(fill yes)
				)
			)
		)
		(pad "S" smd custom
			(at 0.98425 0.9525)
			(size 0.1905 0.1905)
			(layers "F.Cu" "F.Mask" "F.Paste")
			(net "GND")
			(options
				(clearance outline)
				(anchor circle)
			)
			(primitives
				(gr_poly
					(pts
						(arc
							(start -0.1778 0.5715)
							(mid -0.321484 0.511984)
							(end -0.381 0.3683)
						)
						(arc
							(start -0.381 -0.3683)
							(mid -0.321484 -0.511984)
							(end -0.1778 -0.5715)
						)
						(arc
							(start 0.1778 -0.5715)
							(mid 0.321484 -0.511984)
							(end 0.381 -0.3683)
						)
						(arc
							(start 0.381 0.3683)
							(mid 0.321484 0.511984)
							(end 0.1778 0.5715)
						)
					)
					(width 0)
					(fill yes)
				)
			)
		)
	)
	(footprint ""
		(layer "F.Cu")
		(at 74.462386 -106.598212 90)
		(property "Reference" "PR168"
			(at 0 0 90)
			(layer "F.SilkS")
			(hide yes)
			(effects
				(font
					(size 1.27 1.27)
				)
			)
		)
		(property "Value" "100KR2F-L1-GP"
			(at 0.064008 -3.993896 90)
			(unlocked yes)
			(layer "F.Fab")
			(hide yes)
			(effects
				(font
					(size 1.016 1.016)
					(thickness 0.1524)
				)
			)
		)
		(property "Device Type" "R402H16"
			(at 0.064008 -5.517896 90)
			(unlocked yes)
			(layer "F.Fab")
			(hide yes)
			(effects
				(font
					(size 1.016 1.016)
					(thickness 0.1524)
				)
			)
		)
		(duplicate_pad_numbers_are_jumpers no)
		(fp_line
			(start 0.508 -0.9398)
			(end -0.508 -0.9398)
			(stroke
				(width 0.1524)
				(type default)
			)
			(layer "F.SilkS")
		)
		(fp_line
			(start -0.508 -0.9398)
			(end -0.508 0.9398)
			(stroke
				(width 0.1524)
				(type default)
			)
			(layer "F.SilkS")
		)
		(fp_rect
			(start -0.508 0.9398)
			(end 0.508 -0.9398)
			(stroke
				(width 0)
				(type default)
			)
			(fill no)
			(layer "F.CrtYd")
		)
		(fp_rect
			(start -0.508 0.9398)
			(end 0.508 -0.9398)
			(stroke
				(width 0)
				(type default)
			)
			(fill no)
			(layer "F.Fab")
		)
		(pad "1" smd custom
			(at 0 -0.4445 90)
			(size 0.1397 0.1397)
			(layers "F.Cu" "F.Mask" "F.Paste")
			(net "P12V")
			(options
				(clearance outline)
				(anchor circle)
			)
			(primitives
				(gr_poly
					(pts
						(arc
							(start -0.1778 -0.2794)
							(mid -0.249642 -0.249642)
							(end -0.2794 -0.1778)
						)
						(arc
							(start -0.2794 0.1778)
							(mid -0.249642 0.249642)
							(end -0.1778 0.2794)
						)
						(arc
							(start 0.1778 0.2794)
							(mid 0.249642 0.249642)
							(end 0.2794 0.1778)
						)
						(arc
							(start 0.2794 -0.1778)
							(mid 0.249642 -0.249642)
							(end 0.1778 -0.2794)
						)
					)
					(width 0)
					(fill yes)
				)
			)
		)
		(pad "2" smd custom
			(at 0 0.4445 90)
			(size 0.1397 0.1397)
			(layers "F.Cu" "F.Mask" "F.Paste")
			(net "P1V8_EN_LV")
			(options
				(clearance outline)
				(anchor circle)
			)
			(primitives
				(gr_poly
					(pts
						(arc
							(start -0.1778 -0.2794)
							(mid -0.249642 -0.249642)
							(end -0.2794 -0.1778)
						)
						(arc
							(start -0.2794 0.1778)
							(mid -0.249642 0.249642)
							(end -0.1778 0.2794)
						)
						(arc
							(start 0.1778 0.2794)
							(mid 0.249642 0.249642)
							(end 0.2794 0.1778)
						)
						(arc
							(start 0.2794 -0.1778)
							(mid 0.249642 -0.249642)
							(end 0.1778 -0.2794)
						)
					)
					(width 0)
					(fill yes)
				)
			)
		)
	)
	(footprint ""
		(layer "F.Cu")
		(at 133.36397 -98.806 180)
		(property "Reference" "SC1270"
			(at 0 0 180)
			(layer "F.SilkS")
			(hide yes)
			(effects
				(font
					(size 1.27 1.27)
				)
			)
		)
		(property "Value" "SCD01U10V1KX-GP"
			(at -2.8321 -1.7399 180)
			(unlocked yes)
			(layer "F.Fab")
			(hide yes)
			(effects
				(font
					(size 1.016 1.016)
					(thickness 0.1524)
				)
			)
		)
		(property "Device Type" "C0201H13"
			(at -2.8321 -3.2639 180)
			(unlocked yes)
			(layer "F.Fab")
			(hide yes)
			(effects
				(font
					(size 1.016 1.016)
					(thickness 0.1524)
				)
			)
		)
		(duplicate_pad_numbers_are_jumpers no)
		(fp_rect
			(start -0.2794 0.6477)
			(end 0.2794 -0.6477)
			(stroke
				(width 0)
				(type default)
			)
			(fill no)
			(layer "F.CrtYd")
		)
		(fp_rect
			(start -0.2794 0.6477)
			(end 0.2794 -0.6477)
			(stroke
				(width 0)
				(type default)
			)
			(fill no)
			(layer "F.Fab")
		)
		(pad "1" smd custom
			(at 0 -0.2794 180)
			(size 0.0762 0.0762)
			(layers "F.Cu" "F.Mask" "F.Paste")
			(net "3X24_SAS_TX22_P")
			(options
				(clearance outline)
				(anchor circle)
			)
			(primitives
				(gr_poly
					(pts
						(arc
							(start 0.1524 -0.127)
							(mid 0.137521 -0.162921)
							(end 0.1016 -0.1778)
						)
						(arc
							(start -0.1016 -0.1778)
							(mid -0.137521 -0.162921)
							(end -0.1524 -0.127)
						)
						(arc
							(start -0.1524 0.127)
							(mid -0.137521 0.162921)
							(end -0.1016 0.1778)
						)
						(arc
							(start 0.1016 0.1778)
							(mid 0.137521 0.162921)
							(end 0.1524 0.127)
						)
					)
					(width 0)
					(fill yes)
				)
			)
		)
		(pad "2" smd custom
			(at 0 0.2794 180)
			(size 0.0762 0.0762)
			(layers "F.Cu" "F.Mask" "F.Paste")
			(net "SAS_EXP_GF_TX_DP2")
			(options
				(clearance outline)
				(anchor circle)
			)
			(primitives
				(gr_poly
					(pts
						(arc
							(start 0.1524 -0.127)
							(mid 0.137521 -0.162921)
							(end 0.1016 -0.1778)
						)
						(arc
							(start -0.1016 -0.1778)
							(mid -0.137521 -0.162921)
							(end -0.1524 -0.127)
						)
						(arc
							(start -0.1524 0.127)
							(mid -0.137521 0.162921)
							(end -0.1016 0.1778)
						)
						(arc
							(start 0.1016 0.1778)
							(mid 0.137521 0.162921)
							(end 0.1524 0.127)
						)
					)
					(width 0)
					(fill yes)
				)
			)
		)
	)
	(footprint ""
		(layer "F.Cu")
		(at 49.53 -224.917 180)
		(property "Reference" "R2108"
			(at 0 0 180)
			(layer "F.SilkS")
			(hide yes)
			(effects
				(font
					(size 1.27 1.27)
				)
			)
		)
		(property "Value" "3K74R2F-GP"
			(at 0.064008 -3.993896 180)
			(unlocked yes)
			(layer "F.Fab")
			(hide yes)
			(effects
				(font
					(size 1.016 1.016)
					(thickness 0.1524)
				)
			)
		)
		(property "Device Type" "R402H16"
			(at 0.064008 -5.517896 180)
			(unlocked yes)
			(layer "F.Fab")
			(hide yes)
			(effects
				(font
					(size 1.016 1.016)
					(thickness 0.1524)
				)
			)
		)
		(duplicate_pad_numbers_are_jumpers no)
		(fp_line
			(start 0.508 -0.9398)
			(end -0.508 -0.9398)
			(stroke
				(width 0.1524)
				(type default)
			)
			(layer "F.SilkS")
		)
		(fp_line
			(start -0.508 -0.9398)
			(end -0.508 0.9398)
			(stroke
				(width 0.1524)
				(type default)
			)
			(layer "F.SilkS")
		)
		(fp_rect
			(start -0.508 0.9398)
			(end 0.508 -0.9398)
			(stroke
				(width 0)
				(type default)
			)
			(fill no)
			(layer "F.CrtYd")
		)
		(fp_rect
			(start -0.508 0.9398)
			(end 0.508 -0.9398)
			(stroke
				(width 0)
				(type default)
			)
			(fill no)
			(layer "F.Fab")
		)
		(pad "1" smd custom
			(at 0 -0.4445 180)
			(size 0.1397 0.1397)
			(layers "F.Cu" "F.Mask" "F.Paste")
			(net "MB0_CM_OV_R")
			(options
				(clearance outline)
				(anchor circle)
			)
			(primitives
				(gr_poly
					(pts
						(arc
							(start -0.1778 -0.2794)
							(mid -0.249642 -0.249642)
							(end -0.2794 -0.1778)
						)
						(arc
							(start -0.2794 0.1778)
							(mid -0.249642 0.249642)
							(end -0.1778 0.2794)
						)
						(arc
							(start 0.1778 0.2794)
							(mid 0.249642 0.249642)
							(end 0.2794 0.1778)
						)
						(arc
							(start 0.2794 -0.1778)
							(mid 0.249642 -0.249642)
							(end 0.1778 -0.2794)
						)
					)
					(width 0)
					(fill yes)
				)
			)
		)
		(pad "2" smd custom
			(at 0 0.4445 180)
			(size 0.1397 0.1397)
			(layers "F.Cu" "F.Mask" "F.Paste")
			(net "AGND_CURRENT_MON")
			(options
				(clearance outline)
				(anchor circle)
			)
			(primitives
				(gr_poly
					(pts
						(arc
							(start -0.1778 -0.2794)
							(mid -0.249642 -0.249642)
							(end -0.2794 -0.1778)
						)
						(arc
							(start -0.2794 0.1778)
							(mid -0.249642 0.249642)
							(end -0.1778 0.2794)
						)
						(arc
							(start 0.1778 0.2794)
							(mid 0.249642 0.249642)
							(end 0.2794 0.1778)
						)
						(arc
							(start 0.2794 -0.1778)
							(mid 0.249642 -0.249642)
							(end 0.1778 -0.2794)
						)
					)
					(width 0)
					(fill yes)
				)
			)
		)
	)
	(footprint ""
		(layer "F.Cu")
		(at 172.47997 -67.183 180)
		(property "Reference" "C294"
			(at 0 0 180)
			(layer "F.SilkS")
			(hide yes)
			(effects
				(font
					(size 1.27 1.27)
				)
			)
		)
		(property "Value" "SCD1U25V2KX-2-GP"
			(at 1.1811 -2.7051 180)
			(unlocked yes)
			(layer "F.Fab")
			(hide yes)
			(effects
				(font
					(size 1.016 1.016)
					(thickness 0.1524)
				)
			)
		)
		(property "Device Type" "C402H22"
			(at 1.1811 -4.2291 180)
			(unlocked yes)
			(layer "F.Fab")
			(hide yes)
			(effects
				(font
					(size 1.016 1.016)
					(thickness 0.1524)
				)
			)
		)
		(duplicate_pad_numbers_are_jumpers no)
		(fp_rect
			(start -0.4318 0.9525)
			(end 0.4318 -0.9525)
			(stroke
				(width 0)
				(type default)
			)
			(fill no)
			(layer "F.CrtYd")
		)
		(fp_rect
			(start -0.4318 0.9525)
			(end 0.4318 -0.9525)
			(stroke
				(width 0)
				(type default)
			)
			(fill no)
			(layer "F.Fab")
		)
		(pad "1" smd custom
			(at 0 -0.4445 180)
			(size 0.1524 0.1524)
			(layers "F.Cu" "F.Mask" "F.Paste")
			(net "GND")
			(options
				(clearance outline)
				(anchor circle)
			)
			(primitives
				(gr_poly
					(pts
						(arc
							(start 0.3048 -0.2032)
							(mid 0.275042 -0.275042)
							(end 0.2032 -0.3048)
						)
						(arc
							(start -0.2032 -0.3048)
							(mid -0.275042 -0.275042)
							(end -0.3048 -0.2032)
						)
						(arc
							(start -0.3048 0.2032)
							(mid -0.275042 0.275042)
							(end -0.2032 0.3048)
						)
						(arc
							(start 0.2032 0.3048)
							(mid 0.275042 0.275042)
							(end 0.3048 0.2032)
						)
					)
					(width 0)
					(fill yes)
				)
			)
		)
		(pad "2" smd custom
			(at 0 0.4445 180)
			(size 0.1524 0.1524)
			(layers "F.Cu" "F.Mask" "F.Paste")
			(net "TP_MSB_B47_CPU_GBE_TX_P")
			(options
				(clearance outline)
				(anchor circle)
			)
			(primitives
				(gr_poly
					(pts
						(arc
							(start 0.3048 -0.2032)
							(mid 0.275042 -0.275042)
							(end 0.2032 -0.3048)
						)
						(arc
							(start -0.2032 -0.3048)
							(mid -0.275042 -0.275042)
							(end -0.3048 -0.2032)
						)
						(arc
							(start -0.3048 0.2032)
							(mid -0.275042 0.275042)
							(end -0.2032 0.3048)
						)
						(arc
							(start 0.2032 0.3048)
							(mid 0.275042 0.275042)
							(end 0.3048 0.2032)
						)
					)
					(width 0)
					(fill yes)
				)
			)
		)
	)
	(footprint ""
		(layer "F.Cu")
		(at 326.009 -143.383 90)
		(property "Reference" "C307"
			(at 0 0 90)
			(layer "F.SilkS")
			(hide yes)
			(effects
				(font
					(size 1.27 1.27)
				)
			)
		)
		(property "Value" "SC15P50V2JN-2-GP"
			(at 1.1811 -2.7051 90)
			(unlocked yes)
			(layer "F.Fab")
			(hide yes)
			(effects
				(font
					(size 1.016 1.016)
					(thickness 0.1524)
				)
			)
		)
		(property "Device Type" "C402H22"
			(at 1.1811 -4.2291 90)
			(unlocked yes)
			(layer "F.Fab")
			(hide yes)
			(effects
				(font
					(size 1.016 1.016)
					(thickness 0.1524)
				)
			)
		)
		(duplicate_pad_numbers_are_jumpers no)
		(fp_rect
			(start -0.4318 0.9525)
			(end 0.4318 -0.9525)
			(stroke
				(width 0)
				(type default)
			)
			(fill no)
			(layer "F.CrtYd")
		)
		(fp_rect
			(start -0.4318 0.9525)
			(end 0.4318 -0.9525)
			(stroke
				(width 0)
				(type default)
			)
			(fill no)
			(layer "F.Fab")
		)
		(pad "1" smd custom
			(at 0 -0.4445 90)
			(size 0.1524 0.1524)
			(layers "F.Cu" "F.Mask" "F.Paste")
			(net "RTC_OSCO")
			(options
				(clearance outline)
				(anchor circle)
			)
			(primitives
				(gr_poly
					(pts
						(arc
							(start 0.3048 -0.2032)
							(mid 0.275042 -0.275042)
							(end 0.2032 -0.3048)
						)
						(arc
							(start -0.2032 -0.3048)
							(mid -0.275042 -0.275042)
							(end -0.3048 -0.2032)
						)
						(arc
							(start -0.3048 0.2032)
							(mid -0.275042 0.275042)
							(end -0.2032 0.3048)
						)
						(arc
							(start 0.2032 0.3048)
							(mid 0.275042 0.275042)
							(end 0.3048 0.2032)
						)
					)
					(width 0)
					(fill yes)
				)
			)
		)
		(pad "2" smd custom
			(at 0 0.4445 90)
			(size 0.1524 0.1524)
			(layers "F.Cu" "F.Mask" "F.Paste")
			(net "GND")
			(options
				(clearance outline)
				(anchor circle)
			)
			(primitives
				(gr_poly
					(pts
						(arc
							(start 0.3048 -0.2032)
							(mid 0.275042 -0.275042)
							(end 0.2032 -0.3048)
						)
						(arc
							(start -0.2032 -0.3048)
							(mid -0.275042 -0.275042)
							(end -0.3048 -0.2032)
						)
						(arc
							(start -0.3048 0.2032)
							(mid -0.275042 0.275042)
							(end -0.2032 0.3048)
						)
						(arc
							(start 0.2032 0.3048)
							(mid 0.275042 0.275042)
							(end 0.3048 0.2032)
						)
					)
					(width 0)
					(fill yes)
				)
			)
		)
	)
	(footprint ""
		(layer "F.Cu")
		(at 266.7 -170.053)
		(property "Reference" "TP87"
			(at 0 0 0)
			(layer "F.SilkS")
			(hide yes)
			(effects
				(font
					(size 1.27 1.27)
				)
			)
		)
		(property "Value" "TPAD28"
			(at 0.0127 -1.8034 0)
			(unlocked yes)
			(layer "F.Fab")
			(hide yes)
			(effects
				(font
					(size 1.016 1.016)
					(thickness 0.1524)
				)
			)
		)
		(property "Device Type" "TPAD28"
			(at 0.0127 -3.3274 0)
			(unlocked yes)
			(layer "F.Fab")
			(hide yes)
			(effects
				(font
					(size 1.016 1.016)
					(thickness 0.1524)
				)
			)
		)
		(duplicate_pad_numbers_are_jumpers no)
		(fp_poly
			(pts
				(arc
					(start 0.3556 0)
					(mid -0.3556 0)
					(end 0.3556 0)
				)
			)
			(stroke
				(width 0)
				(type default)
			)
			(fill no)
			(layer "F.CrtYd")
		)
		(fp_poly
			(pts
				(arc
					(start 0.6096 0)
					(mid -0.6096 0)
					(end 0.6096 0)
				)
			)
			(stroke
				(width 0)
				(type default)
			)
			(fill no)
			(layer "F.Fab")
		)
		(pad "1" smd circle
			(at 0 0)
			(size 0.7112 0.7112)
			(layers "F.Cu" "F.Mask" "F.Paste")
			(net "BMC_MBC_I2C_E_SDA")
		)
	)
	(footprint ""
		(layer "F.Cu")
		(at 208.153 -216.789 90)
		(property "Reference" "R443"
			(at 0 0 90)
			(layer "F.SilkS")
			(hide yes)
			(effects
				(font
					(size 1.27 1.27)
				)
			)
		)
		(property "Value" "10KR2F-2-GP"
			(at 0.064008 -3.993896 90)
			(unlocked yes)
			(layer "F.Fab")
			(hide yes)
			(effects
				(font
					(size 1.016 1.016)
					(thickness 0.1524)
				)
			)
		)
		(property "Device Type" "R402H16"
			(at 0.064008 -5.517896 90)
			(unlocked yes)
			(layer "F.Fab")
			(hide yes)
			(effects
				(font
					(size 1.016 1.016)
					(thickness 0.1524)
				)
			)
		)
		(duplicate_pad_numbers_are_jumpers no)
		(fp_line
			(start 0.508 -0.9398)
			(end -0.508 -0.9398)
			(stroke
				(width 0.1524)
				(type default)
			)
			(layer "F.SilkS")
		)
		(fp_line
			(start -0.508 -0.9398)
			(end -0.508 0.9398)
			(stroke
				(width 0.1524)
				(type default)
			)
			(layer "F.SilkS")
		)
		(fp_rect
			(start -0.508 0.9398)
			(end 0.508 -0.9398)
			(stroke
				(width 0)
				(type default)
			)
			(fill no)
			(layer "F.CrtYd")
		)
		(fp_rect
			(start -0.508 0.9398)
			(end 0.508 -0.9398)
			(stroke
				(width 0)
				(type default)
			)
			(fill no)
			(layer "F.Fab")
		)
		(pad "1" smd custom
			(at 0 -0.4445 90)
			(size 0.1397 0.1397)
			(layers "F.Cu" "F.Mask" "F.Paste")
			(net "P3V3_STBY")
			(options
				(clearance outline)
				(anchor circle)
			)
			(primitives
				(gr_poly
					(pts
						(arc
							(start -0.1778 -0.2794)
							(mid -0.249642 -0.249642)
							(end -0.2794 -0.1778)
						)
						(arc
							(start -0.2794 0.1778)
							(mid -0.249642 0.249642)
							(end -0.1778 0.2794)
						)
						(arc
							(start 0.1778 0.2794)
							(mid 0.249642 0.249642)
							(end 0.2794 0.1778)
						)
						(arc
							(start 0.2794 -0.1778)
							(mid 0.249642 -0.249642)
							(end 0.1778 -0.2794)
						)
					)
					(width 0)
					(fill yes)
				)
			)
		)
		(pad "2" smd custom
			(at 0 0.4445 90)
			(size 0.1397 0.1397)
			(layers "F.Cu" "F.Mask" "F.Paste")
			(net "DP_BMC_CPU_RST_N")
			(options
				(clearance outline)
				(anchor circle)
			)
			(primitives
				(gr_poly
					(pts
						(arc
							(start -0.1778 -0.2794)
							(mid -0.249642 -0.249642)
							(end -0.2794 -0.1778)
						)
						(arc
							(start -0.2794 0.1778)
							(mid -0.249642 0.249642)
							(end -0.1778 0.2794)
						)
						(arc
							(start 0.1778 0.2794)
							(mid 0.249642 0.249642)
							(end 0.2794 0.1778)
						)
						(arc
							(start 0.2794 -0.1778)
							(mid 0.249642 -0.249642)
							(end 0.1778 -0.2794)
						)
					)
					(width 0)
					(fill yes)
				)
			)
		)
	)
	(footprint ""
		(layer "F.Cu")
		(at 36.449 -178.943 180)
		(property "Reference" "SR1276"
			(at 0 0 180)
			(layer "F.SilkS")
			(hide yes)
			(effects
				(font
					(size 1.27 1.27)
				)
			)
		)
		(property "Value" "1KR2J-1-GP"
			(at 0.064008 -3.993896 180)
			(unlocked yes)
			(layer "F.Fab")
			(hide yes)
			(effects
				(font
					(size 1.016 1.016)
					(thickness 0.1524)
				)
			)
		)
		(property "Device Type" "R402H16"
			(at 0.064008 -5.517896 180)
			(unlocked yes)
			(layer "F.Fab")
			(hide yes)
			(effects
				(font
					(size 1.016 1.016)
					(thickness 0.1524)
				)
			)
		)
		(duplicate_pad_numbers_are_jumpers no)
		(fp_line
			(start 0.508 -0.9398)
			(end -0.508 -0.9398)
			(stroke
				(width 0.1524)
				(type default)
			)
			(layer "F.SilkS")
		)
		(fp_line
			(start -0.508 -0.9398)
			(end -0.508 0.9398)
			(stroke
				(width 0.1524)
				(type default)
			)
			(layer "F.SilkS")
		)
		(fp_rect
			(start -0.508 0.9398)
			(end 0.508 -0.9398)
			(stroke
				(width 0)
				(type default)
			)
			(fill no)
			(layer "F.CrtYd")
		)
		(fp_rect
			(start -0.508 0.9398)
			(end 0.508 -0.9398)
			(stroke
				(width 0)
				(type default)
			)
			(fill no)
			(layer "F.Fab")
		)
		(pad "1" smd custom
			(at 0 -0.4445 180)
			(size 0.1397 0.1397)
			(layers "F.Cu" "F.Mask" "F.Paste")
			(net "DP_EXP_RST_R")
			(options
				(clearance outline)
				(anchor circle)
			)
			(primitives
				(gr_poly
					(pts
						(arc
							(start -0.1778 -0.2794)
							(mid -0.249642 -0.249642)
							(end -0.2794 -0.1778)
						)
						(arc
							(start -0.2794 0.1778)
							(mid -0.249642 0.249642)
							(end -0.1778 0.2794)
						)
						(arc
							(start 0.1778 0.2794)
							(mid 0.249642 0.249642)
							(end 0.2794 0.1778)
						)
						(arc
							(start 0.2794 -0.1778)
							(mid 0.249642 -0.249642)
							(end 0.1778 -0.2794)
						)
					)
					(width 0)
					(fill yes)
				)
			)
		)
		(pad "2" smd custom
			(at 0 0.4445 180)
			(size 0.1397 0.1397)
			(layers "F.Cu" "F.Mask" "F.Paste")
			(net "P1V8_E")
			(options
				(clearance outline)
				(anchor circle)
			)
			(primitives
				(gr_poly
					(pts
						(arc
							(start -0.1778 -0.2794)
							(mid -0.249642 -0.249642)
							(end -0.2794 -0.1778)
						)
						(arc
							(start -0.2794 0.1778)
							(mid -0.249642 0.249642)
							(end -0.1778 0.2794)
						)
						(arc
							(start 0.1778 0.2794)
							(mid 0.249642 0.249642)
							(end 0.2794 0.1778)
						)
						(arc
							(start 0.2794 -0.1778)
							(mid 0.249642 -0.249642)
							(end 0.1778 -0.2794)
						)
					)
					(width 0)
					(fill yes)
				)
			)
		)
	)
	(footprint ""
		(layer "F.Cu")
		(at 299.847 -211.201 180)
		(property "Reference" "PR78"
			(at 0 0 180)
			(layer "F.SilkS")
			(hide yes)
			(effects
				(font
					(size 1.27 1.27)
				)
			)
		)
		(property "Value" "0R6J-3-GP"
			(at -0.0508 -4.8514 180)
			(unlocked yes)
			(layer "F.Fab")
			(hide yes)
			(effects
				(font
					(size 1.016 1.016)
					(thickness 0.1524)
				)
			)
		)
		(property "Device Type" "R1206H28"
			(at 0 -6.3754 180)
			(unlocked yes)
			(layer "F.Fab")
			(hide yes)
			(effects
				(font
					(size 1.016 1.016)
					(thickness 0.1524)
				)
			)
		)
		(duplicate_pad_numbers_are_jumpers no)
		(fp_line
			(start 1.016 2.2352)
			(end -1.016 2.2352)
			(stroke
				(width 0.1524)
				(type default)
			)
			(layer "F.SilkS")
		)
		(fp_line
			(start 1.016 -2.2352)
			(end 1.016 2.2352)
			(stroke
				(width 0.1524)
				(type default)
			)
			(layer "F.SilkS")
		)
		(fp_line
			(start -1.016 2.2352)
			(end -1.016 -2.2352)
			(stroke
				(width 0.1524)
				(type default)
			)
			(layer "F.SilkS")
		)
		(fp_line
			(start -1.016 -2.2352)
			(end 1.016 -2.2352)
			(stroke
				(width 0.1524)
				(type default)
			)
			(layer "F.SilkS")
		)
		(fp_rect
			(start -1.0922 2.3114)
			(end 1.0922 -2.3114)
			(stroke
				(width 0)
				(type default)
			)
			(fill no)
			(layer "F.CrtYd")
		)
		(fp_poly
			(pts
				(xy -1.0922 -2.3114) (xy 1.0922 -2.3114) (xy 1.0922 2.3114) (xy -1.0922 2.3114)
			)
			(stroke
				(width 0)
				(type default)
			)
			(fill no)
			(layer "F.Fab")
		)
		(pad "1" smd rect
			(at 0 -1.397 180)
			(size 1.651 1.27)
			(layers "F.Cu" "F.Mask" "F.Paste")
			(net "P1V53_STBY")
		)
		(pad "2" smd rect
			(at 0 1.397 180)
			(size 1.651 1.27)
			(layers "F.Cu" "F.Mask" "F.Paste")
			(net "TPS74801_1V53_STBY_OUT")
		)
	)
	(footprint ""
		(layer "F.Cu")
		(at 189.865 -24.003 90)
		(property "Reference" "R375"
			(at 0 0 90)
			(layer "F.SilkS")
			(hide yes)
			(effects
				(font
					(size 1.27 1.27)
				)
			)
		)
		(property "Value" "33R2J-2-GP"
			(at 0.064008 -3.993896 90)
			(unlocked yes)
			(layer "F.Fab")
			(hide yes)
			(effects
				(font
					(size 1.016 1.016)
					(thickness 0.1524)
				)
			)
		)
		(property "Device Type" "R402H16"
			(at 0.064008 -5.517896 90)
			(unlocked yes)
			(layer "F.Fab")
			(hide yes)
			(effects
				(font
					(size 1.016 1.016)
					(thickness 0.1524)
				)
			)
		)
		(duplicate_pad_numbers_are_jumpers no)
		(fp_line
			(start 0.508 -0.9398)
			(end -0.508 -0.9398)
			(stroke
				(width 0.1524)
				(type default)
			)
			(layer "F.SilkS")
		)
		(fp_line
			(start -0.508 -0.9398)
			(end -0.508 0.9398)
			(stroke
				(width 0.1524)
				(type default)
			)
			(layer "F.SilkS")
		)
		(fp_rect
			(start -0.508 0.9398)
			(end 0.508 -0.9398)
			(stroke
				(width 0)
				(type default)
			)
			(fill no)
			(layer "F.CrtYd")
		)
		(fp_rect
			(start -0.508 0.9398)
			(end 0.508 -0.9398)
			(stroke
				(width 0)
				(type default)
			)
			(fill no)
			(layer "F.Fab")
		)
		(pad "1" smd custom
			(at 0 -0.4445 90)
			(size 0.1397 0.1397)
			(layers "F.Cu" "F.Mask" "F.Paste")
			(net "RMII_PHY_BMC_RXD1_R")
			(options
				(clearance outline)
				(anchor circle)
			)
			(primitives
				(gr_poly
					(pts
						(arc
							(start -0.1778 -0.2794)
							(mid -0.249642 -0.249642)
							(end -0.2794 -0.1778)
						)
						(arc
							(start -0.2794 0.1778)
							(mid -0.249642 0.249642)
							(end -0.1778 0.2794)
						)
						(arc
							(start 0.1778 0.2794)
							(mid 0.249642 0.249642)
							(end 0.2794 0.1778)
						)
						(arc
							(start 0.2794 -0.1778)
							(mid 0.249642 -0.249642)
							(end 0.1778 -0.2794)
						)
					)
					(width 0)
					(fill yes)
				)
			)
		)
		(pad "2" smd custom
			(at 0 0.4445 90)
			(size 0.1397 0.1397)
			(layers "F.Cu" "F.Mask" "F.Paste")
			(net "RMII_PHY_BMC_RXD1")
			(options
				(clearance outline)
				(anchor circle)
			)
			(primitives
				(gr_poly
					(pts
						(arc
							(start -0.1778 -0.2794)
							(mid -0.249642 -0.249642)
							(end -0.2794 -0.1778)
						)
						(arc
							(start -0.2794 0.1778)
							(mid -0.249642 0.249642)
							(end -0.1778 0.2794)
						)
						(arc
							(start 0.1778 0.2794)
							(mid 0.249642 0.249642)
							(end 0.2794 0.1778)
						)
						(arc
							(start 0.2794 -0.1778)
							(mid 0.249642 -0.249642)
							(end 0.1778 -0.2794)
						)
					)
					(width 0)
					(fill yes)
				)
			)
		)
	)
	(footprint ""
		(layer "F.Cu")
		(at 205.486 -86.614)
		(property "Reference" "SR827"
			(at 0 0 0)
			(layer "F.SilkS")
			(hide yes)
			(effects
				(font
					(size 1.27 1.27)
				)
			)
		)
		(property "Value" "D51R3F-2-GP"
			(at -0.0254 -2.5146 0)
			(unlocked yes)
			(layer "F.Fab")
			(hide yes)
			(effects
				(font
					(size 1.016 1.016)
					(thickness 0.1524)
				)
			)
		)
		(property "Device Type" "R603H22"
			(at -0.0254 -4.0386 0)
			(unlocked yes)
			(layer "F.Fab")
			(hide yes)
			(effects
				(font
					(size 1.016 1.016)
					(thickness 0.1524)
				)
			)
		)
		(duplicate_pad_numbers_are_jumpers no)
		(fp_line
			(start -0.4826 0)
			(end -0.2032 0)
			(stroke
				(width 0.2032)
				(type default)
			)
			(layer "F.SilkS")
		)
		(fp_line
			(start 0.2032 0)
			(end 0.4826 0)
			(stroke
				(width 0.2032)
				(type default)
			)
			(layer "F.SilkS")
		)
		(fp_rect
			(start -0.5842 1.3335)
			(end 0.5842 -1.3335)
			(stroke
				(width 0)
				(type default)
			)
			(fill no)
			(layer "F.CrtYd")
		)
		(fp_rect
			(start -0.5842 1.3335)
			(end 0.5842 -1.3335)
			(stroke
				(width 0)
				(type default)
			)
			(fill no)
			(layer "F.Fab")
		)
		(pad "1" smd custom
			(at 0 -0.762)
			(size 0.2159 0.2159)
			(layers "F.Cu" "F.Mask" "F.Paste")
			(net "P1V5_E")
			(options
				(clearance outline)
				(anchor circle)
			)
			(primitives
				(gr_poly
					(pts
						(arc
							(start -0.3302 -0.4318)
							(mid -0.402042 -0.402042)
							(end -0.4318 -0.3302)
						)
						(arc
							(start -0.4318 0.3302)
							(mid -0.402042 0.402042)
							(end -0.3302 0.4318)
						)
						(arc
							(start 0.3302 0.4318)
							(mid 0.402042 0.402042)
							(end 0.4318 0.3302)
						)
						(arc
							(start 0.4318 -0.3302)
							(mid 0.402042 -0.402042)
							(end 0.3302 -0.4318)
						)
					)
					(width 0)
					(fill yes)
				)
			)
		)
		(pad "2" smd custom
			(at 0 0.762)
			(size 0.2159 0.2159)
			(layers "F.Cu" "F.Mask" "F.Paste")
			(net "GB_VDDH2")
			(options
				(clearance outline)
				(anchor circle)
			)
			(primitives
				(gr_poly
					(pts
						(arc
							(start -0.3302 -0.4318)
							(mid -0.402042 -0.402042)
							(end -0.4318 -0.3302)
						)
						(arc
							(start -0.4318 0.3302)
							(mid -0.402042 0.402042)
							(end -0.3302 0.4318)
						)
						(arc
							(start 0.3302 0.4318)
							(mid 0.402042 0.402042)
							(end 0.4318 0.3302)
						)
						(arc
							(start 0.4318 -0.3302)
							(mid 0.402042 -0.402042)
							(end 0.3302 -0.4318)
						)
					)
					(width 0)
					(fill yes)
				)
			)
		)
	)
	(footprint ""
		(layer "F.Cu")
		(at 197.485 -164.846 -90)
		(property "Reference" "R579"
			(at 0 0 270)
			(layer "F.SilkS")
			(hide yes)
			(effects
				(font
					(size 1.27 1.27)
				)
			)
		)
		(property "Value" "0R2J-2-GP"
			(at 0.064008 -3.993896 270)
			(unlocked yes)
			(layer "F.Fab")
			(hide yes)
			(effects
				(font
					(size 1.016 1.016)
					(thickness 0.1524)
				)
			)
		)
		(property "Device Type" "R402H16"
			(at 0.064008 -5.517896 270)
			(unlocked yes)
			(layer "F.Fab")
			(hide yes)
			(effects
				(font
					(size 1.016 1.016)
					(thickness 0.1524)
				)
			)
		)
		(duplicate_pad_numbers_are_jumpers no)
		(fp_line
			(start -0.508 -0.9398)
			(end -0.508 0.9398)
			(stroke
				(width 0.1524)
				(type default)
			)
			(layer "F.SilkS")
		)
		(fp_line
			(start 0.508 -0.9398)
			(end -0.508 -0.9398)
			(stroke
				(width 0.1524)
				(type default)
			)
			(layer "F.SilkS")
		)
		(fp_rect
			(start -0.508 0.9398)
			(end 0.508 -0.9398)
			(stroke
				(width 0)
				(type default)
			)
			(fill no)
			(layer "F.CrtYd")
		)
		(fp_rect
			(start -0.508 0.9398)
			(end 0.508 -0.9398)
			(stroke
				(width 0)
				(type default)
			)
			(fill no)
			(layer "F.Fab")
		)
		(pad "1" smd custom
			(at 0 -0.4445 270)
			(size 0.1397 0.1397)
			(layers "F.Cu" "F.Mask" "F.Paste")
			(net "P3V3_PG")
			(options
				(clearance outline)
				(anchor circle)
			)
			(primitives
				(gr_poly
					(pts
						(arc
							(start -0.1778 -0.2794)
							(mid -0.249642 -0.249642)
							(end -0.2794 -0.1778)
						)
						(arc
							(start -0.2794 0.1778)
							(mid -0.249642 0.249642)
							(end -0.1778 0.2794)
						)
						(arc
							(start 0.1778 0.2794)
							(mid 0.249642 0.249642)
							(end 0.2794 0.1778)
						)
						(arc
							(start 0.2794 -0.1778)
							(mid 0.249642 -0.249642)
							(end 0.1778 -0.2794)
						)
					)
					(width 0)
					(fill yes)
				)
			)
		)
		(pad "2" smd custom
			(at 0 0.4445 270)
			(size 0.1397 0.1397)
			(layers "F.Cu" "F.Mask" "F.Paste")
			(net "P3V3_PG_R")
			(options
				(clearance outline)
				(anchor circle)
			)
			(primitives
				(gr_poly
					(pts
						(arc
							(start -0.1778 -0.2794)
							(mid -0.249642 -0.249642)
							(end -0.2794 -0.1778)
						)
						(arc
							(start -0.2794 0.1778)
							(mid -0.249642 0.249642)
							(end -0.1778 0.2794)
						)
						(arc
							(start 0.1778 0.2794)
							(mid 0.249642 0.249642)
							(end 0.2794 0.1778)
						)
						(arc
							(start 0.2794 -0.1778)
							(mid 0.249642 -0.249642)
							(end 0.1778 -0.2794)
						)
					)
					(width 0)
					(fill yes)
				)
			)
		)
	)
	(footprint ""
		(layer "F.Cu")
		(at 86.49716 -36.957 -90)
		(property "Reference" "SC883"
			(at 0 0 270)
			(layer "F.SilkS")
			(hide yes)
			(effects
				(font
					(size 1.27 1.27)
				)
			)
		)
		(property "Value" "SCD01U10V1KX-GP"
			(at -2.8321 -1.7399 270)
			(unlocked yes)
			(layer "F.Fab")
			(hide yes)
			(effects
				(font
					(size 1.016 1.016)
					(thickness 0.1524)
				)
			)
		)
		(property "Device Type" "C0201H13"
			(at -2.8321 -3.2639 270)
			(unlocked yes)
			(layer "F.Fab")
			(hide yes)
			(effects
				(font
					(size 1.016 1.016)
					(thickness 0.1524)
				)
			)
		)
		(duplicate_pad_numbers_are_jumpers no)
		(fp_rect
			(start -0.2794 0.6477)
			(end 0.2794 -0.6477)
			(stroke
				(width 0)
				(type default)
			)
			(fill no)
			(layer "F.CrtYd")
		)
		(fp_rect
			(start -0.2794 0.6477)
			(end 0.2794 -0.6477)
			(stroke
				(width 0)
				(type default)
			)
			(fill no)
			(layer "F.Fab")
		)
		(pad "1" smd custom
			(at 0 -0.2794 270)
			(size 0.0762 0.0762)
			(layers "F.Cu" "F.Mask" "F.Paste")
			(net "SAS3008_RAID_TX_C_P2")
			(options
				(clearance outline)
				(anchor circle)
			)
			(primitives
				(gr_poly
					(pts
						(arc
							(start 0.1524 -0.127)
							(mid 0.137521 -0.162921)
							(end 0.1016 -0.1778)
						)
						(arc
							(start -0.1016 -0.1778)
							(mid -0.137521 -0.162921)
							(end -0.1524 -0.127)
						)
						(arc
							(start -0.1524 0.127)
							(mid -0.137521 0.162921)
							(end -0.1016 0.1778)
						)
						(arc
							(start 0.1016 0.1778)
							(mid 0.137521 0.162921)
							(end 0.1524 0.127)
						)
					)
					(width 0)
					(fill yes)
				)
			)
		)
		(pad "2" smd custom
			(at 0 0.2794 270)
			(size 0.0762 0.0762)
			(layers "F.Cu" "F.Mask" "F.Paste")
			(net "SAS3008_RAID_TX_P2")
			(options
				(clearance outline)
				(anchor circle)
			)
			(primitives
				(gr_poly
					(pts
						(arc
							(start 0.1524 -0.127)
							(mid 0.137521 -0.162921)
							(end 0.1016 -0.1778)
						)
						(arc
							(start -0.1016 -0.1778)
							(mid -0.137521 -0.162921)
							(end -0.1524 -0.127)
						)
						(arc
							(start -0.1524 0.127)
							(mid -0.137521 0.162921)
							(end -0.1016 0.1778)
						)
						(arc
							(start 0.1016 0.1778)
							(mid 0.137521 0.162921)
							(end 0.1524 0.127)
						)
					)
					(width 0)
					(fill yes)
				)
			)
		)
	)
	(footprint ""
		(layer "F.Cu")
		(at 174.179992 -25.781)
		(property "Reference" "C235"
			(at 0 0 0)
			(layer "F.SilkS")
			(hide yes)
			(effects
				(font
					(size 1.27 1.27)
				)
			)
		)
		(property "Value" "SC27P50V2JN-2DLGP"
			(at 1.1811 -2.7051 0)
			(unlocked yes)
			(layer "F.Fab")
			(hide yes)
			(effects
				(font
					(size 1.016 1.016)
					(thickness 0.1524)
				)
			)
		)
		(property "Device Type" "C402H22"
			(at 1.1811 -4.2291 0)
			(unlocked yes)
			(layer "F.Fab")
			(hide yes)
			(effects
				(font
					(size 1.016 1.016)
					(thickness 0.1524)
				)
			)
		)
		(duplicate_pad_numbers_are_jumpers no)
		(fp_rect
			(start -0.4318 0.9525)
			(end 0.4318 -0.9525)
			(stroke
				(width 0)
				(type default)
			)
			(fill no)
			(layer "F.CrtYd")
		)
		(fp_rect
			(start -0.4318 0.9525)
			(end 0.4318 -0.9525)
			(stroke
				(width 0)
				(type default)
			)
			(fill no)
			(layer "F.Fab")
		)
		(pad "1" smd custom
			(at 0 -0.4445)
			(size 0.1524 0.1524)
			(layers "F.Cu" "F.Mask" "F.Paste")
			(net "BCM5221_TX_C_DN")
			(options
				(clearance outline)
				(anchor circle)
			)
			(primitives
				(gr_poly
					(pts
						(arc
							(start 0.3048 -0.2032)
							(mid 0.275042 -0.275042)
							(end 0.2032 -0.3048)
						)
						(arc
							(start -0.2032 -0.3048)
							(mid -0.275042 -0.275042)
							(end -0.3048 -0.2032)
						)
						(arc
							(start -0.3048 0.2032)
							(mid -0.275042 0.275042)
							(end -0.2032 0.3048)
						)
						(arc
							(start 0.2032 0.3048)
							(mid 0.275042 0.275042)
							(end 0.3048 0.2032)
						)
					)
					(width 0)
					(fill yes)
				)
			)
		)
		(pad "2" smd custom
			(at 0 0.4445)
			(size 0.1524 0.1524)
			(layers "F.Cu" "F.Mask" "F.Paste")
			(net "BCM5221_TX_C_DP")
			(options
				(clearance outline)
				(anchor circle)
			)
			(primitives
				(gr_poly
					(pts
						(arc
							(start 0.3048 -0.2032)
							(mid 0.275042 -0.275042)
							(end 0.2032 -0.3048)
						)
						(arc
							(start -0.2032 -0.3048)
							(mid -0.275042 -0.275042)
							(end -0.3048 -0.2032)
						)
						(arc
							(start -0.3048 0.2032)
							(mid -0.275042 0.275042)
							(end -0.2032 0.3048)
						)
						(arc
							(start 0.2032 0.3048)
							(mid 0.275042 0.275042)
							(end 0.3048 0.2032)
						)
					)
					(width 0)
					(fill yes)
				)
			)
		)
	)
	(footprint ""
		(layer "F.Cu")
		(at 336.169 -113.538)
		(property "Reference" "PR16"
			(at 0 0 0)
			(layer "F.SilkS")
			(hide yes)
			(effects
				(font
					(size 1.27 1.27)
				)
			)
		)
		(property "Value" "5K36R2F-GP"
			(at 0.064008 -3.993896 0)
			(unlocked yes)
			(layer "F.Fab")
			(hide yes)
			(effects
				(font
					(size 1.016 1.016)
					(thickness 0.1524)
				)
			)
		)
		(property "Device Type" "R402H16"
			(at 0.064008 -5.517896 0)
			(unlocked yes)
			(layer "F.Fab")
			(hide yes)
			(effects
				(font
					(size 1.016 1.016)
					(thickness 0.1524)
				)
			)
		)
		(duplicate_pad_numbers_are_jumpers no)
		(fp_line
			(start -0.508 -0.9398)
			(end -0.508 0.9398)
			(stroke
				(width 0.1524)
				(type default)
			)
			(layer "F.SilkS")
		)
		(fp_line
			(start 0.508 -0.9398)
			(end -0.508 -0.9398)
			(stroke
				(width 0.1524)
				(type default)
			)
			(layer "F.SilkS")
		)
		(fp_rect
			(start -0.508 0.9398)
			(end 0.508 -0.9398)
			(stroke
				(width 0)
				(type default)
			)
			(fill no)
			(layer "F.CrtYd")
		)
		(fp_rect
			(start -0.508 0.9398)
			(end 0.508 -0.9398)
			(stroke
				(width 0)
				(type default)
			)
			(fill no)
			(layer "F.Fab")
		)
		(pad "1" smd custom
			(at 0 -0.4445)
			(size 0.1397 0.1397)
			(layers "F.Cu" "F.Mask" "F.Paste")
			(net "P12V")
			(options
				(clearance outline)
				(anchor circle)
			)
			(primitives
				(gr_poly
					(pts
						(arc
							(start -0.1778 -0.2794)
							(mid -0.249642 -0.249642)
							(end -0.2794 -0.1778)
						)
						(arc
							(start -0.2794 0.1778)
							(mid -0.249642 0.249642)
							(end -0.1778 0.2794)
						)
						(arc
							(start 0.1778 0.2794)
							(mid 0.249642 0.249642)
							(end 0.2794 0.1778)
						)
						(arc
							(start 0.2794 -0.1778)
							(mid 0.249642 -0.249642)
							(end 0.1778 -0.2794)
						)
					)
					(width 0)
					(fill yes)
				)
			)
		)
		(pad "2" smd custom
			(at 0 0.4445)
			(size 0.1397 0.1397)
			(layers "F.Cu" "F.Mask" "F.Paste")
			(net "P5V_STBY_EN_R")
			(options
				(clearance outline)
				(anchor circle)
			)
			(primitives
				(gr_poly
					(pts
						(arc
							(start -0.1778 -0.2794)
							(mid -0.249642 -0.249642)
							(end -0.2794 -0.1778)
						)
						(arc
							(start -0.2794 0.1778)
							(mid -0.249642 0.249642)
							(end -0.1778 0.2794)
						)
						(arc
							(start 0.1778 0.2794)
							(mid 0.249642 0.249642)
							(end 0.2794 0.1778)
						)
						(arc
							(start 0.2794 -0.1778)
							(mid 0.249642 -0.249642)
							(end 0.1778 -0.2794)
						)
					)
					(width 0)
					(fill yes)
				)
			)
		)
	)
	(footprint ""
		(layer "F.Cu")
		(at 309.88 -205.105)
		(property "Reference" "R5301"
			(at 0 0 0)
			(layer "F.SilkS")
			(hide yes)
			(effects
				(font
					(size 1.27 1.27)
				)
			)
		)
		(property "Value" "0R2J-2-GP"
			(at 0.064008 -3.993896 0)
			(unlocked yes)
			(layer "F.Fab")
			(hide yes)
			(effects
				(font
					(size 1.016 1.016)
					(thickness 0.1524)
				)
			)
		)
		(property "Device Type" "R402H16"
			(at 0.064008 -5.517896 0)
			(unlocked yes)
			(layer "F.Fab")
			(hide yes)
			(effects
				(font
					(size 1.016 1.016)
					(thickness 0.1524)
				)
			)
		)
		(duplicate_pad_numbers_are_jumpers no)
		(fp_line
			(start -0.508 -0.9398)
			(end -0.508 0.9398)
			(stroke
				(width 0.1524)
				(type default)
			)
			(layer "F.SilkS")
		)
		(fp_line
			(start 0.508 -0.9398)
			(end -0.508 -0.9398)
			(stroke
				(width 0.1524)
				(type default)
			)
			(layer "F.SilkS")
		)
		(fp_rect
			(start -0.508 0.9398)
			(end 0.508 -0.9398)
			(stroke
				(width 0)
				(type default)
			)
			(fill no)
			(layer "F.CrtYd")
		)
		(fp_rect
			(start -0.508 0.9398)
			(end 0.508 -0.9398)
			(stroke
				(width 0)
				(type default)
			)
			(fill no)
			(layer "F.Fab")
		)
		(pad "1" smd custom
			(at 0 -0.4445)
			(size 0.1397 0.1397)
			(layers "F.Cu" "F.Mask" "F.Paste")
			(net "BMC_I2C_SCL_10")
			(options
				(clearance outline)
				(anchor circle)
			)
			(primitives
				(gr_poly
					(pts
						(arc
							(start -0.1778 -0.2794)
							(mid -0.249642 -0.249642)
							(end -0.2794 -0.1778)
						)
						(arc
							(start -0.2794 0.1778)
							(mid -0.249642 0.249642)
							(end -0.1778 0.2794)
						)
						(arc
							(start 0.1778 0.2794)
							(mid 0.249642 0.249642)
							(end 0.2794 0.1778)
						)
						(arc
							(start 0.2794 -0.1778)
							(mid 0.249642 -0.249642)
							(end 0.1778 -0.2794)
						)
					)
					(width 0)
					(fill yes)
				)
			)
		)
		(pad "2" smd custom
			(at 0 0.4445)
			(size 0.1397 0.1397)
			(layers "F.Cu" "F.Mask" "F.Paste")
			(net "LED_DR_I2C_SCL")
			(options
				(clearance outline)
				(anchor circle)
			)
			(primitives
				(gr_poly
					(pts
						(arc
							(start -0.1778 -0.2794)
							(mid -0.249642 -0.249642)
							(end -0.2794 -0.1778)
						)
						(arc
							(start -0.2794 0.1778)
							(mid -0.249642 0.249642)
							(end -0.1778 0.2794)
						)
						(arc
							(start 0.1778 0.2794)
							(mid 0.249642 0.249642)
							(end 0.2794 0.1778)
						)
						(arc
							(start 0.2794 -0.1778)
							(mid 0.249642 -0.249642)
							(end 0.1778 -0.2794)
						)
					)
					(width 0)
					(fill yes)
				)
			)
		)
	)
	(footprint ""
		(layer "F.Cu")
		(at 52.08397 -141.097 -90)
		(property "Reference" "SU79"
			(at 0 0 270)
			(layer "F.SilkS")
			(hide yes)
			(effects
				(font
					(size 1.27 1.27)
				)
			)
		)
		(property "Value" "SN74LVC1G08DCKR-GP"
			(at -2.3368 -8.6868 270)
			(unlocked yes)
			(layer "F.Fab")
			(hide yes)
			(effects
				(font
					(size 1.016 1.016)
					(thickness 0.1524)
				)
			)
		)
		(property "Device Type" "SC70-5H44"
			(at -2.3114 -10.414 270)
			(unlocked yes)
			(layer "F.Fab")
			(hide yes)
			(effects
				(font
					(size 1.016 1.016)
					(thickness 0.1524)
				)
			)
		)
		(duplicate_pad_numbers_are_jumpers no)
		(fp_line
			(start -1.27 1.7018)
			(end -1.27 -1.7018)
			(stroke
				(width 0.1524)
				(type default)
			)
			(layer "F.SilkS")
		)
		(fp_line
			(start 1.27 1.7018)
			(end -1.27 1.7018)
			(stroke
				(width 0.1524)
				(type default)
			)
			(layer "F.SilkS")
		)
		(fp_line
			(start -1.27 -1.7018)
			(end 1.27 -1.7018)
			(stroke
				(width 0.1524)
				(type default)
			)
			(layer "F.SilkS")
		)
		(fp_line
			(start 1.27 -1.7018)
			(end 1.27 1.7018)
			(stroke
				(width 0.1524)
				(type default)
			)
			(layer "F.SilkS")
		)
		(fp_line
			(start 0.6604 -1.8034)
			(end 1.3843 -1.8034)
			(stroke
				(width 0.3302)
				(type default)
			)
			(layer "F.SilkS")
		)
		(fp_line
			(start 1.3843 -1.8034)
			(end 1.3843 -1.1176)
			(stroke
				(width 0.3302)
				(type default)
			)
			(layer "F.SilkS")
		)
		(fp_rect
			(start -1.524 1.9558)
			(end 1.524 -1.9558)
			(stroke
				(width 0)
				(type default)
			)
			(fill no)
			(layer "F.CrtYd")
		)
		(fp_poly
			(pts
				(xy -1.524 -1.9558) (xy 1.524 -1.9558) (xy 1.524 1.9558) (xy -1.524 1.9558)
			)
			(stroke
				(width 0)
				(type default)
			)
			(fill no)
			(layer "F.Fab")
		)
		(pad "1" smd rect
			(at 0.65024 -0.8255 270)
			(size 0.4064 1.2192)
			(layers "F.Cu" "F.Mask" "F.Paste")
			(net "RST_BTN_N")
		)
		(pad "2" smd rect
			(at 0 -0.8255 270)
			(size 0.4064 1.2192)
			(layers "F.Cu" "F.Mask" "F.Paste")
			(net "DP_EXP_RST")
		)
		(pad "3" smd rect
			(at -0.65024 -0.8255 270)
			(size 0.4064 1.2192)
			(layers "F.Cu" "F.Mask" "F.Paste")
			(net "GND")
		)
		(pad "4" smd rect
			(at -0.65024 0.8255 270)
			(size 0.4064 1.2192)
			(layers "F.Cu" "F.Mask" "F.Paste")
			(net "EXP_RST_2")
		)
		(pad "5" smd rect
			(at 0.65024 0.8255 270)
			(size 0.4064 1.2192)
			(layers "F.Cu" "F.Mask" "F.Paste")
			(net "P1V8_E")
		)
	)
	(footprint ""
		(layer "F.Cu")
		(at 291.084 -161.544)
		(property "Reference" "R474"
			(at 0 0 0)
			(layer "F.SilkS")
			(hide yes)
			(effects
				(font
					(size 1.27 1.27)
				)
			)
		)
		(property "Value" "0R2J-2-GP"
			(at 0.064008 -3.993896 0)
			(unlocked yes)
			(layer "F.Fab")
			(hide yes)
			(effects
				(font
					(size 1.016 1.016)
					(thickness 0.1524)
				)
			)
		)
		(property "Device Type" "R402H16"
			(at 0.064008 -5.517896 0)
			(unlocked yes)
			(layer "F.Fab")
			(hide yes)
			(effects
				(font
					(size 1.016 1.016)
					(thickness 0.1524)
				)
			)
		)
		(duplicate_pad_numbers_are_jumpers no)
		(fp_line
			(start -0.508 -0.9398)
			(end -0.508 0.9398)
			(stroke
				(width 0.1524)
				(type default)
			)
			(layer "F.SilkS")
		)
		(fp_line
			(start 0.508 -0.9398)
			(end -0.508 -0.9398)
			(stroke
				(width 0.1524)
				(type default)
			)
			(layer "F.SilkS")
		)
		(fp_rect
			(start -0.508 0.9398)
			(end 0.508 -0.9398)
			(stroke
				(width 0)
				(type default)
			)
			(fill no)
			(layer "F.CrtYd")
		)
		(fp_rect
			(start -0.508 0.9398)
			(end 0.508 -0.9398)
			(stroke
				(width 0)
				(type default)
			)
			(fill no)
			(layer "F.Fab")
		)
		(pad "1" smd custom
			(at 0 -0.4445)
			(size 0.1397 0.1397)
			(layers "F.Cu" "F.Mask" "F.Paste")
			(net "BMC_RXD1")
			(options
				(clearance outline)
				(anchor circle)
			)
			(primitives
				(gr_poly
					(pts
						(arc
							(start -0.1778 -0.2794)
							(mid -0.249642 -0.249642)
							(end -0.2794 -0.1778)
						)
						(arc
							(start -0.2794 0.1778)
							(mid -0.249642 0.249642)
							(end -0.1778 0.2794)
						)
						(arc
							(start 0.1778 0.2794)
							(mid 0.249642 0.249642)
							(end 0.2794 0.1778)
						)
						(arc
							(start 0.2794 -0.1778)
							(mid 0.249642 -0.249642)
							(end 0.1778 -0.2794)
						)
					)
					(width 0)
					(fill yes)
				)
			)
		)
		(pad "2" smd custom
			(at 0 0.4445)
			(size 0.1397 0.1397)
			(layers "F.Cu" "F.Mask" "F.Paste")
			(net "CPU_BMC_UART_RX")
			(options
				(clearance outline)
				(anchor circle)
			)
			(primitives
				(gr_poly
					(pts
						(arc
							(start -0.1778 -0.2794)
							(mid -0.249642 -0.249642)
							(end -0.2794 -0.1778)
						)
						(arc
							(start -0.2794 0.1778)
							(mid -0.249642 0.249642)
							(end -0.1778 0.2794)
						)
						(arc
							(start 0.1778 0.2794)
							(mid 0.249642 0.249642)
							(end 0.2794 0.1778)
						)
						(arc
							(start 0.2794 -0.1778)
							(mid 0.249642 -0.249642)
							(end 0.1778 -0.2794)
						)
					)
					(width 0)
					(fill yes)
				)
			)
		)
	)
	(footprint ""
		(layer "F.Cu")
		(at 317.754 -120.523 180)
		(property "Reference" "PR25"
			(at 0 0 180)
			(layer "F.SilkS")
			(hide yes)
			(effects
				(font
					(size 1.27 1.27)
				)
			)
		)
		(property "Value" "10KR2F-2-GP"
			(at 0.064008 -3.993896 180)
			(unlocked yes)
			(layer "F.Fab")
			(hide yes)
			(effects
				(font
					(size 1.016 1.016)
					(thickness 0.1524)
				)
			)
		)
		(property "Device Type" "R402H16"
			(at 0.064008 -5.517896 180)
			(unlocked yes)
			(layer "F.Fab")
			(hide yes)
			(effects
				(font
					(size 1.016 1.016)
					(thickness 0.1524)
				)
			)
		)
		(duplicate_pad_numbers_are_jumpers no)
		(fp_line
			(start 0.508 -0.9398)
			(end -0.508 -0.9398)
			(stroke
				(width 0.1524)
				(type default)
			)
			(layer "F.SilkS")
		)
		(fp_line
			(start -0.508 -0.9398)
			(end -0.508 0.9398)
			(stroke
				(width 0.1524)
				(type default)
			)
			(layer "F.SilkS")
		)
		(fp_rect
			(start -0.508 0.9398)
			(end 0.508 -0.9398)
			(stroke
				(width 0)
				(type default)
			)
			(fill no)
			(layer "F.CrtYd")
		)
		(fp_rect
			(start -0.508 0.9398)
			(end 0.508 -0.9398)
			(stroke
				(width 0)
				(type default)
			)
			(fill no)
			(layer "F.Fab")
		)
		(pad "1" smd custom
			(at 0 -0.4445 180)
			(size 0.1397 0.1397)
			(layers "F.Cu" "F.Mask" "F.Paste")
			(net "P3V3_STBY_PG")
			(options
				(clearance outline)
				(anchor circle)
			)
			(primitives
				(gr_poly
					(pts
						(arc
							(start -0.1778 -0.2794)
							(mid -0.249642 -0.249642)
							(end -0.2794 -0.1778)
						)
						(arc
							(start -0.2794 0.1778)
							(mid -0.249642 0.249642)
							(end -0.1778 0.2794)
						)
						(arc
							(start 0.1778 0.2794)
							(mid 0.249642 0.249642)
							(end 0.2794 0.1778)
						)
						(arc
							(start 0.2794 -0.1778)
							(mid 0.249642 -0.249642)
							(end 0.1778 -0.2794)
						)
					)
					(width 0)
					(fill yes)
				)
			)
		)
		(pad "2" smd custom
			(at 0 0.4445 180)
			(size 0.1397 0.1397)
			(layers "F.Cu" "F.Mask" "F.Paste")
			(net "P3V3_STBY_VREG")
			(options
				(clearance outline)
				(anchor circle)
			)
			(primitives
				(gr_poly
					(pts
						(arc
							(start -0.1778 -0.2794)
							(mid -0.249642 -0.249642)
							(end -0.2794 -0.1778)
						)
						(arc
							(start -0.2794 0.1778)
							(mid -0.249642 0.249642)
							(end -0.1778 0.2794)
						)
						(arc
							(start 0.1778 0.2794)
							(mid 0.249642 0.249642)
							(end 0.2794 0.1778)
						)
						(arc
							(start 0.2794 -0.1778)
							(mid 0.249642 -0.249642)
							(end 0.1778 -0.2794)
						)
					)
					(width 0)
					(fill yes)
				)
			)
		)
	)
	(footprint ""
		(layer "F.Cu")
		(at 86.49716 -44.577 -90)
		(property "Reference" "SC901"
			(at 0 0 270)
			(layer "F.SilkS")
			(hide yes)
			(effects
				(font
					(size 1.27 1.27)
				)
			)
		)
		(property "Value" "SCD01U10V1KX-GP"
			(at -2.8321 -1.7399 270)
			(unlocked yes)
			(layer "F.Fab")
			(hide yes)
			(effects
				(font
					(size 1.016 1.016)
					(thickness 0.1524)
				)
			)
		)
		(property "Device Type" "C0201H13"
			(at -2.8321 -3.2639 270)
			(unlocked yes)
			(layer "F.Fab")
			(hide yes)
			(effects
				(font
					(size 1.016 1.016)
					(thickness 0.1524)
				)
			)
		)
		(duplicate_pad_numbers_are_jumpers no)
		(fp_rect
			(start -0.2794 0.6477)
			(end 0.2794 -0.6477)
			(stroke
				(width 0)
				(type default)
			)
			(fill no)
			(layer "F.CrtYd")
		)
		(fp_rect
			(start -0.2794 0.6477)
			(end 0.2794 -0.6477)
			(stroke
				(width 0)
				(type default)
			)
			(fill no)
			(layer "F.Fab")
		)
		(pad "1" smd custom
			(at 0 -0.2794 270)
			(size 0.0762 0.0762)
			(layers "F.Cu" "F.Mask" "F.Paste")
			(net "SAS3008_RAID_TX_C_N4")
			(options
				(clearance outline)
				(anchor circle)
			)
			(primitives
				(gr_poly
					(pts
						(arc
							(start 0.1524 -0.127)
							(mid 0.137521 -0.162921)
							(end 0.1016 -0.1778)
						)
						(arc
							(start -0.1016 -0.1778)
							(mid -0.137521 -0.162921)
							(end -0.1524 -0.127)
						)
						(arc
							(start -0.1524 0.127)
							(mid -0.137521 0.162921)
							(end -0.1016 0.1778)
						)
						(arc
							(start 0.1016 0.1778)
							(mid 0.137521 0.162921)
							(end 0.1524 0.127)
						)
					)
					(width 0)
					(fill yes)
				)
			)
		)
		(pad "2" smd custom
			(at 0 0.2794 270)
			(size 0.0762 0.0762)
			(layers "F.Cu" "F.Mask" "F.Paste")
			(net "IOC_RAID_TX_N4")
			(options
				(clearance outline)
				(anchor circle)
			)
			(primitives
				(gr_poly
					(pts
						(arc
							(start 0.1524 -0.127)
							(mid 0.137521 -0.162921)
							(end 0.1016 -0.1778)
						)
						(arc
							(start -0.1016 -0.1778)
							(mid -0.137521 -0.162921)
							(end -0.1524 -0.127)
						)
						(arc
							(start -0.1524 0.127)
							(mid -0.137521 0.162921)
							(end -0.1016 0.1778)
						)
						(arc
							(start 0.1016 0.1778)
							(mid 0.137521 0.162921)
							(end 0.1524 0.127)
						)
					)
					(width 0)
					(fill yes)
				)
			)
		)
	)
	(footprint ""
		(layer "F.Cu")
		(at 310.896 -188.087 90)
		(property "Reference" "R304"
			(at 0 0 90)
			(layer "F.SilkS")
			(hide yes)
			(effects
				(font
					(size 1.27 1.27)
				)
			)
		)
		(property "Value" "0R2J-2-GP"
			(at 0.064008 -3.993896 90)
			(unlocked yes)
			(layer "F.Fab")
			(hide yes)
			(effects
				(font
					(size 1.016 1.016)
					(thickness 0.1524)
				)
			)
		)
		(property "Device Type" "R402H16"
			(at 0.064008 -5.517896 90)
			(unlocked yes)
			(layer "F.Fab")
			(hide yes)
			(effects
				(font
					(size 1.016 1.016)
					(thickness 0.1524)
				)
			)
		)
		(duplicate_pad_numbers_are_jumpers no)
		(fp_line
			(start 0.508 -0.9398)
			(end -0.508 -0.9398)
			(stroke
				(width 0.1524)
				(type default)
			)
			(layer "F.SilkS")
		)
		(fp_line
			(start -0.508 -0.9398)
			(end -0.508 0.9398)
			(stroke
				(width 0.1524)
				(type default)
			)
			(layer "F.SilkS")
		)
		(fp_rect
			(start -0.508 0.9398)
			(end 0.508 -0.9398)
			(stroke
				(width 0)
				(type default)
			)
			(fill no)
			(layer "F.CrtYd")
		)
		(fp_rect
			(start -0.508 0.9398)
			(end 0.508 -0.9398)
			(stroke
				(width 0)
				(type default)
			)
			(fill no)
			(layer "F.Fab")
		)
		(pad "1" smd custom
			(at 0 -0.4445 90)
			(size 0.1397 0.1397)
			(layers "F.Cu" "F.Mask" "F.Paste")
			(net "HB0_R_IN2")
			(options
				(clearance outline)
				(anchor circle)
			)
			(primitives
				(gr_poly
					(pts
						(arc
							(start -0.1778 -0.2794)
							(mid -0.249642 -0.249642)
							(end -0.2794 -0.1778)
						)
						(arc
							(start -0.2794 0.1778)
							(mid -0.249642 0.249642)
							(end -0.1778 0.2794)
						)
						(arc
							(start 0.1778 0.2794)
							(mid 0.249642 0.249642)
							(end 0.2794 0.1778)
						)
						(arc
							(start 0.2794 -0.1778)
							(mid 0.249642 -0.249642)
							(end 0.1778 -0.2794)
						)
					)
					(width 0)
					(fill yes)
				)
			)
		)
		(pad "2" smd custom
			(at 0 0.4445 90)
			(size 0.1397 0.1397)
			(layers "F.Cu" "F.Mask" "F.Paste")
			(net "HB_B_SIDE_IN")
			(options
				(clearance outline)
				(anchor circle)
			)
			(primitives
				(gr_poly
					(pts
						(arc
							(start -0.1778 -0.2794)
							(mid -0.249642 -0.249642)
							(end -0.2794 -0.1778)
						)
						(arc
							(start -0.2794 0.1778)
							(mid -0.249642 0.249642)
							(end -0.1778 0.2794)
						)
						(arc
							(start 0.1778 0.2794)
							(mid 0.249642 0.249642)
							(end 0.2794 0.1778)
						)
						(arc
							(start 0.2794 -0.1778)
							(mid 0.249642 -0.249642)
							(end 0.1778 -0.2794)
						)
					)
					(width 0)
					(fill yes)
				)
			)
		)
	)
	(footprint ""
		(layer "F.Cu")
		(at 335.534 -4.318 90)
		(property "Reference" "LED15"
			(at 0 0 90)
			(layer "F.SilkS")
			(hide yes)
			(effects
				(font
					(size 1.27 1.27)
				)
			)
		)
		(property "Value" "LED-Y-11-GP"
			(at -0.1016 -8.1788 90)
			(unlocked yes)
			(layer "F.Fab")
			(hide yes)
			(effects
				(font
					(size 1.016 1.016)
					(thickness 0.1524)
				)
			)
		)
		(property "Device Type" "19-21UBC-1"
			(at -0.0508 -9.8552 90)
			(unlocked yes)
			(layer "F.Fab")
			(hide yes)
			(effects
				(font
					(size 1.016 1.016)
					(thickness 0.1524)
				)
			)
		)
		(duplicate_pad_numbers_are_jumpers no)
		(fp_line
			(start 1.4351 -0.7747)
			(end 1.4351 0.7747)
			(stroke
				(width 0.1524)
				(type default)
			)
			(layer "F.SilkS")
		)
		(fp_line
			(start -1.4351 -0.7747)
			(end 1.4351 -0.7747)
			(stroke
				(width 0.1524)
				(type default)
			)
			(layer "F.SilkS")
		)
		(fp_line
			(start -1.7653 -0.7747)
			(end -1.7653 0.7747)
			(stroke
				(width 0.508)
				(type default)
			)
			(layer "F.SilkS")
		)
		(fp_line
			(start 1.4351 0.7747)
			(end -1.4351 0.7747)
			(stroke
				(width 0.1524)
				(type default)
			)
			(layer "F.SilkS")
		)
		(fp_line
			(start -1.4351 0.7747)
			(end -1.4351 -0.7747)
			(stroke
				(width 0.1524)
				(type default)
			)
			(layer "F.SilkS")
		)
		(fp_rect
			(start -2.0193 1.0287)
			(end 1.6891 -1.0287)
			(stroke
				(width 0)
				(type default)
			)
			(fill no)
			(layer "F.CrtYd")
		)
		(fp_poly
			(pts
				(xy -2.0193 -1.0287) (xy -2.0193 1.0287) (xy 1.6891 1.0287) (xy 1.6891 -1.0287)
			)
			(stroke
				(width 0)
				(type default)
			)
			(fill no)
			(layer "F.Fab")
		)
		(pad "1" smd rect
			(at -0.7112 0 90)
			(size 0.9398 1.0668)
			(layers "F.Cu" "F.Mask" "F.Paste")
			(net "DEBUG CONSOLE_LED_1")
		)
		(pad "2" smd rect
			(at 0.7112 0 90)
			(size 0.9398 1.0668)
			(layers "F.Cu" "F.Mask" "F.Paste")
			(net "CONSOLE_LED_1")
		)
	)
	(footprint ""
		(layer "F.Cu")
		(at 221.860872 -178.634136)
		(property "Reference" "R498"
			(at 0 0 0)
			(layer "F.SilkS")
			(hide yes)
			(effects
				(font
					(size 1.27 1.27)
				)
			)
		)
		(property "Value" "0R2J-2-GP"
			(at 0.064008 -3.993896 0)
			(unlocked yes)
			(layer "F.Fab")
			(hide yes)
			(effects
				(font
					(size 1.016 1.016)
					(thickness 0.1524)
				)
			)
		)
		(property "Device Type" "R402H16"
			(at 0.064008 -5.517896 0)
			(unlocked yes)
			(layer "F.Fab")
			(hide yes)
			(effects
				(font
					(size 1.016 1.016)
					(thickness 0.1524)
				)
			)
		)
		(duplicate_pad_numbers_are_jumpers no)
		(fp_line
			(start -0.508 -0.9398)
			(end -0.508 0.9398)
			(stroke
				(width 0.1524)
				(type default)
			)
			(layer "F.SilkS")
		)
		(fp_line
			(start 0.508 -0.9398)
			(end -0.508 -0.9398)
			(stroke
				(width 0.1524)
				(type default)
			)
			(layer "F.SilkS")
		)
		(fp_rect
			(start -0.508 0.9398)
			(end 0.508 -0.9398)
			(stroke
				(width 0)
				(type default)
			)
			(fill no)
			(layer "F.CrtYd")
		)
		(fp_rect
			(start -0.508 0.9398)
			(end 0.508 -0.9398)
			(stroke
				(width 0)
				(type default)
			)
			(fill no)
			(layer "F.Fab")
		)
		(pad "1" smd custom
			(at 0 -0.4445)
			(size 0.1397 0.1397)
			(layers "F.Cu" "F.Mask" "F.Paste")
			(net "HB_A_OUT_EXP")
			(options
				(clearance outline)
				(anchor circle)
			)
			(primitives
				(gr_poly
					(pts
						(arc
							(start -0.1778 -0.2794)
							(mid -0.249642 -0.249642)
							(end -0.2794 -0.1778)
						)
						(arc
							(start -0.2794 0.1778)
							(mid -0.249642 0.249642)
							(end -0.1778 0.2794)
						)
						(arc
							(start 0.1778 0.2794)
							(mid 0.249642 0.249642)
							(end 0.2794 0.1778)
						)
						(arc
							(start 0.2794 -0.1778)
							(mid 0.249642 -0.249642)
							(end 0.1778 -0.2794)
						)
					)
					(width 0)
					(fill yes)
				)
			)
		)
		(pad "2" smd custom
			(at 0 0.4445)
			(size 0.1397 0.1397)
			(layers "F.Cu" "F.Mask" "F.Paste")
			(net "INVERTER_G1_EXP")
			(options
				(clearance outline)
				(anchor circle)
			)
			(primitives
				(gr_poly
					(pts
						(arc
							(start -0.1778 -0.2794)
							(mid -0.249642 -0.249642)
							(end -0.2794 -0.1778)
						)
						(arc
							(start -0.2794 0.1778)
							(mid -0.249642 0.249642)
							(end -0.1778 0.2794)
						)
						(arc
							(start 0.1778 0.2794)
							(mid 0.249642 0.249642)
							(end 0.2794 0.1778)
						)
						(arc
							(start 0.2794 -0.1778)
							(mid 0.249642 -0.249642)
							(end 0.1778 -0.2794)
						)
					)
					(width 0)
					(fill yes)
				)
			)
		)
	)
	(footprint ""
		(layer "F.Cu")
		(at 77.343 -20.701 90)
		(property "Reference" "PSP3"
			(at 0 0 90)
			(layer "F.SilkS")
			(hide yes)
			(effects
				(font
					(size 1.27 1.27)
				)
			)
		)
		(property "Value" "COPPER-CLOSE-GP-U"
			(at 0.0762 -2.8702 90)
			(unlocked yes)
			(layer "F.Fab")
			(hide yes)
			(effects
				(font
					(size 1.016 1.016)
					(thickness 0.1524)
				)
			)
		)
		(property "Device Type" "CON2C-U"
			(at 0.0762 -4.3942 90)
			(unlocked yes)
			(layer "F.Fab")
			(hide yes)
			(effects
				(font
					(size 1.016 1.016)
					(thickness 0.1524)
				)
			)
		)
		(duplicate_pad_numbers_are_jumpers no)
		(fp_rect
			(start -0.9398 0.9652)
			(end 0.9398 -0.9652)
			(stroke
				(width 0)
				(type default)
			)
			(fill no)
			(layer "F.CrtYd")
		)
		(fp_rect
			(start -0.9398 0.9652)
			(end 0.9398 -0.9652)
			(stroke
				(width 0)
				(type default)
			)
			(fill no)
			(layer "F.Fab")
		)
		(pad "1" smd custom
			(at 0 -0.5334 90)
			(size 0.17145 0.17145)
			(layers "F.Cu" "F.Mask" "F.Paste")
			(net "GND")
			(options
				(clearance outline)
				(anchor circle)
			)
			(primitives
				(gr_poly
					(pts
						(xy -0.127 0.3429) (xy -0.127 0.1651) (xy -0.635 -0.3429) (xy 0.635 -0.3429) (xy 0.127 0.1651)
						(xy 0.127 0.3429)
					)
					(width 0)
					(fill yes)
				)
			)
		)
		(pad "2" smd custom
			(at 0 0.5334 90)
			(size 0.17145 0.17145)
			(layers "F.Cu" "F.Mask" "F.Paste")
			(net "AGND_P0V9_C")
			(options
				(clearance outline)
				(anchor circle)
			)
			(primitives
				(gr_poly
					(pts
						(xy -0.635 0.3429) (xy -0.127 -0.1651) (xy -0.127 -0.3429) (xy 0.127 -0.3429) (xy 0.127 -0.1651)
						(xy 0.635 0.3429)
					)
					(width 0)
					(fill yes)
				)
			)
		)
	)
	(footprint ""
		(layer "F.Cu")
		(at 318.008 -177.673 -90)
		(property "Reference" "C190"
			(at 0 0 270)
			(layer "F.SilkS")
			(hide yes)
			(effects
				(font
					(size 1.27 1.27)
				)
			)
		)
		(property "Value" "SCD1U16V2KX-3GP"
			(at 1.1811 -2.7051 270)
			(unlocked yes)
			(layer "F.Fab")
			(hide yes)
			(effects
				(font
					(size 1.016 1.016)
					(thickness 0.1524)
				)
			)
		)
		(property "Device Type" "C402H22"
			(at 1.1811 -4.2291 270)
			(unlocked yes)
			(layer "F.Fab")
			(hide yes)
			(effects
				(font
					(size 1.016 1.016)
					(thickness 0.1524)
				)
			)
		)
		(duplicate_pad_numbers_are_jumpers no)
		(fp_rect
			(start -0.4318 0.9525)
			(end 0.4318 -0.9525)
			(stroke
				(width 0)
				(type default)
			)
			(fill no)
			(layer "F.CrtYd")
		)
		(fp_rect
			(start -0.4318 0.9525)
			(end 0.4318 -0.9525)
			(stroke
				(width 0)
				(type default)
			)
			(fill no)
			(layer "F.Fab")
		)
		(pad "1" smd custom
			(at 0 -0.4445 270)
			(size 0.1524 0.1524)
			(layers "F.Cu" "F.Mask" "F.Paste")
			(net "GND")
			(options
				(clearance outline)
				(anchor circle)
			)
			(primitives
				(gr_poly
					(pts
						(arc
							(start 0.3048 -0.2032)
							(mid 0.275042 -0.275042)
							(end 0.2032 -0.3048)
						)
						(arc
							(start -0.2032 -0.3048)
							(mid -0.275042 -0.275042)
							(end -0.3048 -0.2032)
						)
						(arc
							(start -0.3048 0.2032)
							(mid -0.275042 0.275042)
							(end -0.2032 0.3048)
						)
						(arc
							(start 0.2032 0.3048)
							(mid 0.275042 0.275042)
							(end 0.3048 0.2032)
						)
					)
					(width 0)
					(fill yes)
				)
			)
		)
		(pad "2" smd custom
			(at 0 0.4445 270)
			(size 0.1524 0.1524)
			(layers "F.Cu" "F.Mask" "F.Paste")
			(net "ADCVREFFN")
			(options
				(clearance outline)
				(anchor circle)
			)
			(primitives
				(gr_poly
					(pts
						(arc
							(start 0.3048 -0.2032)
							(mid 0.275042 -0.275042)
							(end 0.2032 -0.3048)
						)
						(arc
							(start -0.2032 -0.3048)
							(mid -0.275042 -0.275042)
							(end -0.3048 -0.2032)
						)
						(arc
							(start -0.3048 0.2032)
							(mid -0.275042 0.275042)
							(end -0.2032 0.3048)
						)
						(arc
							(start 0.2032 0.3048)
							(mid 0.275042 0.275042)
							(end 0.3048 0.2032)
						)
					)
					(width 0)
					(fill yes)
				)
			)
		)
	)
	(footprint ""
		(layer "F.Cu")
		(at 119.196612 -205.867 180)
		(property "Reference" "SR875"
			(at 0 0 180)
			(layer "F.SilkS")
			(hide yes)
			(effects
				(font
					(size 1.27 1.27)
				)
			)
		)
		(property "Value" "0R2J-2-GP"
			(at 0.064008 -3.993896 180)
			(unlocked yes)
			(layer "F.Fab")
			(hide yes)
			(effects
				(font
					(size 1.016 1.016)
					(thickness 0.1524)
				)
			)
		)
		(property "Device Type" "R402H16"
			(at 0.064008 -5.517896 180)
			(unlocked yes)
			(layer "F.Fab")
			(hide yes)
			(effects
				(font
					(size 1.016 1.016)
					(thickness 0.1524)
				)
			)
		)
		(duplicate_pad_numbers_are_jumpers no)
		(fp_line
			(start 0.508 -0.9398)
			(end -0.508 -0.9398)
			(stroke
				(width 0.1524)
				(type default)
			)
			(layer "F.SilkS")
		)
		(fp_line
			(start -0.508 -0.9398)
			(end -0.508 0.9398)
			(stroke
				(width 0.1524)
				(type default)
			)
			(layer "F.SilkS")
		)
		(fp_rect
			(start -0.508 0.9398)
			(end 0.508 -0.9398)
			(stroke
				(width 0)
				(type default)
			)
			(fill no)
			(layer "F.CrtYd")
		)
		(fp_rect
			(start -0.508 0.9398)
			(end 0.508 -0.9398)
			(stroke
				(width 0)
				(type default)
			)
			(fill no)
			(layer "F.Fab")
		)
		(pad "1" smd custom
			(at 0 -0.4445 180)
			(size 0.1397 0.1397)
			(layers "F.Cu" "F.Mask" "F.Paste")
			(net "SAS_HDD_REDV_TX7_N")
			(options
				(clearance outline)
				(anchor circle)
			)
			(primitives
				(gr_poly
					(pts
						(arc
							(start -0.1778 -0.2794)
							(mid -0.249642 -0.249642)
							(end -0.2794 -0.1778)
						)
						(arc
							(start -0.2794 0.1778)
							(mid -0.249642 0.249642)
							(end -0.1778 0.2794)
						)
						(arc
							(start 0.1778 0.2794)
							(mid 0.249642 0.249642)
							(end 0.2794 0.1778)
						)
						(arc
							(start 0.2794 -0.1778)
							(mid 0.249642 -0.249642)
							(end 0.1778 -0.2794)
						)
					)
					(width 0)
					(fill yes)
				)
			)
		)
		(pad "2" smd custom
			(at 0 0.4445 180)
			(size 0.1397 0.1397)
			(layers "F.Cu" "F.Mask" "F.Paste")
			(net "REDV_TX7_N")
			(options
				(clearance outline)
				(anchor circle)
			)
			(primitives
				(gr_poly
					(pts
						(arc
							(start -0.1778 -0.2794)
							(mid -0.249642 -0.249642)
							(end -0.2794 -0.1778)
						)
						(arc
							(start -0.2794 0.1778)
							(mid -0.249642 0.249642)
							(end -0.1778 0.2794)
						)
						(arc
							(start 0.1778 0.2794)
							(mid 0.249642 0.249642)
							(end 0.2794 0.1778)
						)
						(arc
							(start 0.2794 -0.1778)
							(mid 0.249642 -0.249642)
							(end 0.1778 -0.2794)
						)
					)
					(width 0)
					(fill yes)
				)
			)
		)
	)
	(footprint ""
		(layer "F.Cu")
		(at 332.096872 -232.482136)
		(property "Reference" "R179"
			(at 0 0 0)
			(layer "F.SilkS")
			(hide yes)
			(effects
				(font
					(size 1.27 1.27)
				)
			)
		)
		(property "Value" "0R2J-2-GP"
			(at 0.064008 -3.993896 0)
			(unlocked yes)
			(layer "F.Fab")
			(hide yes)
			(effects
				(font
					(size 1.016 1.016)
					(thickness 0.1524)
				)
			)
		)
		(property "Device Type" "R402H16"
			(at 0.064008 -5.517896 0)
			(unlocked yes)
			(layer "F.Fab")
			(hide yes)
			(effects
				(font
					(size 1.016 1.016)
					(thickness 0.1524)
				)
			)
		)
		(duplicate_pad_numbers_are_jumpers no)
		(fp_line
			(start -0.508 -0.9398)
			(end -0.508 0.9398)
			(stroke
				(width 0.1524)
				(type default)
			)
			(layer "F.SilkS")
		)
		(fp_line
			(start 0.508 -0.9398)
			(end -0.508 -0.9398)
			(stroke
				(width 0.1524)
				(type default)
			)
			(layer "F.SilkS")
		)
		(fp_rect
			(start -0.508 0.9398)
			(end 0.508 -0.9398)
			(stroke
				(width 0)
				(type default)
			)
			(fill no)
			(layer "F.CrtYd")
		)
		(fp_rect
			(start -0.508 0.9398)
			(end 0.508 -0.9398)
			(stroke
				(width 0)
				(type default)
			)
			(fill no)
			(layer "F.Fab")
		)
		(pad "1" smd custom
			(at 0 -0.4445)
			(size 0.1397 0.1397)
			(layers "F.Cu" "F.Mask" "F.Paste")
			(net "ADC_12V")
			(options
				(clearance outline)
				(anchor circle)
			)
			(primitives
				(gr_poly
					(pts
						(arc
							(start -0.1778 -0.2794)
							(mid -0.249642 -0.249642)
							(end -0.2794 -0.1778)
						)
						(arc
							(start -0.2794 0.1778)
							(mid -0.249642 0.249642)
							(end -0.1778 0.2794)
						)
						(arc
							(start 0.1778 0.2794)
							(mid 0.249642 0.249642)
							(end 0.2794 0.1778)
						)
						(arc
							(start 0.2794 -0.1778)
							(mid 0.249642 -0.249642)
							(end 0.1778 -0.2794)
						)
					)
					(width 0)
					(fill yes)
				)
			)
		)
		(pad "2" smd custom
			(at 0 0.4445)
			(size 0.1397 0.1397)
			(layers "F.Cu" "F.Mask" "F.Paste")
			(net "12V_SENSE")
			(options
				(clearance outline)
				(anchor circle)
			)
			(primitives
				(gr_poly
					(pts
						(arc
							(start -0.1778 -0.2794)
							(mid -0.249642 -0.249642)
							(end -0.2794 -0.1778)
						)
						(arc
							(start -0.2794 0.1778)
							(mid -0.249642 0.249642)
							(end -0.1778 0.2794)
						)
						(arc
							(start 0.1778 0.2794)
							(mid 0.249642 0.249642)
							(end 0.2794 0.1778)
						)
						(arc
							(start 0.2794 -0.1778)
							(mid 0.249642 -0.249642)
							(end 0.1778 -0.2794)
						)
					)
					(width 0)
					(fill yes)
				)
			)
		)
	)
	(footprint ""
		(layer "F.Cu")
		(at 300.482 -102.108 180)
		(property "Reference" "R590"
			(at 0 0 180)
			(layer "F.SilkS")
			(hide yes)
			(effects
				(font
					(size 1.27 1.27)
				)
			)
		)
		(property "Value" "4K7R2F-GP"
			(at 0.064008 -3.993896 180)
			(unlocked yes)
			(layer "F.Fab")
			(hide yes)
			(effects
				(font
					(size 1.016 1.016)
					(thickness 0.1524)
				)
			)
		)
		(property "Device Type" "R402H16"
			(at 0.064008 -5.517896 180)
			(unlocked yes)
			(layer "F.Fab")
			(hide yes)
			(effects
				(font
					(size 1.016 1.016)
					(thickness 0.1524)
				)
			)
		)
		(duplicate_pad_numbers_are_jumpers no)
		(fp_line
			(start 0.508 -0.9398)
			(end -0.508 -0.9398)
			(stroke
				(width 0.1524)
				(type default)
			)
			(layer "F.SilkS")
		)
		(fp_line
			(start -0.508 -0.9398)
			(end -0.508 0.9398)
			(stroke
				(width 0.1524)
				(type default)
			)
			(layer "F.SilkS")
		)
		(fp_rect
			(start -0.508 0.9398)
			(end 0.508 -0.9398)
			(stroke
				(width 0)
				(type default)
			)
			(fill no)
			(layer "F.CrtYd")
		)
		(fp_rect
			(start -0.508 0.9398)
			(end 0.508 -0.9398)
			(stroke
				(width 0)
				(type default)
			)
			(fill no)
			(layer "F.Fab")
		)
		(pad "1" smd custom
			(at 0 -0.4445 180)
			(size 0.1397 0.1397)
			(layers "F.Cu" "F.Mask" "F.Paste")
			(net "TEMP_2_A0")
			(options
				(clearance outline)
				(anchor circle)
			)
			(primitives
				(gr_poly
					(pts
						(arc
							(start -0.1778 -0.2794)
							(mid -0.249642 -0.249642)
							(end -0.2794 -0.1778)
						)
						(arc
							(start -0.2794 0.1778)
							(mid -0.249642 0.249642)
							(end -0.1778 0.2794)
						)
						(arc
							(start 0.1778 0.2794)
							(mid 0.249642 0.249642)
							(end 0.2794 0.1778)
						)
						(arc
							(start 0.2794 -0.1778)
							(mid 0.249642 -0.249642)
							(end 0.1778 -0.2794)
						)
					)
					(width 0)
					(fill yes)
				)
			)
		)
		(pad "2" smd custom
			(at 0 0.4445 180)
			(size 0.1397 0.1397)
			(layers "F.Cu" "F.Mask" "F.Paste")
			(net "GND")
			(options
				(clearance outline)
				(anchor circle)
			)
			(primitives
				(gr_poly
					(pts
						(arc
							(start -0.1778 -0.2794)
							(mid -0.249642 -0.249642)
							(end -0.2794 -0.1778)
						)
						(arc
							(start -0.2794 0.1778)
							(mid -0.249642 0.249642)
							(end -0.1778 0.2794)
						)
						(arc
							(start 0.1778 0.2794)
							(mid 0.249642 0.249642)
							(end 0.2794 0.1778)
						)
						(arc
							(start 0.2794 -0.1778)
							(mid 0.249642 -0.249642)
							(end 0.1778 -0.2794)
						)
					)
					(width 0)
					(fill yes)
				)
			)
		)
	)
	(footprint ""
		(layer "F.Cu")
		(at 95.377 -233.807)
		(property "Reference" "SR950"
			(at 0 0 0)
			(layer "F.SilkS")
			(hide yes)
			(effects
				(font
					(size 1.27 1.27)
				)
			)
		)
		(property "Value" "4K7R2F-GP"
			(at 0.064008 -3.993896 0)
			(unlocked yes)
			(layer "F.Fab")
			(hide yes)
			(effects
				(font
					(size 1.016 1.016)
					(thickness 0.1524)
				)
			)
		)
		(property "Device Type" "R402H16"
			(at 0.064008 -5.517896 0)
			(unlocked yes)
			(layer "F.Fab")
			(hide yes)
			(effects
				(font
					(size 1.016 1.016)
					(thickness 0.1524)
				)
			)
		)
		(duplicate_pad_numbers_are_jumpers no)
		(fp_line
			(start -0.508 -0.9398)
			(end -0.508 0.9398)
			(stroke
				(width 0.1524)
				(type default)
			)
			(layer "F.SilkS")
		)
		(fp_line
			(start 0.508 -0.9398)
			(end -0.508 -0.9398)
			(stroke
				(width 0.1524)
				(type default)
			)
			(layer "F.SilkS")
		)
		(fp_rect
			(start -0.508 0.9398)
			(end 0.508 -0.9398)
			(stroke
				(width 0)
				(type default)
			)
			(fill no)
			(layer "F.CrtYd")
		)
		(fp_rect
			(start -0.508 0.9398)
			(end 0.508 -0.9398)
			(stroke
				(width 0)
				(type default)
			)
			(fill no)
			(layer "F.Fab")
		)
		(pad "1" smd custom
			(at 0 -0.4445)
			(size 0.1397 0.1397)
			(layers "F.Cu" "F.Mask" "F.Paste")
			(net "SAS_FAULT_LED9")
			(options
				(clearance outline)
				(anchor circle)
			)
			(primitives
				(gr_poly
					(pts
						(arc
							(start -0.1778 -0.2794)
							(mid -0.249642 -0.249642)
							(end -0.2794 -0.1778)
						)
						(arc
							(start -0.2794 0.1778)
							(mid -0.249642 0.249642)
							(end -0.1778 0.2794)
						)
						(arc
							(start 0.1778 0.2794)
							(mid 0.249642 0.249642)
							(end 0.2794 0.1778)
						)
						(arc
							(start 0.2794 -0.1778)
							(mid 0.249642 -0.249642)
							(end 0.1778 -0.2794)
						)
					)
					(width 0)
					(fill yes)
				)
			)
		)
		(pad "2" smd custom
			(at 0 0.4445)
			(size 0.1397 0.1397)
			(layers "F.Cu" "F.Mask" "F.Paste")
			(net "P3V3_STBY")
			(options
				(clearance outline)
				(anchor circle)
			)
			(primitives
				(gr_poly
					(pts
						(arc
							(start -0.1778 -0.2794)
							(mid -0.249642 -0.249642)
							(end -0.2794 -0.1778)
						)
						(arc
							(start -0.2794 0.1778)
							(mid -0.249642 0.249642)
							(end -0.1778 0.2794)
						)
						(arc
							(start 0.1778 0.2794)
							(mid 0.249642 0.249642)
							(end 0.2794 0.1778)
						)
						(arc
							(start 0.2794 -0.1778)
							(mid 0.249642 -0.249642)
							(end 0.1778 -0.2794)
						)
					)
					(width 0)
					(fill yes)
				)
			)
		)
	)
	(footprint ""
		(layer "F.Cu")
		(at 177.854864 -38.172136 180)
		(property "Reference" "R395"
			(at 0 0 180)
			(layer "F.SilkS")
			(hide yes)
			(effects
				(font
					(size 1.27 1.27)
				)
			)
		)
		(property "Value" "150R2F-1-GP"
			(at 0.064008 -3.993896 180)
			(unlocked yes)
			(layer "F.Fab")
			(hide yes)
			(effects
				(font
					(size 1.016 1.016)
					(thickness 0.1524)
				)
			)
		)
		(property "Device Type" "R402H16"
			(at 0.064008 -5.517896 180)
			(unlocked yes)
			(layer "F.Fab")
			(hide yes)
			(effects
				(font
					(size 1.016 1.016)
					(thickness 0.1524)
				)
			)
		)
		(duplicate_pad_numbers_are_jumpers no)
		(fp_line
			(start 0.508 -0.9398)
			(end -0.508 -0.9398)
			(stroke
				(width 0.1524)
				(type default)
			)
			(layer "F.SilkS")
		)
		(fp_line
			(start -0.508 -0.9398)
			(end -0.508 0.9398)
			(stroke
				(width 0.1524)
				(type default)
			)
			(layer "F.SilkS")
		)
		(fp_rect
			(start -0.508 0.9398)
			(end 0.508 -0.9398)
			(stroke
				(width 0)
				(type default)
			)
			(fill no)
			(layer "F.CrtYd")
		)
		(fp_rect
			(start -0.508 0.9398)
			(end 0.508 -0.9398)
			(stroke
				(width 0)
				(type default)
			)
			(fill no)
			(layer "F.Fab")
		)
		(pad "1" smd custom
			(at 0 -0.4445 180)
			(size 0.1397 0.1397)
			(layers "F.Cu" "F.Mask" "F.Paste")
			(net "PHY_LOW_PWR")
			(options
				(clearance outline)
				(anchor circle)
			)
			(primitives
				(gr_poly
					(pts
						(arc
							(start -0.1778 -0.2794)
							(mid -0.249642 -0.249642)
							(end -0.2794 -0.1778)
						)
						(arc
							(start -0.2794 0.1778)
							(mid -0.249642 0.249642)
							(end -0.1778 0.2794)
						)
						(arc
							(start 0.1778 0.2794)
							(mid 0.249642 0.249642)
							(end 0.2794 0.1778)
						)
						(arc
							(start 0.2794 -0.1778)
							(mid 0.249642 -0.249642)
							(end 0.1778 -0.2794)
						)
					)
					(width 0)
					(fill yes)
				)
			)
		)
		(pad "2" smd custom
			(at 0 0.4445 180)
			(size 0.1397 0.1397)
			(layers "F.Cu" "F.Mask" "F.Paste")
			(net "GND")
			(options
				(clearance outline)
				(anchor circle)
			)
			(primitives
				(gr_poly
					(pts
						(arc
							(start -0.1778 -0.2794)
							(mid -0.249642 -0.249642)
							(end -0.2794 -0.1778)
						)
						(arc
							(start -0.2794 0.1778)
							(mid -0.249642 0.249642)
							(end -0.1778 0.2794)
						)
						(arc
							(start 0.1778 0.2794)
							(mid 0.249642 0.249642)
							(end 0.2794 0.1778)
						)
						(arc
							(start 0.2794 -0.1778)
							(mid 0.249642 -0.249642)
							(end 0.1778 -0.2794)
						)
					)
					(width 0)
					(fill yes)
				)
			)
		)
	)
	(footprint ""
		(layer "F.Cu")
		(at 184.531 -115.697 -90)
		(property "Reference" "R524"
			(at 0 0 270)
			(layer "F.SilkS")
			(hide yes)
			(effects
				(font
					(size 1.27 1.27)
				)
			)
		)
		(property "Value" "1KR2F-3-GP"
			(at 0.064008 -3.993896 270)
			(unlocked yes)
			(layer "F.Fab")
			(hide yes)
			(effects
				(font
					(size 1.016 1.016)
					(thickness 0.1524)
				)
			)
		)
		(property "Device Type" "R402H16"
			(at 0.064008 -5.517896 270)
			(unlocked yes)
			(layer "F.Fab")
			(hide yes)
			(effects
				(font
					(size 1.016 1.016)
					(thickness 0.1524)
				)
			)
		)
		(duplicate_pad_numbers_are_jumpers no)
		(fp_line
			(start -0.508 -0.9398)
			(end -0.508 0.9398)
			(stroke
				(width 0.1524)
				(type default)
			)
			(layer "F.SilkS")
		)
		(fp_line
			(start 0.508 -0.9398)
			(end -0.508 -0.9398)
			(stroke
				(width 0.1524)
				(type default)
			)
			(layer "F.SilkS")
		)
		(fp_rect
			(start -0.508 0.9398)
			(end 0.508 -0.9398)
			(stroke
				(width 0)
				(type default)
			)
			(fill no)
			(layer "F.CrtYd")
		)
		(fp_rect
			(start -0.508 0.9398)
			(end 0.508 -0.9398)
			(stroke
				(width 0)
				(type default)
			)
			(fill no)
			(layer "F.Fab")
		)
		(pad "1" smd custom
			(at 0 -0.4445 270)
			(size 0.1397 0.1397)
			(layers "F.Cu" "F.Mask" "F.Paste")
			(net "P3V3")
			(options
				(clearance outline)
				(anchor circle)
			)
			(primitives
				(gr_poly
					(pts
						(arc
							(start -0.1778 -0.2794)
							(mid -0.249642 -0.249642)
							(end -0.2794 -0.1778)
						)
						(arc
							(start -0.2794 0.1778)
							(mid -0.249642 0.249642)
							(end -0.1778 0.2794)
						)
						(arc
							(start 0.1778 0.2794)
							(mid 0.249642 0.249642)
							(end 0.2794 0.1778)
						)
						(arc
							(start 0.2794 -0.1778)
							(mid 0.249642 -0.249642)
							(end 0.1778 -0.2794)
						)
					)
					(width 0)
					(fill yes)
				)
			)
		)
		(pad "2" smd custom
			(at 0 0.4445 270)
			(size 0.1397 0.1397)
			(layers "F.Cu" "F.Mask" "F.Paste")
			(net "PMU_PLTRST_N")
			(options
				(clearance outline)
				(anchor circle)
			)
			(primitives
				(gr_poly
					(pts
						(arc
							(start -0.1778 -0.2794)
							(mid -0.249642 -0.249642)
							(end -0.2794 -0.1778)
						)
						(arc
							(start -0.2794 0.1778)
							(mid -0.249642 0.249642)
							(end -0.1778 0.2794)
						)
						(arc
							(start 0.1778 0.2794)
							(mid 0.249642 0.249642)
							(end 0.2794 0.1778)
						)
						(arc
							(start 0.2794 -0.1778)
							(mid 0.249642 -0.249642)
							(end 0.1778 -0.2794)
						)
					)
					(width 0)
					(fill yes)
				)
			)
		)
	)
	(footprint ""
		(layer "F.Cu")
		(at 144.907 -106.934 90)
		(property "Reference" "SC1164"
			(at 0 0 90)
			(layer "F.SilkS")
			(hide yes)
			(effects
				(font
					(size 1.27 1.27)
				)
			)
		)
		(property "Value" "SC100U6D3V0MX-2GP"
			(at -0.00254 -4.78536 90)
			(unlocked yes)
			(layer "F.Fab")
			(hide yes)
			(effects
				(font
					(size 1.016 1.016)
					(thickness 0.1524)
				)
			)
		)
		(property "Device Type" "C1210H107"
			(at -0.00254 -6.38048 90)
			(unlocked yes)
			(layer "F.Fab")
			(hide yes)
			(effects
				(font
					(size 1.016 1.016)
					(thickness 0.1524)
				)
			)
		)
		(duplicate_pad_numbers_are_jumpers no)
		(fp_line
			(start 1.5748 -2.3368)
			(end -1.5748 -2.3368)
			(stroke
				(width 0.1524)
				(type default)
			)
			(layer "F.SilkS")
		)
		(fp_line
			(start -1.5748 -2.3368)
			(end -1.5748 -0.762)
			(stroke
				(width 0.1524)
				(type default)
			)
			(layer "F.SilkS")
		)
		(fp_line
			(start 1.5748 -0.762)
			(end 1.5748 -2.3368)
			(stroke
				(width 0.1524)
				(type default)
			)
			(layer "F.SilkS")
		)
		(fp_line
			(start -1.5748 0.762)
			(end -1.5748 2.3368)
			(stroke
				(width 0.1524)
				(type default)
			)
			(layer "F.SilkS")
		)
		(fp_line
			(start 1.5748 2.3368)
			(end 1.5748 0.762)
			(stroke
				(width 0.1524)
				(type default)
			)
			(layer "F.SilkS")
		)
		(fp_line
			(start -1.5748 2.3368)
			(end 1.5748 2.3368)
			(stroke
				(width 0.1524)
				(type default)
			)
			(layer "F.SilkS")
		)
		(fp_rect
			(start -1.651 2.413)
			(end 1.651 -2.413)
			(stroke
				(width 0)
				(type default)
			)
			(fill no)
			(layer "F.CrtYd")
		)
		(fp_poly
			(pts
				(xy 1.651 2.413) (xy 1.651 -2.413) (xy -1.651 -2.413) (xy -1.651 2.413)
			)
			(stroke
				(width 0)
				(type default)
			)
			(fill no)
			(layer "F.Fab")
		)
		(pad "1" smd rect
			(at 0 -1.4732 90)
			(size 2.794 1.397)
			(layers "F.Cu" "F.Mask" "F.Paste")
			(net "GND")
		)
		(pad "2" smd rect
			(at 0 1.4732 90)
			(size 2.794 1.397)
			(layers "F.Cu" "F.Mask" "F.Paste")
			(net "GB_VDDA")
		)
	)
	(footprint ""
		(layer "F.Cu")
		(at 39.0652 -120.4722 -90)
		(property "Reference" "SR939"
			(at 0 0 270)
			(layer "F.SilkS")
			(hide yes)
			(effects
				(font
					(size 1.27 1.27)
				)
			)
		)
		(property "Value" "0R2J-2-GP"
			(at 0.064008 -3.993896 270)
			(unlocked yes)
			(layer "F.Fab")
			(hide yes)
			(effects
				(font
					(size 1.016 1.016)
					(thickness 0.1524)
				)
			)
		)
		(property "Device Type" "R402H16"
			(at 0.064008 -5.517896 270)
			(unlocked yes)
			(layer "F.Fab")
			(hide yes)
			(effects
				(font
					(size 1.016 1.016)
					(thickness 0.1524)
				)
			)
		)
		(duplicate_pad_numbers_are_jumpers no)
		(fp_line
			(start -0.508 -0.9398)
			(end -0.508 0.9398)
			(stroke
				(width 0.1524)
				(type default)
			)
			(layer "F.SilkS")
		)
		(fp_line
			(start 0.508 -0.9398)
			(end -0.508 -0.9398)
			(stroke
				(width 0.1524)
				(type default)
			)
			(layer "F.SilkS")
		)
		(fp_rect
			(start -0.508 0.9398)
			(end 0.508 -0.9398)
			(stroke
				(width 0)
				(type default)
			)
			(fill no)
			(layer "F.CrtYd")
		)
		(fp_rect
			(start -0.508 0.9398)
			(end 0.508 -0.9398)
			(stroke
				(width 0)
				(type default)
			)
			(fill no)
			(layer "F.Fab")
		)
		(pad "1" smd custom
			(at 0 -0.4445 270)
			(size 0.1397 0.1397)
			(layers "F.Cu" "F.Mask" "F.Paste")
			(net "SDB_TX_R")
			(options
				(clearance outline)
				(anchor circle)
			)
			(primitives
				(gr_poly
					(pts
						(arc
							(start -0.1778 -0.2794)
							(mid -0.249642 -0.249642)
							(end -0.2794 -0.1778)
						)
						(arc
							(start -0.2794 0.1778)
							(mid -0.249642 0.249642)
							(end -0.1778 0.2794)
						)
						(arc
							(start 0.1778 0.2794)
							(mid 0.249642 0.249642)
							(end 0.2794 0.1778)
						)
						(arc
							(start 0.2794 -0.1778)
							(mid 0.249642 -0.249642)
							(end 0.1778 -0.2794)
						)
					)
					(width 0)
					(fill yes)
				)
			)
		)
		(pad "2" smd custom
			(at 0 0.4445 270)
			(size 0.1397 0.1397)
			(layers "F.Cu" "F.Mask" "F.Paste")
			(net "SDB_TX")
			(options
				(clearance outline)
				(anchor circle)
			)
			(primitives
				(gr_poly
					(pts
						(arc
							(start -0.1778 -0.2794)
							(mid -0.249642 -0.249642)
							(end -0.2794 -0.1778)
						)
						(arc
							(start -0.2794 0.1778)
							(mid -0.249642 0.249642)
							(end -0.1778 0.2794)
						)
						(arc
							(start 0.1778 0.2794)
							(mid 0.249642 0.249642)
							(end 0.2794 0.1778)
						)
						(arc
							(start 0.2794 -0.1778)
							(mid 0.249642 -0.249642)
							(end 0.1778 -0.2794)
						)
					)
					(width 0)
					(fill yes)
				)
			)
		)
	)
	(footprint ""
		(layer "F.Cu")
		(at 331.343 -211.455 180)
		(property "Reference" "R200"
			(at 0 0 180)
			(layer "F.SilkS")
			(hide yes)
			(effects
				(font
					(size 1.27 1.27)
				)
			)
		)
		(property "Value" "8K2R2J-3-GP"
			(at 0.064008 -3.993896 180)
			(unlocked yes)
			(layer "F.Fab")
			(hide yes)
			(effects
				(font
					(size 1.016 1.016)
					(thickness 0.1524)
				)
			)
		)
		(property "Device Type" "R402H16"
			(at 0.064008 -5.517896 180)
			(unlocked yes)
			(layer "F.Fab")
			(hide yes)
			(effects
				(font
					(size 1.016 1.016)
					(thickness 0.1524)
				)
			)
		)
		(duplicate_pad_numbers_are_jumpers no)
		(fp_line
			(start 0.508 -0.9398)
			(end -0.508 -0.9398)
			(stroke
				(width 0.1524)
				(type default)
			)
			(layer "F.SilkS")
		)
		(fp_line
			(start -0.508 -0.9398)
			(end -0.508 0.9398)
			(stroke
				(width 0.1524)
				(type default)
			)
			(layer "F.SilkS")
		)
		(fp_rect
			(start -0.508 0.9398)
			(end 0.508 -0.9398)
			(stroke
				(width 0)
				(type default)
			)
			(fill no)
			(layer "F.CrtYd")
		)
		(fp_rect
			(start -0.508 0.9398)
			(end 0.508 -0.9398)
			(stroke
				(width 0)
				(type default)
			)
			(fill no)
			(layer "F.Fab")
		)
		(pad "1" smd custom
			(at 0 -0.4445 180)
			(size 0.1397 0.1397)
			(layers "F.Cu" "F.Mask" "F.Paste")
			(net "EEPROM_WP")
			(options
				(clearance outline)
				(anchor circle)
			)
			(primitives
				(gr_poly
					(pts
						(arc
							(start -0.1778 -0.2794)
							(mid -0.249642 -0.249642)
							(end -0.2794 -0.1778)
						)
						(arc
							(start -0.2794 0.1778)
							(mid -0.249642 0.249642)
							(end -0.1778 0.2794)
						)
						(arc
							(start 0.1778 0.2794)
							(mid 0.249642 0.249642)
							(end 0.2794 0.1778)
						)
						(arc
							(start 0.2794 -0.1778)
							(mid 0.249642 -0.249642)
							(end 0.1778 -0.2794)
						)
					)
					(width 0)
					(fill yes)
				)
			)
		)
		(pad "2" smd custom
			(at 0 0.4445 180)
			(size 0.1397 0.1397)
			(layers "F.Cu" "F.Mask" "F.Paste")
			(net "GND")
			(options
				(clearance outline)
				(anchor circle)
			)
			(primitives
				(gr_poly
					(pts
						(arc
							(start -0.1778 -0.2794)
							(mid -0.249642 -0.249642)
							(end -0.2794 -0.1778)
						)
						(arc
							(start -0.2794 0.1778)
							(mid -0.249642 0.249642)
							(end -0.1778 0.2794)
						)
						(arc
							(start 0.1778 0.2794)
							(mid 0.249642 0.249642)
							(end 0.2794 0.1778)
						)
						(arc
							(start 0.2794 -0.1778)
							(mid 0.249642 -0.249642)
							(end 0.1778 -0.2794)
						)
					)
					(width 0)
					(fill yes)
				)
			)
		)
	)
	(footprint ""
		(layer "F.Cu")
		(at 75.184 -22.733 180)
		(property "Reference" "PR195"
			(at 0 0 180)
			(layer "F.SilkS")
			(hide yes)
			(effects
				(font
					(size 1.27 1.27)
				)
			)
		)
		(property "Value" "0R2J-2-GP"
			(at 0.064008 -3.993896 180)
			(unlocked yes)
			(layer "F.Fab")
			(hide yes)
			(effects
				(font
					(size 1.016 1.016)
					(thickness 0.1524)
				)
			)
		)
		(property "Device Type" "R402H16"
			(at 0.064008 -5.517896 180)
			(unlocked yes)
			(layer "F.Fab")
			(hide yes)
			(effects
				(font
					(size 1.016 1.016)
					(thickness 0.1524)
				)
			)
		)
		(duplicate_pad_numbers_are_jumpers no)
		(fp_line
			(start 0.508 -0.9398)
			(end -0.508 -0.9398)
			(stroke
				(width 0.1524)
				(type default)
			)
			(layer "F.SilkS")
		)
		(fp_line
			(start -0.508 -0.9398)
			(end -0.508 0.9398)
			(stroke
				(width 0.1524)
				(type default)
			)
			(layer "F.SilkS")
		)
		(fp_rect
			(start -0.508 0.9398)
			(end 0.508 -0.9398)
			(stroke
				(width 0)
				(type default)
			)
			(fill no)
			(layer "F.CrtYd")
		)
		(fp_rect
			(start -0.508 0.9398)
			(end 0.508 -0.9398)
			(stroke
				(width 0)
				(type default)
			)
			(fill no)
			(layer "F.Fab")
		)
		(pad "1" smd custom
			(at 0 -0.4445 180)
			(size 0.1397 0.1397)
			(layers "F.Cu" "F.Mask" "F.Paste")
			(net "VT235_EN")
			(options
				(clearance outline)
				(anchor circle)
			)
			(primitives
				(gr_poly
					(pts
						(arc
							(start -0.1778 -0.2794)
							(mid -0.249642 -0.249642)
							(end -0.2794 -0.1778)
						)
						(arc
							(start -0.2794 0.1778)
							(mid -0.249642 0.249642)
							(end -0.1778 0.2794)
						)
						(arc
							(start 0.1778 0.2794)
							(mid 0.249642 0.249642)
							(end 0.2794 0.1778)
						)
						(arc
							(start 0.2794 -0.1778)
							(mid 0.249642 -0.249642)
							(end 0.1778 -0.2794)
						)
					)
					(width 0)
					(fill yes)
				)
			)
		)
		(pad "2" smd custom
			(at 0 0.4445 180)
			(size 0.1397 0.1397)
			(layers "F.Cu" "F.Mask" "F.Paste")
			(net "BMC_EN_0V955_C")
			(options
				(clearance outline)
				(anchor circle)
			)
			(primitives
				(gr_poly
					(pts
						(arc
							(start -0.1778 -0.2794)
							(mid -0.249642 -0.249642)
							(end -0.2794 -0.1778)
						)
						(arc
							(start -0.2794 0.1778)
							(mid -0.249642 0.249642)
							(end -0.1778 0.2794)
						)
						(arc
							(start 0.1778 0.2794)
							(mid 0.249642 0.249642)
							(end 0.2794 0.1778)
						)
						(arc
							(start 0.2794 -0.1778)
							(mid 0.249642 -0.249642)
							(end 0.1778 -0.2794)
						)
					)
					(width 0)
					(fill yes)
				)
			)
		)
	)
	(footprint ""
		(layer "F.Cu")
		(at 24.580088 -181.865016)
		(property "Reference" "SR304"
			(at 0 0 0)
			(layer "F.SilkS")
			(hide yes)
			(effects
				(font
					(size 1.27 1.27)
				)
			)
		)
		(property "Value" "0R2J-2-GP"
			(at 0.064008 -3.993896 0)
			(unlocked yes)
			(layer "F.Fab")
			(hide yes)
			(effects
				(font
					(size 1.016 1.016)
					(thickness 0.1524)
				)
			)
		)
		(property "Device Type" "R402H16"
			(at 0.064008 -5.517896 0)
			(unlocked yes)
			(layer "F.Fab")
			(hide yes)
			(effects
				(font
					(size 1.016 1.016)
					(thickness 0.1524)
				)
			)
		)
		(duplicate_pad_numbers_are_jumpers no)
		(fp_line
			(start -0.508 -0.9398)
			(end -0.508 0.9398)
			(stroke
				(width 0.1524)
				(type default)
			)
			(layer "F.SilkS")
		)
		(fp_line
			(start 0.508 -0.9398)
			(end -0.508 -0.9398)
			(stroke
				(width 0.1524)
				(type default)
			)
			(layer "F.SilkS")
		)
		(fp_rect
			(start -0.508 0.9398)
			(end 0.508 -0.9398)
			(stroke
				(width 0)
				(type default)
			)
			(fill no)
			(layer "F.CrtYd")
		)
		(fp_rect
			(start -0.508 0.9398)
			(end 0.508 -0.9398)
			(stroke
				(width 0)
				(type default)
			)
			(fill no)
			(layer "F.Fab")
		)
		(pad "1" smd custom
			(at 0 -0.4445)
			(size 0.1397 0.1397)
			(layers "F.Cu" "F.Mask" "F.Paste")
			(net "PRE_SCL")
			(options
				(clearance outline)
				(anchor circle)
			)
			(primitives
				(gr_poly
					(pts
						(arc
							(start -0.1778 -0.2794)
							(mid -0.249642 -0.249642)
							(end -0.2794 -0.1778)
						)
						(arc
							(start -0.2794 0.1778)
							(mid -0.249642 0.249642)
							(end -0.1778 0.2794)
						)
						(arc
							(start 0.1778 0.2794)
							(mid 0.249642 0.249642)
							(end 0.2794 0.1778)
						)
						(arc
							(start 0.2794 -0.1778)
							(mid 0.249642 -0.249642)
							(end 0.1778 -0.2794)
						)
					)
					(width 0)
					(fill yes)
				)
			)
		)
		(pad "2" smd custom
			(at 0 0.4445)
			(size 0.1397 0.1397)
			(layers "F.Cu" "F.Mask" "F.Paste")
			(net "BMC_IOEXP_SCL_10")
			(options
				(clearance outline)
				(anchor circle)
			)
			(primitives
				(gr_poly
					(pts
						(arc
							(start -0.1778 -0.2794)
							(mid -0.249642 -0.249642)
							(end -0.2794 -0.1778)
						)
						(arc
							(start -0.2794 0.1778)
							(mid -0.249642 0.249642)
							(end -0.1778 0.2794)
						)
						(arc
							(start 0.1778 0.2794)
							(mid 0.249642 0.249642)
							(end 0.2794 0.1778)
						)
						(arc
							(start 0.2794 -0.1778)
							(mid 0.249642 -0.249642)
							(end 0.1778 -0.2794)
						)
					)
					(width 0)
					(fill yes)
				)
			)
		)
	)
	(footprint ""
		(layer "F.Cu")
		(at 184.404 -224.155 90)
		(property "Reference" "R1578"
			(at 0 0 90)
			(layer "F.SilkS")
			(hide yes)
			(effects
				(font
					(size 1.27 1.27)
				)
			)
		)
		(property "Value" "10KR2F-2-GP"
			(at 0.064008 -3.993896 90)
			(unlocked yes)
			(layer "F.Fab")
			(hide yes)
			(effects
				(font
					(size 1.016 1.016)
					(thickness 0.1524)
				)
			)
		)
		(property "Device Type" "R402H16"
			(at 0.064008 -5.517896 90)
			(unlocked yes)
			(layer "F.Fab")
			(hide yes)
			(effects
				(font
					(size 1.016 1.016)
					(thickness 0.1524)
				)
			)
		)
		(duplicate_pad_numbers_are_jumpers no)
		(fp_line
			(start 0.508 -0.9398)
			(end -0.508 -0.9398)
			(stroke
				(width 0.1524)
				(type default)
			)
			(layer "F.SilkS")
		)
		(fp_line
			(start -0.508 -0.9398)
			(end -0.508 0.9398)
			(stroke
				(width 0.1524)
				(type default)
			)
			(layer "F.SilkS")
		)
		(fp_rect
			(start -0.508 0.9398)
			(end 0.508 -0.9398)
			(stroke
				(width 0)
				(type default)
			)
			(fill no)
			(layer "F.CrtYd")
		)
		(fp_rect
			(start -0.508 0.9398)
			(end 0.508 -0.9398)
			(stroke
				(width 0)
				(type default)
			)
			(fill no)
			(layer "F.Fab")
		)
		(pad "1" smd custom
			(at 0 -0.4445 90)
			(size 0.1397 0.1397)
			(layers "F.Cu" "F.Mask" "F.Paste")
			(net "P3V3_STBY")
			(options
				(clearance outline)
				(anchor circle)
			)
			(primitives
				(gr_poly
					(pts
						(arc
							(start -0.1778 -0.2794)
							(mid -0.249642 -0.249642)
							(end -0.2794 -0.1778)
						)
						(arc
							(start -0.2794 0.1778)
							(mid -0.249642 0.249642)
							(end -0.1778 0.2794)
						)
						(arc
							(start 0.1778 0.2794)
							(mid 0.249642 0.249642)
							(end 0.2794 0.1778)
						)
						(arc
							(start 0.2794 -0.1778)
							(mid 0.249642 -0.249642)
							(end 0.1778 -0.2794)
						)
					)
					(width 0)
					(fill yes)
				)
			)
		)
		(pad "2" smd custom
			(at 0 0.4445 90)
			(size 0.1397 0.1397)
			(layers "F.Cu" "F.Mask" "F.Paste")
			(net "PWRBTN_FP_N")
			(options
				(clearance outline)
				(anchor circle)
			)
			(primitives
				(gr_poly
					(pts
						(arc
							(start -0.1778 -0.2794)
							(mid -0.249642 -0.249642)
							(end -0.2794 -0.1778)
						)
						(arc
							(start -0.2794 0.1778)
							(mid -0.249642 0.249642)
							(end -0.1778 0.2794)
						)
						(arc
							(start 0.1778 0.2794)
							(mid 0.249642 0.249642)
							(end 0.2794 0.1778)
						)
						(arc
							(start 0.2794 -0.1778)
							(mid 0.249642 -0.249642)
							(end 0.1778 -0.2794)
						)
					)
					(width 0)
					(fill yes)
				)
			)
		)
	)
	(footprint ""
		(layer "F.Cu")
		(at 256.413 -122.047 -90)
		(property "Reference" "C340"
			(at 0 0 270)
			(layer "F.SilkS")
			(hide yes)
			(effects
				(font
					(size 1.27 1.27)
				)
			)
		)
		(property "Value" "SCD1U25V2KX-2-GP"
			(at 1.1811 -2.7051 270)
			(unlocked yes)
			(layer "F.Fab")
			(hide yes)
			(effects
				(font
					(size 1.016 1.016)
					(thickness 0.1524)
				)
			)
		)
		(property "Device Type" "C402H22"
			(at 1.1811 -4.2291 270)
			(unlocked yes)
			(layer "F.Fab")
			(hide yes)
			(effects
				(font
					(size 1.016 1.016)
					(thickness 0.1524)
				)
			)
		)
		(duplicate_pad_numbers_are_jumpers no)
		(fp_rect
			(start -0.4318 0.9525)
			(end 0.4318 -0.9525)
			(stroke
				(width 0)
				(type default)
			)
			(fill no)
			(layer "F.CrtYd")
		)
		(fp_rect
			(start -0.4318 0.9525)
			(end 0.4318 -0.9525)
			(stroke
				(width 0)
				(type default)
			)
			(fill no)
			(layer "F.Fab")
		)
		(pad "1" smd custom
			(at 0 -0.4445 270)
			(size 0.1524 0.1524)
			(layers "F.Cu" "F.Mask" "F.Paste")
			(net "P3V3_STBY")
			(options
				(clearance outline)
				(anchor circle)
			)
			(primitives
				(gr_poly
					(pts
						(arc
							(start 0.3048 -0.2032)
							(mid 0.275042 -0.275042)
							(end 0.2032 -0.3048)
						)
						(arc
							(start -0.2032 -0.3048)
							(mid -0.275042 -0.275042)
							(end -0.3048 -0.2032)
						)
						(arc
							(start -0.3048 0.2032)
							(mid -0.275042 0.275042)
							(end -0.2032 0.3048)
						)
						(arc
							(start 0.2032 0.3048)
							(mid 0.275042 0.275042)
							(end 0.3048 0.2032)
						)
					)
					(width 0)
					(fill yes)
				)
			)
		)
		(pad "2" smd custom
			(at 0 0.4445 270)
			(size 0.1524 0.1524)
			(layers "F.Cu" "F.Mask" "F.Paste")
			(net "GND")
			(options
				(clearance outline)
				(anchor circle)
			)
			(primitives
				(gr_poly
					(pts
						(arc
							(start 0.3048 -0.2032)
							(mid 0.275042 -0.275042)
							(end 0.2032 -0.3048)
						)
						(arc
							(start -0.2032 -0.3048)
							(mid -0.275042 -0.275042)
							(end -0.3048 -0.2032)
						)
						(arc
							(start -0.3048 0.2032)
							(mid -0.275042 0.275042)
							(end -0.2032 0.3048)
						)
						(arc
							(start 0.2032 0.3048)
							(mid 0.275042 0.275042)
							(end 0.3048 0.2032)
						)
					)
					(width 0)
					(fill yes)
				)
			)
		)
	)
	(footprint ""
		(layer "F.Cu")
		(at 184.776872 -202.560936 90)
		(property "Reference" "R426"
			(at 0 0 90)
			(layer "F.SilkS")
			(hide yes)
			(effects
				(font
					(size 1.27 1.27)
				)
			)
		)
		(property "Value" "10KR2F-2-GP"
			(at 0.064008 -3.993896 90)
			(unlocked yes)
			(layer "F.Fab")
			(hide yes)
			(effects
				(font
					(size 1.016 1.016)
					(thickness 0.1524)
				)
			)
		)
		(property "Device Type" "R402H16"
			(at 0.064008 -5.517896 90)
			(unlocked yes)
			(layer "F.Fab")
			(hide yes)
			(effects
				(font
					(size 1.016 1.016)
					(thickness 0.1524)
				)
			)
		)
		(duplicate_pad_numbers_are_jumpers no)
		(fp_line
			(start 0.508 -0.9398)
			(end -0.508 -0.9398)
			(stroke
				(width 0.1524)
				(type default)
			)
			(layer "F.SilkS")
		)
		(fp_line
			(start -0.508 -0.9398)
			(end -0.508 0.9398)
			(stroke
				(width 0.1524)
				(type default)
			)
			(layer "F.SilkS")
		)
		(fp_rect
			(start -0.508 0.9398)
			(end 0.508 -0.9398)
			(stroke
				(width 0)
				(type default)
			)
			(fill no)
			(layer "F.CrtYd")
		)
		(fp_rect
			(start -0.508 0.9398)
			(end 0.508 -0.9398)
			(stroke
				(width 0)
				(type default)
			)
			(fill no)
			(layer "F.Fab")
		)
		(pad "1" smd custom
			(at 0 -0.4445 90)
			(size 0.1397 0.1397)
			(layers "F.Cu" "F.Mask" "F.Paste")
			(net "I2C_B_BUF_READY")
			(options
				(clearance outline)
				(anchor circle)
			)
			(primitives
				(gr_poly
					(pts
						(arc
							(start -0.1778 -0.2794)
							(mid -0.249642 -0.249642)
							(end -0.2794 -0.1778)
						)
						(arc
							(start -0.2794 0.1778)
							(mid -0.249642 0.249642)
							(end -0.1778 0.2794)
						)
						(arc
							(start 0.1778 0.2794)
							(mid 0.249642 0.249642)
							(end 0.2794 0.1778)
						)
						(arc
							(start 0.2794 -0.1778)
							(mid 0.249642 -0.249642)
							(end 0.1778 -0.2794)
						)
					)
					(width 0)
					(fill yes)
				)
			)
		)
		(pad "2" smd custom
			(at 0 0.4445 90)
			(size 0.1397 0.1397)
			(layers "F.Cu" "F.Mask" "F.Paste")
			(net "P3V3_STBY")
			(options
				(clearance outline)
				(anchor circle)
			)
			(primitives
				(gr_poly
					(pts
						(arc
							(start -0.1778 -0.2794)
							(mid -0.249642 -0.249642)
							(end -0.2794 -0.1778)
						)
						(arc
							(start -0.2794 0.1778)
							(mid -0.249642 0.249642)
							(end -0.1778 0.2794)
						)
						(arc
							(start 0.1778 0.2794)
							(mid 0.249642 0.249642)
							(end 0.2794 0.1778)
						)
						(arc
							(start 0.2794 -0.1778)
							(mid 0.249642 -0.249642)
							(end 0.1778 -0.2794)
						)
					)
					(width 0)
					(fill yes)
				)
			)
		)
	)
	(footprint ""
		(layer "F.Cu")
		(at 311.277 -201.041)
		(property "Reference" "R172"
			(at 0 0 0)
			(layer "F.SilkS")
			(hide yes)
			(effects
				(font
					(size 1.27 1.27)
				)
			)
		)
		(property "Value" "4K7R2J-2-GP"
			(at 0.064008 -3.993896 0)
			(unlocked yes)
			(layer "F.Fab")
			(hide yes)
			(effects
				(font
					(size 1.016 1.016)
					(thickness 0.1524)
				)
			)
		)
		(property "Device Type" "R402H16"
			(at 0.064008 -5.517896 0)
			(unlocked yes)
			(layer "F.Fab")
			(hide yes)
			(effects
				(font
					(size 1.016 1.016)
					(thickness 0.1524)
				)
			)
		)
		(duplicate_pad_numbers_are_jumpers no)
		(fp_line
			(start -0.508 -0.9398)
			(end -0.508 0.9398)
			(stroke
				(width 0.1524)
				(type default)
			)
			(layer "F.SilkS")
		)
		(fp_line
			(start 0.508 -0.9398)
			(end -0.508 -0.9398)
			(stroke
				(width 0.1524)
				(type default)
			)
			(layer "F.SilkS")
		)
		(fp_rect
			(start -0.508 0.9398)
			(end 0.508 -0.9398)
			(stroke
				(width 0)
				(type default)
			)
			(fill no)
			(layer "F.CrtYd")
		)
		(fp_rect
			(start -0.508 0.9398)
			(end 0.508 -0.9398)
			(stroke
				(width 0)
				(type default)
			)
			(fill no)
			(layer "F.Fab")
		)
		(pad "1" smd custom
			(at 0 -0.4445)
			(size 0.1397 0.1397)
			(layers "F.Cu" "F.Mask" "F.Paste")
			(net "P3V3_STBY")
			(options
				(clearance outline)
				(anchor circle)
			)
			(primitives
				(gr_poly
					(pts
						(arc
							(start -0.1778 -0.2794)
							(mid -0.249642 -0.249642)
							(end -0.2794 -0.1778)
						)
						(arc
							(start -0.2794 0.1778)
							(mid -0.249642 0.249642)
							(end -0.1778 0.2794)
						)
						(arc
							(start 0.1778 0.2794)
							(mid 0.249642 0.249642)
							(end 0.2794 0.1778)
						)
						(arc
							(start 0.2794 -0.1778)
							(mid 0.249642 -0.249642)
							(end 0.1778 -0.2794)
						)
					)
					(width 0)
					(fill yes)
				)
			)
		)
		(pad "2" smd custom
			(at 0 0.4445)
			(size 0.1397 0.1397)
			(layers "F.Cu" "F.Mask" "F.Paste")
			(net "LED_DR_RESET#")
			(options
				(clearance outline)
				(anchor circle)
			)
			(primitives
				(gr_poly
					(pts
						(arc
							(start -0.1778 -0.2794)
							(mid -0.249642 -0.249642)
							(end -0.2794 -0.1778)
						)
						(arc
							(start -0.2794 0.1778)
							(mid -0.249642 0.249642)
							(end -0.1778 0.2794)
						)
						(arc
							(start 0.1778 0.2794)
							(mid 0.249642 0.249642)
							(end 0.2794 0.1778)
						)
						(arc
							(start 0.2794 -0.1778)
							(mid 0.249642 -0.249642)
							(end 0.1778 -0.2794)
						)
					)
					(width 0)
					(fill yes)
				)
			)
		)
	)
	(footprint ""
		(layer "F.Cu")
		(at 174.353728 -32.515048)
		(property "Reference" "R386"
			(at 0 0 0)
			(layer "F.SilkS")
			(hide yes)
			(effects
				(font
					(size 1.27 1.27)
				)
			)
		)
		(property "Value" "0R2J-2-GP"
			(at 0.064008 -3.993896 0)
			(unlocked yes)
			(layer "F.Fab")
			(hide yes)
			(effects
				(font
					(size 1.016 1.016)
					(thickness 0.1524)
				)
			)
		)
		(property "Device Type" "R402H16"
			(at 0.064008 -5.517896 0)
			(unlocked yes)
			(layer "F.Fab")
			(hide yes)
			(effects
				(font
					(size 1.016 1.016)
					(thickness 0.1524)
				)
			)
		)
		(duplicate_pad_numbers_are_jumpers no)
		(fp_line
			(start -0.508 -0.9398)
			(end -0.508 0.9398)
			(stroke
				(width 0.1524)
				(type default)
			)
			(layer "F.SilkS")
		)
		(fp_line
			(start 0.508 -0.9398)
			(end -0.508 -0.9398)
			(stroke
				(width 0.1524)
				(type default)
			)
			(layer "F.SilkS")
		)
		(fp_rect
			(start -0.508 0.9398)
			(end 0.508 -0.9398)
			(stroke
				(width 0)
				(type default)
			)
			(fill no)
			(layer "F.CrtYd")
		)
		(fp_rect
			(start -0.508 0.9398)
			(end 0.508 -0.9398)
			(stroke
				(width 0)
				(type default)
			)
			(fill no)
			(layer "F.Fab")
		)
		(pad "1" smd custom
			(at 0 -0.4445)
			(size 0.1397 0.1397)
			(layers "F.Cu" "F.Mask" "F.Paste")
			(net "BCM5221_MB_RX_DN")
			(options
				(clearance outline)
				(anchor circle)
			)
			(primitives
				(gr_poly
					(pts
						(arc
							(start -0.1778 -0.2794)
							(mid -0.249642 -0.249642)
							(end -0.2794 -0.1778)
						)
						(arc
							(start -0.2794 0.1778)
							(mid -0.249642 0.249642)
							(end -0.1778 0.2794)
						)
						(arc
							(start 0.1778 0.2794)
							(mid 0.249642 0.249642)
							(end 0.2794 0.1778)
						)
						(arc
							(start 0.2794 -0.1778)
							(mid 0.249642 -0.249642)
							(end 0.1778 -0.2794)
						)
					)
					(width 0)
					(fill yes)
				)
			)
		)
		(pad "2" smd custom
			(at 0 0.4445)
			(size 0.1397 0.1397)
			(layers "F.Cu" "F.Mask" "F.Paste")
			(net "BCM5221_RX_C_DN")
			(options
				(clearance outline)
				(anchor circle)
			)
			(primitives
				(gr_poly
					(pts
						(arc
							(start -0.1778 -0.2794)
							(mid -0.249642 -0.249642)
							(end -0.2794 -0.1778)
						)
						(arc
							(start -0.2794 0.1778)
							(mid -0.249642 0.249642)
							(end -0.1778 0.2794)
						)
						(arc
							(start 0.1778 0.2794)
							(mid 0.249642 0.249642)
							(end 0.2794 0.1778)
						)
						(arc
							(start 0.2794 -0.1778)
							(mid 0.249642 -0.249642)
							(end 0.1778 -0.2794)
						)
					)
					(width 0)
					(fill yes)
				)
			)
		)
	)
	(footprint ""
		(layer "F.Cu")
		(at 113.792 -77.343)
		(property "Reference" "STP73"
			(at 0 0 0)
			(layer "F.SilkS")
			(hide yes)
			(effects
				(font
					(size 1.27 1.27)
				)
			)
		)
		(property "Value" "TPAD28"
			(at 0.0127 -1.8034 0)
			(unlocked yes)
			(layer "F.Fab")
			(hide yes)
			(effects
				(font
					(size 1.016 1.016)
					(thickness 0.1524)
				)
			)
		)
		(property "Device Type" "TPAD28"
			(at 0.0127 -3.3274 0)
			(unlocked yes)
			(layer "F.Fab")
			(hide yes)
			(effects
				(font
					(size 1.016 1.016)
					(thickness 0.1524)
				)
			)
		)
		(duplicate_pad_numbers_are_jumpers no)
		(fp_poly
			(pts
				(arc
					(start 0.3556 0)
					(mid -0.3556 0)
					(end 0.3556 0)
				)
			)
			(stroke
				(width 0)
				(type default)
			)
			(fill no)
			(layer "F.CrtYd")
		)
		(fp_poly
			(pts
				(arc
					(start 0.6096 0)
					(mid -0.6096 0)
					(end 0.6096 0)
				)
			)
			(stroke
				(width 0)
				(type default)
			)
			(fill no)
			(layer "F.Fab")
		)
		(pad "1" smd circle
			(at 0 0)
			(size 0.7112 0.7112)
			(layers "F.Cu" "F.Mask" "F.Paste")
			(net "EXP_TEST_MUX34")
		)
	)
	(footprint ""
		(layer "F.Cu")
		(at 274.193 -163.576 90)
		(property "Reference" "R671"
			(at 0 0 90)
			(layer "F.SilkS")
			(hide yes)
			(effects
				(font
					(size 1.27 1.27)
				)
			)
		)
		(property "Value" "0R2J-2-GP"
			(at 0.064008 -3.993896 90)
			(unlocked yes)
			(layer "F.Fab")
			(hide yes)
			(effects
				(font
					(size 1.016 1.016)
					(thickness 0.1524)
				)
			)
		)
		(property "Device Type" "R402H16"
			(at 0.064008 -5.517896 90)
			(unlocked yes)
			(layer "F.Fab")
			(hide yes)
			(effects
				(font
					(size 1.016 1.016)
					(thickness 0.1524)
				)
			)
		)
		(duplicate_pad_numbers_are_jumpers no)
		(fp_line
			(start 0.508 -0.9398)
			(end -0.508 -0.9398)
			(stroke
				(width 0.1524)
				(type default)
			)
			(layer "F.SilkS")
		)
		(fp_line
			(start -0.508 -0.9398)
			(end -0.508 0.9398)
			(stroke
				(width 0.1524)
				(type default)
			)
			(layer "F.SilkS")
		)
		(fp_rect
			(start -0.508 0.9398)
			(end 0.508 -0.9398)
			(stroke
				(width 0)
				(type default)
			)
			(fill no)
			(layer "F.CrtYd")
		)
		(fp_rect
			(start -0.508 0.9398)
			(end 0.508 -0.9398)
			(stroke
				(width 0)
				(type default)
			)
			(fill no)
			(layer "F.Fab")
		)
		(pad "1" smd custom
			(at 0 -0.4445 90)
			(size 0.1397 0.1397)
			(layers "F.Cu" "F.Mask" "F.Paste")
			(net "USB_OCS_N1")
			(options
				(clearance outline)
				(anchor circle)
			)
			(primitives
				(gr_poly
					(pts
						(arc
							(start -0.1778 -0.2794)
							(mid -0.249642 -0.249642)
							(end -0.2794 -0.1778)
						)
						(arc
							(start -0.2794 0.1778)
							(mid -0.249642 0.249642)
							(end -0.1778 0.2794)
						)
						(arc
							(start 0.1778 0.2794)
							(mid 0.249642 0.249642)
							(end 0.2794 0.1778)
						)
						(arc
							(start 0.2794 -0.1778)
							(mid 0.249642 -0.249642)
							(end 0.1778 -0.2794)
						)
					)
					(width 0)
					(fill yes)
				)
			)
		)
		(pad "2" smd custom
			(at 0 0.4445 90)
			(size 0.1397 0.1397)
			(layers "F.Cu" "F.Mask" "F.Paste")
			(net "TP_BMC_GPIOI0")
			(options
				(clearance outline)
				(anchor circle)
			)
			(primitives
				(gr_poly
					(pts
						(arc
							(start -0.1778 -0.2794)
							(mid -0.249642 -0.249642)
							(end -0.2794 -0.1778)
						)
						(arc
							(start -0.2794 0.1778)
							(mid -0.249642 0.249642)
							(end -0.1778 0.2794)
						)
						(arc
							(start 0.1778 0.2794)
							(mid 0.249642 0.249642)
							(end 0.2794 0.1778)
						)
						(arc
							(start 0.2794 -0.1778)
							(mid 0.249642 -0.249642)
							(end 0.1778 -0.2794)
						)
					)
					(width 0)
					(fill yes)
				)
			)
		)
	)
	(footprint ""
		(layer "F.Cu")
		(at 193.167 -16.129 -90)
		(property "Reference" "R5307"
			(at 0 0 270)
			(layer "F.SilkS")
			(hide yes)
			(effects
				(font
					(size 1.27 1.27)
				)
			)
		)
		(property "Value" "0R2J-2-GP"
			(at 0.064008 -3.993896 270)
			(unlocked yes)
			(layer "F.Fab")
			(hide yes)
			(effects
				(font
					(size 1.016 1.016)
					(thickness 0.1524)
				)
			)
		)
		(property "Device Type" "R402H16"
			(at 0.064008 -5.517896 270)
			(unlocked yes)
			(layer "F.Fab")
			(hide yes)
			(effects
				(font
					(size 1.016 1.016)
					(thickness 0.1524)
				)
			)
		)
		(duplicate_pad_numbers_are_jumpers no)
		(fp_line
			(start -0.508 -0.9398)
			(end -0.508 0.9398)
			(stroke
				(width 0.1524)
				(type default)
			)
			(layer "F.SilkS")
		)
		(fp_line
			(start 0.508 -0.9398)
			(end -0.508 -0.9398)
			(stroke
				(width 0.1524)
				(type default)
			)
			(layer "F.SilkS")
		)
		(fp_rect
			(start -0.508 0.9398)
			(end 0.508 -0.9398)
			(stroke
				(width 0)
				(type default)
			)
			(fill no)
			(layer "F.CrtYd")
		)
		(fp_rect
			(start -0.508 0.9398)
			(end 0.508 -0.9398)
			(stroke
				(width 0)
				(type default)
			)
			(fill no)
			(layer "F.Fab")
		)
		(pad "1" smd custom
			(at 0 -0.4445 270)
			(size 0.1397 0.1397)
			(layers "F.Cu" "F.Mask" "F.Paste")
			(net "BMC_I2C_SCL_10")
			(options
				(clearance outline)
				(anchor circle)
			)
			(primitives
				(gr_poly
					(pts
						(arc
							(start -0.1778 -0.2794)
							(mid -0.249642 -0.249642)
							(end -0.2794 -0.1778)
						)
						(arc
							(start -0.2794 0.1778)
							(mid -0.249642 0.249642)
							(end -0.1778 0.2794)
						)
						(arc
							(start 0.1778 0.2794)
							(mid 0.249642 0.249642)
							(end 0.2794 0.1778)
						)
						(arc
							(start 0.2794 -0.1778)
							(mid 0.249642 -0.249642)
							(end 0.1778 -0.2794)
						)
					)
					(width 0)
					(fill yes)
				)
			)
		)
		(pad "2" smd custom
			(at 0 0.4445 270)
			(size 0.1397 0.1397)
			(layers "F.Cu" "F.Mask" "F.Paste")
			(net "TEMP_1_SCL")
			(options
				(clearance outline)
				(anchor circle)
			)
			(primitives
				(gr_poly
					(pts
						(arc
							(start -0.1778 -0.2794)
							(mid -0.249642 -0.249642)
							(end -0.2794 -0.1778)
						)
						(arc
							(start -0.2794 0.1778)
							(mid -0.249642 0.249642)
							(end -0.1778 0.2794)
						)
						(arc
							(start 0.1778 0.2794)
							(mid 0.249642 0.249642)
							(end 0.2794 0.1778)
						)
						(arc
							(start 0.2794 -0.1778)
							(mid 0.249642 -0.249642)
							(end 0.1778 -0.2794)
						)
					)
					(width 0)
					(fill yes)
				)
			)
		)
	)
	(footprint ""
		(layer "F.Cu")
		(at 283.074872 -64.080136)
		(property "Reference" "C268"
			(at 0 0 0)
			(layer "F.SilkS")
			(hide yes)
			(effects
				(font
					(size 1.27 1.27)
				)
			)
		)
		(property "Value" "SC22U6D3V5MX-2GP"
			(at -0.0762 -6.1214 0)
			(unlocked yes)
			(layer "F.Fab")
			(hide yes)
			(effects
				(font
					(size 1.016 1.016)
					(thickness 0.1524)
				)
			)
		)
		(property "Device Type" "C805H58"
			(at -0.0762 -8.1534 0)
			(unlocked yes)
			(layer "F.Fab")
			(hide yes)
			(effects
				(font
					(size 1.016 1.016)
					(thickness 0.1524)
				)
			)
		)
		(duplicate_pad_numbers_are_jumpers no)
		(fp_line
			(start 0.635 0)
			(end -0.635 0)
			(stroke
				(width 0.508)
				(type default)
			)
			(layer "F.SilkS")
		)
		(fp_rect
			(start -0.9652 1.778)
			(end 0.9652 -1.778)
			(stroke
				(width 0)
				(type default)
			)
			(fill no)
			(layer "F.CrtYd")
		)
		(fp_poly
			(pts
				(xy -0.9652 -1.778) (xy 0.9652 -1.778) (xy 0.9652 1.778) (xy -0.9652 1.778)
			)
			(stroke
				(width 0)
				(type default)
			)
			(fill no)
			(layer "F.Fab")
		)
		(pad "1" smd rect
			(at 0 -0.9652)
			(size 1.397 1.143)
			(layers "F.Cu" "F.Mask" "F.Paste")
			(net "PRSNT_EN_HPIC")
		)
		(pad "2" smd rect
			(at 0 0.9652)
			(size 1.397 1.143)
			(layers "F.Cu" "F.Mask" "F.Paste")
			(net "GND")
		)
	)
	(footprint ""
		(layer "F.Cu")
		(at 288.987992 -191.842136 180)
		(property "Reference" "C184"
			(at 0 0 180)
			(layer "F.SilkS")
			(hide yes)
			(effects
				(font
					(size 1.27 1.27)
				)
			)
		)
		(property "Value" "SCD1U16V2KX-3GP"
			(at 1.1811 -2.7051 180)
			(unlocked yes)
			(layer "F.Fab")
			(hide yes)
			(effects
				(font
					(size 1.016 1.016)
					(thickness 0.1524)
				)
			)
		)
		(property "Device Type" "C402H22"
			(at 1.1811 -4.2291 180)
			(unlocked yes)
			(layer "F.Fab")
			(hide yes)
			(effects
				(font
					(size 1.016 1.016)
					(thickness 0.1524)
				)
			)
		)
		(duplicate_pad_numbers_are_jumpers no)
		(fp_rect
			(start -0.4318 0.9525)
			(end 0.4318 -0.9525)
			(stroke
				(width 0)
				(type default)
			)
			(fill no)
			(layer "F.CrtYd")
		)
		(fp_rect
			(start -0.4318 0.9525)
			(end 0.4318 -0.9525)
			(stroke
				(width 0)
				(type default)
			)
			(fill no)
			(layer "F.Fab")
		)
		(pad "1" smd custom
			(at 0 -0.4445 180)
			(size 0.1524 0.1524)
			(layers "F.Cu" "F.Mask" "F.Paste")
			(net "GND")
			(options
				(clearance outline)
				(anchor circle)
			)
			(primitives
				(gr_poly
					(pts
						(arc
							(start 0.3048 -0.2032)
							(mid 0.275042 -0.275042)
							(end 0.2032 -0.3048)
						)
						(arc
							(start -0.2032 -0.3048)
							(mid -0.275042 -0.275042)
							(end -0.3048 -0.2032)
						)
						(arc
							(start -0.3048 0.2032)
							(mid -0.275042 0.275042)
							(end -0.2032 0.3048)
						)
						(arc
							(start 0.2032 0.3048)
							(mid 0.275042 0.275042)
							(end 0.3048 0.2032)
						)
					)
					(width 0)
					(fill yes)
				)
			)
		)
		(pad "2" smd custom
			(at 0 0.4445 180)
			(size 0.1524 0.1524)
			(layers "F.Cu" "F.Mask" "F.Paste")
			(net "DDR_VREF")
			(options
				(clearance outline)
				(anchor circle)
			)
			(primitives
				(gr_poly
					(pts
						(arc
							(start 0.3048 -0.2032)
							(mid 0.275042 -0.275042)
							(end 0.2032 -0.3048)
						)
						(arc
							(start -0.2032 -0.3048)
							(mid -0.275042 -0.275042)
							(end -0.3048 -0.2032)
						)
						(arc
							(start -0.3048 0.2032)
							(mid -0.275042 0.275042)
							(end -0.2032 0.3048)
						)
						(arc
							(start 0.2032 0.3048)
							(mid 0.275042 0.275042)
							(end 0.3048 0.2032)
						)
					)
					(width 0)
					(fill yes)
				)
			)
		)
	)
	(footprint ""
		(layer "F.Cu")
		(at 306.578 -181.737)
		(property "Reference" "TP110"
			(at 0 0 0)
			(layer "F.SilkS")
			(hide yes)
			(effects
				(font
					(size 1.27 1.27)
				)
			)
		)
		(property "Value" "TPAD28"
			(at 0.0127 -1.8034 0)
			(unlocked yes)
			(layer "F.Fab")
			(hide yes)
			(effects
				(font
					(size 1.016 1.016)
					(thickness 0.1524)
				)
			)
		)
		(property "Device Type" "TPAD28"
			(at 0.0127 -3.3274 0)
			(unlocked yes)
			(layer "F.Fab")
			(hide yes)
			(effects
				(font
					(size 1.016 1.016)
					(thickness 0.1524)
				)
			)
		)
		(duplicate_pad_numbers_are_jumpers no)
		(fp_poly
			(pts
				(arc
					(start 0.3556 0)
					(mid -0.3556 0)
					(end 0.3556 0)
				)
			)
			(stroke
				(width 0)
				(type default)
			)
			(fill no)
			(layer "F.CrtYd")
		)
		(fp_poly
			(pts
				(arc
					(start 0.6096 0)
					(mid -0.6096 0)
					(end 0.6096 0)
				)
			)
			(stroke
				(width 0)
				(type default)
			)
			(fill no)
			(layer "F.Fab")
		)
		(pad "1" smd circle
			(at 0 0)
			(size 0.7112 0.7112)
			(layers "F.Cu" "F.Mask" "F.Paste")
			(net "TP_BMC_GPIOL6")
		)
	)
	(footprint ""
		(layer "F.Cu")
		(at 184.903872 -196.083936 180)
		(property "Reference" "C247"
			(at 0 0 180)
			(layer "F.SilkS")
			(hide yes)
			(effects
				(font
					(size 1.27 1.27)
				)
			)
		)
		(property "Value" "SC220P50V3JN-GP"
			(at 0 -2.8194 180)
			(unlocked yes)
			(layer "F.Fab")
			(hide yes)
			(effects
				(font
					(size 1.016 1.016)
					(thickness 0.1524)
				)
			)
		)
		(property "Device Type" "C603H36"
			(at 0 -4.3434 180)
			(unlocked yes)
			(layer "F.Fab")
			(hide yes)
			(effects
				(font
					(size 1.016 1.016)
					(thickness 0.1524)
				)
			)
		)
		(duplicate_pad_numbers_are_jumpers no)
		(fp_line
			(start 0.508 0)
			(end -0.508 0)
			(stroke
				(width 0.2032)
				(type default)
			)
			(layer "F.SilkS")
		)
		(fp_rect
			(start -0.5842 1.3335)
			(end 0.5842 -1.3335)
			(stroke
				(width 0)
				(type default)
			)
			(fill no)
			(layer "F.CrtYd")
		)
		(fp_rect
			(start -0.5842 1.3335)
			(end 0.5842 -1.3335)
			(stroke
				(width 0)
				(type default)
			)
			(fill no)
			(layer "F.Fab")
		)
		(pad "1" smd custom
			(at 0 -0.762 180)
			(size 0.2159 0.2159)
			(layers "F.Cu" "F.Mask" "F.Paste")
			(net "BMC_I2C_C_SDA")
			(options
				(clearance outline)
				(anchor circle)
			)
			(primitives
				(gr_poly
					(pts
						(arc
							(start -0.3302 -0.4318)
							(mid -0.402042 -0.402042)
							(end -0.4318 -0.3302)
						)
						(arc
							(start -0.4318 0.3302)
							(mid -0.402042 0.402042)
							(end -0.3302 0.4318)
						)
						(arc
							(start 0.3302 0.4318)
							(mid 0.402042 0.402042)
							(end 0.4318 0.3302)
						)
						(arc
							(start 0.4318 -0.3302)
							(mid 0.402042 -0.402042)
							(end 0.3302 -0.4318)
						)
					)
					(width 0)
					(fill yes)
				)
			)
		)
		(pad "2" smd custom
			(at 0 0.762 180)
			(size 0.2159 0.2159)
			(layers "F.Cu" "F.Mask" "F.Paste")
			(net "GND")
			(options
				(clearance outline)
				(anchor circle)
			)
			(primitives
				(gr_poly
					(pts
						(arc
							(start -0.3302 -0.4318)
							(mid -0.402042 -0.402042)
							(end -0.4318 -0.3302)
						)
						(arc
							(start -0.4318 0.3302)
							(mid -0.402042 0.402042)
							(end -0.3302 0.4318)
						)
						(arc
							(start 0.3302 0.4318)
							(mid 0.402042 0.402042)
							(end 0.4318 0.3302)
						)
						(arc
							(start 0.4318 -0.3302)
							(mid 0.402042 -0.402042)
							(end 0.3302 -0.4318)
						)
					)
					(width 0)
					(fill yes)
				)
			)
		)
	)
	(footprint ""
		(layer "F.Cu")
		(at 270.959072 -52.126896 180)
		(property "Reference" "PU9"
			(at 0 0 180)
			(layer "F.SilkS")
			(hide yes)
			(effects
				(font
					(size 1.27 1.27)
				)
			)
		)
		(property "Value" "2N7002DW-7F-GP"
			(at -2.3622 -8.2042 180)
			(unlocked yes)
			(layer "F.Fab")
			(hide yes)
			(effects
				(font
					(size 1.016 1.016)
					(thickness 0.1524)
				)
			)
		)
		(property "Device Type" "SOT-363H44"
			(at -2.3622 -10.1092 180)
			(unlocked yes)
			(layer "F.Fab")
			(hide yes)
			(effects
				(font
					(size 1.016 1.016)
					(thickness 0.1524)
				)
			)
		)
		(duplicate_pad_numbers_are_jumpers no)
		(fp_line
			(start 1.4478 1.7018)
			(end 1.4478 -1.7018)
			(stroke
				(width 0.1524)
				(type default)
			)
			(layer "F.SilkS")
		)
		(fp_line
			(start 1.4478 -1.7018)
			(end -1.4478 -1.7018)
			(stroke
				(width 0.1524)
				(type default)
			)
			(layer "F.SilkS")
		)
		(fp_line
			(start -1.27 1.524)
			(end -1.27 0.6604)
			(stroke
				(width 0.4826)
				(type default)
			)
			(layer "F.SilkS")
		)
		(fp_line
			(start -1.4478 1.7018)
			(end 1.4478 1.7018)
			(stroke
				(width 0.1524)
				(type default)
			)
			(layer "F.SilkS")
		)
		(fp_line
			(start -1.4478 -1.7018)
			(end -1.4478 1.7018)
			(stroke
				(width 0.1524)
				(type default)
			)
			(layer "F.SilkS")
		)
		(fp_poly
			(pts
				(xy -1.524 -1.778) (xy 1.524 -1.778) (xy 1.524 1.778) (xy -1.524 1.778)
			)
			(stroke
				(width 0)
				(type default)
			)
			(fill no)
			(layer "F.CrtYd")
		)
		(fp_poly
			(pts
				(xy -1.524 -1.778) (xy 1.524 -1.778) (xy 1.524 1.778) (xy -1.524 1.778)
			)
			(stroke
				(width 0)
				(type default)
			)
			(fill no)
			(layer "F.Fab")
		)
		(pad "1" smd rect
			(at -0.65024 0.9398 180)
			(size 0.4064 1.016)
			(layers "F.Cu" "F.Mask" "F.Paste")
			(net "GND")
		)
		(pad "2" smd rect
			(at 0 0.9398 180)
			(size 0.4064 1.016)
			(layers "F.Cu" "F.Mask" "F.Paste")
			(net "P3V3_EN_B")
		)
		(pad "3" smd rect
			(at 0.65024 0.9398 180)
			(size 0.4064 1.016)
			(layers "F.Cu" "F.Mask" "F.Paste")
			(net "P3V3_EN_LV")
		)
		(pad "4" smd rect
			(at 0.65024 -0.9398 180)
			(size 0.4064 1.016)
			(layers "F.Cu" "F.Mask" "F.Paste")
			(net "GND")
		)
		(pad "5" smd rect
			(at 0 -0.9398 180)
			(size 0.4064 1.016)
			(layers "F.Cu" "F.Mask" "F.Paste")
			(net "P3V3_S_LV")
		)
		(pad "6" smd rect
			(at -0.65024 -0.9398 180)
			(size 0.4064 1.016)
			(layers "F.Cu" "F.Mask" "F.Paste")
			(net "P3V3_S_LV")
		)
	)
	(footprint ""
		(layer "F.Cu")
		(at 91.929966 -61.468)
		(property "Reference" "STP36"
			(at 0 0 0)
			(layer "F.SilkS")
			(hide yes)
			(effects
				(font
					(size 1.27 1.27)
				)
			)
		)
		(property "Value" "TPAD28"
			(at 0.0127 -1.8034 0)
			(unlocked yes)
			(layer "F.Fab")
			(hide yes)
			(effects
				(font
					(size 1.016 1.016)
					(thickness 0.1524)
				)
			)
		)
		(property "Device Type" "TPAD28"
			(at 0.0127 -3.3274 0)
			(unlocked yes)
			(layer "F.Fab")
			(hide yes)
			(effects
				(font
					(size 1.016 1.016)
					(thickness 0.1524)
				)
			)
		)
		(duplicate_pad_numbers_are_jumpers no)
		(fp_poly
			(pts
				(arc
					(start 0.3556 0)
					(mid -0.3556 0)
					(end 0.3556 0)
				)
			)
			(stroke
				(width 0)
				(type default)
			)
			(fill no)
			(layer "F.CrtYd")
		)
		(fp_poly
			(pts
				(arc
					(start 0.6096 0)
					(mid -0.6096 0)
					(end 0.6096 0)
				)
			)
			(stroke
				(width 0)
				(type default)
			)
			(fill no)
			(layer "F.Fab")
		)
		(pad "1" smd circle
			(at 0 0)
			(size 0.7112 0.7112)
			(layers "F.Cu" "F.Mask" "F.Paste")
			(net "ICE1_TMS")
		)
	)
	(footprint ""
		(layer "F.Cu")
		(at 333.912718 -156.695648 90)
		(property "Reference" "R248"
			(at 0 0 90)
			(layer "F.SilkS")
			(hide yes)
			(effects
				(font
					(size 1.27 1.27)
				)
			)
		)
		(property "Value" "4K7R2F-GP"
			(at 0.064008 -3.993896 90)
			(unlocked yes)
			(layer "F.Fab")
			(hide yes)
			(effects
				(font
					(size 1.016 1.016)
					(thickness 0.1524)
				)
			)
		)
		(property "Device Type" "R402H16"
			(at 0.064008 -5.517896 90)
			(unlocked yes)
			(layer "F.Fab")
			(hide yes)
			(effects
				(font
					(size 1.016 1.016)
					(thickness 0.1524)
				)
			)
		)
		(duplicate_pad_numbers_are_jumpers no)
		(fp_line
			(start 0.508 -0.9398)
			(end -0.508 -0.9398)
			(stroke
				(width 0.1524)
				(type default)
			)
			(layer "F.SilkS")
		)
		(fp_line
			(start -0.508 -0.9398)
			(end -0.508 0.9398)
			(stroke
				(width 0.1524)
				(type default)
			)
			(layer "F.SilkS")
		)
		(fp_rect
			(start -0.508 0.9398)
			(end 0.508 -0.9398)
			(stroke
				(width 0)
				(type default)
			)
			(fill no)
			(layer "F.CrtYd")
		)
		(fp_rect
			(start -0.508 0.9398)
			(end 0.508 -0.9398)
			(stroke
				(width 0)
				(type default)
			)
			(fill no)
			(layer "F.Fab")
		)
		(pad "1" smd custom
			(at 0 -0.4445 90)
			(size 0.1397 0.1397)
			(layers "F.Cu" "F.Mask" "F.Paste")
			(net "P3V3_STBY")
			(options
				(clearance outline)
				(anchor circle)
			)
			(primitives
				(gr_poly
					(pts
						(arc
							(start -0.1778 -0.2794)
							(mid -0.249642 -0.249642)
							(end -0.2794 -0.1778)
						)
						(arc
							(start -0.2794 0.1778)
							(mid -0.249642 0.249642)
							(end -0.1778 0.2794)
						)
						(arc
							(start 0.1778 0.2794)
							(mid 0.249642 0.249642)
							(end 0.2794 0.1778)
						)
						(arc
							(start 0.2794 -0.1778)
							(mid 0.249642 -0.249642)
							(end 0.1778 -0.2794)
						)
					)
					(width 0)
					(fill yes)
				)
			)
		)
		(pad "2" smd custom
			(at 0 0.4445 90)
			(size 0.1397 0.1397)
			(layers "F.Cu" "F.Mask" "F.Paste")
			(net "USB_EN_4")
			(options
				(clearance outline)
				(anchor circle)
			)
			(primitives
				(gr_poly
					(pts
						(arc
							(start -0.1778 -0.2794)
							(mid -0.249642 -0.249642)
							(end -0.2794 -0.1778)
						)
						(arc
							(start -0.2794 0.1778)
							(mid -0.249642 0.249642)
							(end -0.1778 0.2794)
						)
						(arc
							(start 0.1778 0.2794)
							(mid 0.249642 0.249642)
							(end 0.2794 0.1778)
						)
						(arc
							(start 0.2794 -0.1778)
							(mid 0.249642 -0.249642)
							(end 0.1778 -0.2794)
						)
					)
					(width 0)
					(fill yes)
				)
			)
		)
	)
	(footprint ""
		(layer "F.Cu")
		(at 102.37597 -114.3 180)
		(property "Reference" "SC1090"
			(at 0 0 180)
			(layer "F.SilkS")
			(hide yes)
			(effects
				(font
					(size 1.27 1.27)
				)
			)
		)
		(property "Value" "SCD01U10V1KX-GP"
			(at -2.8321 -1.7399 180)
			(unlocked yes)
			(layer "F.Fab")
			(hide yes)
			(effects
				(font
					(size 1.016 1.016)
					(thickness 0.1524)
				)
			)
		)
		(property "Device Type" "C0201H13"
			(at -2.8321 -3.2639 180)
			(unlocked yes)
			(layer "F.Fab")
			(hide yes)
			(effects
				(font
					(size 1.016 1.016)
					(thickness 0.1524)
				)
			)
		)
		(duplicate_pad_numbers_are_jumpers no)
		(fp_rect
			(start -0.2794 0.6477)
			(end 0.2794 -0.6477)
			(stroke
				(width 0)
				(type default)
			)
			(fill no)
			(layer "F.CrtYd")
		)
		(fp_rect
			(start -0.2794 0.6477)
			(end 0.2794 -0.6477)
			(stroke
				(width 0)
				(type default)
			)
			(fill no)
			(layer "F.Fab")
		)
		(pad "1" smd custom
			(at 0 -0.2794 180)
			(size 0.0762 0.0762)
			(layers "F.Cu" "F.Mask" "F.Paste")
			(net "SAS_HDD_TX11_P")
			(options
				(clearance outline)
				(anchor circle)
			)
			(primitives
				(gr_poly
					(pts
						(arc
							(start 0.1524 -0.127)
							(mid 0.137521 -0.162921)
							(end 0.1016 -0.1778)
						)
						(arc
							(start -0.1016 -0.1778)
							(mid -0.137521 -0.162921)
							(end -0.1524 -0.127)
						)
						(arc
							(start -0.1524 0.127)
							(mid -0.137521 0.162921)
							(end -0.1016 0.1778)
						)
						(arc
							(start 0.1016 0.1778)
							(mid 0.137521 0.162921)
							(end 0.1524 0.127)
						)
					)
					(width 0)
					(fill yes)
				)
			)
		)
		(pad "2" smd custom
			(at 0 0.2794 180)
			(size 0.0762 0.0762)
			(layers "F.Cu" "F.Mask" "F.Paste")
			(net "SAS_EXP_GF_TX_DP15")
			(options
				(clearance outline)
				(anchor circle)
			)
			(primitives
				(gr_poly
					(pts
						(arc
							(start 0.1524 -0.127)
							(mid 0.137521 -0.162921)
							(end 0.1016 -0.1778)
						)
						(arc
							(start -0.1016 -0.1778)
							(mid -0.137521 -0.162921)
							(end -0.1524 -0.127)
						)
						(arc
							(start -0.1524 0.127)
							(mid -0.137521 0.162921)
							(end -0.1016 0.1778)
						)
						(arc
							(start 0.1016 0.1778)
							(mid 0.137521 0.162921)
							(end 0.1524 0.127)
						)
					)
					(width 0)
					(fill yes)
				)
			)
		)
	)
	(footprint ""
		(layer "F.Cu")
		(at 260.277864 -218.558872 180)
		(property "Reference" "PC93"
			(at 0 0 180)
			(layer "F.SilkS")
			(hide yes)
			(effects
				(font
					(size 1.27 1.27)
				)
			)
		)
		(property "Value" "SC1KP50V2KX-1GP"
			(at 1.1811 -2.7051 180)
			(unlocked yes)
			(layer "F.Fab")
			(hide yes)
			(effects
				(font
					(size 1.016 1.016)
					(thickness 0.1524)
				)
			)
		)
		(property "Device Type" "C402H22"
			(at 1.1811 -4.2291 180)
			(unlocked yes)
			(layer "F.Fab")
			(hide yes)
			(effects
				(font
					(size 1.016 1.016)
					(thickness 0.1524)
				)
			)
		)
		(duplicate_pad_numbers_are_jumpers no)
		(fp_rect
			(start -0.4318 0.9525)
			(end 0.4318 -0.9525)
			(stroke
				(width 0)
				(type default)
			)
			(fill no)
			(layer "F.CrtYd")
		)
		(fp_rect
			(start -0.4318 0.9525)
			(end 0.4318 -0.9525)
			(stroke
				(width 0)
				(type default)
			)
			(fill no)
			(layer "F.Fab")
		)
		(pad "1" smd custom
			(at 0 -0.4445 180)
			(size 0.1524 0.1524)
			(layers "F.Cu" "F.Mask" "F.Paste")
			(net "TPS74801_1V26_STBY_OUT")
			(options
				(clearance outline)
				(anchor circle)
			)
			(primitives
				(gr_poly
					(pts
						(arc
							(start 0.3048 -0.2032)
							(mid 0.275042 -0.275042)
							(end 0.2032 -0.3048)
						)
						(arc
							(start -0.2032 -0.3048)
							(mid -0.275042 -0.275042)
							(end -0.3048 -0.2032)
						)
						(arc
							(start -0.3048 0.2032)
							(mid -0.275042 0.275042)
							(end -0.2032 0.3048)
						)
						(arc
							(start 0.2032 0.3048)
							(mid 0.275042 0.275042)
							(end 0.3048 0.2032)
						)
					)
					(width 0)
					(fill yes)
				)
			)
		)
		(pad "2" smd custom
			(at 0 0.4445 180)
			(size 0.1524 0.1524)
			(layers "F.Cu" "F.Mask" "F.Paste")
			(net "TPS74801_1V26_STBY_FB")
			(options
				(clearance outline)
				(anchor circle)
			)
			(primitives
				(gr_poly
					(pts
						(arc
							(start 0.3048 -0.2032)
							(mid 0.275042 -0.275042)
							(end 0.2032 -0.3048)
						)
						(arc
							(start -0.2032 -0.3048)
							(mid -0.275042 -0.275042)
							(end -0.3048 -0.2032)
						)
						(arc
							(start -0.3048 0.2032)
							(mid -0.275042 0.275042)
							(end -0.2032 0.3048)
						)
						(arc
							(start 0.2032 0.3048)
							(mid 0.275042 0.275042)
							(end 0.3048 0.2032)
						)
					)
					(width 0)
					(fill yes)
				)
			)
		)
	)
	(footprint ""
		(layer "F.Cu")
		(at 318.008 -180.721 -90)
		(property "Reference" "R337"
			(at 0 0 270)
			(layer "F.SilkS")
			(hide yes)
			(effects
				(font
					(size 1.27 1.27)
				)
			)
		)
		(property "Value" "49K9R2F-L-GP"
			(at 0.064008 -3.993896 270)
			(unlocked yes)
			(layer "F.Fab")
			(hide yes)
			(effects
				(font
					(size 1.016 1.016)
					(thickness 0.1524)
				)
			)
		)
		(property "Device Type" "R402H16"
			(at 0.064008 -5.517896 270)
			(unlocked yes)
			(layer "F.Fab")
			(hide yes)
			(effects
				(font
					(size 1.016 1.016)
					(thickness 0.1524)
				)
			)
		)
		(duplicate_pad_numbers_are_jumpers no)
		(fp_line
			(start -0.508 -0.9398)
			(end -0.508 0.9398)
			(stroke
				(width 0.1524)
				(type default)
			)
			(layer "F.SilkS")
		)
		(fp_line
			(start 0.508 -0.9398)
			(end -0.508 -0.9398)
			(stroke
				(width 0.1524)
				(type default)
			)
			(layer "F.SilkS")
		)
		(fp_rect
			(start -0.508 0.9398)
			(end 0.508 -0.9398)
			(stroke
				(width 0)
				(type default)
			)
			(fill no)
			(layer "F.CrtYd")
		)
		(fp_rect
			(start -0.508 0.9398)
			(end 0.508 -0.9398)
			(stroke
				(width 0)
				(type default)
			)
			(fill no)
			(layer "F.Fab")
		)
		(pad "1" smd custom
			(at 0 -0.4445 270)
			(size 0.1397 0.1397)
			(layers "F.Cu" "F.Mask" "F.Paste")
			(net "GND")
			(options
				(clearance outline)
				(anchor circle)
			)
			(primitives
				(gr_poly
					(pts
						(arc
							(start -0.1778 -0.2794)
							(mid -0.249642 -0.249642)
							(end -0.2794 -0.1778)
						)
						(arc
							(start -0.2794 0.1778)
							(mid -0.249642 0.249642)
							(end -0.1778 0.2794)
						)
						(arc
							(start 0.1778 0.2794)
							(mid 0.249642 0.249642)
							(end 0.2794 0.1778)
						)
						(arc
							(start 0.2794 -0.1778)
							(mid 0.249642 -0.249642)
							(end 0.1778 -0.2794)
						)
					)
					(width 0)
					(fill yes)
				)
			)
		)
		(pad "2" smd custom
			(at 0 0.4445 270)
			(size 0.1397 0.1397)
			(layers "F.Cu" "F.Mask" "F.Paste")
			(net "ADCVREXT")
			(options
				(clearance outline)
				(anchor circle)
			)
			(primitives
				(gr_poly
					(pts
						(arc
							(start -0.1778 -0.2794)
							(mid -0.249642 -0.249642)
							(end -0.2794 -0.1778)
						)
						(arc
							(start -0.2794 0.1778)
							(mid -0.249642 0.249642)
							(end -0.1778 0.2794)
						)
						(arc
							(start 0.1778 0.2794)
							(mid 0.249642 0.249642)
							(end 0.2794 0.1778)
						)
						(arc
							(start 0.2794 -0.1778)
							(mid 0.249642 -0.249642)
							(end 0.1778 -0.2794)
						)
					)
					(width 0)
					(fill yes)
				)
			)
		)
	)
	(footprint ""
		(layer "F.Cu")
		(at 84.34197 -134.366)
		(property "Reference" "SU72"
			(at 0 0 0)
			(layer "F.SilkS")
			(hide yes)
			(effects
				(font
					(size 1.27 1.27)
				)
			)
		)
		(property "Value" "SNLVC8T245DGVR-GP"
			(at 0 -11.1252 0)
			(unlocked yes)
			(layer "F.Fab")
			(hide yes)
			(effects
				(font
					(size 1.016 1.016)
					(thickness 0.1524)
				)
			)
		)
		(property "Device Type" "TVSOP24H48"
			(at 0 -12.6492 0)
			(unlocked yes)
			(layer "F.Fab")
			(hide yes)
			(effects
				(font
					(size 1.016 1.016)
					(thickness 0.1524)
				)
			)
		)
		(duplicate_pad_numbers_are_jumpers no)
		(fp_line
			(start -2.9337 -1.397)
			(end -2.9337 1.397)
			(stroke
				(width 0.1524)
				(type default)
			)
			(layer "F.SilkS")
		)
		(fp_line
			(start -2.9337 -0.3683)
			(end -2.5654 0)
			(stroke
				(width 0.1524)
				(type default)
			)
			(layer "F.SilkS")
		)
		(fp_line
			(start -2.9337 1.397)
			(end 2.2987 1.397)
			(stroke
				(width 0.1524)
				(type default)
			)
			(layer "F.SilkS")
		)
		(fp_line
			(start -2.7559 1.397)
			(end -2.7559 3.8354)
			(stroke
				(width 0.508)
				(type default)
			)
			(layer "F.SilkS")
		)
		(fp_line
			(start -2.5654 0)
			(end -2.9337 0.3683)
			(stroke
				(width 0.1524)
				(type default)
			)
			(layer "F.SilkS")
		)
		(fp_line
			(start 2.2987 -1.397)
			(end -2.9337 -1.397)
			(stroke
				(width 0.1524)
				(type default)
			)
			(layer "F.SilkS")
		)
		(fp_line
			(start 2.2987 1.397)
			(end 2.2987 -1.397)
			(stroke
				(width 0.1524)
				(type default)
			)
			(layer "F.SilkS")
		)
		(fp_rect
			(start -3.0099 4.0894)
			(end 3.0099 -4.0894)
			(stroke
				(width 0)
				(type default)
			)
			(fill no)
			(layer "F.CrtYd")
		)
		(fp_poly
			(pts
				(xy -3.0099 -4.0894) (xy 3.0099 -4.0894) (xy 3.0099 4.0894) (xy -3.0099 4.0894)
			)
			(stroke
				(width 0)
				(type default)
			)
			(fill no)
			(layer "F.Fab")
		)
		(pad "1" smd rect
			(at -2.19964 2.8194)
			(size 0.2032 1.524)
			(layers "F.Cu" "F.Mask" "F.Paste")
			(net "P1V8_E")
		)
		(pad "2" smd rect
			(at -1.79959 2.8194)
			(size 0.2032 1.524)
			(layers "F.Cu" "F.Mask" "F.Paste")
			(net "P1V8_E")
		)
		(pad "3" smd rect
			(at -1.39954 2.8194)
			(size 0.2032 1.524)
			(layers "F.Cu" "F.Mask" "F.Paste")
			(net "EXP_GPIO_3")
		)
		(pad "4" smd rect
			(at -0.99949 2.8194)
			(size 0.2032 1.524)
			(layers "F.Cu" "F.Mask" "F.Paste")
			(net "EXP_GPIO_7")
		)
		(pad "5" smd rect
			(at -0.59944 2.8194)
			(size 0.2032 1.524)
			(layers "F.Cu" "F.Mask" "F.Paste")
			(net "EXP_GPIO_9")
		)
		(pad "6" smd rect
			(at -0.19939 2.8194)
			(size 0.2032 1.524)
			(layers "F.Cu" "F.Mask" "F.Paste")
			(net "EXP_GPIO_10")
		)
		(pad "7" smd rect
			(at 0.19939 2.8194)
			(size 0.2032 1.524)
			(layers "F.Cu" "F.Mask" "F.Paste")
			(net "EXP_GPIO_11")
		)
		(pad "8" smd rect
			(at 0.59944 2.8194)
			(size 0.2032 1.524)
			(layers "F.Cu" "F.Mask" "F.Paste")
			(net "Net_1015")
		)
		(pad "9" smd rect
			(at 0.99949 2.8194)
			(size 0.2032 1.524)
			(layers "F.Cu" "F.Mask" "F.Paste")
			(net "Net_1016")
		)
		(pad "10" smd rect
			(at 1.39954 2.8194)
			(size 0.2032 1.524)
			(layers "F.Cu" "F.Mask" "F.Paste")
			(net "Net_1017")
		)
		(pad "11" smd rect
			(at 1.79959 2.8194)
			(size 0.2032 1.524)
			(layers "F.Cu" "F.Mask" "F.Paste")
			(net "GND")
		)
		(pad "12" smd rect
			(at 2.19964 2.8194)
			(size 0.2032 1.524)
			(layers "F.Cu" "F.Mask" "F.Paste")
			(net "GND")
		)
		(pad "13" smd rect
			(at 2.19964 -2.8194)
			(size 0.2032 1.524)
			(layers "F.Cu" "F.Mask" "F.Paste")
			(net "GND")
		)
		(pad "14" smd rect
			(at 1.79959 -2.8194)
			(size 0.2032 1.524)
			(layers "F.Cu" "F.Mask" "F.Paste")
			(net "Net_1012")
		)
		(pad "15" smd rect
			(at 1.39954 -2.8194)
			(size 0.2032 1.524)
			(layers "F.Cu" "F.Mask" "F.Paste")
			(net "Net_1013")
		)
		(pad "16" smd rect
			(at 0.99949 -2.8194)
			(size 0.2032 1.524)
			(layers "F.Cu" "F.Mask" "F.Paste")
			(net "Net_1014")
		)
		(pad "17" smd rect
			(at 0.59944 -2.8194)
			(size 0.2032 1.524)
			(layers "F.Cu" "F.Mask" "F.Paste")
			(net "BUS_SW_EN")
		)
		(pad "18" smd rect
			(at 0.19939 -2.8194)
			(size 0.2032 1.524)
			(layers "F.Cu" "F.Mask" "F.Paste")
			(net "HDD_LED_RESET_N")
		)
		(pad "19" smd rect
			(at -0.19939 -2.8194)
			(size 0.2032 1.524)
			(layers "F.Cu" "F.Mask" "F.Paste")
			(net "HDD_PWR_RESET_N")
		)
		(pad "20" smd rect
			(at -0.59944 -2.8194)
			(size 0.2032 1.524)
			(layers "F.Cu" "F.Mask" "F.Paste")
			(net "EXP_HB")
		)
		(pad "21" smd rect
			(at -0.99949 -2.8194)
			(size 0.2032 1.524)
			(layers "F.Cu" "F.Mask" "F.Paste")
			(net "FAN_PWM_PCIE_R")
		)
		(pad "22" smd rect
			(at -1.39954 -2.8194)
			(size 0.2032 1.524)
			(layers "F.Cu" "F.Mask" "F.Paste")
			(net "GND")
		)
		(pad "23" smd rect
			(at -1.79959 -2.8194)
			(size 0.2032 1.524)
			(layers "F.Cu" "F.Mask" "F.Paste")
			(net "P3V3_STBY")
		)
		(pad "24" smd rect
			(at -2.19964 -2.8194)
			(size 0.2032 1.524)
			(layers "F.Cu" "F.Mask" "F.Paste")
			(net "P3V3_STBY")
		)
	)
	(footprint ""
		(layer "F.Cu")
		(at 271.901412 -190.937896)
		(property "Reference" "R299"
			(at 0 0 0)
			(layer "F.SilkS")
			(hide yes)
			(effects
				(font
					(size 1.27 1.27)
				)
			)
		)
		(property "Value" "0R2J-2-GP"
			(at 0.064008 -3.993896 0)
			(unlocked yes)
			(layer "F.Fab")
			(hide yes)
			(effects
				(font
					(size 1.016 1.016)
					(thickness 0.1524)
				)
			)
		)
		(property "Device Type" "R402H16"
			(at 0.064008 -5.517896 0)
			(unlocked yes)
			(layer "F.Fab")
			(hide yes)
			(effects
				(font
					(size 1.016 1.016)
					(thickness 0.1524)
				)
			)
		)
		(duplicate_pad_numbers_are_jumpers no)
		(fp_line
			(start -0.508 -0.9398)
			(end -0.508 0.9398)
			(stroke
				(width 0.1524)
				(type default)
			)
			(layer "F.SilkS")
		)
		(fp_line
			(start 0.508 -0.9398)
			(end -0.508 -0.9398)
			(stroke
				(width 0.1524)
				(type default)
			)
			(layer "F.SilkS")
		)
		(fp_rect
			(start -0.508 0.9398)
			(end 0.508 -0.9398)
			(stroke
				(width 0)
				(type default)
			)
			(fill no)
			(layer "F.CrtYd")
		)
		(fp_rect
			(start -0.508 0.9398)
			(end 0.508 -0.9398)
			(stroke
				(width 0)
				(type default)
			)
			(fill no)
			(layer "F.Fab")
		)
		(pad "1" smd custom
			(at 0 -0.4445)
			(size 0.1397 0.1397)
			(layers "F.Cu" "F.Mask" "F.Paste")
			(net "FM_BMC_RESET_N")
			(options
				(clearance outline)
				(anchor circle)
			)
			(primitives
				(gr_poly
					(pts
						(arc
							(start -0.1778 -0.2794)
							(mid -0.249642 -0.249642)
							(end -0.2794 -0.1778)
						)
						(arc
							(start -0.2794 0.1778)
							(mid -0.249642 0.249642)
							(end -0.1778 0.2794)
						)
						(arc
							(start 0.1778 0.2794)
							(mid 0.249642 0.249642)
							(end 0.2794 0.1778)
						)
						(arc
							(start 0.2794 -0.1778)
							(mid 0.249642 -0.249642)
							(end 0.1778 -0.2794)
						)
					)
					(width 0)
					(fill yes)
				)
			)
		)
		(pad "2" smd custom
			(at 0 0.4445)
			(size 0.1397 0.1397)
			(layers "F.Cu" "F.Mask" "F.Paste")
			(net "BMC0_SRST_N")
			(options
				(clearance outline)
				(anchor circle)
			)
			(primitives
				(gr_poly
					(pts
						(arc
							(start -0.1778 -0.2794)
							(mid -0.249642 -0.249642)
							(end -0.2794 -0.1778)
						)
						(arc
							(start -0.2794 0.1778)
							(mid -0.249642 0.249642)
							(end -0.1778 0.2794)
						)
						(arc
							(start 0.1778 0.2794)
							(mid 0.249642 0.249642)
							(end 0.2794 0.1778)
						)
						(arc
							(start 0.2794 -0.1778)
							(mid 0.249642 -0.249642)
							(end 0.1778 -0.2794)
						)
					)
					(width 0)
					(fill yes)
				)
			)
		)
	)
	(footprint ""
		(layer "F.Cu")
		(at 80.626966 -91.567 -90)
		(property "Reference" "SL22"
			(at 0 0 270)
			(layer "F.SilkS")
			(hide yes)
			(effects
				(font
					(size 1.27 1.27)
				)
			)
		)
		(property "Value" "MPZ2012S601AT-GP"
			(at 0 -4.2418 270)
			(unlocked yes)
			(layer "F.Fab")
			(hide yes)
			(effects
				(font
					(size 1.016 1.016)
					(thickness 0.1524)
				)
			)
		)
		(property "Device Type" "L805H42"
			(at 0 -5.7912 270)
			(unlocked yes)
			(layer "F.Fab")
			(hide yes)
			(effects
				(font
					(size 1.016 1.016)
					(thickness 0.1524)
				)
			)
		)
		(duplicate_pad_numbers_are_jumpers no)
		(fp_line
			(start -0.889 1.7018)
			(end -0.889 -1.7018)
			(stroke
				(width 0.1524)
				(type default)
			)
			(layer "F.SilkS")
		)
		(fp_line
			(start 0.889 1.7018)
			(end -0.889 1.7018)
			(stroke
				(width 0.1524)
				(type default)
			)
			(layer "F.SilkS")
		)
		(fp_line
			(start -0.889 -1.7018)
			(end 0.889 -1.7018)
			(stroke
				(width 0.1524)
				(type default)
			)
			(layer "F.SilkS")
		)
		(fp_line
			(start 0.889 -1.7018)
			(end 0.889 1.7018)
			(stroke
				(width 0.1524)
				(type default)
			)
			(layer "F.SilkS")
		)
		(fp_rect
			(start -0.9652 1.778)
			(end 0.9652 -1.778)
			(stroke
				(width 0)
				(type default)
			)
			(fill no)
			(layer "F.CrtYd")
		)
		(fp_rect
			(start -0.9652 1.778)
			(end 0.9652 -1.778)
			(stroke
				(width 0)
				(type default)
			)
			(fill no)
			(layer "F.Fab")
		)
		(pad "1" smd rect
			(at 0 -0.9652 270)
			(size 1.397 1.143)
			(layers "F.Cu" "F.Mask" "F.Paste")
			(net "SYSPLL_VDDA09")
		)
		(pad "2" smd rect
			(at 0 0.9652 270)
			(size 1.397 1.143)
			(layers "F.Cu" "F.Mask" "F.Paste")
			(net "P0V9_E")
		)
	)
	(footprint ""
		(layer "F.Cu")
		(at 56.134 -180.086 180)
		(property "Reference" "SR812"
			(at 0 0 180)
			(layer "F.SilkS")
			(hide yes)
			(effects
				(font
					(size 1.27 1.27)
				)
			)
		)
		(property "Value" "4K75R2F-1-GP"
			(at 0.064008 -3.993896 180)
			(unlocked yes)
			(layer "F.Fab")
			(hide yes)
			(effects
				(font
					(size 1.016 1.016)
					(thickness 0.1524)
				)
			)
		)
		(property "Device Type" "R402H16"
			(at 0.064008 -5.517896 180)
			(unlocked yes)
			(layer "F.Fab")
			(hide yes)
			(effects
				(font
					(size 1.016 1.016)
					(thickness 0.1524)
				)
			)
		)
		(duplicate_pad_numbers_are_jumpers no)
		(fp_line
			(start 0.508 -0.9398)
			(end -0.508 -0.9398)
			(stroke
				(width 0.1524)
				(type default)
			)
			(layer "F.SilkS")
		)
		(fp_line
			(start -0.508 -0.9398)
			(end -0.508 0.9398)
			(stroke
				(width 0.1524)
				(type default)
			)
			(layer "F.SilkS")
		)
		(fp_rect
			(start -0.508 0.9398)
			(end 0.508 -0.9398)
			(stroke
				(width 0)
				(type default)
			)
			(fill no)
			(layer "F.CrtYd")
		)
		(fp_rect
			(start -0.508 0.9398)
			(end 0.508 -0.9398)
			(stroke
				(width 0)
				(type default)
			)
			(fill no)
			(layer "F.Fab")
		)
		(pad "1" smd custom
			(at 0 -0.4445 180)
			(size 0.1397 0.1397)
			(layers "F.Cu" "F.Mask" "F.Paste")
			(net "P1V8_E")
			(options
				(clearance outline)
				(anchor circle)
			)
			(primitives
				(gr_poly
					(pts
						(arc
							(start -0.1778 -0.2794)
							(mid -0.249642 -0.249642)
							(end -0.2794 -0.1778)
						)
						(arc
							(start -0.2794 0.1778)
							(mid -0.249642 0.249642)
							(end -0.1778 0.2794)
						)
						(arc
							(start 0.1778 0.2794)
							(mid 0.249642 0.249642)
							(end 0.2794 0.1778)
						)
						(arc
							(start 0.2794 -0.1778)
							(mid 0.249642 -0.249642)
							(end 0.1778 -0.2794)
						)
					)
					(width 0)
					(fill yes)
				)
			)
		)
		(pad "2" smd custom
			(at 0 0.4445 180)
			(size 0.1397 0.1397)
			(layers "F.Cu" "F.Mask" "F.Paste")
			(net "ICE_TCK")
			(options
				(clearance outline)
				(anchor circle)
			)
			(primitives
				(gr_poly
					(pts
						(arc
							(start -0.1778 -0.2794)
							(mid -0.249642 -0.249642)
							(end -0.2794 -0.1778)
						)
						(arc
							(start -0.2794 0.1778)
							(mid -0.249642 0.249642)
							(end -0.1778 0.2794)
						)
						(arc
							(start 0.1778 0.2794)
							(mid 0.249642 0.249642)
							(end 0.2794 0.1778)
						)
						(arc
							(start 0.2794 -0.1778)
							(mid 0.249642 -0.249642)
							(end 0.1778 -0.2794)
						)
					)
					(width 0)
					(fill yes)
				)
			)
		)
	)
	(footprint ""
		(layer "F.Cu")
		(at 257.483864 -223.511872 90)
		(property "Reference" "PC100"
			(at 0 0 90)
			(layer "F.SilkS")
			(hide yes)
			(effects
				(font
					(size 1.27 1.27)
				)
			)
		)
		(property "Value" "SC470P50V2KX-3GP"
			(at 1.1811 -2.7051 90)
			(unlocked yes)
			(layer "F.Fab")
			(hide yes)
			(effects
				(font
					(size 1.016 1.016)
					(thickness 0.1524)
				)
			)
		)
		(property "Device Type" "C402H22"
			(at 1.1811 -4.2291 90)
			(unlocked yes)
			(layer "F.Fab")
			(hide yes)
			(effects
				(font
					(size 1.016 1.016)
					(thickness 0.1524)
				)
			)
		)
		(duplicate_pad_numbers_are_jumpers no)
		(fp_rect
			(start -0.4318 0.9525)
			(end 0.4318 -0.9525)
			(stroke
				(width 0)
				(type default)
			)
			(fill no)
			(layer "F.CrtYd")
		)
		(fp_rect
			(start -0.4318 0.9525)
			(end 0.4318 -0.9525)
			(stroke
				(width 0)
				(type default)
			)
			(fill no)
			(layer "F.Fab")
		)
		(pad "1" smd custom
			(at 0 -0.4445 90)
			(size 0.1524 0.1524)
			(layers "F.Cu" "F.Mask" "F.Paste")
			(net "GND")
			(options
				(clearance outline)
				(anchor circle)
			)
			(primitives
				(gr_poly
					(pts
						(arc
							(start 0.3048 -0.2032)
							(mid 0.275042 -0.275042)
							(end 0.2032 -0.3048)
						)
						(arc
							(start -0.2032 -0.3048)
							(mid -0.275042 -0.275042)
							(end -0.3048 -0.2032)
						)
						(arc
							(start -0.3048 0.2032)
							(mid -0.275042 0.275042)
							(end -0.2032 0.3048)
						)
						(arc
							(start 0.2032 0.3048)
							(mid 0.275042 0.275042)
							(end 0.3048 0.2032)
						)
					)
					(width 0)
					(fill yes)
				)
			)
		)
		(pad "2" smd custom
			(at 0 0.4445 90)
			(size 0.1524 0.1524)
			(layers "F.Cu" "F.Mask" "F.Paste")
			(net "TPS74801_1V26_STBY_SS")
			(options
				(clearance outline)
				(anchor circle)
			)
			(primitives
				(gr_poly
					(pts
						(arc
							(start 0.3048 -0.2032)
							(mid 0.275042 -0.275042)
							(end 0.2032 -0.3048)
						)
						(arc
							(start -0.2032 -0.3048)
							(mid -0.275042 -0.275042)
							(end -0.3048 -0.2032)
						)
						(arc
							(start -0.3048 0.2032)
							(mid -0.275042 0.275042)
							(end -0.2032 0.3048)
						)
						(arc
							(start 0.2032 0.3048)
							(mid 0.275042 0.275042)
							(end 0.3048 0.2032)
						)
					)
					(width 0)
					(fill yes)
				)
			)
		)
	)
	(footprint ""
		(layer "F.Cu")
		(at 117.475 -32.131)
		(property "Reference" "STP141"
			(at 0 0 0)
			(layer "F.SilkS")
			(hide yes)
			(effects
				(font
					(size 1.27 1.27)
				)
			)
		)
		(property "Value" "TPAD28"
			(at 0.0127 -1.8034 0)
			(unlocked yes)
			(layer "F.Fab")
			(hide yes)
			(effects
				(font
					(size 1.016 1.016)
					(thickness 0.1524)
				)
			)
		)
		(property "Device Type" "TPAD28"
			(at 0.0127 -3.3274 0)
			(unlocked yes)
			(layer "F.Fab")
			(hide yes)
			(effects
				(font
					(size 1.016 1.016)
					(thickness 0.1524)
				)
			)
		)
		(duplicate_pad_numbers_are_jumpers no)
		(fp_poly
			(pts
				(arc
					(start 0.3556 0)
					(mid -0.3556 0)
					(end 0.3556 0)
				)
			)
			(stroke
				(width 0)
				(type default)
			)
			(fill no)
			(layer "F.CrtYd")
		)
		(fp_poly
			(pts
				(arc
					(start 0.6096 0)
					(mid -0.6096 0)
					(end 0.6096 0)
				)
			)
			(stroke
				(width 0)
				(type default)
			)
			(fill no)
			(layer "F.Fab")
		)
		(pad "1" smd circle
			(at 0 0)
			(size 0.7112 0.7112)
			(layers "F.Cu" "F.Mask" "F.Paste")
			(net "IOC_GPIO_22")
		)
	)
	(footprint ""
		(layer "F.Cu")
		(at 16.071088 -202.185016)
		(property "Reference" "SR578"
			(at 0 0 0)
			(layer "F.SilkS")
			(hide yes)
			(effects
				(font
					(size 1.27 1.27)
				)
			)
		)
		(property "Value" "4K7R2F-GP"
			(at 0.064008 -3.993896 0)
			(unlocked yes)
			(layer "F.Fab")
			(hide yes)
			(effects
				(font
					(size 1.016 1.016)
					(thickness 0.1524)
				)
			)
		)
		(property "Device Type" "R402H16"
			(at 0.064008 -5.517896 0)
			(unlocked yes)
			(layer "F.Fab")
			(hide yes)
			(effects
				(font
					(size 1.016 1.016)
					(thickness 0.1524)
				)
			)
		)
		(duplicate_pad_numbers_are_jumpers no)
		(fp_line
			(start -0.508 -0.9398)
			(end -0.508 0.9398)
			(stroke
				(width 0.1524)
				(type default)
			)
			(layer "F.SilkS")
		)
		(fp_line
			(start 0.508 -0.9398)
			(end -0.508 -0.9398)
			(stroke
				(width 0.1524)
				(type default)
			)
			(layer "F.SilkS")
		)
		(fp_rect
			(start -0.508 0.9398)
			(end 0.508 -0.9398)
			(stroke
				(width 0)
				(type default)
			)
			(fill no)
			(layer "F.CrtYd")
		)
		(fp_rect
			(start -0.508 0.9398)
			(end 0.508 -0.9398)
			(stroke
				(width 0)
				(type default)
			)
			(fill no)
			(layer "F.Fab")
		)
		(pad "1" smd custom
			(at 0 -0.4445)
			(size 0.1397 0.1397)
			(layers "F.Cu" "F.Mask" "F.Paste")
			(net "BMC_I2C_SCL_10")
			(options
				(clearance outline)
				(anchor circle)
			)
			(primitives
				(gr_poly
					(pts
						(arc
							(start -0.1778 -0.2794)
							(mid -0.249642 -0.249642)
							(end -0.2794 -0.1778)
						)
						(arc
							(start -0.2794 0.1778)
							(mid -0.249642 0.249642)
							(end -0.1778 0.2794)
						)
						(arc
							(start 0.1778 0.2794)
							(mid 0.249642 0.249642)
							(end 0.2794 0.1778)
						)
						(arc
							(start 0.2794 -0.1778)
							(mid 0.249642 -0.249642)
							(end 0.1778 -0.2794)
						)
					)
					(width 0)
					(fill yes)
				)
			)
		)
		(pad "2" smd custom
			(at 0 0.4445)
			(size 0.1397 0.1397)
			(layers "F.Cu" "F.Mask" "F.Paste")
			(net "P3V3_STBY")
			(options
				(clearance outline)
				(anchor circle)
			)
			(primitives
				(gr_poly
					(pts
						(arc
							(start -0.1778 -0.2794)
							(mid -0.249642 -0.249642)
							(end -0.2794 -0.1778)
						)
						(arc
							(start -0.2794 0.1778)
							(mid -0.249642 0.249642)
							(end -0.1778 0.2794)
						)
						(arc
							(start 0.1778 0.2794)
							(mid 0.249642 0.249642)
							(end 0.2794 0.1778)
						)
						(arc
							(start 0.2794 -0.1778)
							(mid 0.249642 -0.249642)
							(end 0.1778 -0.2794)
						)
					)
					(width 0)
					(fill yes)
				)
			)
		)
	)
	(footprint ""
		(layer "F.Cu")
		(at 160.02 -146.05 -90)
		(property "Reference" "SC1287"
			(at 0 0 270)
			(layer "F.SilkS")
			(hide yes)
			(effects
				(font
					(size 1.27 1.27)
				)
			)
		)
		(property "Value" "SCD1U16V2KX-3GP"
			(at 1.1811 -2.7051 270)
			(unlocked yes)
			(layer "F.Fab")
			(hide yes)
			(effects
				(font
					(size 1.016 1.016)
					(thickness 0.1524)
				)
			)
		)
		(property "Device Type" "C402H22"
			(at 1.1811 -4.2291 270)
			(unlocked yes)
			(layer "F.Fab")
			(hide yes)
			(effects
				(font
					(size 1.016 1.016)
					(thickness 0.1524)
				)
			)
		)
		(duplicate_pad_numbers_are_jumpers no)
		(fp_rect
			(start -0.4318 0.9525)
			(end 0.4318 -0.9525)
			(stroke
				(width 0)
				(type default)
			)
			(fill no)
			(layer "F.CrtYd")
		)
		(fp_rect
			(start -0.4318 0.9525)
			(end 0.4318 -0.9525)
			(stroke
				(width 0)
				(type default)
			)
			(fill no)
			(layer "F.Fab")
		)
		(pad "1" smd custom
			(at 0 -0.4445 270)
			(size 0.1524 0.1524)
			(layers "F.Cu" "F.Mask" "F.Paste")
			(net "IOC_I2C_VREF")
			(options
				(clearance outline)
				(anchor circle)
			)
			(primitives
				(gr_poly
					(pts
						(arc
							(start 0.3048 -0.2032)
							(mid 0.275042 -0.275042)
							(end 0.2032 -0.3048)
						)
						(arc
							(start -0.2032 -0.3048)
							(mid -0.275042 -0.275042)
							(end -0.3048 -0.2032)
						)
						(arc
							(start -0.3048 0.2032)
							(mid -0.275042 0.275042)
							(end -0.2032 0.3048)
						)
						(arc
							(start 0.2032 0.3048)
							(mid 0.275042 0.275042)
							(end 0.3048 0.2032)
						)
					)
					(width 0)
					(fill yes)
				)
			)
		)
		(pad "2" smd custom
			(at 0 0.4445 270)
			(size 0.1524 0.1524)
			(layers "F.Cu" "F.Mask" "F.Paste")
			(net "GND")
			(options
				(clearance outline)
				(anchor circle)
			)
			(primitives
				(gr_poly
					(pts
						(arc
							(start 0.3048 -0.2032)
							(mid 0.275042 -0.275042)
							(end 0.2032 -0.3048)
						)
						(arc
							(start -0.2032 -0.3048)
							(mid -0.275042 -0.275042)
							(end -0.3048 -0.2032)
						)
						(arc
							(start -0.3048 0.2032)
							(mid -0.275042 0.275042)
							(end -0.2032 0.3048)
						)
						(arc
							(start 0.2032 0.3048)
							(mid 0.275042 0.275042)
							(end 0.3048 0.2032)
						)
					)
					(width 0)
					(fill yes)
				)
			)
		)
	)
	(footprint ""
		(layer "F.Cu")
		(at 296.545 -161.544 180)
		(property "Reference" "R284"
			(at 0 0 180)
			(layer "F.SilkS")
			(hide yes)
			(effects
				(font
					(size 1.27 1.27)
				)
			)
		)
		(property "Value" "0R2J-2-GP"
			(at 0.064008 -3.993896 180)
			(unlocked yes)
			(layer "F.Fab")
			(hide yes)
			(effects
				(font
					(size 1.016 1.016)
					(thickness 0.1524)
				)
			)
		)
		(property "Device Type" "R402H16"
			(at 0.064008 -5.517896 180)
			(unlocked yes)
			(layer "F.Fab")
			(hide yes)
			(effects
				(font
					(size 1.016 1.016)
					(thickness 0.1524)
				)
			)
		)
		(duplicate_pad_numbers_are_jumpers no)
		(fp_line
			(start 0.508 -0.9398)
			(end -0.508 -0.9398)
			(stroke
				(width 0.1524)
				(type default)
			)
			(layer "F.SilkS")
		)
		(fp_line
			(start -0.508 -0.9398)
			(end -0.508 0.9398)
			(stroke
				(width 0.1524)
				(type default)
			)
			(layer "F.SilkS")
		)
		(fp_rect
			(start -0.508 0.9398)
			(end 0.508 -0.9398)
			(stroke
				(width 0)
				(type default)
			)
			(fill no)
			(layer "F.CrtYd")
		)
		(fp_rect
			(start -0.508 0.9398)
			(end 0.508 -0.9398)
			(stroke
				(width 0)
				(type default)
			)
			(fill no)
			(layer "F.Fab")
		)
		(pad "1" smd custom
			(at 0 -0.4445 180)
			(size 0.1397 0.1397)
			(layers "F.Cu" "F.Mask" "F.Paste")
			(net "RMII_PHY_BMC_RXD1")
			(options
				(clearance outline)
				(anchor circle)
			)
			(primitives
				(gr_poly
					(pts
						(arc
							(start -0.1778 -0.2794)
							(mid -0.249642 -0.249642)
							(end -0.2794 -0.1778)
						)
						(arc
							(start -0.2794 0.1778)
							(mid -0.249642 0.249642)
							(end -0.1778 0.2794)
						)
						(arc
							(start 0.1778 0.2794)
							(mid 0.249642 0.249642)
							(end 0.2794 0.1778)
						)
						(arc
							(start 0.2794 -0.1778)
							(mid 0.249642 -0.249642)
							(end 0.1778 -0.2794)
						)
					)
					(width 0)
					(fill yes)
				)
			)
		)
		(pad "2" smd custom
			(at 0 0.4445 180)
			(size 0.1397 0.1397)
			(layers "F.Cu" "F.Mask" "F.Paste")
			(net "RMII0_PHY_BMC_C_RXD1")
			(options
				(clearance outline)
				(anchor circle)
			)
			(primitives
				(gr_poly
					(pts
						(arc
							(start -0.1778 -0.2794)
							(mid -0.249642 -0.249642)
							(end -0.2794 -0.1778)
						)
						(arc
							(start -0.2794 0.1778)
							(mid -0.249642 0.249642)
							(end -0.1778 0.2794)
						)
						(arc
							(start 0.1778 0.2794)
							(mid 0.249642 0.249642)
							(end 0.2794 0.1778)
						)
						(arc
							(start 0.2794 -0.1778)
							(mid 0.249642 -0.249642)
							(end 0.1778 -0.2794)
						)
					)
					(width 0)
					(fill yes)
				)
			)
		)
	)
	(footprint ""
		(layer "F.Cu")
		(at 157.459934 -11.210036)
		(property "Reference" "RJ1"
			(at 0 0 0)
			(layer "F.SilkS")
			(hide yes)
			(effects
				(font
					(size 1.27 1.27)
				)
			)
		)
		(property "Value" "RJ45-LED-12P-10-GP"
			(at -2.15773 -12.96797 0)
			(unlocked yes)
			(layer "F.Fab")
			(hide yes)
			(effects
				(font
					(size 1.016 1.016)
					(thickness 0.1524)
				)
			)
		)
		(property "Device Type" "XRJH-01H-D-H71-D81-W"
			(at -2.15773 -14.49197 0)
			(unlocked yes)
			(layer "F.Fab")
			(hide yes)
			(effects
				(font
					(size 1.016 1.016)
					(thickness 0.1524)
				)
			)
		)
		(duplicate_pad_numbers_are_jumpers no)
		(fp_line
			(start -10.033 -1.2446)
			(end -9.144 -1.2446)
			(stroke
				(width 0.1524)
				(type default)
			)
			(layer "F.SilkS")
		)
		(fp_line
			(start -10.033 1.2446)
			(end -10.033 -1.2446)
			(stroke
				(width 0.1524)
				(type default)
			)
			(layer "F.SilkS")
		)
		(fp_line
			(start -9.144 -11.176)
			(end 9.144 -11.176)
			(stroke
				(width 0.1524)
				(type default)
			)
			(layer "F.SilkS")
		)
		(fp_line
			(start -9.144 -1.2446)
			(end -9.144 -11.176)
			(stroke
				(width 0.1524)
				(type default)
			)
			(layer "F.SilkS")
		)
		(fp_line
			(start -9.144 1.2446)
			(end -10.033 1.2446)
			(stroke
				(width 0.1524)
				(type default)
			)
			(layer "F.SilkS")
		)
		(fp_line
			(start -9.144 13.462)
			(end -9.144 1.2446)
			(stroke
				(width 0.1524)
				(type default)
			)
			(layer "F.SilkS")
		)
		(fp_line
			(start 9.144 -11.176)
			(end 9.144 -1.2446)
			(stroke
				(width 0.1524)
				(type default)
			)
			(layer "F.SilkS")
		)
		(fp_line
			(start 9.144 -1.2446)
			(end 10.033 -1.2446)
			(stroke
				(width 0.1524)
				(type default)
			)
			(layer "F.SilkS")
		)
		(fp_line
			(start 9.144 1.2446)
			(end 9.144 13.462)
			(stroke
				(width 0.1524)
				(type default)
			)
			(layer "F.SilkS")
		)
		(fp_line
			(start 9.144 13.462)
			(end -9.144 13.462)
			(stroke
				(width 0.1524)
				(type default)
			)
			(layer "F.SilkS")
		)
		(fp_line
			(start 10.033 -1.2446)
			(end 10.033 1.2446)
			(stroke
				(width 0.1524)
				(type default)
			)
			(layer "F.SilkS")
		)
		(fp_line
			(start 10.033 1.2446)
			(end 9.144 1.2446)
			(stroke
				(width 0.1524)
				(type default)
			)
			(layer "F.SilkS")
		)
		(fp_circle
			(center -8.789924 0)
			(end -7.443724 0)
			(stroke
				(width 0.3048)
				(type default)
			)
			(fill no)
			(layer "F.SilkS")
		)
		(fp_circle
			(center -7.519924 6.35)
			(end -6.326124 6.35)
			(stroke
				(width 0.3048)
				(type default)
			)
			(fill no)
			(layer "F.SilkS")
		)
		(fp_circle
			(center -7.519924 8.89)
			(end -6.326124 8.89)
			(stroke
				(width 0.3048)
				(type default)
			)
			(fill no)
			(layer "F.SilkS")
		)
		(fp_circle
			(center -6.100064 -9.139936)
			(end -5.084064 -9.139936)
			(stroke
				(width 0.3048)
				(type default)
			)
			(fill no)
			(layer "F.SilkS")
		)
		(fp_circle
			(center -5.07492 -6.599936)
			(end -4.05892 -6.599936)
			(stroke
				(width 0.3048)
				(type default)
			)
			(fill no)
			(layer "F.SilkS")
		)
		(fp_circle
			(center -4.070096 -9.139936)
			(end -3.054096 -9.139936)
			(stroke
				(width 0.3048)
				(type default)
			)
			(fill no)
			(layer "F.SilkS")
		)
		(fp_circle
			(center -3.044952 -6.599936)
			(end -2.028952 -6.599936)
			(stroke
				(width 0.3048)
				(type default)
			)
			(fill no)
			(layer "F.SilkS")
		)
		(fp_circle
			(center -2.040128 -9.139936)
			(end -1.024128 -9.139936)
			(stroke
				(width 0.3048)
				(type default)
			)
			(fill no)
			(layer "F.SilkS")
		)
		(fp_circle
			(center -1.014984 -6.599936)
			(end 0.001016 -6.599936)
			(stroke
				(width 0.3048)
				(type default)
			)
			(fill no)
			(layer "F.SilkS")
		)
		(fp_circle
			(center 1.014984 -6.599936)
			(end 2.030984 -6.599936)
			(stroke
				(width 0.3048)
				(type default)
			)
			(fill no)
			(layer "F.SilkS")
		)
		(fp_circle
			(center 2.040128 -9.139936)
			(end 3.056128 -9.139936)
			(stroke
				(width 0.3048)
				(type default)
			)
			(fill no)
			(layer "F.SilkS")
		)
		(fp_circle
			(center 3.044952 -6.599936)
			(end 4.060952 -6.599936)
			(stroke
				(width 0.3048)
				(type default)
			)
			(fill no)
			(layer "F.SilkS")
		)
		(fp_circle
			(center 4.070096 -9.139936)
			(end 5.086096 -9.139936)
			(stroke
				(width 0.3048)
				(type default)
			)
			(fill no)
			(layer "F.SilkS")
		)
		(fp_circle
			(center 5.07492 -6.599936)
			(end 6.09092 -6.599936)
			(stroke
				(width 0.3048)
				(type default)
			)
			(fill no)
			(layer "F.SilkS")
		)
		(fp_circle
			(center 6.100064 -9.139936)
			(end 7.116064 -9.139936)
			(stroke
				(width 0.3048)
				(type default)
			)
			(fill no)
			(layer "F.SilkS")
		)
		(fp_circle
			(center 7.519924 3.81)
			(end 8.713724 3.81)
			(stroke
				(width 0.3048)
				(type default)
			)
			(fill no)
			(layer "F.SilkS")
		)
		(fp_circle
			(center 7.519924 6.35)
			(end 8.713724 6.35)
			(stroke
				(width 0.3048)
				(type default)
			)
			(fill no)
			(layer "F.SilkS")
		)
		(fp_circle
			(center 7.519924 8.89)
			(end 8.713724 8.89)
			(stroke
				(width 0.3048)
				(type default)
			)
			(fill no)
			(layer "F.SilkS")
		)
		(fp_circle
			(center 8.789924 0)
			(end 10.136124 0)
			(stroke
				(width 0.3048)
				(type default)
			)
			(fill no)
			(layer "F.SilkS")
		)
		(fp_rect
			(start -8.89 13.208)
			(end 8.89 -10.922)
			(stroke
				(width 0)
				(type default)
			)
			(fill no)
			(layer "F.CrtYd")
		)
		(fp_poly
			(pts
				(xy -9.398 13.716) (xy -9.398 1.4986) (xy -10.287 1.4986) (xy -10.287 -1.4986) (xy -9.398 -1.4986)
				(xy -9.398 -11.43) (xy 9.398 -11.43) (xy 9.398 -1.4986) (xy 10.287 -1.4986) (xy 10.287 -0.00635)
				(xy 8.89 -0.00635) (xy 8.89 -10.922) (xy -8.89 -10.922) (xy -8.89 13.208) (xy 8.89 13.208) (xy 8.89 0.00635)
				(xy 10.287 0.00635) (xy 10.287 1.4986) (xy 9.398 1.4986) (xy 9.398 13.716)
			)
			(stroke
				(width 0)
				(type default)
			)
			(fill no)
			(layer "F.CrtYd")
		)
		(fp_poly
			(pts
				(xy -9.398 13.716) (xy -9.398 1.4986) (xy -10.287 1.4986) (xy -10.287 -1.4986) (xy -9.398 -1.4986)
				(xy -9.398 -11.43) (xy 9.398 -11.43) (xy 9.398 -1.4986) (xy 10.287 -1.4986) (xy 10.287 1.4986) (xy 9.398 1.4986)
				(xy 9.398 13.716)
			)
			(stroke
				(width 0)
				(type default)
			)
			(fill no)
			(layer "F.Fab")
		)
		(pad "" np_thru_hole circle
			(at -4.824984 0)
			(size 0.254 0.254)
			(drill 3.2512)
			(layers "*.Cu" "*.Mask")
			(clearance 1.8542)
			(thermal_gap 1.8542)
		)
		(pad "" np_thru_hole circle
			(at 4.824984 0)
			(size 0.254 0.254)
			(drill 3.2512)
			(layers "*.Cu" "*.Mask")
			(clearance 1.8542)
			(thermal_gap 1.8542)
		)
		(pad "1" thru_hole circle
			(at 5.07492 -6.599936)
			(size 1.3208 1.3208)
			(drill 0.9144)
			(layers "*.Cu" "*.Mask")
			(remove_unused_layers no)
			(net "RJ45_GND_1")
			(clearance 0.1524)
			(thermal_gap 0.1524)
		)
		(pad "2" thru_hole circle
			(at 3.044952 -6.599936)
			(size 1.3208 1.3208)
			(drill 0.9144)
			(layers "*.Cu" "*.Mask")
			(remove_unused_layers no)
			(net "TP_LAN_5")
			(clearance 0.1524)
			(thermal_gap 0.1524)
		)
		(pad "3" thru_hole circle
			(at 1.014984 -6.599936)
			(size 1.3208 1.3208)
			(drill 0.9144)
			(layers "*.Cu" "*.Mask")
			(remove_unused_layers no)
			(net "TP_LAN_7")
			(clearance 0.1524)
			(thermal_gap 0.1524)
		)
		(pad "4" thru_hole circle
			(at -1.014984 -6.599936)
			(size 1.3208 1.3208)
			(drill 0.9144)
			(layers "*.Cu" "*.Mask")
			(remove_unused_layers no)
			(net "BCM5221_MB_RX_DP")
			(clearance 0.1524)
			(thermal_gap 0.1524)
		)
		(pad "5" thru_hole circle
			(at -3.044952 -6.599936)
			(size 1.3208 1.3208)
			(drill 0.9144)
			(layers "*.Cu" "*.Mask")
			(remove_unused_layers no)
			(net "BCM5221_MB_RX_DN")
			(clearance 0.1524)
			(thermal_gap 0.1524)
		)
		(pad "6" thru_hole circle
			(at -5.07492 -6.599936)
			(size 1.3208 1.3208)
			(drill 0.9144)
			(layers "*.Cu" "*.Mask")
			(remove_unused_layers no)
			(net "PHY_AVDD")
			(clearance 0.1524)
			(thermal_gap 0.1524)
		)
		(pad "7" thru_hole circle
			(at 6.100064 -9.139936)
			(size 1.3208 1.3208)
			(drill 0.9144)
			(layers "*.Cu" "*.Mask")
			(remove_unused_layers no)
			(net "RJ45_GND_7")
			(clearance 0.1524)
			(thermal_gap 0.1524)
		)
		(pad "8" thru_hole circle
			(at 4.070096 -9.139936)
			(size 1.3208 1.3208)
			(drill 0.9144)
			(layers "*.Cu" "*.Mask")
			(remove_unused_layers no)
			(net "TP_LAN_4")
			(clearance 0.1524)
			(thermal_gap 0.1524)
		)
		(pad "9" thru_hole circle
			(at 2.040128 -9.139936)
			(size 1.3208 1.3208)
			(drill 0.9144)
			(layers "*.Cu" "*.Mask")
			(remove_unused_layers no)
			(net "TP_LAN_6")
			(clearance 0.1524)
			(thermal_gap 0.1524)
		)
		(pad "10" thru_hole circle
			(at -2.040128 -9.139936)
			(size 1.3208 1.3208)
			(drill 0.9144)
			(layers "*.Cu" "*.Mask")
			(remove_unused_layers no)
			(net "BCM5221_MB_TX_DN")
			(clearance 0.1524)
			(thermal_gap 0.1524)
		)
		(pad "11" thru_hole circle
			(at -4.070096 -9.139936)
			(size 1.3208 1.3208)
			(drill 0.9144)
			(layers "*.Cu" "*.Mask")
			(remove_unused_layers no)
			(net "BCM5221_MB_TX_DP")
			(clearance 0.1524)
			(thermal_gap 0.1524)
		)
		(pad "12" thru_hole circle
			(at -6.100064 -9.139936)
			(size 1.3208 1.3208)
			(drill 0.9144)
			(layers "*.Cu" "*.Mask")
			(remove_unused_layers no)
			(net "PHY_AVDD")
			(clearance 0.1524)
			(thermal_gap 0.1524)
		)
		(pad "13" thru_hole circle
			(at 8.789924 0)
			(size 1.9812 1.9812)
			(drill 1.5748)
			(layers "*.Cu" "*.Mask")
			(remove_unused_layers no)
			(net "GND")
			(clearance 0.1524)
			(thermal_gap 0.1524)
		)
		(pad "14" thru_hole circle
			(at -8.789924 0)
			(size 1.9812 1.9812)
			(drill 1.5748)
			(layers "*.Cu" "*.Mask")
			(remove_unused_layers no)
			(net "GND")
			(clearance 0.1524)
			(thermal_gap 0.1524)
		)
		(pad "D1" thru_hole circle
			(at -7.519924 6.35)
			(size 1.6764 1.6764)
			(drill 1.27)
			(layers "*.Cu" "*.Mask")
			(remove_unused_layers no)
			(net "PHY_ACTLED_N")
			(clearance 0.1524)
			(thermal_gap 0.1524)
		)
		(pad "D2" thru_hole circle
			(at -7.519924 8.89)
			(size 1.6764 1.6764)
			(drill 1.27)
			(layers "*.Cu" "*.Mask")
			(remove_unused_layers no)
			(net "LED_MDI0_ACT")
			(clearance 0.1524)
			(thermal_gap 0.1524)
		)
		(pad "D3" thru_hole circle
			(at 7.519924 3.81)
			(size 1.6764 1.6764)
			(drill 1.27)
			(layers "*.Cu" "*.Mask")
			(remove_unused_layers no)
			(net "Net_2092")
			(clearance 0.1524)
			(thermal_gap 0.1524)
		)
		(pad "D4" thru_hole circle
			(at 7.519924 6.35)
			(size 1.6764 1.6764)
			(drill 1.27)
			(layers "*.Cu" "*.Mask")
			(remove_unused_layers no)
			(net "LED_MDI0_LINK")
			(clearance 0.1524)
			(thermal_gap 0.1524)
		)
		(pad "D5" thru_hole circle
			(at 7.519924 8.89)
			(size 1.6764 1.6764)
			(drill 1.27)
			(layers "*.Cu" "*.Mask")
			(remove_unused_layers no)
			(net "PHY_LNKLED_N")
			(clearance 0.1524)
			(thermal_gap 0.1524)
		)
		(zone
			(layer "F.Cu")
			(hatch none 0.5)
			(connect_pads
				(clearance 0)
			)
			(min_thickness 0.25)
			(keepout
				(tracks allowed)
				(vias not_allowed)
				(pads allowed)
				(copperpour not_allowed)
				(footprints allowed)
			)
			(placement
				(enabled no)
				(sheetname "")
			)
			(fill
				(thermal_gap 0.5)
				(thermal_bridge_width 0.5)
				(island_removal_mode 0)
			)
			(polygon
				(pts
					(xy 148.26996 -12.800076) (xy 148.26996 -15.40002) (xy 150.370032 -15.40002) (xy 150.370032 -12.800076)
				)
			)
		)
		(zone
			(layer "F.Cu")
			(hatch none 0.5)
			(connect_pads
				(clearance 0)
			)
			(min_thickness 0.25)
			(keepout
				(tracks not_allowed)
				(vias allowed)
				(pads allowed)
				(copperpour not_allowed)
				(footprints allowed)
			)
			(placement
				(enabled no)
				(sheetname "")
			)
			(fill
				(thermal_gap 0.5)
				(thermal_bridge_width 0.5)
				(island_removal_mode 0)
			)
			(polygon
				(pts
					(xy 148.26996 -12.800076) (xy 150.370032 -12.800076) (xy 150.370032 -15.40002) (xy 148.26996 -15.40002)
				)
			)
		)
		(zone
			(layer "F.Cu")
			(hatch none 0.5)
			(connect_pads
				(clearance 0)
			)
			(min_thickness 0.25)
			(keepout
				(tracks not_allowed)
				(vias allowed)
				(pads allowed)
				(copperpour not_allowed)
				(footprints allowed)
			)
			(placement
				(enabled no)
				(sheetname "")
			)
			(fill
				(thermal_gap 0.5)
				(thermal_bridge_width 0.5)
				(island_removal_mode 0)
			)
			(polygon
				(pts
					(xy 164.549836 -12.800076) (xy 166.649908 -12.800076) (xy 166.649908 -15.40002) (xy 164.549836 -15.40002)
				)
			)
		)
		(zone
			(layer "F.Cu")
			(hatch none 0.5)
			(connect_pads
				(clearance 0)
			)
			(min_thickness 0.25)
			(keepout
				(tracks allowed)
				(vias not_allowed)
				(pads allowed)
				(copperpour not_allowed)
				(footprints allowed)
			)
			(placement
				(enabled no)
				(sheetname "")
			)
			(fill
				(thermal_gap 0.5)
				(thermal_bridge_width 0.5)
				(island_removal_mode 0)
			)
			(polygon
				(pts
					(xy 166.649908 -12.800076) (xy 166.649908 -15.40002) (xy 164.549836 -15.40002) (xy 164.549836 -12.800076)
				)
			)
		)
		(zone
			(layer "F.Cu")
			(hatch none 0.5)
			(connect_pads
				(clearance 0)
			)
			(min_thickness 0.25)
			(keepout
				(tracks not_allowed)
				(vias allowed)
				(pads allowed)
				(copperpour not_allowed)
				(footprints allowed)
			)
			(placement
				(enabled no)
				(sheetname "")
			)
			(fill
				(thermal_gap 0.5)
				(thermal_bridge_width 0.5)
				(island_removal_mode 0)
			)
			(polygon
				(pts
					(xy 148.26996 2.29997) (xy 166.649908 2.29997) (xy 166.649908 -1.249934) (xy 164.141658 -1.249934)
					(xy 164.141658 -7.200138) (xy 150.77821 -7.200138) (xy 150.77821 -1.249934) (xy 148.26996 -1.249934)
				)
			)
		)
		(zone
			(layer "F.Cu")
			(hatch none 0.5)
			(connect_pads
				(clearance 0)
			)
			(min_thickness 0.25)
			(keepout
				(tracks allowed)
				(vias not_allowed)
				(pads allowed)
				(copperpour not_allowed)
				(footprints allowed)
			)
			(placement
				(enabled no)
				(sheetname "")
			)
			(fill
				(thermal_gap 0.5)
				(thermal_bridge_width 0.5)
				(island_removal_mode 0)
			)
			(polygon
				(pts
					(xy 148.26996 2.29997) (xy 166.649908 2.29997) (xy 166.649908 -1.249934) (xy 164.141658 -1.249934)
					(xy 164.141658 -7.200138) (xy 150.77821 -7.200138) (xy 150.77821 -1.249934) (xy 148.26996 -1.249934)
				)
			)
		)
		(zone
			(layers "F.Cu" "B.Cu" "In1.Cu" "In2.Cu" "In3.Cu" "In4.Cu" "In5.Cu" "In6.Cu")
			(hatch none 0.5)
			(connect_pads
				(clearance 0)
			)
			(min_thickness 0.25)
			(keepout
				(tracks not_allowed)
				(vias allowed)
				(pads allowed)
				(copperpour not_allowed)
				(footprints allowed)
			)
			(placement
				(enabled no)
				(sheetname "")
			)
			(fill
				(thermal_gap 0.5)
				(thermal_bridge_width 0.5)
				(island_removal_mode 0)
			)
			(polygon
				(pts
					(arc
						(start 154.56535 -11.210036)
						(mid 150.70455 -11.210036)
						(end 154.56535 -11.210036)
					)
				)
			)
		)
		(zone
			(layers "F.Cu" "B.Cu" "In1.Cu" "In2.Cu" "In3.Cu" "In4.Cu" "In5.Cu" "In6.Cu")
			(hatch none 0.5)
			(connect_pads
				(clearance 0)
			)
			(min_thickness 0.25)
			(keepout
				(tracks not_allowed)
				(vias allowed)
				(pads allowed)
				(copperpour not_allowed)
				(footprints allowed)
			)
			(placement
				(enabled no)
				(sheetname "")
			)
			(fill
				(thermal_gap 0.5)
				(thermal_bridge_width 0.5)
				(island_removal_mode 0)
			)
			(polygon
				(pts
					(arc
						(start 164.215318 -11.210036)
						(mid 160.354518 -11.210036)
						(end 164.215318 -11.210036)
					)
				)
			)
		)
	)
	(footprint ""
		(layer "F.Cu")
		(at 305.308 -182.88)
		(property "Reference" "TP114"
			(at 0 0 0)
			(layer "F.SilkS")
			(hide yes)
			(effects
				(font
					(size 1.27 1.27)
				)
			)
		)
		(property "Value" "TPAD28"
			(at 0.0127 -1.8034 0)
			(unlocked yes)
			(layer "F.Fab")
			(hide yes)
			(effects
				(font
					(size 1.016 1.016)
					(thickness 0.1524)
				)
			)
		)
		(property "Device Type" "TPAD28"
			(at 0.0127 -3.3274 0)
			(unlocked yes)
			(layer "F.Fab")
			(hide yes)
			(effects
				(font
					(size 1.016 1.016)
					(thickness 0.1524)
				)
			)
		)
		(duplicate_pad_numbers_are_jumpers no)
		(fp_poly
			(pts
				(arc
					(start 0.3556 0)
					(mid -0.3556 0)
					(end 0.3556 0)
				)
			)
			(stroke
				(width 0)
				(type default)
			)
			(fill no)
			(layer "F.CrtYd")
		)
		(fp_poly
			(pts
				(arc
					(start 0.6096 0)
					(mid -0.6096 0)
					(end 0.6096 0)
				)
			)
			(stroke
				(width 0)
				(type default)
			)
			(fill no)
			(layer "F.Fab")
		)
		(pad "1" smd circle
			(at 0 0)
			(size 0.7112 0.7112)
			(layers "F.Cu" "F.Mask" "F.Paste")
			(net "TP_BMC_GPIOM5")
		)
	)
	(footprint ""
		(layer "F.Cu")
		(at 206.206852 -111.64316)
		(property "Reference" "PC226"
			(at 0 0 0)
			(layer "F.SilkS")
			(hide yes)
			(effects
				(font
					(size 1.27 1.27)
				)
			)
		)
		(property "Value" "SC22U25V5MX-GP"
			(at -0.0762 -6.1214 0)
			(unlocked yes)
			(layer "F.Fab")
			(hide yes)
			(effects
				(font
					(size 1.016 1.016)
					(thickness 0.1524)
				)
			)
		)
		(property "Device Type" "C805H58"
			(at -0.0762 -8.1534 0)
			(unlocked yes)
			(layer "F.Fab")
			(hide yes)
			(effects
				(font
					(size 1.016 1.016)
					(thickness 0.1524)
				)
			)
		)
		(duplicate_pad_numbers_are_jumpers no)
		(fp_line
			(start 0.635 0)
			(end -0.635 0)
			(stroke
				(width 0.508)
				(type default)
			)
			(layer "F.SilkS")
		)
		(fp_rect
			(start -0.9652 1.778)
			(end 0.9652 -1.778)
			(stroke
				(width 0)
				(type default)
			)
			(fill no)
			(layer "F.CrtYd")
		)
		(fp_poly
			(pts
				(xy -0.9652 -1.778) (xy 0.9652 -1.778) (xy 0.9652 1.778) (xy -0.9652 1.778)
			)
			(stroke
				(width 0)
				(type default)
			)
			(fill no)
			(layer "F.Fab")
		)
		(pad "1" smd rect
			(at 0 -0.9652)
			(size 1.397 1.143)
			(layers "F.Cu" "F.Mask" "F.Paste")
			(net "P1V5_E_VIN")
		)
		(pad "2" smd rect
			(at 0 0.9652)
			(size 1.397 1.143)
			(layers "F.Cu" "F.Mask" "F.Paste")
			(net "GND")
		)
	)
	(footprint ""
		(layer "F.Cu")
		(at 141.97457 -93.9546)
		(property "Reference" "R593"
			(at 0 0 0)
			(layer "F.SilkS")
			(hide yes)
			(effects
				(font
					(size 1.27 1.27)
				)
			)
		)
		(property "Value" "0R2J-2-GP"
			(at 0.064008 -3.993896 0)
			(unlocked yes)
			(layer "F.Fab")
			(hide yes)
			(effects
				(font
					(size 1.016 1.016)
					(thickness 0.1524)
				)
			)
		)
		(property "Device Type" "R402H16"
			(at 0.064008 -5.517896 0)
			(unlocked yes)
			(layer "F.Fab")
			(hide yes)
			(effects
				(font
					(size 1.016 1.016)
					(thickness 0.1524)
				)
			)
		)
		(duplicate_pad_numbers_are_jumpers no)
		(fp_line
			(start -0.508 -0.9398)
			(end -0.508 0.9398)
			(stroke
				(width 0.1524)
				(type default)
			)
			(layer "F.SilkS")
		)
		(fp_line
			(start 0.508 -0.9398)
			(end -0.508 -0.9398)
			(stroke
				(width 0.1524)
				(type default)
			)
			(layer "F.SilkS")
		)
		(fp_rect
			(start -0.508 0.9398)
			(end 0.508 -0.9398)
			(stroke
				(width 0)
				(type default)
			)
			(fill no)
			(layer "F.CrtYd")
		)
		(fp_rect
			(start -0.508 0.9398)
			(end 0.508 -0.9398)
			(stroke
				(width 0)
				(type default)
			)
			(fill no)
			(layer "F.Fab")
		)
		(pad "1" smd custom
			(at 0 -0.4445)
			(size 0.1397 0.1397)
			(layers "F.Cu" "F.Mask" "F.Paste")
			(net "BMC_I2C_D_SDA")
			(options
				(clearance outline)
				(anchor circle)
			)
			(primitives
				(gr_poly
					(pts
						(arc
							(start -0.1778 -0.2794)
							(mid -0.249642 -0.249642)
							(end -0.2794 -0.1778)
						)
						(arc
							(start -0.2794 0.1778)
							(mid -0.249642 0.249642)
							(end -0.1778 0.2794)
						)
						(arc
							(start 0.1778 0.2794)
							(mid 0.249642 0.249642)
							(end 0.2794 0.1778)
						)
						(arc
							(start 0.2794 -0.1778)
							(mid 0.249642 -0.249642)
							(end 0.1778 -0.2794)
						)
					)
					(width 0)
					(fill yes)
				)
			)
		)
		(pad "2" smd custom
			(at 0 0.4445)
			(size 0.1397 0.1397)
			(layers "F.Cu" "F.Mask" "F.Paste")
			(net "TEMP_3_SDA")
			(options
				(clearance outline)
				(anchor circle)
			)
			(primitives
				(gr_poly
					(pts
						(arc
							(start -0.1778 -0.2794)
							(mid -0.249642 -0.249642)
							(end -0.2794 -0.1778)
						)
						(arc
							(start -0.2794 0.1778)
							(mid -0.249642 0.249642)
							(end -0.1778 0.2794)
						)
						(arc
							(start 0.1778 0.2794)
							(mid 0.249642 0.249642)
							(end 0.2794 0.1778)
						)
						(arc
							(start 0.2794 -0.1778)
							(mid 0.249642 -0.249642)
							(end 0.1778 -0.2794)
						)
					)
					(width 0)
					(fill yes)
				)
			)
		)
	)
	(footprint ""
		(layer "F.Cu")
		(at 347.599 -98.552 90)
		(property "Reference" "PC15"
			(at 0 0 90)
			(layer "F.SilkS")
			(hide yes)
			(effects
				(font
					(size 1.27 1.27)
				)
			)
		)
		(property "Value" "SC22U10V5MX-GP"
			(at -0.0762 -6.1214 90)
			(unlocked yes)
			(layer "F.Fab")
			(hide yes)
			(effects
				(font
					(size 1.016 1.016)
					(thickness 0.1524)
				)
			)
		)
		(property "Device Type" "C805H56"
			(at -0.0762 -8.1534 90)
			(unlocked yes)
			(layer "F.Fab")
			(hide yes)
			(effects
				(font
					(size 1.016 1.016)
					(thickness 0.1524)
				)
			)
		)
		(duplicate_pad_numbers_are_jumpers no)
		(fp_line
			(start 0.635 0)
			(end -0.635 0)
			(stroke
				(width 0.508)
				(type default)
			)
			(layer "F.SilkS")
		)
		(fp_rect
			(start -0.9652 1.778)
			(end 0.9652 -1.778)
			(stroke
				(width 0)
				(type default)
			)
			(fill no)
			(layer "F.CrtYd")
		)
		(fp_poly
			(pts
				(xy -0.9652 -1.778) (xy 0.9652 -1.778) (xy 0.9652 1.778) (xy -0.9652 1.778)
			)
			(stroke
				(width 0)
				(type default)
			)
			(fill no)
			(layer "F.Fab")
		)
		(pad "1" smd rect
			(at 0 -0.9652 90)
			(size 1.397 1.143)
			(layers "F.Cu" "F.Mask" "F.Paste")
			(net "P5V_STBY")
		)
		(pad "2" smd rect
			(at 0 0.9652 90)
			(size 1.397 1.143)
			(layers "F.Cu" "F.Mask" "F.Paste")
			(net "GND")
		)
	)
	(footprint ""
		(layer "F.Cu")
		(at 332.867 -10.541)
		(property "Reference" "R85"
			(at 0 0 0)
			(layer "F.SilkS")
			(hide yes)
			(effects
				(font
					(size 1.27 1.27)
				)
			)
		)
		(property "Value" "150R2F-1-GP"
			(at 0.064008 -3.993896 0)
			(unlocked yes)
			(layer "F.Fab")
			(hide yes)
			(effects
				(font
					(size 1.016 1.016)
					(thickness 0.1524)
				)
			)
		)
		(property "Device Type" "R402H16"
			(at 0.064008 -5.517896 0)
			(unlocked yes)
			(layer "F.Fab")
			(hide yes)
			(effects
				(font
					(size 1.016 1.016)
					(thickness 0.1524)
				)
			)
		)
		(duplicate_pad_numbers_are_jumpers no)
		(fp_line
			(start -0.508 -0.9398)
			(end -0.508 0.9398)
			(stroke
				(width 0.1524)
				(type default)
			)
			(layer "F.SilkS")
		)
		(fp_line
			(start 0.508 -0.9398)
			(end -0.508 -0.9398)
			(stroke
				(width 0.1524)
				(type default)
			)
			(layer "F.SilkS")
		)
		(fp_rect
			(start -0.508 0.9398)
			(end 0.508 -0.9398)
			(stroke
				(width 0)
				(type default)
			)
			(fill no)
			(layer "F.CrtYd")
		)
		(fp_rect
			(start -0.508 0.9398)
			(end 0.508 -0.9398)
			(stroke
				(width 0)
				(type default)
			)
			(fill no)
			(layer "F.Fab")
		)
		(pad "1" smd custom
			(at 0 -0.4445)
			(size 0.1397 0.1397)
			(layers "F.Cu" "F.Mask" "F.Paste")
			(net "P3V3_STBY")
			(options
				(clearance outline)
				(anchor circle)
			)
			(primitives
				(gr_poly
					(pts
						(arc
							(start -0.1778 -0.2794)
							(mid -0.249642 -0.249642)
							(end -0.2794 -0.1778)
						)
						(arc
							(start -0.2794 0.1778)
							(mid -0.249642 0.249642)
							(end -0.1778 0.2794)
						)
						(arc
							(start 0.1778 0.2794)
							(mid 0.249642 0.249642)
							(end 0.2794 0.1778)
						)
						(arc
							(start 0.2794 -0.1778)
							(mid 0.249642 -0.249642)
							(end 0.1778 -0.2794)
						)
					)
					(width 0)
					(fill yes)
				)
			)
		)
		(pad "2" smd custom
			(at 0 0.4445)
			(size 0.1397 0.1397)
			(layers "F.Cu" "F.Mask" "F.Paste")
			(net "CONSOLE_LED_0")
			(options
				(clearance outline)
				(anchor circle)
			)
			(primitives
				(gr_poly
					(pts
						(arc
							(start -0.1778 -0.2794)
							(mid -0.249642 -0.249642)
							(end -0.2794 -0.1778)
						)
						(arc
							(start -0.2794 0.1778)
							(mid -0.249642 0.249642)
							(end -0.1778 0.2794)
						)
						(arc
							(start 0.1778 0.2794)
							(mid 0.249642 0.249642)
							(end 0.2794 0.1778)
						)
						(arc
							(start 0.2794 -0.1778)
							(mid 0.249642 -0.249642)
							(end 0.1778 -0.2794)
						)
					)
					(width 0)
					(fill yes)
				)
			)
		)
	)
	(footprint ""
		(layer "F.Cu")
		(at 322.190872 -119.071136)
		(property "Reference" "PC29"
			(at 0 0 0)
			(layer "F.SilkS")
			(hide yes)
			(effects
				(font
					(size 1.27 1.27)
				)
			)
		)
		(property "Value" "SC1U10V3KX-4GP-U"
			(at 0 -2.8194 0)
			(unlocked yes)
			(layer "F.Fab")
			(hide yes)
			(effects
				(font
					(size 1.016 1.016)
					(thickness 0.1524)
				)
			)
		)
		(property "Device Type" "C603H36"
			(at 0 -4.3434 0)
			(unlocked yes)
			(layer "F.Fab")
			(hide yes)
			(effects
				(font
					(size 1.016 1.016)
					(thickness 0.1524)
				)
			)
		)
		(duplicate_pad_numbers_are_jumpers no)
		(fp_line
			(start 0.508 0)
			(end -0.508 0)
			(stroke
				(width 0.2032)
				(type default)
			)
			(layer "F.SilkS")
		)
		(fp_rect
			(start -0.5842 1.3335)
			(end 0.5842 -1.3335)
			(stroke
				(width 0)
				(type default)
			)
			(fill no)
			(layer "F.CrtYd")
		)
		(fp_rect
			(start -0.5842 1.3335)
			(end 0.5842 -1.3335)
			(stroke
				(width 0)
				(type default)
			)
			(fill no)
			(layer "F.Fab")
		)
		(pad "1" smd custom
			(at 0 -0.762)
			(size 0.2159 0.2159)
			(layers "F.Cu" "F.Mask" "F.Paste")
			(net "GND")
			(options
				(clearance outline)
				(anchor circle)
			)
			(primitives
				(gr_poly
					(pts
						(arc
							(start -0.3302 -0.4318)
							(mid -0.402042 -0.402042)
							(end -0.4318 -0.3302)
						)
						(arc
							(start -0.4318 0.3302)
							(mid -0.402042 0.402042)
							(end -0.3302 0.4318)
						)
						(arc
							(start 0.3302 0.4318)
							(mid 0.402042 0.402042)
							(end 0.4318 0.3302)
						)
						(arc
							(start 0.4318 -0.3302)
							(mid 0.402042 -0.402042)
							(end 0.3302 -0.4318)
						)
					)
					(width 0)
					(fill yes)
				)
			)
		)
		(pad "2" smd custom
			(at 0 0.762)
			(size 0.2159 0.2159)
			(layers "F.Cu" "F.Mask" "F.Paste")
			(net "P3V3_STBY_VREG")
			(options
				(clearance outline)
				(anchor circle)
			)
			(primitives
				(gr_poly
					(pts
						(arc
							(start -0.3302 -0.4318)
							(mid -0.402042 -0.402042)
							(end -0.4318 -0.3302)
						)
						(arc
							(start -0.4318 0.3302)
							(mid -0.402042 0.402042)
							(end -0.3302 0.4318)
						)
						(arc
							(start 0.3302 0.4318)
							(mid 0.402042 0.402042)
							(end 0.4318 0.3302)
						)
						(arc
							(start 0.4318 -0.3302)
							(mid 0.402042 -0.402042)
							(end 0.3302 -0.4318)
						)
					)
					(width 0)
					(fill yes)
				)
			)
		)
	)
	(footprint ""
		(layer "F.Cu")
		(at 181.728872 -192.146936)
		(property "Reference" "R430"
			(at 0 0 0)
			(layer "F.SilkS")
			(hide yes)
			(effects
				(font
					(size 1.27 1.27)
				)
			)
		)
		(property "Value" "10KR2F-2-GP"
			(at 0.064008 -3.993896 0)
			(unlocked yes)
			(layer "F.Fab")
			(hide yes)
			(effects
				(font
					(size 1.016 1.016)
					(thickness 0.1524)
				)
			)
		)
		(property "Device Type" "R402H16"
			(at 0.064008 -5.517896 0)
			(unlocked yes)
			(layer "F.Fab")
			(hide yes)
			(effects
				(font
					(size 1.016 1.016)
					(thickness 0.1524)
				)
			)
		)
		(duplicate_pad_numbers_are_jumpers no)
		(fp_line
			(start -0.508 -0.9398)
			(end -0.508 0.9398)
			(stroke
				(width 0.1524)
				(type default)
			)
			(layer "F.SilkS")
		)
		(fp_line
			(start 0.508 -0.9398)
			(end -0.508 -0.9398)
			(stroke
				(width 0.1524)
				(type default)
			)
			(layer "F.SilkS")
		)
		(fp_rect
			(start -0.508 0.9398)
			(end 0.508 -0.9398)
			(stroke
				(width 0)
				(type default)
			)
			(fill no)
			(layer "F.CrtYd")
		)
		(fp_rect
			(start -0.508 0.9398)
			(end 0.508 -0.9398)
			(stroke
				(width 0)
				(type default)
			)
			(fill no)
			(layer "F.Fab")
		)
		(pad "1" smd custom
			(at 0 -0.4445)
			(size 0.1397 0.1397)
			(layers "F.Cu" "F.Mask" "F.Paste")
			(net "I2C_C_BUF_READY")
			(options
				(clearance outline)
				(anchor circle)
			)
			(primitives
				(gr_poly
					(pts
						(arc
							(start -0.1778 -0.2794)
							(mid -0.249642 -0.249642)
							(end -0.2794 -0.1778)
						)
						(arc
							(start -0.2794 0.1778)
							(mid -0.249642 0.249642)
							(end -0.1778 0.2794)
						)
						(arc
							(start 0.1778 0.2794)
							(mid 0.249642 0.249642)
							(end 0.2794 0.1778)
						)
						(arc
							(start 0.2794 -0.1778)
							(mid 0.249642 -0.249642)
							(end 0.1778 -0.2794)
						)
					)
					(width 0)
					(fill yes)
				)
			)
		)
		(pad "2" smd custom
			(at 0 0.4445)
			(size 0.1397 0.1397)
			(layers "F.Cu" "F.Mask" "F.Paste")
			(net "P3V3_STBY")
			(options
				(clearance outline)
				(anchor circle)
			)
			(primitives
				(gr_poly
					(pts
						(arc
							(start -0.1778 -0.2794)
							(mid -0.249642 -0.249642)
							(end -0.2794 -0.1778)
						)
						(arc
							(start -0.2794 0.1778)
							(mid -0.249642 0.249642)
							(end -0.1778 0.2794)
						)
						(arc
							(start 0.1778 0.2794)
							(mid 0.249642 0.249642)
							(end 0.2794 0.1778)
						)
						(arc
							(start 0.2794 -0.1778)
							(mid 0.249642 -0.249642)
							(end 0.1778 -0.2794)
						)
					)
					(width 0)
					(fill yes)
				)
			)
		)
	)
	(footprint ""
		(layer "F.Cu")
		(at 268.224 -171.069)
		(property "Reference" "TP82"
			(at 0 0 0)
			(layer "F.SilkS")
			(hide yes)
			(effects
				(font
					(size 1.27 1.27)
				)
			)
		)
		(property "Value" "TPAD28"
			(at 0.0127 -1.8034 0)
			(unlocked yes)
			(layer "F.Fab")
			(hide yes)
			(effects
				(font
					(size 1.016 1.016)
					(thickness 0.1524)
				)
			)
		)
		(property "Device Type" "TPAD28"
			(at 0.0127 -3.3274 0)
			(unlocked yes)
			(layer "F.Fab")
			(hide yes)
			(effects
				(font
					(size 1.016 1.016)
					(thickness 0.1524)
				)
			)
		)
		(duplicate_pad_numbers_are_jumpers no)
		(fp_poly
			(pts
				(arc
					(start 0.3556 0)
					(mid -0.3556 0)
					(end 0.3556 0)
				)
			)
			(stroke
				(width 0)
				(type default)
			)
			(fill no)
			(layer "F.CrtYd")
		)
		(fp_poly
			(pts
				(arc
					(start 0.6096 0)
					(mid -0.6096 0)
					(end 0.6096 0)
				)
			)
			(stroke
				(width 0)
				(type default)
			)
			(fill no)
			(layer "F.Fab")
		)
		(pad "1" smd circle
			(at 0 0)
			(size 0.7112 0.7112)
			(layers "F.Cu" "F.Mask" "F.Paste")
			(net "BMC_MBC_I2C_E_SCL")
		)
	)
	(footprint ""
		(layer "F.Cu")
		(at 162.274504 -24.184356 180)
		(property "Reference" "R419"
			(at 0 0 180)
			(layer "F.SilkS")
			(hide yes)
			(effects
				(font
					(size 1.27 1.27)
				)
			)
		)
		(property "Value" "0R2J-2-GP"
			(at 0.064008 -3.993896 180)
			(unlocked yes)
			(layer "F.Fab")
			(hide yes)
			(effects
				(font
					(size 1.016 1.016)
					(thickness 0.1524)
				)
			)
		)
		(property "Device Type" "R402H16"
			(at 0.064008 -5.517896 180)
			(unlocked yes)
			(layer "F.Fab")
			(hide yes)
			(effects
				(font
					(size 1.016 1.016)
					(thickness 0.1524)
				)
			)
		)
		(duplicate_pad_numbers_are_jumpers no)
		(fp_line
			(start 0.508 -0.9398)
			(end -0.508 -0.9398)
			(stroke
				(width 0.1524)
				(type default)
			)
			(layer "F.SilkS")
		)
		(fp_line
			(start -0.508 -0.9398)
			(end -0.508 0.9398)
			(stroke
				(width 0.1524)
				(type default)
			)
			(layer "F.SilkS")
		)
		(fp_rect
			(start -0.508 0.9398)
			(end 0.508 -0.9398)
			(stroke
				(width 0)
				(type default)
			)
			(fill no)
			(layer "F.CrtYd")
		)
		(fp_rect
			(start -0.508 0.9398)
			(end 0.508 -0.9398)
			(stroke
				(width 0)
				(type default)
			)
			(fill no)
			(layer "F.Fab")
		)
		(pad "1" smd custom
			(at 0 -0.4445 180)
			(size 0.1397 0.1397)
			(layers "F.Cu" "F.Mask" "F.Paste")
			(net "TP_LAN_7")
			(options
				(clearance outline)
				(anchor circle)
			)
			(primitives
				(gr_poly
					(pts
						(arc
							(start -0.1778 -0.2794)
							(mid -0.249642 -0.249642)
							(end -0.2794 -0.1778)
						)
						(arc
							(start -0.2794 0.1778)
							(mid -0.249642 0.249642)
							(end -0.1778 0.2794)
						)
						(arc
							(start 0.1778 0.2794)
							(mid 0.249642 0.249642)
							(end 0.2794 0.1778)
						)
						(arc
							(start 0.2794 -0.1778)
							(mid 0.249642 -0.249642)
							(end 0.1778 -0.2794)
						)
					)
					(width 0)
					(fill yes)
				)
			)
		)
		(pad "2" smd custom
			(at 0 0.4445 180)
			(size 0.1397 0.1397)
			(layers "F.Cu" "F.Mask" "F.Paste")
			(net "GND")
			(options
				(clearance outline)
				(anchor circle)
			)
			(primitives
				(gr_poly
					(pts
						(arc
							(start -0.1778 -0.2794)
							(mid -0.249642 -0.249642)
							(end -0.2794 -0.1778)
						)
						(arc
							(start -0.2794 0.1778)
							(mid -0.249642 0.249642)
							(end -0.1778 0.2794)
						)
						(arc
							(start 0.1778 0.2794)
							(mid 0.249642 0.249642)
							(end 0.2794 0.1778)
						)
						(arc
							(start 0.2794 -0.1778)
							(mid 0.249642 -0.249642)
							(end 0.1778 -0.2794)
						)
					)
					(width 0)
					(fill yes)
				)
			)
		)
	)
	(footprint ""
		(layer "F.Cu")
		(at 47.999904 -71.900034)
		(property "Reference" "CN2"
			(at 0 0 0)
			(layer "F.SilkS")
			(hide yes)
			(effects
				(font
					(size 1.27 1.27)
				)
			)
		)
		(property "Value" "AMP-CONN36-2R-GP"
			(at -10.922 -7.0612 0)
			(unlocked yes)
			(layer "F.Fab")
			(hide yes)
			(effects
				(font
					(size 1.016 1.016)
					(thickness 0.1524)
				)
			)
		)
		(property "Device Type" "G40MR36U11AEU"
			(at -10.922 -8.5852 0)
			(unlocked yes)
			(layer "F.Fab")
			(hide yes)
			(effects
				(font
					(size 1.016 1.016)
					(thickness 0.1524)
				)
			)
		)
		(duplicate_pad_numbers_are_jumpers no)
		(fp_line
			(start -9.7409 2.6416)
			(end -9.0424 2.6416)
			(stroke
				(width 0.1524)
				(type default)
			)
			(layer "F.SilkS")
		)
		(fp_line
			(start -9.7409 14.224)
			(end -9.7409 2.6416)
			(stroke
				(width 0.1524)
				(type default)
			)
			(layer "F.SilkS")
		)
		(fp_line
			(start -9.0424 -8.8646)
			(end 9.0424 -8.8646)
			(stroke
				(width 0.1524)
				(type default)
			)
			(layer "F.SilkS")
		)
		(fp_line
			(start -9.0424 2.6416)
			(end -9.0424 -8.8646)
			(stroke
				(width 0.1524)
				(type default)
			)
			(layer "F.SilkS")
		)
		(fp_line
			(start -7.3406 -8.9535)
			(end -6.6548 -8.9535)
			(stroke
				(width 0.3302)
				(type default)
			)
			(layer "F.SilkS")
		)
		(fp_line
			(start 9.0424 -8.8646)
			(end 9.0424 2.6416)
			(stroke
				(width 0.1524)
				(type default)
			)
			(layer "F.SilkS")
		)
		(fp_line
			(start 9.0424 2.6416)
			(end 9.7409 2.6416)
			(stroke
				(width 0.1524)
				(type default)
			)
			(layer "F.SilkS")
		)
		(fp_line
			(start 9.7409 2.6416)
			(end 9.7409 14.224)
			(stroke
				(width 0.1524)
				(type default)
			)
			(layer "F.SilkS")
		)
		(fp_line
			(start 9.7409 14.224)
			(end -9.7409 14.224)
			(stroke
				(width 0.1524)
				(type default)
			)
			(layer "F.SilkS")
		)
		(fp_poly
			(pts
				(xy -7.007606 -8.94334) (xy -6.372606 -9.57834) (xy -7.642606 -9.57834)
			)
			(stroke
				(width 0)
				(type default)
			)
			(fill yes)
			(layer "F.SilkS")
		)
		(fp_poly
			(pts
				(xy -9.0297 13.97) (xy -9.0297 2.8956) (xy -8.6995 2.8956) (xy -8.6995 -8.6106) (xy 8.6995 -8.6106)
				(xy 8.6995 2.8956) (xy 9.0297 2.8956) (xy 9.0297 13.97)
			)
			(stroke
				(width 0)
				(type default)
			)
			(fill no)
			(layer "F.CrtYd")
		)
		(fp_poly
			(pts
				(xy -9.9949 16.7894) (xy -9.9949 2.3876) (xy -9.2964 2.3876) (xy -9.2964 -9.1186) (xy 9.2964 -9.1186)
				(xy 9.2964 2.3876) (xy 9.9949 2.3876) (xy 9.9949 16.7894) (xy 0.00508 16.7894) (xy 0.00508 13.97)
				(xy 9.0297 13.97) (xy 9.0297 2.8956) (xy 8.6995 2.8956) (xy 8.6995 -8.6106) (xy -8.6995 -8.6106)
				(xy -8.6995 2.8956) (xy -9.0297 2.8956) (xy -9.0297 13.97) (xy 0 13.97) (xy 0 16.7894)
			)
			(stroke
				(width 0)
				(type default)
			)
			(fill no)
			(layer "F.CrtYd")
		)
		(fp_poly
			(pts
				(xy -9.9949 16.7894) (xy -9.9949 2.3876) (xy -9.2964 2.3876) (xy -9.2964 -9.1186) (xy 9.2964 -9.1186)
				(xy 9.2964 2.3876) (xy 9.9949 2.3876) (xy 9.9949 16.7894)
			)
			(stroke
				(width 0)
				(type default)
			)
			(fill no)
			(layer "F.Fab")
		)
		(pad "" np_thru_hole circle
			(at -7.999984 0)
			(size 0.254 0.254)
			(drill 1.5748)
			(layers "*.Cu" "*.Mask")
			(clearance 1.016)
			(thermal_gap 1.016)
		)
		(pad "" np_thru_hole circle
			(at 7.999984 0)
			(size 0.254 0.254)
			(drill 1.5748)
			(layers "*.Cu" "*.Mask")
			(clearance 1.016)
			(thermal_gap 1.016)
		)
		(pad "37" thru_hole circle
			(at -8.899906 5.72008)
			(size 1.1684 1.1684)
			(drill 0.8128)
			(layers "*.Cu" "*.Mask")
			(remove_unused_layers no)
			(net "GND")
			(clearance 0.1778)
			(thermal_gap 0.1778)
		)
		(pad "38" thru_hole circle
			(at -8.899906 9.219946)
			(size 1.1684 1.1684)
			(drill 0.8128)
			(layers "*.Cu" "*.Mask")
			(remove_unused_layers no)
			(net "GND")
			(clearance 0.1778)
			(thermal_gap 0.1778)
		)
		(pad "39" thru_hole circle
			(at -8.899906 11.219942)
			(size 1.1684 1.1684)
			(drill 0.8128)
			(layers "*.Cu" "*.Mask")
			(remove_unused_layers no)
			(net "GND")
			(clearance 0.1778)
			(thermal_gap 0.1778)
		)
		(pad "40" thru_hole circle
			(at 8.899906 12.21994)
			(size 1.1684 1.1684)
			(drill 0.8128)
			(layers "*.Cu" "*.Mask")
			(remove_unused_layers no)
			(net "GND")
			(clearance 0.1778)
			(thermal_gap 0.1778)
		)
		(pad "41" thru_hole circle
			(at 8.899906 9.219946)
			(size 1.1684 1.1684)
			(drill 0.8128)
			(layers "*.Cu" "*.Mask")
			(remove_unused_layers no)
			(net "GND")
			(clearance 0.1778)
			(thermal_gap 0.1778)
		)
		(pad "42" thru_hole circle
			(at 8.899906 5.72008)
			(size 1.1684 1.1684)
			(drill 0.8128)
			(layers "*.Cu" "*.Mask")
			(remove_unused_layers no)
			(net "GND")
			(clearance 0.1778)
			(thermal_gap 0.1778)
		)
		(pad "A1" smd oval
			(at -6.599936 -5.180076)
			(size 0.3556 1.8034)
			(layers "F.Cu" "F.Mask" "F.Paste")
			(net "GND")
		)
		(pad "A2" smd oval
			(at -5.80009 -5.180076)
			(size 0.3556 1.8034)
			(layers "F.Cu" "F.Mask" "F.Paste")
			(net "MINI_RX_P_20")
		)
		(pad "A3" smd oval
			(at -4.99999 -5.180076)
			(size 0.3556 1.8034)
			(layers "F.Cu" "F.Mask" "F.Paste")
			(net "MINI_RX_N_20")
		)
		(pad "A4" smd oval
			(at -4.19989 -5.180076)
			(size 0.3556 1.8034)
			(layers "F.Cu" "F.Mask" "F.Paste")
			(net "GND")
		)
		(pad "A5" smd oval
			(at -3.400044 -5.180076)
			(size 0.3556 1.8034)
			(layers "F.Cu" "F.Mask" "F.Paste")
			(net "MINI_RX_P_21")
		)
		(pad "A6" smd oval
			(at -2.599944 -5.180076)
			(size 0.3556 1.8034)
			(layers "F.Cu" "F.Mask" "F.Paste")
			(net "MINI_RX_N_21")
		)
		(pad "A7" smd oval
			(at -1.800098 -5.180076)
			(size 0.3556 1.8034)
			(layers "F.Cu" "F.Mask" "F.Paste")
			(net "GND")
		)
		(pad "A8" smd oval
			(at -0.999998 -5.180076)
			(size 0.3556 1.8034)
			(layers "F.Cu" "F.Mask" "F.Paste")
			(net "INT_CONN_A_SB7")
		)
		(pad "A9" smd oval
			(at -0.199898 -5.180076)
			(size 0.3556 1.8034)
			(layers "F.Cu" "F.Mask" "F.Paste")
			(net "INT_CONN_A_SB3")
		)
		(pad "A10" smd oval
			(at 0.599948 -5.180076)
			(size 0.3556 1.8034)
			(layers "F.Cu" "F.Mask" "F.Paste")
			(net "INT_CONN_A_SB4")
		)
		(pad "A11" smd oval
			(at 1.400048 -5.180076)
			(size 0.3556 1.8034)
			(layers "F.Cu" "F.Mask" "F.Paste")
			(net "INT_CONN_A_SB5")
		)
		(pad "A12" smd oval
			(at 2.199894 -5.180076)
			(size 0.3556 1.8034)
			(layers "F.Cu" "F.Mask" "F.Paste")
			(net "GND")
		)
		(pad "A13" smd oval
			(at 2.999994 -5.180076)
			(size 0.3556 1.8034)
			(layers "F.Cu" "F.Mask" "F.Paste")
			(net "MINI_RX_P_22")
		)
		(pad "A14" smd oval
			(at 3.800094 -5.180076)
			(size 0.3556 1.8034)
			(layers "F.Cu" "F.Mask" "F.Paste")
			(net "MINI_RX_N_22")
		)
		(pad "A15" smd oval
			(at 4.59994 -5.180076)
			(size 0.3556 1.8034)
			(layers "F.Cu" "F.Mask" "F.Paste")
			(net "GND")
		)
		(pad "A16" smd oval
			(at 5.40004 -5.180076)
			(size 0.3556 1.8034)
			(layers "F.Cu" "F.Mask" "F.Paste")
			(net "MINI_RX_P_23")
		)
		(pad "A17" smd oval
			(at 6.199886 -5.180076)
			(size 0.3556 1.8034)
			(layers "F.Cu" "F.Mask" "F.Paste")
			(net "MINI_RX_N_23")
		)
		(pad "A18" smd oval
			(at 6.999986 -5.180076)
			(size 0.3556 1.8034)
			(layers "F.Cu" "F.Mask" "F.Paste")
			(net "GND")
		)
		(pad "B1" smd oval
			(at -6.999986 -7.690104)
			(size 0.3556 1.8034)
			(layers "F.Cu" "F.Mask" "F.Paste")
			(net "GND")
		)
		(pad "B2" smd oval
			(at -6.199886 -7.690104)
			(size 0.3556 1.8034)
			(layers "F.Cu" "F.Mask" "F.Paste")
			(net "SAS_EXP2CONN_TX_P_20")
		)
		(pad "B3" smd oval
			(at -5.40004 -7.690104)
			(size 0.3556 1.8034)
			(layers "F.Cu" "F.Mask" "F.Paste")
			(net "SAS_EXP2CONN_TX_N_20")
		)
		(pad "B4" smd oval
			(at -4.59994 -7.690104)
			(size 0.3556 1.8034)
			(layers "F.Cu" "F.Mask" "F.Paste")
			(net "GND")
		)
		(pad "B5" smd oval
			(at -3.800094 -7.690104)
			(size 0.3556 1.8034)
			(layers "F.Cu" "F.Mask" "F.Paste")
			(net "SAS_EXP2CONN_TX_P_21")
		)
		(pad "B6" smd oval
			(at -2.999994 -7.690104)
			(size 0.3556 1.8034)
			(layers "F.Cu" "F.Mask" "F.Paste")
			(net "SAS_EXP2CONN_TX_N_21")
		)
		(pad "B7" smd oval
			(at -2.199894 -7.690104)
			(size 0.3556 1.8034)
			(layers "F.Cu" "F.Mask" "F.Paste")
			(net "GND")
		)
		(pad "B8" smd oval
			(at -1.400048 -7.690104)
			(size 0.3556 1.8034)
			(layers "F.Cu" "F.Mask" "F.Paste")
			(net "INT_CONN_A_SB0")
		)
		(pad "B9" smd oval
			(at -0.599948 -7.690104)
			(size 0.3556 1.8034)
			(layers "F.Cu" "F.Mask" "F.Paste")
			(net "INT_CONN_A_SB1")
		)
		(pad "B10" smd oval
			(at 0.199898 -7.690104)
			(size 0.3556 1.8034)
			(layers "F.Cu" "F.Mask" "F.Paste")
			(net "INT_CONN_A_SB2")
		)
		(pad "B11" smd oval
			(at 0.999998 -7.690104)
			(size 0.3556 1.8034)
			(layers "F.Cu" "F.Mask" "F.Paste")
			(net "INT_CONN_A_SB6")
		)
		(pad "B12" smd oval
			(at 1.800098 -7.690104)
			(size 0.3556 1.8034)
			(layers "F.Cu" "F.Mask" "F.Paste")
			(net "GND")
		)
		(pad "B13" smd oval
			(at 2.599944 -7.690104)
			(size 0.3556 1.8034)
			(layers "F.Cu" "F.Mask" "F.Paste")
			(net "SAS_EXP2CONN_TX_P_22")
		)
		(pad "B14" smd oval
			(at 3.400044 -7.690104)
			(size 0.3556 1.8034)
			(layers "F.Cu" "F.Mask" "F.Paste")
			(net "SAS_EXP2CONN_TX_N_22")
		)
		(pad "B15" smd oval
			(at 4.19989 -7.690104)
			(size 0.3556 1.8034)
			(layers "F.Cu" "F.Mask" "F.Paste")
			(net "GND")
		)
		(pad "B16" smd oval
			(at 4.99999 -7.690104)
			(size 0.3556 1.8034)
			(layers "F.Cu" "F.Mask" "F.Paste")
			(net "SAS_EXP2CONN_TX_P_23")
		)
		(pad "B17" smd oval
			(at 5.80009 -7.690104)
			(size 0.3556 1.8034)
			(layers "F.Cu" "F.Mask" "F.Paste")
			(net "SAS_EXP2CONN_TX_N_23")
		)
		(pad "B18" smd oval
			(at 6.599936 -7.690104)
			(size 0.3556 1.8034)
			(layers "F.Cu" "F.Mask" "F.Paste")
			(net "GND")
		)
		(zone
			(layer "F.Cu")
			(hatch none 0.5)
			(connect_pads
				(clearance 0)
			)
			(min_thickness 0.25)
			(keepout
				(tracks allowed)
				(vias not_allowed)
				(pads allowed)
				(copperpour not_allowed)
				(footprints allowed)
			)
			(placement
				(enabled no)
				(sheetname "")
			)
			(fill
				(thermal_gap 0.5)
				(thermal_bridge_width 0.5)
				(island_removal_mode 0)
			)
			(polygon
				(pts
					(xy 38.849808 -68.49999) (xy 38.849808 -66.764154) (xy 39.349934 -66.764154) (xy 39.349934 -68.49999)
				)
			)
		)
		(zone
			(layer "F.Cu")
			(hatch none 0.5)
			(connect_pads
				(clearance 0)
			)
			(min_thickness 0.25)
			(keepout
				(tracks not_allowed)
				(vias allowed)
				(pads allowed)
				(copperpour not_allowed)
				(footprints allowed)
			)
			(placement
				(enabled no)
				(sheetname "")
			)
			(fill
				(thermal_gap 0.5)
				(thermal_bridge_width 0.5)
				(island_removal_mode 0)
			)
			(polygon
				(pts
					(xy 38.849808 -66.764154) (xy 39.349934 -66.764154) (xy 39.349934 -68.49999) (xy 38.849808 -68.49999)
				)
			)
		)
		(zone
			(layer "F.Cu")
			(hatch none 0.5)
			(connect_pads
				(clearance 0)
			)
			(min_thickness 0.25)
			(keepout
				(tracks allowed)
				(vias not_allowed)
				(pads allowed)
				(copperpour not_allowed)
				(footprints allowed)
			)
			(placement
				(enabled no)
				(sheetname "")
			)
			(fill
				(thermal_gap 0.5)
				(thermal_bridge_width 0.5)
				(island_removal_mode 0)
			)
			(polygon
				(pts
					(xy 38.849808 -65.595754) (xy 38.849808 -63.264288) (xy 39.349934 -63.264288) (xy 39.349934 -65.595754)
				)
			)
		)
		(zone
			(layer "F.Cu")
			(hatch none 0.5)
			(connect_pads
				(clearance 0)
			)
			(min_thickness 0.25)
			(keepout
				(tracks not_allowed)
				(vias allowed)
				(pads allowed)
				(copperpour not_allowed)
				(footprints allowed)
			)
			(placement
				(enabled no)
				(sheetname "")
			)
			(fill
				(thermal_gap 0.5)
				(thermal_bridge_width 0.5)
				(island_removal_mode 0)
			)
			(polygon
				(pts
					(xy 38.849808 -63.264288) (xy 39.349934 -63.264288) (xy 39.349934 -65.595754) (xy 38.849808 -65.595754)
				)
			)
		)
		(zone
			(layer "F.Cu")
			(hatch none 0.5)
			(connect_pads
				(clearance 0)
			)
			(min_thickness 0.25)
			(keepout
				(tracks allowed)
				(vias not_allowed)
				(pads allowed)
				(copperpour not_allowed)
				(footprints allowed)
			)
			(placement
				(enabled no)
				(sheetname "")
			)
			(fill
				(thermal_gap 0.5)
				(thermal_bridge_width 0.5)
				(island_removal_mode 0)
			)
			(polygon
				(pts
					(xy 38.849808 -62.095888) (xy 38.849808 -61.264292) (xy 39.349934 -61.264292) (xy 39.349934 -62.095888)
				)
			)
		)
		(zone
			(layer "F.Cu")
			(hatch none 0.5)
			(connect_pads
				(clearance 0)
			)
			(min_thickness 0.25)
			(keepout
				(tracks not_allowed)
				(vias allowed)
				(pads allowed)
				(copperpour not_allowed)
				(footprints allowed)
			)
			(placement
				(enabled no)
				(sheetname "")
			)
			(fill
				(thermal_gap 0.5)
				(thermal_bridge_width 0.5)
				(island_removal_mode 0)
			)
			(polygon
				(pts
					(xy 38.849808 -61.264292) (xy 39.349934 -61.264292) (xy 39.349934 -62.095888) (xy 38.849808 -62.095888)
				)
			)
		)
		(zone
			(layer "F.Cu")
			(hatch none 0.5)
			(connect_pads
				(clearance 0)
			)
			(min_thickness 0.25)
			(keepout
				(tracks allowed)
				(vias not_allowed)
				(pads allowed)
				(copperpour not_allowed)
				(footprints allowed)
			)
			(placement
				(enabled no)
				(sheetname "")
			)
			(fill
				(thermal_gap 0.5)
				(thermal_bridge_width 0.5)
				(island_removal_mode 0)
			)
			(polygon
				(pts
					(xy 38.849808 -60.095892) (xy 38.849808 -56.930036) (xy 39.349934 -56.930036) (xy 39.349934 -60.095892)
				)
			)
		)
		(zone
			(layer "F.Cu")
			(hatch none 0.5)
			(connect_pads
				(clearance 0)
			)
			(min_thickness 0.25)
			(keepout
				(tracks not_allowed)
				(vias allowed)
				(pads allowed)
				(copperpour not_allowed)
				(footprints allowed)
			)
			(placement
				(enabled no)
				(sheetname "")
			)
			(fill
				(thermal_gap 0.5)
				(thermal_bridge_width 0.5)
				(island_removal_mode 0)
			)
			(polygon
				(pts
					(xy 38.849808 -56.930036) (xy 39.349934 -56.930036) (xy 39.349934 -60.095892) (xy 38.849808 -60.095892)
				)
			)
		)
		(zone
			(layer "F.Cu")
			(hatch none 0.5)
			(connect_pads
				(clearance 0)
			)
			(min_thickness 0.25)
			(keepout
				(tracks not_allowed)
				(vias allowed)
				(pads allowed)
				(copperpour not_allowed)
				(footprints allowed)
			)
			(placement
				(enabled no)
				(sheetname "")
			)
			(fill
				(thermal_gap 0.5)
				(thermal_bridge_width 0.5)
				(island_removal_mode 0)
			)
			(polygon
				(pts
					(xy 40.099996 -56.930036) (xy 55.899812 -56.930036) (xy 55.899812 -68.49999) (xy 40.099996 -68.49999)
				)
			)
		)
		(zone
			(layer "F.Cu")
			(hatch none 0.5)
			(connect_pads
				(clearance 0)
			)
			(min_thickness 0.25)
			(keepout
				(tracks allowed)
				(vias not_allowed)
				(pads allowed)
				(copperpour not_allowed)
				(footprints allowed)
			)
			(placement
				(enabled no)
				(sheetname "")
			)
			(fill
				(thermal_gap 0.5)
				(thermal_bridge_width 0.5)
				(island_removal_mode 0)
			)
			(polygon
				(pts
					(xy 40.099996 -56.930036) (xy 55.899812 -56.930036) (xy 55.899812 -68.49999) (xy 40.099996 -68.49999)
				)
			)
		)
		(zone
			(layer "F.Cu")
			(hatch none 0.5)
			(connect_pads
				(clearance 0)
			)
			(min_thickness 0.25)
			(keepout
				(tracks allowed)
				(vias not_allowed)
				(pads allowed)
				(copperpour not_allowed)
				(footprints allowed)
			)
			(placement
				(enabled no)
				(sheetname "")
			)
			(fill
				(thermal_gap 0.5)
				(thermal_bridge_width 0.5)
				(island_removal_mode 0)
			)
			(polygon
				(pts
					(xy 56.649874 -68.49999) (xy 56.649874 -66.764154) (xy 57.15 -66.764154) (xy 57.15 -68.49999)
				)
			)
		)
		(zone
			(layer "F.Cu")
			(hatch none 0.5)
			(connect_pads
				(clearance 0)
			)
			(min_thickness 0.25)
			(keepout
				(tracks not_allowed)
				(vias allowed)
				(pads allowed)
				(copperpour not_allowed)
				(footprints allowed)
			)
			(placement
				(enabled no)
				(sheetname "")
			)
			(fill
				(thermal_gap 0.5)
				(thermal_bridge_width 0.5)
				(island_removal_mode 0)
			)
			(polygon
				(pts
					(xy 56.649874 -66.764154) (xy 57.15 -66.764154) (xy 57.15 -68.49999) (xy 56.649874 -68.49999)
				)
			)
		)
		(zone
			(layer "F.Cu")
			(hatch none 0.5)
			(connect_pads
				(clearance 0)
			)
			(min_thickness 0.25)
			(keepout
				(tracks allowed)
				(vias not_allowed)
				(pads allowed)
				(copperpour not_allowed)
				(footprints allowed)
			)
			(placement
				(enabled no)
				(sheetname "")
			)
			(fill
				(thermal_gap 0.5)
				(thermal_bridge_width 0.5)
				(island_removal_mode 0)
			)
			(polygon
				(pts
					(xy 56.649874 -65.595754) (xy 56.649874 -63.264288) (xy 57.15 -63.264288) (xy 57.15 -65.595754)
				)
			)
		)
		(zone
			(layer "F.Cu")
			(hatch none 0.5)
			(connect_pads
				(clearance 0)
			)
			(min_thickness 0.25)
			(keepout
				(tracks not_allowed)
				(vias allowed)
				(pads allowed)
				(copperpour not_allowed)
				(footprints allowed)
			)
			(placement
				(enabled no)
				(sheetname "")
			)
			(fill
				(thermal_gap 0.5)
				(thermal_bridge_width 0.5)
				(island_removal_mode 0)
			)
			(polygon
				(pts
					(xy 56.649874 -63.264288) (xy 57.15 -63.264288) (xy 57.15 -65.595754) (xy 56.649874 -65.595754)
				)
			)
		)
		(zone
			(layer "F.Cu")
			(hatch none 0.5)
			(connect_pads
				(clearance 0)
			)
			(min_thickness 0.25)
			(keepout
				(tracks allowed)
				(vias not_allowed)
				(pads allowed)
				(copperpour not_allowed)
				(footprints allowed)
			)
			(placement
				(enabled no)
				(sheetname "")
			)
			(fill
				(thermal_gap 0.5)
				(thermal_bridge_width 0.5)
				(island_removal_mode 0)
			)
			(polygon
				(pts
					(xy 56.649874 -62.095888) (xy 56.649874 -60.264294) (xy 57.15 -60.264294) (xy 57.15 -62.095888)
				)
			)
		)
		(zone
			(layer "F.Cu")
			(hatch none 0.5)
			(connect_pads
				(clearance 0)
			)
			(min_thickness 0.25)
			(keepout
				(tracks not_allowed)
				(vias allowed)
				(pads allowed)
				(copperpour not_allowed)
				(footprints allowed)
			)
			(placement
				(enabled no)
				(sheetname "")
			)
			(fill
				(thermal_gap 0.5)
				(thermal_bridge_width 0.5)
				(island_removal_mode 0)
			)
			(polygon
				(pts
					(xy 56.649874 -60.264294) (xy 57.15 -60.264294) (xy 57.15 -62.095888) (xy 56.649874 -62.095888)
				)
			)
		)
		(zone
			(layer "F.Cu")
			(hatch none 0.5)
			(connect_pads
				(clearance 0)
			)
			(min_thickness 0.25)
			(keepout
				(tracks allowed)
				(vias not_allowed)
				(pads allowed)
				(copperpour not_allowed)
				(footprints allowed)
			)
			(placement
				(enabled no)
				(sheetname "")
			)
			(fill
				(thermal_gap 0.5)
				(thermal_bridge_width 0.5)
				(island_removal_mode 0)
			)
			(polygon
				(pts
					(xy 56.649874 -59.095894) (xy 56.649874 -56.930036) (xy 57.15 -56.930036) (xy 57.15 -59.095894)
				)
			)
		)
		(zone
			(layer "F.Cu")
			(hatch none 0.5)
			(connect_pads
				(clearance 0)
			)
			(min_thickness 0.25)
			(keepout
				(tracks not_allowed)
				(vias allowed)
				(pads allowed)
				(copperpour not_allowed)
				(footprints allowed)
			)
			(placement
				(enabled no)
				(sheetname "")
			)
			(fill
				(thermal_gap 0.5)
				(thermal_bridge_width 0.5)
				(island_removal_mode 0)
			)
			(polygon
				(pts
					(xy 56.649874 -56.930036) (xy 57.15 -56.930036) (xy 57.15 -59.095894) (xy 56.649874 -59.095894)
				)
			)
		)
		(zone
			(layers "F.Cu" "B.Cu" "In1.Cu" "In2.Cu" "In3.Cu" "In4.Cu" "In5.Cu" "In6.Cu")
			(hatch none 0.5)
			(connect_pads
				(clearance 0)
			)
			(min_thickness 0.25)
			(keepout
				(tracks not_allowed)
				(vias allowed)
				(pads allowed)
				(copperpour not_allowed)
				(footprints allowed)
			)
			(placement
				(enabled no)
				(sheetname "")
			)
			(fill
				(thermal_gap 0.5)
				(thermal_bridge_width 0.5)
				(island_removal_mode 0)
			)
			(polygon
				(pts
					(arc
						(start 41.09212 -71.900034)
						(mid 38.90772 -71.900034)
						(end 41.09212 -71.900034)
					)
				)
			)
		)
		(zone
			(layers "F.Cu" "B.Cu" "In1.Cu" "In2.Cu" "In3.Cu" "In4.Cu" "In5.Cu" "In6.Cu")
			(hatch none 0.5)
			(connect_pads
				(clearance 0)
			)
			(min_thickness 0.25)
			(keepout
				(tracks not_allowed)
				(vias allowed)
				(pads allowed)
				(copperpour not_allowed)
				(footprints allowed)
			)
			(placement
				(enabled no)
				(sheetname "")
			)
			(fill
				(thermal_gap 0.5)
				(thermal_bridge_width 0.5)
				(island_removal_mode 0)
			)
			(polygon
				(pts
					(arc
						(start 57.092088 -71.900034)
						(mid 54.907688 -71.900034)
						(end 57.092088 -71.900034)
					)
				)
			)
		)
	)
	(footprint ""
		(layer "F.Cu")
		(at 347.599 -96.52 90)
		(property "Reference" "PC16"
			(at 0 0 90)
			(layer "F.SilkS")
			(hide yes)
			(effects
				(font
					(size 1.27 1.27)
				)
			)
		)
		(property "Value" "SC22U10V5MX-GP"
			(at -0.0762 -6.1214 90)
			(unlocked yes)
			(layer "F.Fab")
			(hide yes)
			(effects
				(font
					(size 1.016 1.016)
					(thickness 0.1524)
				)
			)
		)
		(property "Device Type" "C805H56"
			(at -0.0762 -8.1534 90)
			(unlocked yes)
			(layer "F.Fab")
			(hide yes)
			(effects
				(font
					(size 1.016 1.016)
					(thickness 0.1524)
				)
			)
		)
		(duplicate_pad_numbers_are_jumpers no)
		(fp_line
			(start 0.635 0)
			(end -0.635 0)
			(stroke
				(width 0.508)
				(type default)
			)
			(layer "F.SilkS")
		)
		(fp_rect
			(start -0.9652 1.778)
			(end 0.9652 -1.778)
			(stroke
				(width 0)
				(type default)
			)
			(fill no)
			(layer "F.CrtYd")
		)
		(fp_poly
			(pts
				(xy -0.9652 -1.778) (xy 0.9652 -1.778) (xy 0.9652 1.778) (xy -0.9652 1.778)
			)
			(stroke
				(width 0)
				(type default)
			)
			(fill no)
			(layer "F.Fab")
		)
		(pad "1" smd rect
			(at 0 -0.9652 90)
			(size 1.397 1.143)
			(layers "F.Cu" "F.Mask" "F.Paste")
			(net "P5V_STBY")
		)
		(pad "2" smd rect
			(at 0 0.9652 90)
			(size 1.397 1.143)
			(layers "F.Cu" "F.Mask" "F.Paste")
			(net "GND")
		)
	)
	(footprint ""
		(layer "F.Cu")
		(at 215.392 -162.179 -90)
		(property "Reference" "C87"
			(at 0 0 270)
			(layer "F.SilkS")
			(hide yes)
			(effects
				(font
					(size 1.27 1.27)
				)
			)
		)
		(property "Value" "SCD1U16V2KX-3GP"
			(at 1.1811 -2.7051 270)
			(unlocked yes)
			(layer "F.Fab")
			(hide yes)
			(effects
				(font
					(size 1.016 1.016)
					(thickness 0.1524)
				)
			)
		)
		(property "Device Type" "C402H22"
			(at 1.1811 -4.2291 270)
			(unlocked yes)
			(layer "F.Fab")
			(hide yes)
			(effects
				(font
					(size 1.016 1.016)
					(thickness 0.1524)
				)
			)
		)
		(duplicate_pad_numbers_are_jumpers no)
		(fp_rect
			(start -0.4318 0.9525)
			(end 0.4318 -0.9525)
			(stroke
				(width 0)
				(type default)
			)
			(fill no)
			(layer "F.CrtYd")
		)
		(fp_rect
			(start -0.4318 0.9525)
			(end 0.4318 -0.9525)
			(stroke
				(width 0)
				(type default)
			)
			(fill no)
			(layer "F.Fab")
		)
		(pad "1" smd custom
			(at 0 -0.4445 270)
			(size 0.1524 0.1524)
			(layers "F.Cu" "F.Mask" "F.Paste")
			(net "P1V8_STBY")
			(options
				(clearance outline)
				(anchor circle)
			)
			(primitives
				(gr_poly
					(pts
						(arc
							(start 0.3048 -0.2032)
							(mid 0.275042 -0.275042)
							(end 0.2032 -0.3048)
						)
						(arc
							(start -0.2032 -0.3048)
							(mid -0.275042 -0.275042)
							(end -0.3048 -0.2032)
						)
						(arc
							(start -0.3048 0.2032)
							(mid -0.275042 0.275042)
							(end -0.2032 0.3048)
						)
						(arc
							(start 0.2032 0.3048)
							(mid 0.275042 0.275042)
							(end 0.3048 0.2032)
						)
					)
					(width 0)
					(fill yes)
				)
			)
		)
		(pad "2" smd custom
			(at 0 0.4445 270)
			(size 0.1524 0.1524)
			(layers "F.Cu" "F.Mask" "F.Paste")
			(net "GND")
			(options
				(clearance outline)
				(anchor circle)
			)
			(primitives
				(gr_poly
					(pts
						(arc
							(start 0.3048 -0.2032)
							(mid 0.275042 -0.275042)
							(end 0.2032 -0.3048)
						)
						(arc
							(start -0.2032 -0.3048)
							(mid -0.275042 -0.275042)
							(end -0.3048 -0.2032)
						)
						(arc
							(start -0.3048 0.2032)
							(mid -0.275042 0.275042)
							(end -0.2032 0.3048)
						)
						(arc
							(start 0.2032 0.3048)
							(mid 0.275042 0.275042)
							(end 0.3048 0.2032)
						)
					)
					(width 0)
					(fill yes)
				)
			)
		)
	)
	(footprint ""
		(layer "F.Cu")
		(at 79.62519 -62.705488)
		(property "Reference" "SR712"
			(at 0 0 0)
			(layer "F.SilkS")
			(hide yes)
			(effects
				(font
					(size 1.27 1.27)
				)
			)
		)
		(property "Value" "10R2F-L-GP"
			(at 0.064008 -3.993896 0)
			(unlocked yes)
			(layer "F.Fab")
			(hide yes)
			(effects
				(font
					(size 1.016 1.016)
					(thickness 0.1524)
				)
			)
		)
		(property "Device Type" "R402H14"
			(at 0.064008 -5.517896 0)
			(unlocked yes)
			(layer "F.Fab")
			(hide yes)
			(effects
				(font
					(size 1.016 1.016)
					(thickness 0.1524)
				)
			)
		)
		(duplicate_pad_numbers_are_jumpers no)
		(fp_line
			(start -0.508 -0.9398)
			(end -0.508 0.9398)
			(stroke
				(width 0.1524)
				(type default)
			)
			(layer "F.SilkS")
		)
		(fp_line
			(start 0.508 -0.9398)
			(end -0.508 -0.9398)
			(stroke
				(width 0.1524)
				(type default)
			)
			(layer "F.SilkS")
		)
		(fp_rect
			(start -0.508 0.9398)
			(end 0.508 -0.9398)
			(stroke
				(width 0)
				(type default)
			)
			(fill no)
			(layer "F.CrtYd")
		)
		(fp_rect
			(start -0.508 0.9398)
			(end 0.508 -0.9398)
			(stroke
				(width 0)
				(type default)
			)
			(fill no)
			(layer "F.Fab")
		)
		(pad "1" smd custom
			(at 0 -0.4445)
			(size 0.1397 0.1397)
			(layers "F.Cu" "F.Mask" "F.Paste")
			(net "P1V8_C")
			(options
				(clearance outline)
				(anchor circle)
			)
			(primitives
				(gr_poly
					(pts
						(arc
							(start -0.1778 -0.2794)
							(mid -0.249642 -0.249642)
							(end -0.2794 -0.1778)
						)
						(arc
							(start -0.2794 0.1778)
							(mid -0.249642 0.249642)
							(end -0.1778 0.2794)
						)
						(arc
							(start 0.1778 0.2794)
							(mid 0.249642 0.249642)
							(end 0.2794 0.1778)
						)
						(arc
							(start 0.2794 -0.1778)
							(mid 0.249642 -0.249642)
							(end 0.1778 -0.2794)
						)
					)
					(width 0)
					(fill yes)
				)
			)
		)
		(pad "2" smd custom
			(at 0 0.4445)
			(size 0.1397 0.1397)
			(layers "F.Cu" "F.Mask" "F.Paste")
			(net "SHELL_PLL_VDD")
			(options
				(clearance outline)
				(anchor circle)
			)
			(primitives
				(gr_poly
					(pts
						(arc
							(start -0.1778 -0.2794)
							(mid -0.249642 -0.249642)
							(end -0.2794 -0.1778)
						)
						(arc
							(start -0.2794 0.1778)
							(mid -0.249642 0.249642)
							(end -0.1778 0.2794)
						)
						(arc
							(start 0.1778 0.2794)
							(mid 0.249642 0.249642)
							(end 0.2794 0.1778)
						)
						(arc
							(start 0.2794 -0.1778)
							(mid 0.249642 -0.249642)
							(end 0.1778 -0.2794)
						)
					)
					(width 0)
					(fill yes)
				)
			)
		)
	)
	(footprint ""
		(layer "F.Cu")
		(at 303.320958 -61.595 -90)
		(property "Reference" "R206"
			(at 0 0 270)
			(layer "F.SilkS")
			(hide yes)
			(effects
				(font
					(size 1.27 1.27)
				)
			)
		)
		(property "Value" "0R2J-2-GP"
			(at 0.064008 -3.993896 270)
			(unlocked yes)
			(layer "F.Fab")
			(hide yes)
			(effects
				(font
					(size 1.016 1.016)
					(thickness 0.1524)
				)
			)
		)
		(property "Device Type" "R402H16"
			(at 0.064008 -5.517896 270)
			(unlocked yes)
			(layer "F.Fab")
			(hide yes)
			(effects
				(font
					(size 1.016 1.016)
					(thickness 0.1524)
				)
			)
		)
		(duplicate_pad_numbers_are_jumpers no)
		(fp_line
			(start -0.508 -0.9398)
			(end -0.508 0.9398)
			(stroke
				(width 0.1524)
				(type default)
			)
			(layer "F.SilkS")
		)
		(fp_line
			(start 0.508 -0.9398)
			(end -0.508 -0.9398)
			(stroke
				(width 0.1524)
				(type default)
			)
			(layer "F.SilkS")
		)
		(fp_rect
			(start -0.508 0.9398)
			(end 0.508 -0.9398)
			(stroke
				(width 0)
				(type default)
			)
			(fill no)
			(layer "F.CrtYd")
		)
		(fp_rect
			(start -0.508 0.9398)
			(end 0.508 -0.9398)
			(stroke
				(width 0)
				(type default)
			)
			(fill no)
			(layer "F.Fab")
		)
		(pad "1" smd custom
			(at 0 -0.4445 270)
			(size 0.1397 0.1397)
			(layers "F.Cu" "F.Mask" "F.Paste")
			(net "SAS_I2C_C_10G_SDA")
			(options
				(clearance outline)
				(anchor circle)
			)
			(primitives
				(gr_poly
					(pts
						(arc
							(start -0.1778 -0.2794)
							(mid -0.249642 -0.249642)
							(end -0.2794 -0.1778)
						)
						(arc
							(start -0.2794 0.1778)
							(mid -0.249642 0.249642)
							(end -0.1778 0.2794)
						)
						(arc
							(start 0.1778 0.2794)
							(mid 0.249642 0.249642)
							(end 0.2794 0.1778)
						)
						(arc
							(start 0.2794 -0.1778)
							(mid 0.249642 -0.249642)
							(end 0.1778 -0.2794)
						)
					)
					(width 0)
					(fill yes)
				)
			)
		)
		(pad "2" smd custom
			(at 0 0.4445 270)
			(size 0.1397 0.1397)
			(layers "F.Cu" "F.Mask" "F.Paste")
			(net "BMC_10G_SDA_2")
			(options
				(clearance outline)
				(anchor circle)
			)
			(primitives
				(gr_poly
					(pts
						(arc
							(start -0.1778 -0.2794)
							(mid -0.249642 -0.249642)
							(end -0.2794 -0.1778)
						)
						(arc
							(start -0.2794 0.1778)
							(mid -0.249642 0.249642)
							(end -0.1778 0.2794)
						)
						(arc
							(start 0.1778 0.2794)
							(mid 0.249642 0.249642)
							(end 0.2794 0.1778)
						)
						(arc
							(start 0.2794 -0.1778)
							(mid 0.249642 -0.249642)
							(end 0.1778 -0.2794)
						)
					)
					(width 0)
					(fill yes)
				)
			)
		)
	)
	(footprint ""
		(layer "F.Cu")
		(at 80.626966 -86.868 -90)
		(property "Reference" "SL12"
			(at 0 0 270)
			(layer "F.SilkS")
			(hide yes)
			(effects
				(font
					(size 1.27 1.27)
				)
			)
		)
		(property "Value" "MPZ2012S601AT-GP"
			(at 0 -4.2418 270)
			(unlocked yes)
			(layer "F.Fab")
			(hide yes)
			(effects
				(font
					(size 1.016 1.016)
					(thickness 0.1524)
				)
			)
		)
		(property "Device Type" "L805H42"
			(at 0 -5.7912 270)
			(unlocked yes)
			(layer "F.Fab")
			(hide yes)
			(effects
				(font
					(size 1.016 1.016)
					(thickness 0.1524)
				)
			)
		)
		(duplicate_pad_numbers_are_jumpers no)
		(fp_line
			(start -0.889 1.7018)
			(end -0.889 -1.7018)
			(stroke
				(width 0.1524)
				(type default)
			)
			(layer "F.SilkS")
		)
		(fp_line
			(start 0.889 1.7018)
			(end -0.889 1.7018)
			(stroke
				(width 0.1524)
				(type default)
			)
			(layer "F.SilkS")
		)
		(fp_line
			(start -0.889 -1.7018)
			(end 0.889 -1.7018)
			(stroke
				(width 0.1524)
				(type default)
			)
			(layer "F.SilkS")
		)
		(fp_line
			(start 0.889 -1.7018)
			(end 0.889 1.7018)
			(stroke
				(width 0.1524)
				(type default)
			)
			(layer "F.SilkS")
		)
		(fp_rect
			(start -0.9652 1.778)
			(end 0.9652 -1.778)
			(stroke
				(width 0)
				(type default)
			)
			(fill no)
			(layer "F.CrtYd")
		)
		(fp_rect
			(start -0.9652 1.778)
			(end 0.9652 -1.778)
			(stroke
				(width 0)
				(type default)
			)
			(fill no)
			(layer "F.Fab")
		)
		(pad "1" smd rect
			(at 0 -0.9652 270)
			(size 1.397 1.143)
			(layers "F.Cu" "F.Mask" "F.Paste")
			(net "SYSPLL_VDDA18")
		)
		(pad "2" smd rect
			(at 0 0.9652 270)
			(size 1.397 1.143)
			(layers "F.Cu" "F.Mask" "F.Paste")
			(net "P1V8_E")
		)
	)
	(footprint ""
		(layer "F.Cu")
		(at 53.975 -207.391 -90)
		(property "Reference" "R692"
			(at 0 0 270)
			(layer "F.SilkS")
			(hide yes)
			(effects
				(font
					(size 1.27 1.27)
				)
			)
		)
		(property "Value" "1K33R3F-GP"
			(at -0.0254 -2.5146 270)
			(unlocked yes)
			(layer "F.Fab")
			(hide yes)
			(effects
				(font
					(size 1.016 1.016)
					(thickness 0.1524)
				)
			)
		)
		(property "Device Type" "R603H22"
			(at -0.0254 -4.0386 270)
			(unlocked yes)
			(layer "F.Fab")
			(hide yes)
			(effects
				(font
					(size 1.016 1.016)
					(thickness 0.1524)
				)
			)
		)
		(duplicate_pad_numbers_are_jumpers no)
		(fp_line
			(start -0.4826 0)
			(end -0.2032 0)
			(stroke
				(width 0.2032)
				(type default)
			)
			(layer "F.SilkS")
		)
		(fp_line
			(start 0.2032 0)
			(end 0.4826 0)
			(stroke
				(width 0.2032)
				(type default)
			)
			(layer "F.SilkS")
		)
		(fp_rect
			(start -0.5842 1.3335)
			(end 0.5842 -1.3335)
			(stroke
				(width 0)
				(type default)
			)
			(fill no)
			(layer "F.CrtYd")
		)
		(fp_rect
			(start -0.5842 1.3335)
			(end 0.5842 -1.3335)
			(stroke
				(width 0)
				(type default)
			)
			(fill no)
			(layer "F.Fab")
		)
		(pad "1" smd custom
			(at 0 -0.762 270)
			(size 0.2159 0.2159)
			(layers "F.Cu" "F.Mask" "F.Paste")
			(net "MB0_HS_ENABLE")
			(options
				(clearance outline)
				(anchor circle)
			)
			(primitives
				(gr_poly
					(pts
						(arc
							(start -0.3302 -0.4318)
							(mid -0.402042 -0.402042)
							(end -0.4318 -0.3302)
						)
						(arc
							(start -0.4318 0.3302)
							(mid -0.402042 0.402042)
							(end -0.3302 0.4318)
						)
						(arc
							(start 0.3302 0.4318)
							(mid 0.402042 0.402042)
							(end 0.4318 0.3302)
						)
						(arc
							(start 0.4318 -0.3302)
							(mid 0.402042 -0.402042)
							(end 0.3302 -0.4318)
						)
					)
					(width 0)
					(fill yes)
				)
			)
		)
		(pad "2" smd custom
			(at 0 0.762 270)
			(size 0.2159 0.2159)
			(layers "F.Cu" "F.Mask" "F.Paste")
			(net "GND")
			(options
				(clearance outline)
				(anchor circle)
			)
			(primitives
				(gr_poly
					(pts
						(arc
							(start -0.3302 -0.4318)
							(mid -0.402042 -0.402042)
							(end -0.4318 -0.3302)
						)
						(arc
							(start -0.4318 0.3302)
							(mid -0.402042 0.402042)
							(end -0.3302 0.4318)
						)
						(arc
							(start 0.3302 0.4318)
							(mid 0.402042 0.402042)
							(end 0.4318 0.3302)
						)
						(arc
							(start 0.4318 -0.3302)
							(mid 0.402042 -0.402042)
							(end 0.3302 -0.4318)
						)
					)
					(width 0)
					(fill yes)
				)
			)
		)
	)
	(footprint ""
		(layer "F.Cu")
		(at 205.555596 -118.129812 90)
		(property "Reference" "PC224"
			(at 0 0 90)
			(layer "F.SilkS")
			(hide yes)
			(effects
				(font
					(size 1.27 1.27)
				)
			)
		)
		(property "Value" "SC1U16V3KX-5GP"
			(at 0 -2.8194 90)
			(unlocked yes)
			(layer "F.Fab")
			(hide yes)
			(effects
				(font
					(size 1.016 1.016)
					(thickness 0.1524)
				)
			)
		)
		(property "Device Type" "C603H36"
			(at 0 -4.3434 90)
			(unlocked yes)
			(layer "F.Fab")
			(hide yes)
			(effects
				(font
					(size 1.016 1.016)
					(thickness 0.1524)
				)
			)
		)
		(duplicate_pad_numbers_are_jumpers no)
		(fp_line
			(start 0.508 0)
			(end -0.508 0)
			(stroke
				(width 0.2032)
				(type default)
			)
			(layer "F.SilkS")
		)
		(fp_rect
			(start -0.5842 1.3335)
			(end 0.5842 -1.3335)
			(stroke
				(width 0)
				(type default)
			)
			(fill no)
			(layer "F.CrtYd")
		)
		(fp_rect
			(start -0.5842 1.3335)
			(end 0.5842 -1.3335)
			(stroke
				(width 0)
				(type default)
			)
			(fill no)
			(layer "F.Fab")
		)
		(pad "1" smd custom
			(at 0 -0.762 90)
			(size 0.2159 0.2159)
			(layers "F.Cu" "F.Mask" "F.Paste")
			(net "P1V5_E_VCC")
			(options
				(clearance outline)
				(anchor circle)
			)
			(primitives
				(gr_poly
					(pts
						(arc
							(start -0.3302 -0.4318)
							(mid -0.402042 -0.402042)
							(end -0.4318 -0.3302)
						)
						(arc
							(start -0.4318 0.3302)
							(mid -0.402042 0.402042)
							(end -0.3302 0.4318)
						)
						(arc
							(start 0.3302 0.4318)
							(mid 0.402042 0.402042)
							(end 0.4318 0.3302)
						)
						(arc
							(start 0.4318 -0.3302)
							(mid 0.402042 -0.402042)
							(end 0.3302 -0.4318)
						)
					)
					(width 0)
					(fill yes)
				)
			)
		)
		(pad "2" smd custom
			(at 0 0.762 90)
			(size 0.2159 0.2159)
			(layers "F.Cu" "F.Mask" "F.Paste")
			(net "AGND_P1V5_E")
			(options
				(clearance outline)
				(anchor circle)
			)
			(primitives
				(gr_poly
					(pts
						(arc
							(start -0.3302 -0.4318)
							(mid -0.402042 -0.402042)
							(end -0.4318 -0.3302)
						)
						(arc
							(start -0.4318 0.3302)
							(mid -0.402042 0.402042)
							(end -0.3302 0.4318)
						)
						(arc
							(start 0.3302 0.4318)
							(mid 0.402042 0.402042)
							(end 0.4318 0.3302)
						)
						(arc
							(start 0.4318 -0.3302)
							(mid 0.402042 -0.402042)
							(end 0.3302 -0.4318)
						)
					)
					(width 0)
					(fill yes)
				)
			)
		)
	)
	(footprint ""
		(layer "F.Cu")
		(at 337.312 -106.68 -90)
		(property "Reference" "PC12"
			(at 0 0 270)
			(layer "F.SilkS")
			(hide yes)
			(effects
				(font
					(size 1.27 1.27)
				)
			)
		)
		(property "Value" "SC2K2P50V3KX-GP"
			(at 0 -2.8194 270)
			(unlocked yes)
			(layer "F.Fab")
			(hide yes)
			(effects
				(font
					(size 1.016 1.016)
					(thickness 0.1524)
				)
			)
		)
		(property "Device Type" "C603"
			(at 0 -4.3434 270)
			(unlocked yes)
			(layer "F.Fab")
			(hide yes)
			(effects
				(font
					(size 1.016 1.016)
					(thickness 0.1524)
				)
			)
		)
		(duplicate_pad_numbers_are_jumpers no)
		(fp_line
			(start 0.508 0)
			(end -0.508 0)
			(stroke
				(width 0.2032)
				(type default)
			)
			(layer "F.SilkS")
		)
		(fp_rect
			(start -0.5842 1.3335)
			(end 0.5842 -1.3335)
			(stroke
				(width 0)
				(type default)
			)
			(fill no)
			(layer "F.CrtYd")
		)
		(fp_rect
			(start -0.5842 1.3335)
			(end 0.5842 -1.3335)
			(stroke
				(width 0)
				(type default)
			)
			(fill no)
			(layer "F.Fab")
		)
		(pad "1" smd custom
			(at 0 -0.762 270)
			(size 0.2159 0.2159)
			(layers "F.Cu" "F.Mask" "F.Paste")
			(net "P5V_STBY_SW")
			(options
				(clearance outline)
				(anchor circle)
			)
			(primitives
				(gr_poly
					(pts
						(arc
							(start -0.3302 -0.4318)
							(mid -0.402042 -0.402042)
							(end -0.4318 -0.3302)
						)
						(arc
							(start -0.4318 0.3302)
							(mid -0.402042 0.402042)
							(end -0.3302 0.4318)
						)
						(arc
							(start 0.3302 0.4318)
							(mid 0.402042 0.402042)
							(end 0.4318 0.3302)
						)
						(arc
							(start 0.4318 -0.3302)
							(mid 0.402042 -0.402042)
							(end 0.3302 -0.4318)
						)
					)
					(width 0)
					(fill yes)
				)
			)
		)
		(pad "2" smd custom
			(at 0 0.762 270)
			(size 0.2159 0.2159)
			(layers "F.Cu" "F.Mask" "F.Paste")
			(net "P5V_STBY__SNB")
			(options
				(clearance outline)
				(anchor circle)
			)
			(primitives
				(gr_poly
					(pts
						(arc
							(start -0.3302 -0.4318)
							(mid -0.402042 -0.402042)
							(end -0.4318 -0.3302)
						)
						(arc
							(start -0.4318 0.3302)
							(mid -0.402042 0.402042)
							(end -0.3302 0.4318)
						)
						(arc
							(start 0.3302 0.4318)
							(mid 0.402042 0.402042)
							(end 0.4318 0.3302)
						)
						(arc
							(start 0.4318 -0.3302)
							(mid 0.402042 -0.402042)
							(end 0.3302 -0.4318)
						)
					)
					(width 0)
					(fill yes)
				)
			)
		)
	)
	(footprint ""
		(layer "F.Cu")
		(at 201.250296 -86.372192)
		(property "Reference" "SC1132"
			(at 0 0 0)
			(layer "F.SilkS")
			(hide yes)
			(effects
				(font
					(size 1.27 1.27)
				)
			)
		)
		(property "Value" "SC100U6D3V0MX-2GP"
			(at -0.00254 -4.78536 0)
			(unlocked yes)
			(layer "F.Fab")
			(hide yes)
			(effects
				(font
					(size 1.016 1.016)
					(thickness 0.1524)
				)
			)
		)
		(property "Device Type" "C1210H107"
			(at -0.00254 -6.38048 0)
			(unlocked yes)
			(layer "F.Fab")
			(hide yes)
			(effects
				(font
					(size 1.016 1.016)
					(thickness 0.1524)
				)
			)
		)
		(duplicate_pad_numbers_are_jumpers no)
		(fp_line
			(start -1.5748 -2.3368)
			(end -1.5748 -0.762)
			(stroke
				(width 0.1524)
				(type default)
			)
			(layer "F.SilkS")
		)
		(fp_line
			(start -1.5748 0.762)
			(end -1.5748 2.3368)
			(stroke
				(width 0.1524)
				(type default)
			)
			(layer "F.SilkS")
		)
		(fp_line
			(start -1.5748 2.3368)
			(end 1.5748 2.3368)
			(stroke
				(width 0.1524)
				(type default)
			)
			(layer "F.SilkS")
		)
		(fp_line
			(start 1.5748 -2.3368)
			(end -1.5748 -2.3368)
			(stroke
				(width 0.1524)
				(type default)
			)
			(layer "F.SilkS")
		)
		(fp_line
			(start 1.5748 -0.762)
			(end 1.5748 -2.3368)
			(stroke
				(width 0.1524)
				(type default)
			)
			(layer "F.SilkS")
		)
		(fp_line
			(start 1.5748 2.3368)
			(end 1.5748 0.762)
			(stroke
				(width 0.1524)
				(type default)
			)
			(layer "F.SilkS")
		)
		(fp_rect
			(start -1.651 2.413)
			(end 1.651 -2.413)
			(stroke
				(width 0)
				(type default)
			)
			(fill no)
			(layer "F.CrtYd")
		)
		(fp_poly
			(pts
				(xy 1.651 2.413) (xy 1.651 -2.413) (xy -1.651 -2.413) (xy -1.651 2.413)
			)
			(stroke
				(width 0)
				(type default)
			)
			(fill no)
			(layer "F.Fab")
		)
		(pad "1" smd rect
			(at 0 -1.4732)
			(size 2.794 1.397)
			(layers "F.Cu" "F.Mask" "F.Paste")
			(net "GND")
		)
		(pad "2" smd rect
			(at 0 1.4732)
			(size 2.794 1.397)
			(layers "F.Cu" "F.Mask" "F.Paste")
			(net "GB_VDDH2")
		)
	)
	(footprint ""
		(layer "F.Cu")
		(at 83.8708 -3.683)
		(property "Reference" "PC198"
			(at 0 0 0)
			(layer "F.SilkS")
			(hide yes)
			(effects
				(font
					(size 1.27 1.27)
				)
			)
		)
		(property "Value" "SC22U6D3V6KX-2-GP"
			(at -0.0762 -5.1308 0)
			(unlocked yes)
			(layer "F.Fab")
			(hide yes)
			(effects
				(font
					(size 1.016 1.016)
					(thickness 0.1524)
				)
			)
		)
		(property "Device Type" "C1206H71"
			(at -0.127 -6.6548 0)
			(unlocked yes)
			(layer "F.Fab")
			(hide yes)
			(effects
				(font
					(size 1.016 1.016)
					(thickness 0.1524)
				)
			)
		)
		(duplicate_pad_numbers_are_jumpers no)
		(fp_line
			(start -1.016 -2.2352)
			(end 1.016 -2.2352)
			(stroke
				(width 0.1524)
				(type default)
			)
			(layer "F.SilkS")
		)
		(fp_line
			(start -1.016 -0.8382)
			(end -1.016 -2.2352)
			(stroke
				(width 0.1524)
				(type default)
			)
			(layer "F.SilkS")
		)
		(fp_line
			(start -1.016 2.2352)
			(end -1.016 0.8382)
			(stroke
				(width 0.1524)
				(type default)
			)
			(layer "F.SilkS")
		)
		(fp_line
			(start 1.016 -2.2352)
			(end 1.016 -0.8382)
			(stroke
				(width 0.1524)
				(type default)
			)
			(layer "F.SilkS")
		)
		(fp_line
			(start 1.016 0.8382)
			(end 1.016 2.2352)
			(stroke
				(width 0.1524)
				(type default)
			)
			(layer "F.SilkS")
		)
		(fp_line
			(start 1.016 2.2352)
			(end -1.016 2.2352)
			(stroke
				(width 0.1524)
				(type default)
			)
			(layer "F.SilkS")
		)
		(fp_rect
			(start -1.0922 2.3114)
			(end 1.0922 -2.3114)
			(stroke
				(width 0)
				(type default)
			)
			(fill no)
			(layer "F.CrtYd")
		)
		(fp_poly
			(pts
				(xy 1.0922 -2.3114) (xy 1.0922 2.3114) (xy -1.0922 2.3114) (xy -1.0922 -2.3114)
			)
			(stroke
				(width 0)
				(type default)
			)
			(fill no)
			(layer "F.Fab")
		)
		(pad "1" smd rect
			(at 0 -1.397)
			(size 1.651 1.27)
			(layers "F.Cu" "F.Mask" "F.Paste")
			(net "P0V955_C")
		)
		(pad "2" smd rect
			(at 0 1.397)
			(size 1.651 1.27)
			(layers "F.Cu" "F.Mask" "F.Paste")
			(net "GND")
		)
	)
	(footprint ""
		(layer "F.Cu")
		(at 299.212 -91.948 180)
		(property "Reference" "R159"
			(at 0 0 180)
			(layer "F.SilkS")
			(hide yes)
			(effects
				(font
					(size 1.27 1.27)
				)
			)
		)
		(property "Value" "0R2J-2-GP"
			(at 0.064008 -3.993896 180)
			(unlocked yes)
			(layer "F.Fab")
			(hide yes)
			(effects
				(font
					(size 1.016 1.016)
					(thickness 0.1524)
				)
			)
		)
		(property "Device Type" "R402H16"
			(at 0.064008 -5.517896 180)
			(unlocked yes)
			(layer "F.Fab")
			(hide yes)
			(effects
				(font
					(size 1.016 1.016)
					(thickness 0.1524)
				)
			)
		)
		(duplicate_pad_numbers_are_jumpers no)
		(fp_line
			(start 0.508 -0.9398)
			(end -0.508 -0.9398)
			(stroke
				(width 0.1524)
				(type default)
			)
			(layer "F.SilkS")
		)
		(fp_line
			(start -0.508 -0.9398)
			(end -0.508 0.9398)
			(stroke
				(width 0.1524)
				(type default)
			)
			(layer "F.SilkS")
		)
		(fp_rect
			(start -0.508 0.9398)
			(end 0.508 -0.9398)
			(stroke
				(width 0)
				(type default)
			)
			(fill no)
			(layer "F.CrtYd")
		)
		(fp_rect
			(start -0.508 0.9398)
			(end 0.508 -0.9398)
			(stroke
				(width 0)
				(type default)
			)
			(fill no)
			(layer "F.Fab")
		)
		(pad "1" smd custom
			(at 0 -0.4445 180)
			(size 0.1397 0.1397)
			(layers "F.Cu" "F.Mask" "F.Paste")
			(net "BMC_I2C_D_SDA")
			(options
				(clearance outline)
				(anchor circle)
			)
			(primitives
				(gr_poly
					(pts
						(arc
							(start -0.1778 -0.2794)
							(mid -0.249642 -0.249642)
							(end -0.2794 -0.1778)
						)
						(arc
							(start -0.2794 0.1778)
							(mid -0.249642 0.249642)
							(end -0.1778 0.2794)
						)
						(arc
							(start 0.1778 0.2794)
							(mid 0.249642 0.249642)
							(end 0.2794 0.1778)
						)
						(arc
							(start 0.2794 -0.1778)
							(mid 0.249642 -0.249642)
							(end 0.1778 -0.2794)
						)
					)
					(width 0)
					(fill yes)
				)
			)
		)
		(pad "2" smd custom
			(at 0 0.4445 180)
			(size 0.1397 0.1397)
			(layers "F.Cu" "F.Mask" "F.Paste")
			(net "TEMP_2_SDA")
			(options
				(clearance outline)
				(anchor circle)
			)
			(primitives
				(gr_poly
					(pts
						(arc
							(start -0.1778 -0.2794)
							(mid -0.249642 -0.249642)
							(end -0.2794 -0.1778)
						)
						(arc
							(start -0.2794 0.1778)
							(mid -0.249642 0.249642)
							(end -0.1778 0.2794)
						)
						(arc
							(start 0.1778 0.2794)
							(mid 0.249642 0.249642)
							(end 0.2794 0.1778)
						)
						(arc
							(start 0.2794 -0.1778)
							(mid 0.249642 -0.249642)
							(end 0.1778 -0.2794)
						)
					)
					(width 0)
					(fill yes)
				)
			)
		)
	)
	(footprint ""
		(layer "F.Cu")
		(at 189.927992 -46.609)
		(property "Reference" "Q8"
			(at 0 0 0)
			(layer "F.SilkS")
			(hide yes)
			(effects
				(font
					(size 1.27 1.27)
				)
			)
		)
		(property "Value" "2N7002A-7-GP"
			(at 0.127 -8.9662 0)
			(unlocked yes)
			(layer "F.Fab")
			(hide yes)
			(effects
				(font
					(size 1.016 1.016)
					(thickness 0.1524)
				)
			)
		)
		(property "Device Type" "SOT23DGS2D4H48"
			(at 0.127 -10.4902 0)
			(unlocked yes)
			(layer "F.Fab")
			(hide yes)
			(effects
				(font
					(size 1.016 1.016)
					(thickness 0.1524)
				)
			)
		)
		(duplicate_pad_numbers_are_jumpers no)
		(fp_line
			(start -1.651 -1.778)
			(end -1.651 1.778)
			(stroke
				(width 0.1524)
				(type default)
			)
			(layer "F.SilkS")
		)
		(fp_line
			(start -1.651 1.778)
			(end 1.651 1.778)
			(stroke
				(width 0.1524)
				(type default)
			)
			(layer "F.SilkS")
		)
		(fp_line
			(start 1.651 -1.778)
			(end -1.651 -1.778)
			(stroke
				(width 0.1524)
				(type default)
			)
			(layer "F.SilkS")
		)
		(fp_line
			(start 1.651 1.778)
			(end 1.651 -1.778)
			(stroke
				(width 0.1524)
				(type default)
			)
			(layer "F.SilkS")
		)
		(fp_poly
			(pts
				(xy -1.778 1.8796) (xy -1.778 -1.8796) (xy 1.778 -1.8796) (xy 1.778 1.8796)
			)
			(stroke
				(width 0)
				(type default)
			)
			(fill no)
			(layer "F.CrtYd")
		)
		(fp_poly
			(pts
				(xy -1.778 1.8796) (xy -1.778 -1.8796) (xy 1.778 -1.8796) (xy 1.778 1.8796)
			)
			(stroke
				(width 0)
				(type default)
			)
			(fill no)
			(layer "F.Fab")
		)
		(pad "D" smd custom
			(at 0 -0.9525)
			(size 0.1905 0.1905)
			(layers "F.Cu" "F.Mask" "F.Paste")
			(net "PRSNT_MSB_AND_1")
			(options
				(clearance outline)
				(anchor circle)
			)
			(primitives
				(gr_poly
					(pts
						(arc
							(start -0.1778 0.5715)
							(mid -0.321484 0.511984)
							(end -0.381 0.3683)
						)
						(arc
							(start -0.381 -0.3683)
							(mid -0.321484 -0.511984)
							(end -0.1778 -0.5715)
						)
						(arc
							(start 0.1778 -0.5715)
							(mid 0.321484 -0.511984)
							(end 0.381 -0.3683)
						)
						(arc
							(start 0.381 0.3683)
							(mid 0.321484 0.511984)
							(end 0.1778 0.5715)
						)
					)
					(width 0)
					(fill yes)
				)
			)
		)
		(pad "G" smd custom
			(at -0.98425 0.9525)
			(size 0.1905 0.1905)
			(layers "F.Cu" "F.Mask" "F.Paste")
			(net "PRSNT_MSB_A1")
			(options
				(clearance outline)
				(anchor circle)
			)
			(primitives
				(gr_poly
					(pts
						(arc
							(start -0.1778 0.5715)
							(mid -0.321484 0.511984)
							(end -0.381 0.3683)
						)
						(arc
							(start -0.381 -0.3683)
							(mid -0.321484 -0.511984)
							(end -0.1778 -0.5715)
						)
						(arc
							(start 0.1778 -0.5715)
							(mid 0.321484 -0.511984)
							(end 0.381 -0.3683)
						)
						(arc
							(start 0.381 0.3683)
							(mid 0.321484 0.511984)
							(end 0.1778 0.5715)
						)
					)
					(width 0)
					(fill yes)
				)
			)
		)
		(pad "S" smd custom
			(at 0.98425 0.9525)
			(size 0.1905 0.1905)
			(layers "F.Cu" "F.Mask" "F.Paste")
			(net "GND")
			(options
				(clearance outline)
				(anchor circle)
			)
			(primitives
				(gr_poly
					(pts
						(arc
							(start -0.1778 0.5715)
							(mid -0.321484 0.511984)
							(end -0.381 0.3683)
						)
						(arc
							(start -0.381 -0.3683)
							(mid -0.321484 -0.511984)
							(end -0.1778 -0.5715)
						)
						(arc
							(start 0.1778 -0.5715)
							(mid 0.321484 -0.511984)
							(end 0.381 -0.3683)
						)
						(arc
							(start 0.381 0.3683)
							(mid 0.321484 0.511984)
							(end 0.1778 0.5715)
						)
					)
					(width 0)
					(fill yes)
				)
			)
		)
	)
	(footprint ""
		(layer "F.Cu")
		(at 276.348952 -188.880496)
		(property "Reference" "R297"
			(at 0 0 0)
			(layer "F.SilkS")
			(hide yes)
			(effects
				(font
					(size 1.27 1.27)
				)
			)
		)
		(property "Value" "4K7R2F-GP"
			(at 0.064008 -3.993896 0)
			(unlocked yes)
			(layer "F.Fab")
			(hide yes)
			(effects
				(font
					(size 1.016 1.016)
					(thickness 0.1524)
				)
			)
		)
		(property "Device Type" "R402H16"
			(at 0.064008 -5.517896 0)
			(unlocked yes)
			(layer "F.Fab")
			(hide yes)
			(effects
				(font
					(size 1.016 1.016)
					(thickness 0.1524)
				)
			)
		)
		(duplicate_pad_numbers_are_jumpers no)
		(fp_line
			(start -0.508 -0.9398)
			(end -0.508 0.9398)
			(stroke
				(width 0.1524)
				(type default)
			)
			(layer "F.SilkS")
		)
		(fp_line
			(start 0.508 -0.9398)
			(end -0.508 -0.9398)
			(stroke
				(width 0.1524)
				(type default)
			)
			(layer "F.SilkS")
		)
		(fp_rect
			(start -0.508 0.9398)
			(end 0.508 -0.9398)
			(stroke
				(width 0)
				(type default)
			)
			(fill no)
			(layer "F.CrtYd")
		)
		(fp_rect
			(start -0.508 0.9398)
			(end 0.508 -0.9398)
			(stroke
				(width 0)
				(type default)
			)
			(fill no)
			(layer "F.Fab")
		)
		(pad "1" smd custom
			(at 0 -0.4445)
			(size 0.1397 0.1397)
			(layers "F.Cu" "F.Mask" "F.Paste")
			(net "P3V3_STBY")
			(options
				(clearance outline)
				(anchor circle)
			)
			(primitives
				(gr_poly
					(pts
						(arc
							(start -0.1778 -0.2794)
							(mid -0.249642 -0.249642)
							(end -0.2794 -0.1778)
						)
						(arc
							(start -0.2794 0.1778)
							(mid -0.249642 0.249642)
							(end -0.1778 0.2794)
						)
						(arc
							(start 0.1778 0.2794)
							(mid 0.249642 0.249642)
							(end 0.2794 0.1778)
						)
						(arc
							(start 0.2794 -0.1778)
							(mid 0.249642 -0.249642)
							(end 0.1778 -0.2794)
						)
					)
					(width 0)
					(fill yes)
				)
			)
		)
		(pad "2" smd custom
			(at 0 0.4445)
			(size 0.1397 0.1397)
			(layers "F.Cu" "F.Mask" "F.Paste")
			(net "OSC2_CONT")
			(options
				(clearance outline)
				(anchor circle)
			)
			(primitives
				(gr_poly
					(pts
						(arc
							(start -0.1778 -0.2794)
							(mid -0.249642 -0.249642)
							(end -0.2794 -0.1778)
						)
						(arc
							(start -0.2794 0.1778)
							(mid -0.249642 0.249642)
							(end -0.1778 0.2794)
						)
						(arc
							(start 0.1778 0.2794)
							(mid 0.249642 0.249642)
							(end 0.2794 0.1778)
						)
						(arc
							(start 0.2794 -0.1778)
							(mid 0.249642 -0.249642)
							(end 0.1778 -0.2794)
						)
					)
					(width 0)
					(fill yes)
				)
			)
		)
	)
	(footprint ""
		(layer "F.Cu")
		(at 274.193 -160.401 90)
		(property "Reference" "R234"
			(at 0 0 90)
			(layer "F.SilkS")
			(hide yes)
			(effects
				(font
					(size 1.27 1.27)
				)
			)
		)
		(property "Value" "100KR2F-L1-GP"
			(at 0.064008 -3.993896 90)
			(unlocked yes)
			(layer "F.Fab")
			(hide yes)
			(effects
				(font
					(size 1.016 1.016)
					(thickness 0.1524)
				)
			)
		)
		(property "Device Type" "R402H16"
			(at 0.064008 -5.517896 90)
			(unlocked yes)
			(layer "F.Fab")
			(hide yes)
			(effects
				(font
					(size 1.016 1.016)
					(thickness 0.1524)
				)
			)
		)
		(duplicate_pad_numbers_are_jumpers no)
		(fp_line
			(start 0.508 -0.9398)
			(end -0.508 -0.9398)
			(stroke
				(width 0.1524)
				(type default)
			)
			(layer "F.SilkS")
		)
		(fp_line
			(start -0.508 -0.9398)
			(end -0.508 0.9398)
			(stroke
				(width 0.1524)
				(type default)
			)
			(layer "F.SilkS")
		)
		(fp_rect
			(start -0.508 0.9398)
			(end 0.508 -0.9398)
			(stroke
				(width 0)
				(type default)
			)
			(fill no)
			(layer "F.CrtYd")
		)
		(fp_rect
			(start -0.508 0.9398)
			(end 0.508 -0.9398)
			(stroke
				(width 0)
				(type default)
			)
			(fill no)
			(layer "F.Fab")
		)
		(pad "1" smd custom
			(at 0 -0.4445 90)
			(size 0.1397 0.1397)
			(layers "F.Cu" "F.Mask" "F.Paste")
			(net "GND")
			(options
				(clearance outline)
				(anchor circle)
			)
			(primitives
				(gr_poly
					(pts
						(arc
							(start -0.1778 -0.2794)
							(mid -0.249642 -0.249642)
							(end -0.2794 -0.1778)
						)
						(arc
							(start -0.2794 0.1778)
							(mid -0.249642 0.249642)
							(end -0.1778 0.2794)
						)
						(arc
							(start 0.1778 0.2794)
							(mid 0.249642 0.249642)
							(end 0.2794 0.1778)
						)
						(arc
							(start 0.2794 -0.1778)
							(mid 0.249642 -0.249642)
							(end 0.1778 -0.2794)
						)
					)
					(width 0)
					(fill yes)
				)
			)
		)
		(pad "2" smd custom
			(at 0 0.4445 90)
			(size 0.1397 0.1397)
			(layers "F.Cu" "F.Mask" "F.Paste")
			(net "TP_BMC0_LPC_LAD0")
			(options
				(clearance outline)
				(anchor circle)
			)
			(primitives
				(gr_poly
					(pts
						(arc
							(start -0.1778 -0.2794)
							(mid -0.249642 -0.249642)
							(end -0.2794 -0.1778)
						)
						(arc
							(start -0.2794 0.1778)
							(mid -0.249642 0.249642)
							(end -0.1778 0.2794)
						)
						(arc
							(start 0.1778 0.2794)
							(mid 0.249642 0.249642)
							(end 0.2794 0.1778)
						)
						(arc
							(start 0.2794 -0.1778)
							(mid 0.249642 -0.249642)
							(end 0.1778 -0.2794)
						)
					)
					(width 0)
					(fill yes)
				)
			)
		)
	)
	(footprint ""
		(layer "F.Cu")
		(at 279.302972 -188.507116)
		(property "Reference" "OSC1"
			(at 0 0 0)
			(layer "F.SilkS")
			(hide yes)
			(effects
				(font
					(size 1.27 1.27)
				)
			)
		)
		(property "Value" "OSC-48MHZ-28-GP"
			(at 0.0127 -2.7686 0)
			(unlocked yes)
			(layer "F.Fab")
			(hide yes)
			(effects
				(font
					(size 1.016 1.016)
					(thickness 0.1524)
				)
			)
		)
		(property "Device Type" "OSC-3225-4P-3H48"
			(at 0.0127 -4.2926 0)
			(unlocked yes)
			(layer "F.Fab")
			(hide yes)
			(effects
				(font
					(size 1.016 1.016)
					(thickness 0.1524)
				)
			)
		)
		(duplicate_pad_numbers_are_jumpers no)
		(fp_line
			(start -2.2352 1.6256)
			(end -2.2352 0.635)
			(stroke
				(width 0.3302)
				(type default)
			)
			(layer "F.SilkS")
		)
		(fp_line
			(start -2.1209 -1.5367)
			(end 2.1209 -1.5367)
			(stroke
				(width 0.1524)
				(type default)
			)
			(layer "F.SilkS")
		)
		(fp_line
			(start -2.1209 1.5367)
			(end -2.1209 -1.5367)
			(stroke
				(width 0.1524)
				(type default)
			)
			(layer "F.SilkS")
		)
		(fp_line
			(start -1.3208 1.6256)
			(end -2.2352 1.6256)
			(stroke
				(width 0.3302)
				(type default)
			)
			(layer "F.SilkS")
		)
		(fp_line
			(start 2.1209 -1.5367)
			(end 2.1209 1.5367)
			(stroke
				(width 0.1524)
				(type default)
			)
			(layer "F.SilkS")
		)
		(fp_line
			(start 2.1209 1.5367)
			(end -2.1209 1.5367)
			(stroke
				(width 0.1524)
				(type default)
			)
			(layer "F.SilkS")
		)
		(fp_poly
			(pts
				(xy -2.8321 1.459992) (xy -2.8321 0.189992) (xy -2.1971 0.824992)
			)
			(stroke
				(width 0)
				(type default)
			)
			(fill yes)
			(layer "F.SilkS")
		)
		(fp_rect
			(start -1.6002 1.2446)
			(end 1.6002 -1.2446)
			(stroke
				(width 0)
				(type default)
			)
			(fill no)
			(layer "F.CrtYd")
		)
		(fp_poly
			(pts
				(xy -2.3749 1.7907) (xy -2.3749 -1.7907) (xy 2.3749 -1.7907) (xy 2.3749 1.7907) (xy 1.6002 1.7907)
				(xy 1.6002 -1.2446) (xy -1.6002 -1.2446) (xy -1.6002 1.2446) (xy 1.59512 1.2446) (xy 1.59512 1.7907)
			)
			(stroke
				(width 0)
				(type default)
			)
			(fill no)
			(layer "F.CrtYd")
		)
		(fp_rect
			(start -2.3749 1.7907)
			(end 2.3749 -1.7907)
			(stroke
				(width 0)
				(type default)
			)
			(fill no)
			(layer "F.Fab")
		)
		(pad "1" smd rect
			(at -1.171448 0.824992)
			(size 1.397 0.9144)
			(layers "F.Cu" "F.Mask" "F.Paste")
			(net "OSC2_CONT")
		)
		(pad "2" smd rect
			(at 1.171448 0.824992)
			(size 1.397 0.9144)
			(layers "F.Cu" "F.Mask" "F.Paste")
			(net "GND")
		)
		(pad "3" smd rect
			(at 1.171448 -0.824992)
			(size 1.397 0.9144)
			(layers "F.Cu" "F.Mask" "F.Paste")
			(net "OSC2_OUT")
		)
		(pad "4" smd rect
			(at -1.171448 -0.824992)
			(size 1.397 0.9144)
			(layers "F.Cu" "F.Mask" "F.Paste")
			(net "P3V3_STBY")
		)
		(zone
			(layer "F.Cu")
			(hatch none 0.5)
			(connect_pads
				(clearance 0)
			)
			(min_thickness 0.25)
			(keepout
				(tracks not_allowed)
				(vias allowed)
				(pads allowed)
				(copperpour not_allowed)
				(footprints allowed)
			)
			(placement
				(enabled no)
				(sheetname "")
			)
			(fill
				(thermal_gap 0.5)
				(thermal_bridge_width 0.5)
				(island_removal_mode 0)
			)
			(polygon
				(pts
					(xy 279.155144 -188.464444) (xy 279.4508 -188.464444) (xy 279.4508 -188.549788) (xy 279.155144 -188.549788)
				)
			)
		)
		(zone
			(layer "F.Cu")
			(hatch none 0.5)
			(connect_pads
				(clearance 0)
			)
			(min_thickness 0.25)
			(keepout
				(tracks allowed)
				(vias not_allowed)
				(pads allowed)
				(copperpour not_allowed)
				(footprints allowed)
			)
			(placement
				(enabled no)
				(sheetname "")
			)
			(fill
				(thermal_gap 0.5)
				(thermal_bridge_width 0.5)
				(island_removal_mode 0)
			)
			(polygon
				(pts
					(xy 278.830024 -187.224924) (xy 278.830024 -188.139324) (xy 277.433024 -188.139324) (xy 277.433024 -188.874908)
					(xy 278.830024 -188.874908) (xy 278.830024 -189.789308) (xy 279.77592 -189.789308) (xy 279.77592 -188.874908)
					(xy 281.17292 -188.874908) (xy 281.17292 -188.139324) (xy 279.77592 -188.139324) (xy 279.77592 -187.224924)
				)
			)
		)
	)
	(footprint ""
		(layer "F.Cu")
		(at 294.513 -157.988)
		(property "Reference" "R679"
			(at 0 0 0)
			(layer "F.SilkS")
			(hide yes)
			(effects
				(font
					(size 1.27 1.27)
				)
			)
		)
		(property "Value" "0R2J-2-GP"
			(at 0.064008 -3.993896 0)
			(unlocked yes)
			(layer "F.Fab")
			(hide yes)
			(effects
				(font
					(size 1.016 1.016)
					(thickness 0.1524)
				)
			)
		)
		(property "Device Type" "R402H16"
			(at 0.064008 -5.517896 0)
			(unlocked yes)
			(layer "F.Fab")
			(hide yes)
			(effects
				(font
					(size 1.016 1.016)
					(thickness 0.1524)
				)
			)
		)
		(duplicate_pad_numbers_are_jumpers no)
		(fp_line
			(start -0.508 -0.9398)
			(end -0.508 0.9398)
			(stroke
				(width 0.1524)
				(type default)
			)
			(layer "F.SilkS")
		)
		(fp_line
			(start 0.508 -0.9398)
			(end -0.508 -0.9398)
			(stroke
				(width 0.1524)
				(type default)
			)
			(layer "F.SilkS")
		)
		(fp_rect
			(start -0.508 0.9398)
			(end 0.508 -0.9398)
			(stroke
				(width 0)
				(type default)
			)
			(fill no)
			(layer "F.CrtYd")
		)
		(fp_rect
			(start -0.508 0.9398)
			(end 0.508 -0.9398)
			(stroke
				(width 0)
				(type default)
			)
			(fill no)
			(layer "F.Fab")
		)
		(pad "1" smd custom
			(at 0 -0.4445)
			(size 0.1397 0.1397)
			(layers "F.Cu" "F.Mask" "F.Paste")
			(net "BMC_RXCK_R")
			(options
				(clearance outline)
				(anchor circle)
			)
			(primitives
				(gr_poly
					(pts
						(arc
							(start -0.1778 -0.2794)
							(mid -0.249642 -0.249642)
							(end -0.2794 -0.1778)
						)
						(arc
							(start -0.2794 0.1778)
							(mid -0.249642 0.249642)
							(end -0.1778 0.2794)
						)
						(arc
							(start 0.1778 0.2794)
							(mid 0.249642 0.249642)
							(end 0.2794 0.1778)
						)
						(arc
							(start 0.2794 -0.1778)
							(mid 0.249642 -0.249642)
							(end 0.1778 -0.2794)
						)
					)
					(width 0)
					(fill yes)
				)
			)
		)
		(pad "2" smd custom
			(at 0 0.4445)
			(size 0.1397 0.1397)
			(layers "F.Cu" "F.Mask" "F.Paste")
			(net "CLK_50M_BMC0")
			(options
				(clearance outline)
				(anchor circle)
			)
			(primitives
				(gr_poly
					(pts
						(arc
							(start -0.1778 -0.2794)
							(mid -0.249642 -0.249642)
							(end -0.2794 -0.1778)
						)
						(arc
							(start -0.2794 0.1778)
							(mid -0.249642 0.249642)
							(end -0.1778 0.2794)
						)
						(arc
							(start 0.1778 0.2794)
							(mid 0.249642 0.249642)
							(end 0.2794 0.1778)
						)
						(arc
							(start 0.2794 -0.1778)
							(mid 0.249642 -0.249642)
							(end 0.1778 -0.2794)
						)
					)
					(width 0)
					(fill yes)
				)
			)
		)
	)
	(footprint ""
		(layer "F.Cu")
		(at 199.205596 -121.558812 180)
		(property "Reference" "PC232"
			(at 0 0 180)
			(layer "F.SilkS")
			(hide yes)
			(effects
				(font
					(size 1.27 1.27)
				)
			)
		)
		(property "Value" "SC1U16V3KX-5GP"
			(at 0 -2.8194 180)
			(unlocked yes)
			(layer "F.Fab")
			(hide yes)
			(effects
				(font
					(size 1.016 1.016)
					(thickness 0.1524)
				)
			)
		)
		(property "Device Type" "C603H36"
			(at 0 -4.3434 180)
			(unlocked yes)
			(layer "F.Fab")
			(hide yes)
			(effects
				(font
					(size 1.016 1.016)
					(thickness 0.1524)
				)
			)
		)
		(duplicate_pad_numbers_are_jumpers no)
		(fp_line
			(start 0.508 0)
			(end -0.508 0)
			(stroke
				(width 0.2032)
				(type default)
			)
			(layer "F.SilkS")
		)
		(fp_rect
			(start -0.5842 1.3335)
			(end 0.5842 -1.3335)
			(stroke
				(width 0)
				(type default)
			)
			(fill no)
			(layer "F.CrtYd")
		)
		(fp_rect
			(start -0.5842 1.3335)
			(end 0.5842 -1.3335)
			(stroke
				(width 0)
				(type default)
			)
			(fill no)
			(layer "F.Fab")
		)
		(pad "1" smd custom
			(at 0 -0.762 180)
			(size 0.2159 0.2159)
			(layers "F.Cu" "F.Mask" "F.Paste")
			(net "P1V5_E_VRG5")
			(options
				(clearance outline)
				(anchor circle)
			)
			(primitives
				(gr_poly
					(pts
						(arc
							(start -0.3302 -0.4318)
							(mid -0.402042 -0.402042)
							(end -0.4318 -0.3302)
						)
						(arc
							(start -0.4318 0.3302)
							(mid -0.402042 0.402042)
							(end -0.3302 0.4318)
						)
						(arc
							(start 0.3302 0.4318)
							(mid 0.402042 0.402042)
							(end 0.4318 0.3302)
						)
						(arc
							(start 0.4318 -0.3302)
							(mid 0.402042 -0.402042)
							(end 0.3302 -0.4318)
						)
					)
					(width 0)
					(fill yes)
				)
			)
		)
		(pad "2" smd custom
			(at 0 0.762 180)
			(size 0.2159 0.2159)
			(layers "F.Cu" "F.Mask" "F.Paste")
			(net "GND")
			(options
				(clearance outline)
				(anchor circle)
			)
			(primitives
				(gr_poly
					(pts
						(arc
							(start -0.3302 -0.4318)
							(mid -0.402042 -0.402042)
							(end -0.4318 -0.3302)
						)
						(arc
							(start -0.4318 0.3302)
							(mid -0.402042 0.402042)
							(end -0.3302 0.4318)
						)
						(arc
							(start 0.3302 0.4318)
							(mid 0.402042 0.402042)
							(end 0.4318 0.3302)
						)
						(arc
							(start 0.4318 -0.3302)
							(mid 0.402042 -0.402042)
							(end 0.3302 -0.4318)
						)
					)
					(width 0)
					(fill yes)
				)
			)
		)
	)
	(footprint ""
		(layer "F.Cu")
		(at 85.071966 -61.341 -90)
		(property "Reference" "SC887"
			(at 0 0 270)
			(layer "F.SilkS")
			(hide yes)
			(effects
				(font
					(size 1.27 1.27)
				)
			)
		)
		(property "Value" "SC12P50V2JN-3GP"
			(at 1.1811 -2.7051 270)
			(unlocked yes)
			(layer "F.Fab")
			(hide yes)
			(effects
				(font
					(size 1.016 1.016)
					(thickness 0.1524)
				)
			)
		)
		(property "Device Type" "C402H24"
			(at 1.1811 -4.2291 270)
			(unlocked yes)
			(layer "F.Fab")
			(hide yes)
			(effects
				(font
					(size 1.016 1.016)
					(thickness 0.1524)
				)
			)
		)
		(duplicate_pad_numbers_are_jumpers no)
		(fp_rect
			(start -0.4318 0.9525)
			(end 0.4318 -0.9525)
			(stroke
				(width 0)
				(type default)
			)
			(fill no)
			(layer "F.CrtYd")
		)
		(fp_rect
			(start -0.4318 0.9525)
			(end 0.4318 -0.9525)
			(stroke
				(width 0)
				(type default)
			)
			(fill no)
			(layer "F.Fab")
		)
		(pad "1" smd custom
			(at 0 -0.4445 270)
			(size 0.1524 0.1524)
			(layers "F.Cu" "F.Mask" "F.Paste")
			(net "IOC_REF_CLK_P")
			(options
				(clearance outline)
				(anchor circle)
			)
			(primitives
				(gr_poly
					(pts
						(arc
							(start 0.3048 -0.2032)
							(mid 0.275042 -0.275042)
							(end 0.2032 -0.3048)
						)
						(arc
							(start -0.2032 -0.3048)
							(mid -0.275042 -0.275042)
							(end -0.3048 -0.2032)
						)
						(arc
							(start -0.3048 0.2032)
							(mid -0.275042 0.275042)
							(end -0.2032 0.3048)
						)
						(arc
							(start 0.2032 0.3048)
							(mid 0.275042 0.275042)
							(end 0.3048 0.2032)
						)
					)
					(width 0)
					(fill yes)
				)
			)
		)
		(pad "2" smd custom
			(at 0 0.4445 270)
			(size 0.1524 0.1524)
			(layers "F.Cu" "F.Mask" "F.Paste")
			(net "GND")
			(options
				(clearance outline)
				(anchor circle)
			)
			(primitives
				(gr_poly
					(pts
						(arc
							(start 0.3048 -0.2032)
							(mid 0.275042 -0.275042)
							(end 0.2032 -0.3048)
						)
						(arc
							(start -0.2032 -0.3048)
							(mid -0.275042 -0.275042)
							(end -0.3048 -0.2032)
						)
						(arc
							(start -0.3048 0.2032)
							(mid -0.275042 0.275042)
							(end -0.2032 0.3048)
						)
						(arc
							(start 0.2032 0.3048)
							(mid 0.275042 0.275042)
							(end 0.3048 0.2032)
						)
					)
					(width 0)
					(fill yes)
				)
			)
		)
	)
	(footprint ""
		(layer "F.Cu")
		(at 117.602 -29.845)
		(property "Reference" "STP41"
			(at 0 0 0)
			(layer "F.SilkS")
			(hide yes)
			(effects
				(font
					(size 1.27 1.27)
				)
			)
		)
		(property "Value" "TPAD28"
			(at 0.0127 -1.8034 0)
			(unlocked yes)
			(layer "F.Fab")
			(hide yes)
			(effects
				(font
					(size 1.016 1.016)
					(thickness 0.1524)
				)
			)
		)
		(property "Device Type" "TPAD28"
			(at 0.0127 -3.3274 0)
			(unlocked yes)
			(layer "F.Fab")
			(hide yes)
			(effects
				(font
					(size 1.016 1.016)
					(thickness 0.1524)
				)
			)
		)
		(duplicate_pad_numbers_are_jumpers no)
		(fp_poly
			(pts
				(arc
					(start 0.3556 0)
					(mid -0.3556 0)
					(end 0.3556 0)
				)
			)
			(stroke
				(width 0)
				(type default)
			)
			(fill no)
			(layer "F.CrtYd")
		)
		(fp_poly
			(pts
				(arc
					(start 0.6096 0)
					(mid -0.6096 0)
					(end 0.6096 0)
				)
			)
			(stroke
				(width 0)
				(type default)
			)
			(fill no)
			(layer "F.Fab")
		)
		(pad "1" smd circle
			(at 0 0)
			(size 0.7112 0.7112)
			(layers "F.Cu" "F.Mask" "F.Paste")
			(net "SYS_HALT1#")
		)
	)
	(footprint ""
		(layer "F.Cu")
		(at 6.300216 -213.54288 90)
		(property "Reference" "R621"
			(at 0 0 90)
			(layer "F.SilkS")
			(hide yes)
			(effects
				(font
					(size 1.27 1.27)
				)
			)
		)
		(property "Value" "0R2J-2-GP"
			(at 0.064008 -3.993896 90)
			(unlocked yes)
			(layer "F.Fab")
			(hide yes)
			(effects
				(font
					(size 1.016 1.016)
					(thickness 0.1524)
				)
			)
		)
		(property "Device Type" "R402H16"
			(at 0.064008 -5.517896 90)
			(unlocked yes)
			(layer "F.Fab")
			(hide yes)
			(effects
				(font
					(size 1.016 1.016)
					(thickness 0.1524)
				)
			)
		)
		(duplicate_pad_numbers_are_jumpers no)
		(fp_line
			(start 0.508 -0.9398)
			(end -0.508 -0.9398)
			(stroke
				(width 0.1524)
				(type default)
			)
			(layer "F.SilkS")
		)
		(fp_line
			(start -0.508 -0.9398)
			(end -0.508 0.9398)
			(stroke
				(width 0.1524)
				(type default)
			)
			(layer "F.SilkS")
		)
		(fp_rect
			(start -0.508 0.9398)
			(end 0.508 -0.9398)
			(stroke
				(width 0)
				(type default)
			)
			(fill no)
			(layer "F.CrtYd")
		)
		(fp_rect
			(start -0.508 0.9398)
			(end 0.508 -0.9398)
			(stroke
				(width 0)
				(type default)
			)
			(fill no)
			(layer "F.Fab")
		)
		(pad "1" smd custom
			(at 0 -0.4445 90)
			(size 0.1397 0.1397)
			(layers "F.Cu" "F.Mask" "F.Paste")
			(net "BUS_SW_EN")
			(options
				(clearance outline)
				(anchor circle)
			)
			(primitives
				(gr_poly
					(pts
						(arc
							(start -0.1778 -0.2794)
							(mid -0.249642 -0.249642)
							(end -0.2794 -0.1778)
						)
						(arc
							(start -0.2794 0.1778)
							(mid -0.249642 0.249642)
							(end -0.1778 0.2794)
						)
						(arc
							(start 0.1778 0.2794)
							(mid 0.249642 0.249642)
							(end 0.2794 0.1778)
						)
						(arc
							(start 0.2794 -0.1778)
							(mid 0.249642 -0.249642)
							(end 0.1778 -0.2794)
						)
					)
					(width 0)
					(fill yes)
				)
			)
		)
		(pad "2" smd custom
			(at 0 0.4445 90)
			(size 0.1397 0.1397)
			(layers "F.Cu" "F.Mask" "F.Paste")
			(net "PRSNT_AND_3")
			(options
				(clearance outline)
				(anchor circle)
			)
			(primitives
				(gr_poly
					(pts
						(arc
							(start -0.1778 -0.2794)
							(mid -0.249642 -0.249642)
							(end -0.2794 -0.1778)
						)
						(arc
							(start -0.2794 0.1778)
							(mid -0.249642 0.249642)
							(end -0.1778 0.2794)
						)
						(arc
							(start 0.1778 0.2794)
							(mid 0.249642 0.249642)
							(end 0.2794 0.1778)
						)
						(arc
							(start 0.2794 -0.1778)
							(mid 0.249642 -0.249642)
							(end 0.1778 -0.2794)
						)
					)
					(width 0)
					(fill yes)
				)
			)
		)
	)
	(footprint ""
		(layer "F.Cu")
		(at 118.37797 -114.3 180)
		(property "Reference" "SC1071"
			(at 0 0 180)
			(layer "F.SilkS")
			(hide yes)
			(effects
				(font
					(size 1.27 1.27)
				)
			)
		)
		(property "Value" "SCD01U10V1KX-GP"
			(at -2.8321 -1.7399 180)
			(unlocked yes)
			(layer "F.Fab")
			(hide yes)
			(effects
				(font
					(size 1.016 1.016)
					(thickness 0.1524)
				)
			)
		)
		(property "Device Type" "C0201H13"
			(at -2.8321 -3.2639 180)
			(unlocked yes)
			(layer "F.Fab")
			(hide yes)
			(effects
				(font
					(size 1.016 1.016)
					(thickness 0.1524)
				)
			)
		)
		(duplicate_pad_numbers_are_jumpers no)
		(fp_rect
			(start -0.2794 0.6477)
			(end 0.2794 -0.6477)
			(stroke
				(width 0)
				(type default)
			)
			(fill no)
			(layer "F.CrtYd")
		)
		(fp_rect
			(start -0.2794 0.6477)
			(end 0.2794 -0.6477)
			(stroke
				(width 0)
				(type default)
			)
			(fill no)
			(layer "F.Fab")
		)
		(pad "1" smd custom
			(at 0 -0.2794 180)
			(size 0.0762 0.0762)
			(layers "F.Cu" "F.Mask" "F.Paste")
			(net "SAS_HDD_TX2_P")
			(options
				(clearance outline)
				(anchor circle)
			)
			(primitives
				(gr_poly
					(pts
						(arc
							(start 0.1524 -0.127)
							(mid 0.137521 -0.162921)
							(end 0.1016 -0.1778)
						)
						(arc
							(start -0.1016 -0.1778)
							(mid -0.137521 -0.162921)
							(end -0.1524 -0.127)
						)
						(arc
							(start -0.1524 0.127)
							(mid -0.137521 0.162921)
							(end -0.1016 0.1778)
						)
						(arc
							(start 0.1016 0.1778)
							(mid 0.137521 0.162921)
							(end 0.1524 0.127)
						)
					)
					(width 0)
					(fill yes)
				)
			)
		)
		(pad "2" smd custom
			(at 0 0.2794 180)
			(size 0.0762 0.0762)
			(layers "F.Cu" "F.Mask" "F.Paste")
			(net "SAS_EXP_GF_TX_DP6")
			(options
				(clearance outline)
				(anchor circle)
			)
			(primitives
				(gr_poly
					(pts
						(arc
							(start 0.1524 -0.127)
							(mid 0.137521 -0.162921)
							(end 0.1016 -0.1778)
						)
						(arc
							(start -0.1016 -0.1778)
							(mid -0.137521 -0.162921)
							(end -0.1524 -0.127)
						)
						(arc
							(start -0.1524 0.127)
							(mid -0.137521 0.162921)
							(end -0.1016 0.1778)
						)
						(arc
							(start 0.1016 0.1778)
							(mid 0.137521 0.162921)
							(end 0.1524 0.127)
						)
					)
					(width 0)
					(fill yes)
				)
			)
		)
	)
	(footprint ""
		(layer "F.Cu")
		(at 100.47097 -76.454)
		(property "Reference" "SR805"
			(at 0 0 0)
			(layer "F.SilkS")
			(hide yes)
			(effects
				(font
					(size 1.27 1.27)
				)
			)
		)
		(property "Value" "4K75R2F-1-GP"
			(at 0.064008 -3.993896 0)
			(unlocked yes)
			(layer "F.Fab")
			(hide yes)
			(effects
				(font
					(size 1.016 1.016)
					(thickness 0.1524)
				)
			)
		)
		(property "Device Type" "R402H16"
			(at 0.064008 -5.517896 0)
			(unlocked yes)
			(layer "F.Fab")
			(hide yes)
			(effects
				(font
					(size 1.016 1.016)
					(thickness 0.1524)
				)
			)
		)
		(duplicate_pad_numbers_are_jumpers no)
		(fp_line
			(start -0.508 -0.9398)
			(end -0.508 0.9398)
			(stroke
				(width 0.1524)
				(type default)
			)
			(layer "F.SilkS")
		)
		(fp_line
			(start 0.508 -0.9398)
			(end -0.508 -0.9398)
			(stroke
				(width 0.1524)
				(type default)
			)
			(layer "F.SilkS")
		)
		(fp_rect
			(start -0.508 0.9398)
			(end 0.508 -0.9398)
			(stroke
				(width 0)
				(type default)
			)
			(fill no)
			(layer "F.CrtYd")
		)
		(fp_rect
			(start -0.508 0.9398)
			(end 0.508 -0.9398)
			(stroke
				(width 0)
				(type default)
			)
			(fill no)
			(layer "F.Fab")
		)
		(pad "1" smd custom
			(at 0 -0.4445)
			(size 0.1397 0.1397)
			(layers "F.Cu" "F.Mask" "F.Paste")
			(net "EXP_IDDT")
			(options
				(clearance outline)
				(anchor circle)
			)
			(primitives
				(gr_poly
					(pts
						(arc
							(start -0.1778 -0.2794)
							(mid -0.249642 -0.249642)
							(end -0.2794 -0.1778)
						)
						(arc
							(start -0.2794 0.1778)
							(mid -0.249642 0.249642)
							(end -0.1778 0.2794)
						)
						(arc
							(start 0.1778 0.2794)
							(mid 0.249642 0.249642)
							(end 0.2794 0.1778)
						)
						(arc
							(start 0.2794 -0.1778)
							(mid 0.249642 -0.249642)
							(end 0.1778 -0.2794)
						)
					)
					(width 0)
					(fill yes)
				)
			)
		)
		(pad "2" smd custom
			(at 0 0.4445)
			(size 0.1397 0.1397)
			(layers "F.Cu" "F.Mask" "F.Paste")
			(net "GND")
			(options
				(clearance outline)
				(anchor circle)
			)
			(primitives
				(gr_poly
					(pts
						(arc
							(start -0.1778 -0.2794)
							(mid -0.249642 -0.249642)
							(end -0.2794 -0.1778)
						)
						(arc
							(start -0.2794 0.1778)
							(mid -0.249642 0.249642)
							(end -0.1778 0.2794)
						)
						(arc
							(start 0.1778 0.2794)
							(mid 0.249642 0.249642)
							(end 0.2794 0.1778)
						)
						(arc
							(start 0.2794 -0.1778)
							(mid 0.249642 -0.249642)
							(end 0.1778 -0.2794)
						)
					)
					(width 0)
					(fill yes)
				)
			)
		)
	)
	(footprint ""
		(layer "F.Cu")
		(at 48.26 -230.886)
		(property "Reference" "C274"
			(at 0 0 0)
			(layer "F.SilkS")
			(hide yes)
			(effects
				(font
					(size 1.27 1.27)
				)
			)
		)
		(property "Value" "SCD1U25V3KX-GP"
			(at 0 -2.8194 0)
			(unlocked yes)
			(layer "F.Fab")
			(hide yes)
			(effects
				(font
					(size 1.016 1.016)
					(thickness 0.1524)
				)
			)
		)
		(property "Device Type" "C603H36"
			(at 0 -4.3434 0)
			(unlocked yes)
			(layer "F.Fab")
			(hide yes)
			(effects
				(font
					(size 1.016 1.016)
					(thickness 0.1524)
				)
			)
		)
		(duplicate_pad_numbers_are_jumpers no)
		(fp_line
			(start 0.508 0)
			(end -0.508 0)
			(stroke
				(width 0.2032)
				(type default)
			)
			(layer "F.SilkS")
		)
		(fp_rect
			(start -0.5842 1.3335)
			(end 0.5842 -1.3335)
			(stroke
				(width 0)
				(type default)
			)
			(fill no)
			(layer "F.CrtYd")
		)
		(fp_rect
			(start -0.5842 1.3335)
			(end 0.5842 -1.3335)
			(stroke
				(width 0)
				(type default)
			)
			(fill no)
			(layer "F.Fab")
		)
		(pad "1" smd custom
			(at 0 -0.762)
			(size 0.2159 0.2159)
			(layers "F.Cu" "F.Mask" "F.Paste")
			(net "P12V_PCIE")
			(options
				(clearance outline)
				(anchor circle)
			)
			(primitives
				(gr_poly
					(pts
						(arc
							(start -0.3302 -0.4318)
							(mid -0.402042 -0.402042)
							(end -0.4318 -0.3302)
						)
						(arc
							(start -0.4318 0.3302)
							(mid -0.402042 0.402042)
							(end -0.3302 0.4318)
						)
						(arc
							(start 0.3302 0.4318)
							(mid 0.402042 0.402042)
							(end 0.4318 0.3302)
						)
						(arc
							(start 0.4318 -0.3302)
							(mid 0.402042 -0.402042)
							(end 0.3302 -0.4318)
						)
					)
					(width 0)
					(fill yes)
				)
			)
		)
		(pad "2" smd custom
			(at 0 0.762)
			(size 0.2159 0.2159)
			(layers "F.Cu" "F.Mask" "F.Paste")
			(net "GND")
			(options
				(clearance outline)
				(anchor circle)
			)
			(primitives
				(gr_poly
					(pts
						(arc
							(start -0.3302 -0.4318)
							(mid -0.402042 -0.402042)
							(end -0.4318 -0.3302)
						)
						(arc
							(start -0.4318 0.3302)
							(mid -0.402042 0.402042)
							(end -0.3302 0.4318)
						)
						(arc
							(start 0.3302 0.4318)
							(mid 0.402042 0.402042)
							(end 0.4318 0.3302)
						)
						(arc
							(start 0.4318 -0.3302)
							(mid 0.402042 -0.402042)
							(end 0.3302 -0.4318)
						)
					)
					(width 0)
					(fill yes)
				)
			)
		)
	)
	(footprint ""
		(layer "F.Cu")
		(at 220.17228 -87.85352 -90)
		(property "Reference" "U184"
			(at 0 0 270)
			(layer "F.SilkS")
			(hide yes)
			(effects
				(font
					(size 1.27 1.27)
				)
			)
		)
		(property "Value" "TXS0102DCUR-1-GP"
			(at 0 -11.1252 270)
			(unlocked yes)
			(layer "F.Fab")
			(hide yes)
			(effects
				(font
					(size 1.016 1.016)
					(thickness 0.1524)
				)
			)
		)
		(property "Device Type" "SSOIC8-4H36"
			(at 0 -12.6492 270)
			(unlocked yes)
			(layer "F.Fab")
			(hide yes)
			(effects
				(font
					(size 1.016 1.016)
					(thickness 0.1524)
				)
			)
		)
		(duplicate_pad_numbers_are_jumpers no)
		(fp_line
			(start -1.2573 2.1844)
			(end -1.2573 -2.1844)
			(stroke
				(width 0.1524)
				(type default)
			)
			(layer "F.SilkS")
		)
		(fp_line
			(start 1.2573 2.1844)
			(end -1.2573 2.1844)
			(stroke
				(width 0.1524)
				(type default)
			)
			(layer "F.SilkS")
		)
		(fp_line
			(start -1.2954 0.4572)
			(end -1.2954 2.159)
			(stroke
				(width 0.4064)
				(type default)
			)
			(layer "F.SilkS")
		)
		(fp_line
			(start -1.2065 0.2667)
			(end -1.27 0.2667)
			(stroke
				(width 0.1524)
				(type default)
			)
			(layer "F.SilkS")
		)
		(fp_line
			(start -0.9017 -0.0381)
			(end -1.2065 0.2667)
			(stroke
				(width 0.1524)
				(type default)
			)
			(layer "F.SilkS")
		)
		(fp_line
			(start -1.2573 -0.3556)
			(end -1.2192 -0.3556)
			(stroke
				(width 0.1524)
				(type default)
			)
			(layer "F.SilkS")
		)
		(fp_line
			(start -1.2192 -0.3556)
			(end -0.9017 -0.0381)
			(stroke
				(width 0.1524)
				(type default)
			)
			(layer "F.SilkS")
		)
		(fp_line
			(start -1.2573 -2.1844)
			(end 1.2573 -2.1844)
			(stroke
				(width 0.1524)
				(type default)
			)
			(layer "F.SilkS")
		)
		(fp_line
			(start 1.2573 -2.1844)
			(end 1.2573 2.1844)
			(stroke
				(width 0.1524)
				(type default)
			)
			(layer "F.SilkS")
		)
		(fp_poly
			(pts
				(xy -1.5113 2.4384) (xy 1.5113 2.4384) (xy 1.5113 -2.4384) (xy -1.5113 -2.4384)
			)
			(stroke
				(width 0)
				(type default)
			)
			(fill no)
			(layer "F.CrtYd")
		)
		(fp_poly
			(pts
				(xy -1.5113 -2.4384) (xy 1.5113 -2.4384) (xy 1.5113 2.4384) (xy -1.5113 2.4384)
			)
			(stroke
				(width 0)
				(type default)
			)
			(fill no)
			(layer "F.Fab")
		)
		(pad "1" smd rect
			(at -0.75057 1.1684 270)
			(size 0.3048 1.524)
			(layers "F.Cu" "F.Mask" "F.Paste")
			(net "IOC_UART_R_RX")
		)
		(pad "2" smd rect
			(at -0.25019 1.1684 270)
			(size 0.3048 1.524)
			(layers "F.Cu" "F.Mask" "F.Paste")
			(net "GND")
		)
		(pad "3" smd rect
			(at 0.25019 1.1684 270)
			(size 0.3048 1.524)
			(layers "F.Cu" "F.Mask" "F.Paste")
			(net "P1V8_C")
		)
		(pad "4" smd rect
			(at 0.75057 1.1684 270)
			(size 0.3048 1.524)
			(layers "F.Cu" "F.Mask" "F.Paste")
			(net "IOC_UART_0_RX_R")
		)
		(pad "5" smd rect
			(at 0.75057 -1.1684 270)
			(size 0.3048 1.524)
			(layers "F.Cu" "F.Mask" "F.Paste")
			(net "IOC_UART_0_TX_R")
		)
		(pad "6" smd rect
			(at 0.25019 -1.1684 270)
			(size 0.3048 1.524)
			(layers "F.Cu" "F.Mask" "F.Paste")
			(net "SYS_RST_N_0")
		)
		(pad "7" smd rect
			(at -0.25019 -1.1684 270)
			(size 0.3048 1.524)
			(layers "F.Cu" "F.Mask" "F.Paste")
			(net "P3V3_STBY")
		)
		(pad "8" smd rect
			(at -0.75057 -1.1684 270)
			(size 0.3048 1.524)
			(layers "F.Cu" "F.Mask" "F.Paste")
			(net "IOC_UART_R_TX")
		)
	)
	(footprint ""
		(layer "F.Cu")
		(at 95.89897 -89.662 -90)
		(property "Reference" "SR798"
			(at 0 0 270)
			(layer "F.SilkS")
			(hide yes)
			(effects
				(font
					(size 1.27 1.27)
				)
			)
		)
		(property "Value" "4K75R2F-1-GP"
			(at 0.064008 -3.993896 270)
			(unlocked yes)
			(layer "F.Fab")
			(hide yes)
			(effects
				(font
					(size 1.016 1.016)
					(thickness 0.1524)
				)
			)
		)
		(property "Device Type" "R402H16"
			(at 0.064008 -5.517896 270)
			(unlocked yes)
			(layer "F.Fab")
			(hide yes)
			(effects
				(font
					(size 1.016 1.016)
					(thickness 0.1524)
				)
			)
		)
		(duplicate_pad_numbers_are_jumpers no)
		(fp_line
			(start -0.508 -0.9398)
			(end -0.508 0.9398)
			(stroke
				(width 0.1524)
				(type default)
			)
			(layer "F.SilkS")
		)
		(fp_line
			(start 0.508 -0.9398)
			(end -0.508 -0.9398)
			(stroke
				(width 0.1524)
				(type default)
			)
			(layer "F.SilkS")
		)
		(fp_rect
			(start -0.508 0.9398)
			(end 0.508 -0.9398)
			(stroke
				(width 0)
				(type default)
			)
			(fill no)
			(layer "F.CrtYd")
		)
		(fp_rect
			(start -0.508 0.9398)
			(end 0.508 -0.9398)
			(stroke
				(width 0)
				(type default)
			)
			(fill no)
			(layer "F.Fab")
		)
		(pad "1" smd custom
			(at 0 -0.4445 270)
			(size 0.1397 0.1397)
			(layers "F.Cu" "F.Mask" "F.Paste")
			(net "EXP_CLK_SEL0")
			(options
				(clearance outline)
				(anchor circle)
			)
			(primitives
				(gr_poly
					(pts
						(arc
							(start -0.1778 -0.2794)
							(mid -0.249642 -0.249642)
							(end -0.2794 -0.1778)
						)
						(arc
							(start -0.2794 0.1778)
							(mid -0.249642 0.249642)
							(end -0.1778 0.2794)
						)
						(arc
							(start 0.1778 0.2794)
							(mid 0.249642 0.249642)
							(end 0.2794 0.1778)
						)
						(arc
							(start 0.2794 -0.1778)
							(mid 0.249642 -0.249642)
							(end 0.1778 -0.2794)
						)
					)
					(width 0)
					(fill yes)
				)
			)
		)
		(pad "2" smd custom
			(at 0 0.4445 270)
			(size 0.1397 0.1397)
			(layers "F.Cu" "F.Mask" "F.Paste")
			(net "GND")
			(options
				(clearance outline)
				(anchor circle)
			)
			(primitives
				(gr_poly
					(pts
						(arc
							(start -0.1778 -0.2794)
							(mid -0.249642 -0.249642)
							(end -0.2794 -0.1778)
						)
						(arc
							(start -0.2794 0.1778)
							(mid -0.249642 0.249642)
							(end -0.1778 0.2794)
						)
						(arc
							(start 0.1778 0.2794)
							(mid 0.249642 0.249642)
							(end 0.2794 0.1778)
						)
						(arc
							(start 0.2794 -0.1778)
							(mid 0.249642 -0.249642)
							(end 0.1778 -0.2794)
						)
					)
					(width 0)
					(fill yes)
				)
			)
		)
	)
	(footprint ""
		(layer "F.Cu")
		(at 8.078216 -224.97288 -90)
		(property "Reference" "R537"
			(at 0 0 270)
			(layer "F.SilkS")
			(hide yes)
			(effects
				(font
					(size 1.27 1.27)
				)
			)
		)
		(property "Value" "0R2J-2-GP"
			(at 0.064008 -3.993896 270)
			(unlocked yes)
			(layer "F.Fab")
			(hide yes)
			(effects
				(font
					(size 1.016 1.016)
					(thickness 0.1524)
				)
			)
		)
		(property "Device Type" "R402H16"
			(at 0.064008 -5.517896 270)
			(unlocked yes)
			(layer "F.Fab")
			(hide yes)
			(effects
				(font
					(size 1.016 1.016)
					(thickness 0.1524)
				)
			)
		)
		(duplicate_pad_numbers_are_jumpers no)
		(fp_line
			(start -0.508 -0.9398)
			(end -0.508 0.9398)
			(stroke
				(width 0.1524)
				(type default)
			)
			(layer "F.SilkS")
		)
		(fp_line
			(start 0.508 -0.9398)
			(end -0.508 -0.9398)
			(stroke
				(width 0.1524)
				(type default)
			)
			(layer "F.SilkS")
		)
		(fp_rect
			(start -0.508 0.9398)
			(end 0.508 -0.9398)
			(stroke
				(width 0)
				(type default)
			)
			(fill no)
			(layer "F.CrtYd")
		)
		(fp_rect
			(start -0.508 0.9398)
			(end 0.508 -0.9398)
			(stroke
				(width 0)
				(type default)
			)
			(fill no)
			(layer "F.Fab")
		)
		(pad "1" smd custom
			(at 0 -0.4445 270)
			(size 0.1397 0.1397)
			(layers "F.Cu" "F.Mask" "F.Paste")
			(net "PEER_TRAY_BMC")
			(options
				(clearance outline)
				(anchor circle)
			)
			(primitives
				(gr_poly
					(pts
						(arc
							(start -0.1778 -0.2794)
							(mid -0.249642 -0.249642)
							(end -0.2794 -0.1778)
						)
						(arc
							(start -0.2794 0.1778)
							(mid -0.249642 0.249642)
							(end -0.1778 0.2794)
						)
						(arc
							(start 0.1778 0.2794)
							(mid 0.249642 0.249642)
							(end 0.2794 0.1778)
						)
						(arc
							(start 0.2794 -0.1778)
							(mid 0.249642 -0.249642)
							(end 0.1778 -0.2794)
						)
					)
					(width 0)
					(fill yes)
				)
			)
		)
		(pad "2" smd custom
			(at 0 0.4445 270)
			(size 0.1397 0.1397)
			(layers "F.Cu" "F.Mask" "F.Paste")
			(net "PEER_TRAY_R")
			(options
				(clearance outline)
				(anchor circle)
			)
			(primitives
				(gr_poly
					(pts
						(arc
							(start -0.1778 -0.2794)
							(mid -0.249642 -0.249642)
							(end -0.2794 -0.1778)
						)
						(arc
							(start -0.2794 0.1778)
							(mid -0.249642 0.249642)
							(end -0.1778 0.2794)
						)
						(arc
							(start 0.1778 0.2794)
							(mid 0.249642 0.249642)
							(end 0.2794 0.1778)
						)
						(arc
							(start 0.2794 -0.1778)
							(mid 0.249642 -0.249642)
							(end 0.1778 -0.2794)
						)
					)
					(width 0)
					(fill yes)
				)
			)
		)
	)
	(footprint ""
		(layer "F.Cu")
		(at 78.8924 -9.1948 90)
		(property "Reference" "PC204"
			(at 0 0 90)
			(layer "F.SilkS")
			(hide yes)
			(effects
				(font
					(size 1.27 1.27)
				)
			)
		)
		(property "Value" "SC10U25V6KX-1GP"
			(at -0.0762 -5.1308 90)
			(unlocked yes)
			(layer "F.Fab")
			(hide yes)
			(effects
				(font
					(size 1.016 1.016)
					(thickness 0.1524)
				)
			)
		)
		(property "Device Type" "C1206H71"
			(at -0.127 -6.6548 90)
			(unlocked yes)
			(layer "F.Fab")
			(hide yes)
			(effects
				(font
					(size 1.016 1.016)
					(thickness 0.1524)
				)
			)
		)
		(duplicate_pad_numbers_are_jumpers no)
		(fp_line
			(start 1.016 -2.2352)
			(end 1.016 -0.8382)
			(stroke
				(width 0.1524)
				(type default)
			)
			(layer "F.SilkS")
		)
		(fp_line
			(start -1.016 -2.2352)
			(end 1.016 -2.2352)
			(stroke
				(width 0.1524)
				(type default)
			)
			(layer "F.SilkS")
		)
		(fp_line
			(start -1.016 -0.8382)
			(end -1.016 -2.2352)
			(stroke
				(width 0.1524)
				(type default)
			)
			(layer "F.SilkS")
		)
		(fp_line
			(start 1.016 0.8382)
			(end 1.016 2.2352)
			(stroke
				(width 0.1524)
				(type default)
			)
			(layer "F.SilkS")
		)
		(fp_line
			(start 1.016 2.2352)
			(end -1.016 2.2352)
			(stroke
				(width 0.1524)
				(type default)
			)
			(layer "F.SilkS")
		)
		(fp_line
			(start -1.016 2.2352)
			(end -1.016 0.8382)
			(stroke
				(width 0.1524)
				(type default)
			)
			(layer "F.SilkS")
		)
		(fp_rect
			(start -1.0922 2.3114)
			(end 1.0922 -2.3114)
			(stroke
				(width 0)
				(type default)
			)
			(fill no)
			(layer "F.CrtYd")
		)
		(fp_poly
			(pts
				(xy 1.0922 -2.3114) (xy 1.0922 2.3114) (xy -1.0922 2.3114) (xy -1.0922 -2.3114)
			)
			(stroke
				(width 0)
				(type default)
			)
			(fill no)
			(layer "F.Fab")
		)
		(pad "1" smd rect
			(at 0 -1.397 90)
			(size 1.651 1.27)
			(layers "F.Cu" "F.Mask" "F.Paste")
			(net "VT235_VDDH")
		)
		(pad "2" smd rect
			(at 0 1.397 90)
			(size 1.651 1.27)
			(layers "F.Cu" "F.Mask" "F.Paste")
			(net "GND")
		)
	)
	(footprint ""
		(layer "F.Cu")
		(at 293.819072 -191.842136)
		(property "Reference" "C178"
			(at 0 0 0)
			(layer "F.SilkS")
			(hide yes)
			(effects
				(font
					(size 1.27 1.27)
				)
			)
		)
		(property "Value" "SCD1U16V2KX-3GP"
			(at 1.1811 -2.7051 0)
			(unlocked yes)
			(layer "F.Fab")
			(hide yes)
			(effects
				(font
					(size 1.016 1.016)
					(thickness 0.1524)
				)
			)
		)
		(property "Device Type" "C402H22"
			(at 1.1811 -4.2291 0)
			(unlocked yes)
			(layer "F.Fab")
			(hide yes)
			(effects
				(font
					(size 1.016 1.016)
					(thickness 0.1524)
				)
			)
		)
		(duplicate_pad_numbers_are_jumpers no)
		(fp_rect
			(start -0.4318 0.9525)
			(end 0.4318 -0.9525)
			(stroke
				(width 0)
				(type default)
			)
			(fill no)
			(layer "F.CrtYd")
		)
		(fp_rect
			(start -0.4318 0.9525)
			(end 0.4318 -0.9525)
			(stroke
				(width 0)
				(type default)
			)
			(fill no)
			(layer "F.Fab")
		)
		(pad "1" smd custom
			(at 0 -0.4445)
			(size 0.1524 0.1524)
			(layers "F.Cu" "F.Mask" "F.Paste")
			(net "P1V53_STBY")
			(options
				(clearance outline)
				(anchor circle)
			)
			(primitives
				(gr_poly
					(pts
						(arc
							(start 0.3048 -0.2032)
							(mid 0.275042 -0.275042)
							(end 0.2032 -0.3048)
						)
						(arc
							(start -0.2032 -0.3048)
							(mid -0.275042 -0.275042)
							(end -0.3048 -0.2032)
						)
						(arc
							(start -0.3048 0.2032)
							(mid -0.275042 0.275042)
							(end -0.2032 0.3048)
						)
						(arc
							(start 0.2032 0.3048)
							(mid 0.275042 0.275042)
							(end 0.3048 0.2032)
						)
					)
					(width 0)
					(fill yes)
				)
			)
		)
		(pad "2" smd custom
			(at 0 0.4445)
			(size 0.1524 0.1524)
			(layers "F.Cu" "F.Mask" "F.Paste")
			(net "GND")
			(options
				(clearance outline)
				(anchor circle)
			)
			(primitives
				(gr_poly
					(pts
						(arc
							(start 0.3048 -0.2032)
							(mid 0.275042 -0.275042)
							(end 0.2032 -0.3048)
						)
						(arc
							(start -0.2032 -0.3048)
							(mid -0.275042 -0.275042)
							(end -0.3048 -0.2032)
						)
						(arc
							(start -0.3048 0.2032)
							(mid -0.275042 0.275042)
							(end -0.2032 0.3048)
						)
						(arc
							(start 0.2032 0.3048)
							(mid 0.275042 0.275042)
							(end 0.3048 0.2032)
						)
					)
					(width 0)
					(fill yes)
				)
			)
		)
	)
	(footprint ""
		(layer "F.Cu")
		(at 223.266 -83.82 90)
		(property "Reference" "C311"
			(at 0 0 90)
			(layer "F.SilkS")
			(hide yes)
			(effects
				(font
					(size 1.27 1.27)
				)
			)
		)
		(property "Value" "SC1U25V3KX-GP"
			(at 0 -2.8194 90)
			(unlocked yes)
			(layer "F.Fab")
			(hide yes)
			(effects
				(font
					(size 1.016 1.016)
					(thickness 0.1524)
				)
			)
		)
		(property "Device Type" "C603H36"
			(at 0 -4.3434 90)
			(unlocked yes)
			(layer "F.Fab")
			(hide yes)
			(effects
				(font
					(size 1.016 1.016)
					(thickness 0.1524)
				)
			)
		)
		(duplicate_pad_numbers_are_jumpers no)
		(fp_line
			(start 0.508 0)
			(end -0.508 0)
			(stroke
				(width 0.2032)
				(type default)
			)
			(layer "F.SilkS")
		)
		(fp_rect
			(start -0.5842 1.3335)
			(end 0.5842 -1.3335)
			(stroke
				(width 0)
				(type default)
			)
			(fill no)
			(layer "F.CrtYd")
		)
		(fp_rect
			(start -0.5842 1.3335)
			(end 0.5842 -1.3335)
			(stroke
				(width 0)
				(type default)
			)
			(fill no)
			(layer "F.Fab")
		)
		(pad "1" smd custom
			(at 0 -0.762 90)
			(size 0.2159 0.2159)
			(layers "F.Cu" "F.Mask" "F.Paste")
			(net "P12V_MSB")
			(options
				(clearance outline)
				(anchor circle)
			)
			(primitives
				(gr_poly
					(pts
						(arc
							(start -0.3302 -0.4318)
							(mid -0.402042 -0.402042)
							(end -0.4318 -0.3302)
						)
						(arc
							(start -0.4318 0.3302)
							(mid -0.402042 0.402042)
							(end -0.3302 0.4318)
						)
						(arc
							(start 0.3302 0.4318)
							(mid 0.402042 0.402042)
							(end 0.4318 0.3302)
						)
						(arc
							(start 0.4318 -0.3302)
							(mid 0.402042 -0.402042)
							(end 0.3302 -0.4318)
						)
					)
					(width 0)
					(fill yes)
				)
			)
		)
		(pad "2" smd custom
			(at 0 0.762 90)
			(size 0.2159 0.2159)
			(layers "F.Cu" "F.Mask" "F.Paste")
			(net "GND")
			(options
				(clearance outline)
				(anchor circle)
			)
			(primitives
				(gr_poly
					(pts
						(arc
							(start -0.3302 -0.4318)
							(mid -0.402042 -0.402042)
							(end -0.4318 -0.3302)
						)
						(arc
							(start -0.4318 0.3302)
							(mid -0.402042 0.402042)
							(end -0.3302 0.4318)
						)
						(arc
							(start 0.3302 0.4318)
							(mid 0.402042 0.402042)
							(end 0.4318 0.3302)
						)
						(arc
							(start 0.4318 -0.3302)
							(mid 0.402042 -0.402042)
							(end 0.3302 -0.4318)
						)
					)
					(width 0)
					(fill yes)
				)
			)
		)
	)
	(footprint ""
		(layer "F.Cu")
		(at 57.179972 -186.539886)
		(property "Reference" "SCN3"
			(at 0 0 0)
			(layer "F.SilkS")
			(hide yes)
			(effects
				(font
					(size 1.27 1.27)
				)
			)
		)
		(property "Value" "MLX-CONN20A-S3-GP"
			(at -17.870678 -4.036822 0)
			(unlocked yes)
			(layer "F.Fab")
			(hide yes)
			(effects
				(font
					(size 1.016 1.016)
					(thickness 0.1524)
				)
			)
		)
		(property "Device Type" "70246-2001"
			(at -17.870678 -5.560822 0)
			(unlocked yes)
			(layer "F.Fab")
			(hide yes)
			(effects
				(font
					(size 1.016 1.016)
					(thickness 0.1524)
				)
			)
		)
		(duplicate_pad_numbers_are_jumpers no)
		(fp_line
			(start -16.891 3.556)
			(end -16.891 4.826)
			(stroke
				(width 0.4064)
				(type default)
			)
			(layer "F.SilkS")
		)
		(fp_line
			(start -16.891 4.826)
			(end -15.621 4.826)
			(stroke
				(width 0.4064)
				(type default)
			)
			(layer "F.SilkS")
		)
		(fp_line
			(start -16.764 -4.699)
			(end 16.764 -4.699)
			(stroke
				(width 0.1524)
				(type default)
			)
			(layer "F.SilkS")
		)
		(fp_line
			(start -16.764 4.699)
			(end -16.764 -4.699)
			(stroke
				(width 0.1524)
				(type default)
			)
			(layer "F.SilkS")
		)
		(fp_line
			(start -2.0574 4.191)
			(end 2.0574 4.191)
			(stroke
				(width 0.1524)
				(type default)
			)
			(layer "F.SilkS")
		)
		(fp_line
			(start -2.0574 4.699)
			(end -2.0574 4.191)
			(stroke
				(width 0.1524)
				(type default)
			)
			(layer "F.SilkS")
		)
		(fp_line
			(start 2.0574 4.191)
			(end 2.0574 4.699)
			(stroke
				(width 0.1524)
				(type default)
			)
			(layer "F.SilkS")
		)
		(fp_line
			(start 16.764 -4.699)
			(end 16.764 4.699)
			(stroke
				(width 0.1524)
				(type default)
			)
			(layer "F.SilkS")
		)
		(fp_line
			(start 16.764 4.699)
			(end -16.764 4.699)
			(stroke
				(width 0.1524)
				(type default)
			)
			(layer "F.SilkS")
		)
		(fp_circle
			(center -11.43 -1.27)
			(end -10.2997 -1.27)
			(stroke
				(width 0.3048)
				(type default)
			)
			(fill no)
			(layer "F.SilkS")
		)
		(fp_circle
			(center -11.43 1.27)
			(end -10.2997 1.27)
			(stroke
				(width 0.3048)
				(type default)
			)
			(fill no)
			(layer "F.SilkS")
		)
		(fp_circle
			(center -8.89 -1.27)
			(end -7.7597 -1.27)
			(stroke
				(width 0.3048)
				(type default)
			)
			(fill no)
			(layer "F.SilkS")
		)
		(fp_circle
			(center -8.89 1.27)
			(end -7.7597 1.27)
			(stroke
				(width 0.3048)
				(type default)
			)
			(fill no)
			(layer "F.SilkS")
		)
		(fp_circle
			(center -6.35 -1.27)
			(end -5.2197 -1.27)
			(stroke
				(width 0.3048)
				(type default)
			)
			(fill no)
			(layer "F.SilkS")
		)
		(fp_circle
			(center -6.35 1.27)
			(end -5.2197 1.27)
			(stroke
				(width 0.3048)
				(type default)
			)
			(fill no)
			(layer "F.SilkS")
		)
		(fp_circle
			(center -3.81 -1.27)
			(end -2.6797 -1.27)
			(stroke
				(width 0.3048)
				(type default)
			)
			(fill no)
			(layer "F.SilkS")
		)
		(fp_circle
			(center -3.81 1.27)
			(end -2.6797 1.27)
			(stroke
				(width 0.3048)
				(type default)
			)
			(fill no)
			(layer "F.SilkS")
		)
		(fp_circle
			(center -1.27 -1.27)
			(end -0.1397 -1.27)
			(stroke
				(width 0.3048)
				(type default)
			)
			(fill no)
			(layer "F.SilkS")
		)
		(fp_circle
			(center -1.27 1.27)
			(end -0.1397 1.27)
			(stroke
				(width 0.3048)
				(type default)
			)
			(fill no)
			(layer "F.SilkS")
		)
		(fp_circle
			(center 1.27 -1.27)
			(end 2.4003 -1.27)
			(stroke
				(width 0.3048)
				(type default)
			)
			(fill no)
			(layer "F.SilkS")
		)
		(fp_circle
			(center 1.27 1.27)
			(end 2.4003 1.27)
			(stroke
				(width 0.3048)
				(type default)
			)
			(fill no)
			(layer "F.SilkS")
		)
		(fp_circle
			(center 3.81 -1.27)
			(end 4.9403 -1.27)
			(stroke
				(width 0.3048)
				(type default)
			)
			(fill no)
			(layer "F.SilkS")
		)
		(fp_circle
			(center 3.81 1.27)
			(end 4.9403 1.27)
			(stroke
				(width 0.3048)
				(type default)
			)
			(fill no)
			(layer "F.SilkS")
		)
		(fp_circle
			(center 6.35 -1.27)
			(end 7.4803 -1.27)
			(stroke
				(width 0.3048)
				(type default)
			)
			(fill no)
			(layer "F.SilkS")
		)
		(fp_circle
			(center 6.35 1.27)
			(end 7.4803 1.27)
			(stroke
				(width 0.3048)
				(type default)
			)
			(fill no)
			(layer "F.SilkS")
		)
		(fp_circle
			(center 8.89 -1.27)
			(end 10.0203 -1.27)
			(stroke
				(width 0.3048)
				(type default)
			)
			(fill no)
			(layer "F.SilkS")
		)
		(fp_circle
			(center 8.89 1.27)
			(end 10.0203 1.27)
			(stroke
				(width 0.3048)
				(type default)
			)
			(fill no)
			(layer "F.SilkS")
		)
		(fp_circle
			(center 11.43 -1.27)
			(end 12.5603 -1.27)
			(stroke
				(width 0.3048)
				(type default)
			)
			(fill no)
			(layer "F.SilkS")
		)
		(fp_circle
			(center 11.43 1.27)
			(end 12.5603 1.27)
			(stroke
				(width 0.3048)
				(type default)
			)
			(fill no)
			(layer "F.SilkS")
		)
		(fp_rect
			(start -16.51 4.445)
			(end 16.51 -4.445)
			(stroke
				(width 0)
				(type default)
			)
			(fill no)
			(layer "F.CrtYd")
		)
		(fp_poly
			(pts
				(xy -17.018 4.953) (xy -17.018 -4.953) (xy 17.018 -4.953) (xy 17.018 4.953) (xy 0.00508 4.953) (xy 0.00508 4.445)
				(xy 16.51 4.445) (xy 16.51 -4.445) (xy -16.51 -4.445) (xy -16.51 4.445) (xy 0 4.445) (xy 0 4.953)
			)
			(stroke
				(width 0)
				(type default)
			)
			(fill no)
			(layer "F.CrtYd")
		)
		(fp_rect
			(start -17.018 4.953)
			(end 17.018 -4.953)
			(stroke
				(width 0)
				(type default)
			)
			(fill no)
			(layer "F.Fab")
		)
		(pad "1" thru_hole circle
			(at -11.43 1.27)
			(size 1.5494 1.5494)
			(drill 1.143)
			(layers "*.Cu" "*.Mask")
			(remove_unused_layers no)
			(net "3D3V_ICE")
			(clearance 0.1524)
			(thermal_gap 0.1524)
		)
		(pad "2" thru_hole circle
			(at -11.43 -1.27)
			(size 1.5494 1.5494)
			(drill 1.143)
			(layers "*.Cu" "*.Mask")
			(remove_unused_layers no)
			(net "3D3V_ICE")
			(clearance 0.1524)
			(thermal_gap 0.1524)
		)
		(pad "3" thru_hole circle
			(at -8.89 1.27)
			(size 1.5494 1.5494)
			(drill 1.143)
			(layers "*.Cu" "*.Mask")
			(remove_unused_layers no)
			(net "ICE_TRST_N")
			(clearance 0.1524)
			(thermal_gap 0.1524)
		)
		(pad "4" thru_hole circle
			(at -8.89 -1.27)
			(size 1.5494 1.5494)
			(drill 1.143)
			(layers "*.Cu" "*.Mask")
			(remove_unused_layers no)
			(net "GND")
			(clearance 0.1524)
			(thermal_gap 0.1524)
		)
		(pad "5" thru_hole circle
			(at -6.35 1.27)
			(size 1.5494 1.5494)
			(drill 1.143)
			(layers "*.Cu" "*.Mask")
			(remove_unused_layers no)
			(net "ICE_TDI")
			(clearance 0.1524)
			(thermal_gap 0.1524)
		)
		(pad "6" thru_hole circle
			(at -6.35 -1.27)
			(size 1.5494 1.5494)
			(drill 1.143)
			(layers "*.Cu" "*.Mask")
			(remove_unused_layers no)
			(net "GND")
			(clearance 0.1524)
			(thermal_gap 0.1524)
		)
		(pad "7" thru_hole circle
			(at -3.81 1.27)
			(size 1.5494 1.5494)
			(drill 1.143)
			(layers "*.Cu" "*.Mask")
			(remove_unused_layers no)
			(net "ICE_TMS")
			(clearance 0.1524)
			(thermal_gap 0.1524)
		)
		(pad "8" thru_hole circle
			(at -3.81 -1.27)
			(size 1.5494 1.5494)
			(drill 1.143)
			(layers "*.Cu" "*.Mask")
			(remove_unused_layers no)
			(net "GND")
			(clearance 0.1524)
			(thermal_gap 0.1524)
		)
		(pad "9" thru_hole circle
			(at -1.27 1.27)
			(size 1.5494 1.5494)
			(drill 1.143)
			(layers "*.Cu" "*.Mask")
			(remove_unused_layers no)
			(net "ICE_TCK")
			(clearance 0.1524)
			(thermal_gap 0.1524)
		)
		(pad "10" thru_hole circle
			(at -1.27 -1.27)
			(size 1.5494 1.5494)
			(drill 1.143)
			(layers "*.Cu" "*.Mask")
			(remove_unused_layers no)
			(net "GND")
			(clearance 0.1524)
			(thermal_gap 0.1524)
		)
		(pad "11" thru_hole circle
			(at 1.27 1.27)
			(size 1.5494 1.5494)
			(drill 1.143)
			(layers "*.Cu" "*.Mask")
			(remove_unused_layers no)
			(net "GND")
			(clearance 0.1524)
			(thermal_gap 0.1524)
		)
		(pad "12" thru_hole circle
			(at 1.27 -1.27)
			(size 1.5494 1.5494)
			(drill 1.143)
			(layers "*.Cu" "*.Mask")
			(remove_unused_layers no)
			(net "GND")
			(clearance 0.1524)
			(thermal_gap 0.1524)
		)
		(pad "13" thru_hole circle
			(at 3.81 1.27)
			(size 1.5494 1.5494)
			(drill 1.143)
			(layers "*.Cu" "*.Mask")
			(remove_unused_layers no)
			(net "ICE_TDO")
			(clearance 0.1524)
			(thermal_gap 0.1524)
		)
		(pad "14" thru_hole circle
			(at 3.81 -1.27)
			(size 1.5494 1.5494)
			(drill 1.143)
			(layers "*.Cu" "*.Mask")
			(remove_unused_layers no)
			(net "GND")
			(clearance 0.1524)
			(thermal_gap 0.1524)
		)
		(pad "15" thru_hole circle
			(at 6.35 1.27)
			(size 1.5494 1.5494)
			(drill 1.143)
			(layers "*.Cu" "*.Mask")
			(remove_unused_layers no)
			(net "ICE_RESET_N")
			(clearance 0.1524)
			(thermal_gap 0.1524)
		)
		(pad "16" thru_hole circle
			(at 6.35 -1.27)
			(size 1.5494 1.5494)
			(drill 1.143)
			(layers "*.Cu" "*.Mask")
			(remove_unused_layers no)
			(net "GND")
			(clearance 0.1524)
			(thermal_gap 0.1524)
		)
		(pad "17" thru_hole circle
			(at 8.89 1.27)
			(size 1.5494 1.5494)
			(drill 1.143)
			(layers "*.Cu" "*.Mask")
			(remove_unused_layers no)
			(net "GND")
			(clearance 0.1524)
			(thermal_gap 0.1524)
		)
		(pad "18" thru_hole circle
			(at 8.89 -1.27)
			(size 1.5494 1.5494)
			(drill 1.143)
			(layers "*.Cu" "*.Mask")
			(remove_unused_layers no)
			(net "GND")
			(clearance 0.1524)
			(thermal_gap 0.1524)
		)
		(pad "19" thru_hole circle
			(at 11.43 1.27)
			(size 1.5494 1.5494)
			(drill 1.143)
			(layers "*.Cu" "*.Mask")
			(remove_unused_layers no)
			(net "GND")
			(clearance 0.1524)
			(thermal_gap 0.1524)
		)
		(pad "20" thru_hole circle
			(at 11.43 -1.27)
			(size 1.5494 1.5494)
			(drill 1.143)
			(layers "*.Cu" "*.Mask")
			(remove_unused_layers no)
			(net "GND")
			(clearance 0.1524)
			(thermal_gap 0.1524)
		)
	)
	(footprint ""
		(layer "F.Cu")
		(at 52.832 -224.917 180)
		(property "Reference" "R2109"
			(at 0 0 180)
			(layer "F.SilkS")
			(hide yes)
			(effects
				(font
					(size 1.27 1.27)
				)
			)
		)
		(property "Value" "6K04R2F-GP"
			(at 0.064008 -3.993896 180)
			(unlocked yes)
			(layer "F.Fab")
			(hide yes)
			(effects
				(font
					(size 1.016 1.016)
					(thickness 0.1524)
				)
			)
		)
		(property "Device Type" "R402H16"
			(at 0.064008 -5.517896 180)
			(unlocked yes)
			(layer "F.Fab")
			(hide yes)
			(effects
				(font
					(size 1.016 1.016)
					(thickness 0.1524)
				)
			)
		)
		(duplicate_pad_numbers_are_jumpers no)
		(fp_line
			(start 0.508 -0.9398)
			(end -0.508 -0.9398)
			(stroke
				(width 0.1524)
				(type default)
			)
			(layer "F.SilkS")
		)
		(fp_line
			(start -0.508 -0.9398)
			(end -0.508 0.9398)
			(stroke
				(width 0.1524)
				(type default)
			)
			(layer "F.SilkS")
		)
		(fp_rect
			(start -0.508 0.9398)
			(end 0.508 -0.9398)
			(stroke
				(width 0)
				(type default)
			)
			(fill no)
			(layer "F.CrtYd")
		)
		(fp_rect
			(start -0.508 0.9398)
			(end 0.508 -0.9398)
			(stroke
				(width 0)
				(type default)
			)
			(fill no)
			(layer "F.Fab")
		)
		(pad "1" smd custom
			(at 0 -0.4445 180)
			(size 0.1397 0.1397)
			(layers "F.Cu" "F.Mask" "F.Paste")
			(net "MB0_CM_UV_R")
			(options
				(clearance outline)
				(anchor circle)
			)
			(primitives
				(gr_poly
					(pts
						(arc
							(start -0.1778 -0.2794)
							(mid -0.249642 -0.249642)
							(end -0.2794 -0.1778)
						)
						(arc
							(start -0.2794 0.1778)
							(mid -0.249642 0.249642)
							(end -0.1778 0.2794)
						)
						(arc
							(start 0.1778 0.2794)
							(mid 0.249642 0.249642)
							(end 0.2794 0.1778)
						)
						(arc
							(start 0.2794 -0.1778)
							(mid 0.249642 -0.249642)
							(end 0.1778 -0.2794)
						)
					)
					(width 0)
					(fill yes)
				)
			)
		)
		(pad "2" smd custom
			(at 0 0.4445 180)
			(size 0.1397 0.1397)
			(layers "F.Cu" "F.Mask" "F.Paste")
			(net "AGND_CURRENT_MON")
			(options
				(clearance outline)
				(anchor circle)
			)
			(primitives
				(gr_poly
					(pts
						(arc
							(start -0.1778 -0.2794)
							(mid -0.249642 -0.249642)
							(end -0.2794 -0.1778)
						)
						(arc
							(start -0.2794 0.1778)
							(mid -0.249642 0.249642)
							(end -0.1778 0.2794)
						)
						(arc
							(start 0.1778 0.2794)
							(mid 0.249642 0.249642)
							(end 0.2794 0.1778)
						)
						(arc
							(start 0.2794 -0.1778)
							(mid 0.249642 -0.249642)
							(end 0.1778 -0.2794)
						)
					)
					(width 0)
					(fill yes)
				)
			)
		)
	)
	(footprint ""
		(layer "F.Cu")
		(at 287.782 -161.544 180)
		(property "Reference" "R252"
			(at 0 0 180)
			(layer "F.SilkS")
			(hide yes)
			(effects
				(font
					(size 1.27 1.27)
				)
			)
		)
		(property "Value" "0R2J-2-GP"
			(at 0.064008 -3.993896 180)
			(unlocked yes)
			(layer "F.Fab")
			(hide yes)
			(effects
				(font
					(size 1.016 1.016)
					(thickness 0.1524)
				)
			)
		)
		(property "Device Type" "R402H16"
			(at 0.064008 -5.517896 180)
			(unlocked yes)
			(layer "F.Fab")
			(hide yes)
			(effects
				(font
					(size 1.016 1.016)
					(thickness 0.1524)
				)
			)
		)
		(duplicate_pad_numbers_are_jumpers no)
		(fp_line
			(start 0.508 -0.9398)
			(end -0.508 -0.9398)
			(stroke
				(width 0.1524)
				(type default)
			)
			(layer "F.SilkS")
		)
		(fp_line
			(start -0.508 -0.9398)
			(end -0.508 0.9398)
			(stroke
				(width 0.1524)
				(type default)
			)
			(layer "F.SilkS")
		)
		(fp_rect
			(start -0.508 0.9398)
			(end 0.508 -0.9398)
			(stroke
				(width 0)
				(type default)
			)
			(fill no)
			(layer "F.CrtYd")
		)
		(fp_rect
			(start -0.508 0.9398)
			(end 0.508 -0.9398)
			(stroke
				(width 0)
				(type default)
			)
			(fill no)
			(layer "F.Fab")
		)
		(pad "1" smd custom
			(at 0 -0.4445 180)
			(size 0.1397 0.1397)
			(layers "F.Cu" "F.Mask" "F.Paste")
			(net "BMC_PWRBTN_N")
			(options
				(clearance outline)
				(anchor circle)
			)
			(primitives
				(gr_poly
					(pts
						(arc
							(start -0.1778 -0.2794)
							(mid -0.249642 -0.249642)
							(end -0.2794 -0.1778)
						)
						(arc
							(start -0.2794 0.1778)
							(mid -0.249642 0.249642)
							(end -0.1778 0.2794)
						)
						(arc
							(start 0.1778 0.2794)
							(mid 0.249642 0.249642)
							(end 0.2794 0.1778)
						)
						(arc
							(start 0.2794 -0.1778)
							(mid 0.249642 -0.249642)
							(end 0.1778 -0.2794)
						)
					)
					(width 0)
					(fill yes)
				)
			)
		)
		(pad "2" smd custom
			(at 0 0.4445 180)
			(size 0.1397 0.1397)
			(layers "F.Cu" "F.Mask" "F.Paste")
			(net "BMC_PWRBTN_N_R")
			(options
				(clearance outline)
				(anchor circle)
			)
			(primitives
				(gr_poly
					(pts
						(arc
							(start -0.1778 -0.2794)
							(mid -0.249642 -0.249642)
							(end -0.2794 -0.1778)
						)
						(arc
							(start -0.2794 0.1778)
							(mid -0.249642 0.249642)
							(end -0.1778 0.2794)
						)
						(arc
							(start 0.1778 0.2794)
							(mid 0.249642 0.249642)
							(end 0.2794 0.1778)
						)
						(arc
							(start 0.2794 -0.1778)
							(mid 0.249642 -0.249642)
							(end 0.1778 -0.2794)
						)
					)
					(width 0)
					(fill yes)
				)
			)
		)
	)
	(footprint ""
		(layer "F.Cu")
		(at 47.879 -219.837 -90)
		(property "Reference" "R2117"
			(at 0 0 270)
			(layer "F.SilkS")
			(hide yes)
			(effects
				(font
					(size 1.27 1.27)
				)
			)
		)
		(property "Value" "100KR2J-4-GP"
			(at -1.1811 -1.1303 270)
			(unlocked yes)
			(layer "F.Fab")
			(hide yes)
			(effects
				(font
					(size 1.016 1.016)
					(thickness 0.1524)
				)
			)
		)
		(property "Device Type" "R402H15"
			(at -1.1811 -2.6543 270)
			(unlocked yes)
			(layer "F.Fab")
			(hide yes)
			(effects
				(font
					(size 1.016 1.016)
					(thickness 0.1524)
				)
			)
		)
		(duplicate_pad_numbers_are_jumpers no)
		(fp_line
			(start -0.508 -0.9398)
			(end -0.508 0.9398)
			(stroke
				(width 0.1524)
				(type default)
			)
			(layer "F.SilkS")
		)
		(fp_line
			(start 0.508 -0.9398)
			(end -0.508 -0.9398)
			(stroke
				(width 0.1524)
				(type default)
			)
			(layer "F.SilkS")
		)
		(fp_rect
			(start -0.508 0.9398)
			(end 0.508 -0.9398)
			(stroke
				(width 0)
				(type default)
			)
			(fill no)
			(layer "F.CrtYd")
		)
		(fp_rect
			(start -0.508 0.9398)
			(end 0.508 -0.9398)
			(stroke
				(width 0)
				(type default)
			)
			(fill no)
			(layer "F.Fab")
		)
		(pad "1" smd custom
			(at 0 -0.4445 270)
			(size 0.1397 0.1397)
			(layers "F.Cu" "F.Mask" "F.Paste")
			(net "MB0_VCAP_R")
			(options
				(clearance outline)
				(anchor circle)
			)
			(primitives
				(gr_poly
					(pts
						(arc
							(start -0.1778 -0.2794)
							(mid -0.249642 -0.249642)
							(end -0.2794 -0.1778)
						)
						(arc
							(start -0.2794 0.1778)
							(mid -0.249642 0.249642)
							(end -0.1778 0.2794)
						)
						(arc
							(start 0.1778 0.2794)
							(mid 0.249642 0.249642)
							(end 0.2794 0.1778)
						)
						(arc
							(start 0.2794 -0.1778)
							(mid 0.249642 -0.249642)
							(end 0.1778 -0.2794)
						)
					)
					(width 0)
					(fill yes)
				)
			)
		)
		(pad "2" smd custom
			(at 0 0.4445 270)
			(size 0.1397 0.1397)
			(layers "F.Cu" "F.Mask" "F.Paste")
			(net "MB0_ISET_R")
			(options
				(clearance outline)
				(anchor circle)
			)
			(primitives
				(gr_poly
					(pts
						(arc
							(start -0.1778 -0.2794)
							(mid -0.249642 -0.249642)
							(end -0.2794 -0.1778)
						)
						(arc
							(start -0.2794 0.1778)
							(mid -0.249642 0.249642)
							(end -0.1778 0.2794)
						)
						(arc
							(start 0.1778 0.2794)
							(mid 0.249642 0.249642)
							(end 0.2794 0.1778)
						)
						(arc
							(start 0.2794 -0.1778)
							(mid 0.249642 -0.249642)
							(end 0.1778 -0.2794)
						)
					)
					(width 0)
					(fill yes)
				)
			)
		)
	)
	(footprint ""
		(layer "F.Cu")
		(at 197.485 -163.703 90)
		(property "Reference" "R576"
			(at 0 0 90)
			(layer "F.SilkS")
			(hide yes)
			(effects
				(font
					(size 1.27 1.27)
				)
			)
		)
		(property "Value" "1KR2J-1-GP"
			(at 0.064008 -3.993896 90)
			(unlocked yes)
			(layer "F.Fab")
			(hide yes)
			(effects
				(font
					(size 1.016 1.016)
					(thickness 0.1524)
				)
			)
		)
		(property "Device Type" "R402H16"
			(at 0.064008 -5.517896 90)
			(unlocked yes)
			(layer "F.Fab")
			(hide yes)
			(effects
				(font
					(size 1.016 1.016)
					(thickness 0.1524)
				)
			)
		)
		(duplicate_pad_numbers_are_jumpers no)
		(fp_line
			(start 0.508 -0.9398)
			(end -0.508 -0.9398)
			(stroke
				(width 0.1524)
				(type default)
			)
			(layer "F.SilkS")
		)
		(fp_line
			(start -0.508 -0.9398)
			(end -0.508 0.9398)
			(stroke
				(width 0.1524)
				(type default)
			)
			(layer "F.SilkS")
		)
		(fp_rect
			(start -0.508 0.9398)
			(end 0.508 -0.9398)
			(stroke
				(width 0)
				(type default)
			)
			(fill no)
			(layer "F.CrtYd")
		)
		(fp_rect
			(start -0.508 0.9398)
			(end 0.508 -0.9398)
			(stroke
				(width 0)
				(type default)
			)
			(fill no)
			(layer "F.Fab")
		)
		(pad "1" smd custom
			(at 0 -0.4445 90)
			(size 0.1397 0.1397)
			(layers "F.Cu" "F.Mask" "F.Paste")
			(net "P3V3_PG_R")
			(options
				(clearance outline)
				(anchor circle)
			)
			(primitives
				(gr_poly
					(pts
						(arc
							(start -0.1778 -0.2794)
							(mid -0.249642 -0.249642)
							(end -0.2794 -0.1778)
						)
						(arc
							(start -0.2794 0.1778)
							(mid -0.249642 0.249642)
							(end -0.1778 0.2794)
						)
						(arc
							(start 0.1778 0.2794)
							(mid 0.249642 0.249642)
							(end 0.2794 0.1778)
						)
						(arc
							(start 0.2794 -0.1778)
							(mid 0.249642 -0.249642)
							(end 0.1778 -0.2794)
						)
					)
					(width 0)
					(fill yes)
				)
			)
		)
		(pad "2" smd custom
			(at 0 0.4445 90)
			(size 0.1397 0.1397)
			(layers "F.Cu" "F.Mask" "F.Paste")
			(net "P3V3")
			(options
				(clearance outline)
				(anchor circle)
			)
			(primitives
				(gr_poly
					(pts
						(arc
							(start -0.1778 -0.2794)
							(mid -0.249642 -0.249642)
							(end -0.2794 -0.1778)
						)
						(arc
							(start -0.2794 0.1778)
							(mid -0.249642 0.249642)
							(end -0.1778 0.2794)
						)
						(arc
							(start 0.1778 0.2794)
							(mid 0.249642 0.249642)
							(end 0.2794 0.1778)
						)
						(arc
							(start 0.2794 -0.1778)
							(mid 0.249642 -0.249642)
							(end 0.1778 -0.2794)
						)
					)
					(width 0)
					(fill yes)
				)
			)
		)
	)
	(footprint ""
		(layer "F.Cu")
		(at 288.163 -210.49234 180)
		(property "Reference" "C172"
			(at 0 0 180)
			(layer "F.SilkS")
			(hide yes)
			(effects
				(font
					(size 1.27 1.27)
				)
			)
		)
		(property "Value" "SCD1U16V2KX-3GP"
			(at 1.1811 -2.7051 180)
			(unlocked yes)
			(layer "F.Fab")
			(hide yes)
			(effects
				(font
					(size 1.016 1.016)
					(thickness 0.1524)
				)
			)
		)
		(property "Device Type" "C402H22"
			(at 1.1811 -4.2291 180)
			(unlocked yes)
			(layer "F.Fab")
			(hide yes)
			(effects
				(font
					(size 1.016 1.016)
					(thickness 0.1524)
				)
			)
		)
		(duplicate_pad_numbers_are_jumpers no)
		(fp_rect
			(start -0.4318 0.9525)
			(end 0.4318 -0.9525)
			(stroke
				(width 0)
				(type default)
			)
			(fill no)
			(layer "F.CrtYd")
		)
		(fp_rect
			(start -0.4318 0.9525)
			(end 0.4318 -0.9525)
			(stroke
				(width 0)
				(type default)
			)
			(fill no)
			(layer "F.Fab")
		)
		(pad "1" smd custom
			(at 0 -0.4445 180)
			(size 0.1524 0.1524)
			(layers "F.Cu" "F.Mask" "F.Paste")
			(net "P1V53_STBY")
			(options
				(clearance outline)
				(anchor circle)
			)
			(primitives
				(gr_poly
					(pts
						(arc
							(start 0.3048 -0.2032)
							(mid 0.275042 -0.275042)
							(end 0.2032 -0.3048)
						)
						(arc
							(start -0.2032 -0.3048)
							(mid -0.275042 -0.275042)
							(end -0.3048 -0.2032)
						)
						(arc
							(start -0.3048 0.2032)
							(mid -0.275042 0.275042)
							(end -0.2032 0.3048)
						)
						(arc
							(start 0.2032 0.3048)
							(mid 0.275042 0.275042)
							(end 0.3048 0.2032)
						)
					)
					(width 0)
					(fill yes)
				)
			)
		)
		(pad "2" smd custom
			(at 0 0.4445 180)
			(size 0.1524 0.1524)
			(layers "F.Cu" "F.Mask" "F.Paste")
			(net "GND")
			(options
				(clearance outline)
				(anchor circle)
			)
			(primitives
				(gr_poly
					(pts
						(arc
							(start 0.3048 -0.2032)
							(mid 0.275042 -0.275042)
							(end 0.2032 -0.3048)
						)
						(arc
							(start -0.2032 -0.3048)
							(mid -0.275042 -0.275042)
							(end -0.3048 -0.2032)
						)
						(arc
							(start -0.3048 0.2032)
							(mid -0.275042 0.275042)
							(end -0.2032 0.3048)
						)
						(arc
							(start 0.2032 0.3048)
							(mid 0.275042 0.275042)
							(end 0.3048 0.2032)
						)
					)
					(width 0)
					(fill yes)
				)
			)
		)
	)
	(footprint ""
		(layer "F.Cu")
		(at 40.513 -169.291 90)
		(property "Reference" "R473"
			(at 0 0 90)
			(layer "F.SilkS")
			(hide yes)
			(effects
				(font
					(size 1.27 1.27)
				)
			)
		)
		(property "Value" "22KR2F-GP"
			(at 0.064008 -3.993896 90)
			(unlocked yes)
			(layer "F.Fab")
			(hide yes)
			(effects
				(font
					(size 1.016 1.016)
					(thickness 0.1524)
				)
			)
		)
		(property "Device Type" "R402H16"
			(at 0.064008 -5.517896 90)
			(unlocked yes)
			(layer "F.Fab")
			(hide yes)
			(effects
				(font
					(size 1.016 1.016)
					(thickness 0.1524)
				)
			)
		)
		(duplicate_pad_numbers_are_jumpers no)
		(fp_line
			(start 0.508 -0.9398)
			(end -0.508 -0.9398)
			(stroke
				(width 0.1524)
				(type default)
			)
			(layer "F.SilkS")
		)
		(fp_line
			(start -0.508 -0.9398)
			(end -0.508 0.9398)
			(stroke
				(width 0.1524)
				(type default)
			)
			(layer "F.SilkS")
		)
		(fp_rect
			(start -0.508 0.9398)
			(end 0.508 -0.9398)
			(stroke
				(width 0)
				(type default)
			)
			(fill no)
			(layer "F.CrtYd")
		)
		(fp_rect
			(start -0.508 0.9398)
			(end 0.508 -0.9398)
			(stroke
				(width 0)
				(type default)
			)
			(fill no)
			(layer "F.Fab")
		)
		(pad "1" smd custom
			(at 0 -0.4445 90)
			(size 0.1397 0.1397)
			(layers "F.Cu" "F.Mask" "F.Paste")
			(net "P3V3_STBY")
			(options
				(clearance outline)
				(anchor circle)
			)
			(primitives
				(gr_poly
					(pts
						(arc
							(start -0.1778 -0.2794)
							(mid -0.249642 -0.249642)
							(end -0.2794 -0.1778)
						)
						(arc
							(start -0.2794 0.1778)
							(mid -0.249642 0.249642)
							(end -0.1778 0.2794)
						)
						(arc
							(start 0.1778 0.2794)
							(mid 0.249642 0.249642)
							(end 0.2794 0.1778)
						)
						(arc
							(start 0.2794 -0.1778)
							(mid 0.249642 -0.249642)
							(end 0.1778 -0.2794)
						)
					)
					(width 0)
					(fill yes)
				)
			)
		)
		(pad "2" smd custom
			(at 0 0.4445 90)
			(size 0.1397 0.1397)
			(layers "F.Cu" "F.Mask" "F.Paste")
			(net "FP_PWR_BTN_N")
			(options
				(clearance outline)
				(anchor circle)
			)
			(primitives
				(gr_poly
					(pts
						(arc
							(start -0.1778 -0.2794)
							(mid -0.249642 -0.249642)
							(end -0.2794 -0.1778)
						)
						(arc
							(start -0.2794 0.1778)
							(mid -0.249642 0.249642)
							(end -0.1778 0.2794)
						)
						(arc
							(start 0.1778 0.2794)
							(mid 0.249642 0.249642)
							(end 0.2794 0.1778)
						)
						(arc
							(start 0.2794 -0.1778)
							(mid 0.249642 -0.249642)
							(end 0.1778 -0.2794)
						)
					)
					(width 0)
					(fill yes)
				)
			)
		)
	)
	(footprint ""
		(layer "F.Cu")
		(at 318.008 -171.577 90)
		(property "Reference" "C188"
			(at 0 0 90)
			(layer "F.SilkS")
			(hide yes)
			(effects
				(font
					(size 1.27 1.27)
				)
			)
		)
		(property "Value" "SC1U10V3KX-4GP-U"
			(at 0 -2.8194 90)
			(unlocked yes)
			(layer "F.Fab")
			(hide yes)
			(effects
				(font
					(size 1.016 1.016)
					(thickness 0.1524)
				)
			)
		)
		(property "Device Type" "C603H36"
			(at 0 -4.3434 90)
			(unlocked yes)
			(layer "F.Fab")
			(hide yes)
			(effects
				(font
					(size 1.016 1.016)
					(thickness 0.1524)
				)
			)
		)
		(duplicate_pad_numbers_are_jumpers no)
		(fp_line
			(start 0.508 0)
			(end -0.508 0)
			(stroke
				(width 0.2032)
				(type default)
			)
			(layer "F.SilkS")
		)
		(fp_rect
			(start -0.5842 1.3335)
			(end 0.5842 -1.3335)
			(stroke
				(width 0)
				(type default)
			)
			(fill no)
			(layer "F.CrtYd")
		)
		(fp_rect
			(start -0.5842 1.3335)
			(end 0.5842 -1.3335)
			(stroke
				(width 0)
				(type default)
			)
			(fill no)
			(layer "F.Fab")
		)
		(pad "1" smd custom
			(at 0 -0.762 90)
			(size 0.2159 0.2159)
			(layers "F.Cu" "F.Mask" "F.Paste")
			(net "JTAG_BMC_TRST_N")
			(options
				(clearance outline)
				(anchor circle)
			)
			(primitives
				(gr_poly
					(pts
						(arc
							(start -0.3302 -0.4318)
							(mid -0.402042 -0.402042)
							(end -0.4318 -0.3302)
						)
						(arc
							(start -0.4318 0.3302)
							(mid -0.402042 0.402042)
							(end -0.3302 0.4318)
						)
						(arc
							(start 0.3302 0.4318)
							(mid 0.402042 0.402042)
							(end 0.4318 0.3302)
						)
						(arc
							(start 0.4318 -0.3302)
							(mid 0.402042 -0.402042)
							(end 0.3302 -0.4318)
						)
					)
					(width 0)
					(fill yes)
				)
			)
		)
		(pad "2" smd custom
			(at 0 0.762 90)
			(size 0.2159 0.2159)
			(layers "F.Cu" "F.Mask" "F.Paste")
			(net "GND")
			(options
				(clearance outline)
				(anchor circle)
			)
			(primitives
				(gr_poly
					(pts
						(arc
							(start -0.3302 -0.4318)
							(mid -0.402042 -0.402042)
							(end -0.4318 -0.3302)
						)
						(arc
							(start -0.4318 0.3302)
							(mid -0.402042 0.402042)
							(end -0.3302 0.4318)
						)
						(arc
							(start 0.3302 0.4318)
							(mid 0.402042 0.402042)
							(end 0.4318 0.3302)
						)
						(arc
							(start 0.4318 -0.3302)
							(mid 0.402042 -0.402042)
							(end 0.3302 -0.4318)
						)
					)
					(width 0)
					(fill yes)
				)
			)
		)
	)
	(footprint ""
		(layer "F.Cu")
		(at 306.451 -179.324)
		(property "Reference" "TP175"
			(at 0 0 0)
			(layer "F.SilkS")
			(hide yes)
			(effects
				(font
					(size 1.27 1.27)
				)
			)
		)
		(property "Value" "TPAD28"
			(at 0.0127 -1.8034 0)
			(unlocked yes)
			(layer "F.Fab")
			(hide yes)
			(effects
				(font
					(size 1.016 1.016)
					(thickness 0.1524)
				)
			)
		)
		(property "Device Type" "TPAD28"
			(at 0.0127 -3.3274 0)
			(unlocked yes)
			(layer "F.Fab")
			(hide yes)
			(effects
				(font
					(size 1.016 1.016)
					(thickness 0.1524)
				)
			)
		)
		(duplicate_pad_numbers_are_jumpers no)
		(fp_poly
			(pts
				(arc
					(start 0.3556 0)
					(mid -0.3556 0)
					(end 0.3556 0)
				)
			)
			(stroke
				(width 0)
				(type default)
			)
			(fill no)
			(layer "F.CrtYd")
		)
		(fp_poly
			(pts
				(arc
					(start 0.6096 0)
					(mid -0.6096 0)
					(end 0.6096 0)
				)
			)
			(stroke
				(width 0)
				(type default)
			)
			(fill no)
			(layer "F.Fab")
		)
		(pad "1" smd circle
			(at 0 0)
			(size 0.7112 0.7112)
			(layers "F.Cu" "F.Mask" "F.Paste")
			(net "TP_BMC_GPIOM0")
		)
	)
	(footprint ""
		(layer "F.Cu")
		(at 274.193 -170.561 90)
		(property "Reference" "R239"
			(at 0 0 90)
			(layer "F.SilkS")
			(hide yes)
			(effects
				(font
					(size 1.27 1.27)
				)
			)
		)
		(property "Value" "0R2J-2-GP"
			(at 0.064008 -3.993896 90)
			(unlocked yes)
			(layer "F.Fab")
			(hide yes)
			(effects
				(font
					(size 1.016 1.016)
					(thickness 0.1524)
				)
			)
		)
		(property "Device Type" "R402H16"
			(at 0.064008 -5.517896 90)
			(unlocked yes)
			(layer "F.Fab")
			(hide yes)
			(effects
				(font
					(size 1.016 1.016)
					(thickness 0.1524)
				)
			)
		)
		(duplicate_pad_numbers_are_jumpers no)
		(fp_line
			(start 0.508 -0.9398)
			(end -0.508 -0.9398)
			(stroke
				(width 0.1524)
				(type default)
			)
			(layer "F.SilkS")
		)
		(fp_line
			(start -0.508 -0.9398)
			(end -0.508 0.9398)
			(stroke
				(width 0.1524)
				(type default)
			)
			(layer "F.SilkS")
		)
		(fp_rect
			(start -0.508 0.9398)
			(end 0.508 -0.9398)
			(stroke
				(width 0)
				(type default)
			)
			(fill no)
			(layer "F.CrtYd")
		)
		(fp_rect
			(start -0.508 0.9398)
			(end 0.508 -0.9398)
			(stroke
				(width 0)
				(type default)
			)
			(fill no)
			(layer "F.Fab")
		)
		(pad "1" smd custom
			(at 0 -0.4445 90)
			(size 0.1397 0.1397)
			(layers "F.Cu" "F.Mask" "F.Paste")
			(net "BMC_MBC_I2C_E_SDA")
			(options
				(clearance outline)
				(anchor circle)
			)
			(primitives
				(gr_poly
					(pts
						(arc
							(start -0.1778 -0.2794)
							(mid -0.249642 -0.249642)
							(end -0.2794 -0.1778)
						)
						(arc
							(start -0.2794 0.1778)
							(mid -0.249642 0.249642)
							(end -0.1778 0.2794)
						)
						(arc
							(start 0.1778 0.2794)
							(mid 0.249642 0.249642)
							(end 0.2794 0.1778)
						)
						(arc
							(start 0.2794 -0.1778)
							(mid 0.249642 -0.249642)
							(end 0.1778 -0.2794)
						)
					)
					(width 0)
					(fill yes)
				)
			)
		)
		(pad "2" smd custom
			(at 0 0.4445 90)
			(size 0.1397 0.1397)
			(layers "F.Cu" "F.Mask" "F.Paste")
			(net "BMC0_SMB1_DAT")
			(options
				(clearance outline)
				(anchor circle)
			)
			(primitives
				(gr_poly
					(pts
						(arc
							(start -0.1778 -0.2794)
							(mid -0.249642 -0.249642)
							(end -0.2794 -0.1778)
						)
						(arc
							(start -0.2794 0.1778)
							(mid -0.249642 0.249642)
							(end -0.1778 0.2794)
						)
						(arc
							(start 0.1778 0.2794)
							(mid 0.249642 0.249642)
							(end 0.2794 0.1778)
						)
						(arc
							(start 0.2794 -0.1778)
							(mid 0.249642 -0.249642)
							(end 0.1778 -0.2794)
						)
					)
					(width 0)
					(fill yes)
				)
			)
		)
	)
	(footprint ""
		(layer "F.Cu")
		(at 86.49716 -40.259 -90)
		(property "Reference" "SC895"
			(at 0 0 270)
			(layer "F.SilkS")
			(hide yes)
			(effects
				(font
					(size 1.27 1.27)
				)
			)
		)
		(property "Value" "SCD01U10V1KX-GP"
			(at -2.8321 -1.7399 270)
			(unlocked yes)
			(layer "F.Fab")
			(hide yes)
			(effects
				(font
					(size 1.016 1.016)
					(thickness 0.1524)
				)
			)
		)
		(property "Device Type" "C0201H13"
			(at -2.8321 -3.2639 270)
			(unlocked yes)
			(layer "F.Fab")
			(hide yes)
			(effects
				(font
					(size 1.016 1.016)
					(thickness 0.1524)
				)
			)
		)
		(duplicate_pad_numbers_are_jumpers no)
		(fp_rect
			(start -0.2794 0.6477)
			(end 0.2794 -0.6477)
			(stroke
				(width 0)
				(type default)
			)
			(fill no)
			(layer "F.CrtYd")
		)
		(fp_rect
			(start -0.2794 0.6477)
			(end 0.2794 -0.6477)
			(stroke
				(width 0)
				(type default)
			)
			(fill no)
			(layer "F.Fab")
		)
		(pad "1" smd custom
			(at 0 -0.2794 270)
			(size 0.0762 0.0762)
			(layers "F.Cu" "F.Mask" "F.Paste")
			(net "SAS3008_RAID_TX_C_P7")
			(options
				(clearance outline)
				(anchor circle)
			)
			(primitives
				(gr_poly
					(pts
						(arc
							(start 0.1524 -0.127)
							(mid 0.137521 -0.162921)
							(end 0.1016 -0.1778)
						)
						(arc
							(start -0.1016 -0.1778)
							(mid -0.137521 -0.162921)
							(end -0.1524 -0.127)
						)
						(arc
							(start -0.1524 0.127)
							(mid -0.137521 0.162921)
							(end -0.1016 0.1778)
						)
						(arc
							(start 0.1016 0.1778)
							(mid 0.137521 0.162921)
							(end 0.1524 0.127)
						)
					)
					(width 0)
					(fill yes)
				)
			)
		)
		(pad "2" smd custom
			(at 0 0.2794 270)
			(size 0.0762 0.0762)
			(layers "F.Cu" "F.Mask" "F.Paste")
			(net "IOC_RAID_TX_P7")
			(options
				(clearance outline)
				(anchor circle)
			)
			(primitives
				(gr_poly
					(pts
						(arc
							(start 0.1524 -0.127)
							(mid 0.137521 -0.162921)
							(end 0.1016 -0.1778)
						)
						(arc
							(start -0.1016 -0.1778)
							(mid -0.137521 -0.162921)
							(end -0.1524 -0.127)
						)
						(arc
							(start -0.1524 0.127)
							(mid -0.137521 0.162921)
							(end -0.1016 0.1778)
						)
						(arc
							(start 0.1016 0.1778)
							(mid 0.137521 0.162921)
							(end 0.1524 0.127)
						)
					)
					(width 0)
					(fill yes)
				)
			)
		)
	)
	(footprint ""
		(layer "F.Cu")
		(at 14.682216 -224.08388 -90)
		(property "Reference" "SR298"
			(at 0 0 270)
			(layer "F.SilkS")
			(hide yes)
			(effects
				(font
					(size 1.27 1.27)
				)
			)
		)
		(property "Value" "0R2J-2-GP"
			(at 0.064008 -3.993896 270)
			(unlocked yes)
			(layer "F.Fab")
			(hide yes)
			(effects
				(font
					(size 1.016 1.016)
					(thickness 0.1524)
				)
			)
		)
		(property "Device Type" "R402H16"
			(at 0.064008 -5.517896 270)
			(unlocked yes)
			(layer "F.Fab")
			(hide yes)
			(effects
				(font
					(size 1.016 1.016)
					(thickness 0.1524)
				)
			)
		)
		(duplicate_pad_numbers_are_jumpers no)
		(fp_line
			(start -0.508 -0.9398)
			(end -0.508 0.9398)
			(stroke
				(width 0.1524)
				(type default)
			)
			(layer "F.SilkS")
		)
		(fp_line
			(start 0.508 -0.9398)
			(end -0.508 -0.9398)
			(stroke
				(width 0.1524)
				(type default)
			)
			(layer "F.SilkS")
		)
		(fp_rect
			(start -0.508 0.9398)
			(end 0.508 -0.9398)
			(stroke
				(width 0)
				(type default)
			)
			(fill no)
			(layer "F.CrtYd")
		)
		(fp_rect
			(start -0.508 0.9398)
			(end 0.508 -0.9398)
			(stroke
				(width 0)
				(type default)
			)
			(fill no)
			(layer "F.Fab")
		)
		(pad "1" smd custom
			(at 0 -0.4445 270)
			(size 0.1397 0.1397)
			(layers "F.Cu" "F.Mask" "F.Paste")
			(net "PWR_SDA")
			(options
				(clearance outline)
				(anchor circle)
			)
			(primitives
				(gr_poly
					(pts
						(arc
							(start -0.1778 -0.2794)
							(mid -0.249642 -0.249642)
							(end -0.2794 -0.1778)
						)
						(arc
							(start -0.2794 0.1778)
							(mid -0.249642 0.249642)
							(end -0.1778 0.2794)
						)
						(arc
							(start 0.1778 0.2794)
							(mid 0.249642 0.249642)
							(end 0.2794 0.1778)
						)
						(arc
							(start 0.2794 -0.1778)
							(mid 0.249642 -0.249642)
							(end 0.1778 -0.2794)
						)
					)
					(width 0)
					(fill yes)
				)
			)
		)
		(pad "2" smd custom
			(at 0 0.4445 270)
			(size 0.1397 0.1397)
			(layers "F.Cu" "F.Mask" "F.Paste")
			(net "EXP_SDA_0")
			(options
				(clearance outline)
				(anchor circle)
			)
			(primitives
				(gr_poly
					(pts
						(arc
							(start -0.1778 -0.2794)
							(mid -0.249642 -0.249642)
							(end -0.2794 -0.1778)
						)
						(arc
							(start -0.2794 0.1778)
							(mid -0.249642 0.249642)
							(end -0.1778 0.2794)
						)
						(arc
							(start 0.1778 0.2794)
							(mid 0.249642 0.249642)
							(end 0.2794 0.1778)
						)
						(arc
							(start 0.2794 -0.1778)
							(mid 0.249642 -0.249642)
							(end 0.1778 -0.2794)
						)
					)
					(width 0)
					(fill yes)
				)
			)
		)
	)
	(footprint ""
		(layer "F.Cu")
		(at 48.895 -220.853 90)
		(property "Reference" "R2171"
			(at 0 0 90)
			(layer "F.SilkS")
			(hide yes)
			(effects
				(font
					(size 1.27 1.27)
				)
			)
		)
		(property "Value" "100KR2J-4-GP"
			(at -1.1811 -1.1303 90)
			(unlocked yes)
			(layer "F.Fab")
			(hide yes)
			(effects
				(font
					(size 1.016 1.016)
					(thickness 0.1524)
				)
			)
		)
		(property "Device Type" "R402H15"
			(at -1.1811 -2.6543 90)
			(unlocked yes)
			(layer "F.Fab")
			(hide yes)
			(effects
				(font
					(size 1.016 1.016)
					(thickness 0.1524)
				)
			)
		)
		(duplicate_pad_numbers_are_jumpers no)
		(fp_line
			(start 0.508 -0.9398)
			(end -0.508 -0.9398)
			(stroke
				(width 0.1524)
				(type default)
			)
			(layer "F.SilkS")
		)
		(fp_line
			(start -0.508 -0.9398)
			(end -0.508 0.9398)
			(stroke
				(width 0.1524)
				(type default)
			)
			(layer "F.SilkS")
		)
		(fp_rect
			(start -0.508 0.9398)
			(end 0.508 -0.9398)
			(stroke
				(width 0)
				(type default)
			)
			(fill no)
			(layer "F.CrtYd")
		)
		(fp_rect
			(start -0.508 0.9398)
			(end 0.508 -0.9398)
			(stroke
				(width 0)
				(type default)
			)
			(fill no)
			(layer "F.Fab")
		)
		(pad "1" smd custom
			(at 0 -0.4445 90)
			(size 0.1397 0.1397)
			(layers "F.Cu" "F.Mask" "F.Paste")
			(net "MB0_VCAP_R")
			(options
				(clearance outline)
				(anchor circle)
			)
			(primitives
				(gr_poly
					(pts
						(arc
							(start -0.1778 -0.2794)
							(mid -0.249642 -0.249642)
							(end -0.2794 -0.1778)
						)
						(arc
							(start -0.2794 0.1778)
							(mid -0.249642 0.249642)
							(end -0.1778 0.2794)
						)
						(arc
							(start 0.1778 0.2794)
							(mid 0.249642 0.249642)
							(end 0.2794 0.1778)
						)
						(arc
							(start 0.2794 -0.1778)
							(mid 0.249642 -0.249642)
							(end 0.1778 -0.2794)
						)
					)
					(width 0)
					(fill yes)
				)
			)
		)
		(pad "2" smd custom
			(at 0 0.4445 90)
			(size 0.1397 0.1397)
			(layers "F.Cu" "F.Mask" "F.Paste")
			(net "MB0_PSET_R")
			(options
				(clearance outline)
				(anchor circle)
			)
			(primitives
				(gr_poly
					(pts
						(arc
							(start -0.1778 -0.2794)
							(mid -0.249642 -0.249642)
							(end -0.2794 -0.1778)
						)
						(arc
							(start -0.2794 0.1778)
							(mid -0.249642 0.249642)
							(end -0.1778 0.2794)
						)
						(arc
							(start 0.1778 0.2794)
							(mid 0.249642 0.249642)
							(end 0.2794 0.1778)
						)
						(arc
							(start 0.2794 -0.1778)
							(mid 0.249642 -0.249642)
							(end 0.1778 -0.2794)
						)
					)
					(width 0)
					(fill yes)
				)
			)
		)
	)
	(footprint ""
		(layer "F.Cu")
		(at 95.89897 -82.804 -90)
		(property "Reference" "SR799"
			(at 0 0 270)
			(layer "F.SilkS")
			(hide yes)
			(effects
				(font
					(size 1.27 1.27)
				)
			)
		)
		(property "Value" "4K75R2F-1-GP"
			(at 0.064008 -3.993896 270)
			(unlocked yes)
			(layer "F.Fab")
			(hide yes)
			(effects
				(font
					(size 1.016 1.016)
					(thickness 0.1524)
				)
			)
		)
		(property "Device Type" "R402H16"
			(at 0.064008 -5.517896 270)
			(unlocked yes)
			(layer "F.Fab")
			(hide yes)
			(effects
				(font
					(size 1.016 1.016)
					(thickness 0.1524)
				)
			)
		)
		(duplicate_pad_numbers_are_jumpers no)
		(fp_line
			(start -0.508 -0.9398)
			(end -0.508 0.9398)
			(stroke
				(width 0.1524)
				(type default)
			)
			(layer "F.SilkS")
		)
		(fp_line
			(start 0.508 -0.9398)
			(end -0.508 -0.9398)
			(stroke
				(width 0.1524)
				(type default)
			)
			(layer "F.SilkS")
		)
		(fp_rect
			(start -0.508 0.9398)
			(end 0.508 -0.9398)
			(stroke
				(width 0)
				(type default)
			)
			(fill no)
			(layer "F.CrtYd")
		)
		(fp_rect
			(start -0.508 0.9398)
			(end 0.508 -0.9398)
			(stroke
				(width 0)
				(type default)
			)
			(fill no)
			(layer "F.Fab")
		)
		(pad "1" smd custom
			(at 0 -0.4445 270)
			(size 0.1397 0.1397)
			(layers "F.Cu" "F.Mask" "F.Paste")
			(net "EXP_CLK_SEL1")
			(options
				(clearance outline)
				(anchor circle)
			)
			(primitives
				(gr_poly
					(pts
						(arc
							(start -0.1778 -0.2794)
							(mid -0.249642 -0.249642)
							(end -0.2794 -0.1778)
						)
						(arc
							(start -0.2794 0.1778)
							(mid -0.249642 0.249642)
							(end -0.1778 0.2794)
						)
						(arc
							(start 0.1778 0.2794)
							(mid 0.249642 0.249642)
							(end 0.2794 0.1778)
						)
						(arc
							(start 0.2794 -0.1778)
							(mid 0.249642 -0.249642)
							(end 0.1778 -0.2794)
						)
					)
					(width 0)
					(fill yes)
				)
			)
		)
		(pad "2" smd custom
			(at 0 0.4445 270)
			(size 0.1397 0.1397)
			(layers "F.Cu" "F.Mask" "F.Paste")
			(net "GND")
			(options
				(clearance outline)
				(anchor circle)
			)
			(primitives
				(gr_poly
					(pts
						(arc
							(start -0.1778 -0.2794)
							(mid -0.249642 -0.249642)
							(end -0.2794 -0.1778)
						)
						(arc
							(start -0.2794 0.1778)
							(mid -0.249642 0.249642)
							(end -0.1778 0.2794)
						)
						(arc
							(start 0.1778 0.2794)
							(mid 0.249642 0.249642)
							(end 0.2794 0.1778)
						)
						(arc
							(start 0.2794 -0.1778)
							(mid 0.249642 -0.249642)
							(end 0.1778 -0.2794)
						)
					)
					(width 0)
					(fill yes)
				)
			)
		)
	)
	(footprint ""
		(layer "F.Cu")
		(at 272.923 -44.958 180)
		(property "Reference" "PC44"
			(at 0 0 180)
			(layer "F.SilkS")
			(hide yes)
			(effects
				(font
					(size 1.27 1.27)
				)
			)
		)
		(property "Value" "SC22U25V5MX-GP"
			(at -0.0762 -6.1214 180)
			(unlocked yes)
			(layer "F.Fab")
			(hide yes)
			(effects
				(font
					(size 1.016 1.016)
					(thickness 0.1524)
				)
			)
		)
		(property "Device Type" "C805H58"
			(at -0.0762 -8.1534 180)
			(unlocked yes)
			(layer "F.Fab")
			(hide yes)
			(effects
				(font
					(size 1.016 1.016)
					(thickness 0.1524)
				)
			)
		)
		(duplicate_pad_numbers_are_jumpers no)
		(fp_line
			(start 0.635 0)
			(end -0.635 0)
			(stroke
				(width 0.508)
				(type default)
			)
			(layer "F.SilkS")
		)
		(fp_rect
			(start -0.9652 1.778)
			(end 0.9652 -1.778)
			(stroke
				(width 0)
				(type default)
			)
			(fill no)
			(layer "F.CrtYd")
		)
		(fp_poly
			(pts
				(xy -0.9652 -1.778) (xy 0.9652 -1.778) (xy 0.9652 1.778) (xy -0.9652 1.778)
			)
			(stroke
				(width 0)
				(type default)
			)
			(fill no)
			(layer "F.Fab")
		)
		(pad "1" smd rect
			(at 0 -0.9652 180)
			(size 1.397 1.143)
			(layers "F.Cu" "F.Mask" "F.Paste")
			(net "P1V8_STBY_VIN")
		)
		(pad "2" smd rect
			(at 0 0.9652 180)
			(size 1.397 1.143)
			(layers "F.Cu" "F.Mask" "F.Paste")
			(net "GND")
		)
	)
	(footprint ""
		(layer "F.Cu")
		(at 180.140864 -38.172136 180)
		(property "Reference" "R393"
			(at 0 0 180)
			(layer "F.SilkS")
			(hide yes)
			(effects
				(font
					(size 1.27 1.27)
				)
			)
		)
		(property "Value" "4K75R2F-1-GP"
			(at 0.064008 -3.993896 180)
			(unlocked yes)
			(layer "F.Fab")
			(hide yes)
			(effects
				(font
					(size 1.016 1.016)
					(thickness 0.1524)
				)
			)
		)
		(property "Device Type" "R402H16"
			(at 0.064008 -5.517896 180)
			(unlocked yes)
			(layer "F.Fab")
			(hide yes)
			(effects
				(font
					(size 1.016 1.016)
					(thickness 0.1524)
				)
			)
		)
		(duplicate_pad_numbers_are_jumpers no)
		(fp_line
			(start 0.508 -0.9398)
			(end -0.508 -0.9398)
			(stroke
				(width 0.1524)
				(type default)
			)
			(layer "F.SilkS")
		)
		(fp_line
			(start -0.508 -0.9398)
			(end -0.508 0.9398)
			(stroke
				(width 0.1524)
				(type default)
			)
			(layer "F.SilkS")
		)
		(fp_rect
			(start -0.508 0.9398)
			(end 0.508 -0.9398)
			(stroke
				(width 0)
				(type default)
			)
			(fill no)
			(layer "F.CrtYd")
		)
		(fp_rect
			(start -0.508 0.9398)
			(end 0.508 -0.9398)
			(stroke
				(width 0)
				(type default)
			)
			(fill no)
			(layer "F.Fab")
		)
		(pad "1" smd custom
			(at 0 -0.4445 180)
			(size 0.1397 0.1397)
			(layers "F.Cu" "F.Mask" "F.Paste")
			(net "PHY_AD4")
			(options
				(clearance outline)
				(anchor circle)
			)
			(primitives
				(gr_poly
					(pts
						(arc
							(start -0.1778 -0.2794)
							(mid -0.249642 -0.249642)
							(end -0.2794 -0.1778)
						)
						(arc
							(start -0.2794 0.1778)
							(mid -0.249642 0.249642)
							(end -0.1778 0.2794)
						)
						(arc
							(start 0.1778 0.2794)
							(mid 0.249642 0.249642)
							(end 0.2794 0.1778)
						)
						(arc
							(start 0.2794 -0.1778)
							(mid 0.249642 -0.249642)
							(end 0.1778 -0.2794)
						)
					)
					(width 0)
					(fill yes)
				)
			)
		)
		(pad "2" smd custom
			(at 0 0.4445 180)
			(size 0.1397 0.1397)
			(layers "F.Cu" "F.Mask" "F.Paste")
			(net "GND")
			(options
				(clearance outline)
				(anchor circle)
			)
			(primitives
				(gr_poly
					(pts
						(arc
							(start -0.1778 -0.2794)
							(mid -0.249642 -0.249642)
							(end -0.2794 -0.1778)
						)
						(arc
							(start -0.2794 0.1778)
							(mid -0.249642 0.249642)
							(end -0.1778 0.2794)
						)
						(arc
							(start 0.1778 0.2794)
							(mid 0.249642 0.249642)
							(end 0.2794 0.1778)
						)
						(arc
							(start 0.2794 -0.1778)
							(mid 0.249642 -0.249642)
							(end 0.1778 -0.2794)
						)
					)
					(width 0)
					(fill yes)
				)
			)
		)
	)
	(footprint ""
		(layer "F.Cu")
		(at 96.501966 -63.119)
		(property "Reference" "SR679"
			(at 0 0 0)
			(layer "F.SilkS")
			(hide yes)
			(effects
				(font
					(size 1.27 1.27)
				)
			)
		)
		(property "Value" "4K7R2F-GP"
			(at 0.064008 -3.993896 0)
			(unlocked yes)
			(layer "F.Fab")
			(hide yes)
			(effects
				(font
					(size 1.016 1.016)
					(thickness 0.1524)
				)
			)
		)
		(property "Device Type" "R402H16"
			(at 0.064008 -5.517896 0)
			(unlocked yes)
			(layer "F.Fab")
			(hide yes)
			(effects
				(font
					(size 1.016 1.016)
					(thickness 0.1524)
				)
			)
		)
		(duplicate_pad_numbers_are_jumpers no)
		(fp_line
			(start -0.508 -0.9398)
			(end -0.508 0.9398)
			(stroke
				(width 0.1524)
				(type default)
			)
			(layer "F.SilkS")
		)
		(fp_line
			(start 0.508 -0.9398)
			(end -0.508 -0.9398)
			(stroke
				(width 0.1524)
				(type default)
			)
			(layer "F.SilkS")
		)
		(fp_rect
			(start -0.508 0.9398)
			(end 0.508 -0.9398)
			(stroke
				(width 0)
				(type default)
			)
			(fill no)
			(layer "F.CrtYd")
		)
		(fp_rect
			(start -0.508 0.9398)
			(end 0.508 -0.9398)
			(stroke
				(width 0)
				(type default)
			)
			(fill no)
			(layer "F.Fab")
		)
		(pad "1" smd custom
			(at 0 -0.4445)
			(size 0.1397 0.1397)
			(layers "F.Cu" "F.Mask" "F.Paste")
			(net "P1V8_C")
			(options
				(clearance outline)
				(anchor circle)
			)
			(primitives
				(gr_poly
					(pts
						(arc
							(start -0.1778 -0.2794)
							(mid -0.249642 -0.249642)
							(end -0.2794 -0.1778)
						)
						(arc
							(start -0.2794 0.1778)
							(mid -0.249642 0.249642)
							(end -0.1778 0.2794)
						)
						(arc
							(start 0.1778 0.2794)
							(mid 0.249642 0.249642)
							(end 0.2794 0.1778)
						)
						(arc
							(start 0.2794 -0.1778)
							(mid 0.249642 -0.249642)
							(end 0.1778 -0.2794)
						)
					)
					(width 0)
					(fill yes)
				)
			)
		)
		(pad "2" smd custom
			(at 0 0.4445)
			(size 0.1397 0.1397)
			(layers "F.Cu" "F.Mask" "F.Paste")
			(net "ICE0_TCK")
			(options
				(clearance outline)
				(anchor circle)
			)
			(primitives
				(gr_poly
					(pts
						(arc
							(start -0.1778 -0.2794)
							(mid -0.249642 -0.249642)
							(end -0.2794 -0.1778)
						)
						(arc
							(start -0.2794 0.1778)
							(mid -0.249642 0.249642)
							(end -0.1778 0.2794)
						)
						(arc
							(start 0.1778 0.2794)
							(mid 0.249642 0.249642)
							(end 0.2794 0.1778)
						)
						(arc
							(start 0.2794 -0.1778)
							(mid 0.249642 -0.249642)
							(end 0.1778 -0.2794)
						)
					)
					(width 0)
					(fill yes)
				)
			)
		)
	)
	(footprint ""
		(layer "F.Cu")
		(at 56.896 -211.074)
		(property "Reference" "PR9007"
			(at 0 0 0)
			(layer "F.SilkS")
			(hide yes)
			(effects
				(font
					(size 1.27 1.27)
				)
			)
		)
		(property "Value" "0R2J-2-GP"
			(at 0.064008 -3.993896 0)
			(unlocked yes)
			(layer "F.Fab")
			(hide yes)
			(effects
				(font
					(size 1.016 1.016)
					(thickness 0.1524)
				)
			)
		)
		(property "Device Type" "R402H16"
			(at 0.064008 -5.517896 0)
			(unlocked yes)
			(layer "F.Fab")
			(hide yes)
			(effects
				(font
					(size 1.016 1.016)
					(thickness 0.1524)
				)
			)
		)
		(duplicate_pad_numbers_are_jumpers no)
		(fp_line
			(start -0.508 -0.9398)
			(end -0.508 0.9398)
			(stroke
				(width 0.1524)
				(type default)
			)
			(layer "F.SilkS")
		)
		(fp_line
			(start 0.508 -0.9398)
			(end -0.508 -0.9398)
			(stroke
				(width 0.1524)
				(type default)
			)
			(layer "F.SilkS")
		)
		(fp_rect
			(start -0.508 0.9398)
			(end 0.508 -0.9398)
			(stroke
				(width 0)
				(type default)
			)
			(fill no)
			(layer "F.CrtYd")
		)
		(fp_rect
			(start -0.508 0.9398)
			(end 0.508 -0.9398)
			(stroke
				(width 0)
				(type default)
			)
			(fill no)
			(layer "F.Fab")
		)
		(pad "1" smd custom
			(at 0 -0.4445)
			(size 0.1397 0.1397)
			(layers "F.Cu" "F.Mask" "F.Paste")
			(net "HSW_SDA_2")
			(options
				(clearance outline)
				(anchor circle)
			)
			(primitives
				(gr_poly
					(pts
						(arc
							(start -0.1778 -0.2794)
							(mid -0.249642 -0.249642)
							(end -0.2794 -0.1778)
						)
						(arc
							(start -0.2794 0.1778)
							(mid -0.249642 0.249642)
							(end -0.1778 0.2794)
						)
						(arc
							(start 0.1778 0.2794)
							(mid 0.249642 0.249642)
							(end 0.2794 0.1778)
						)
						(arc
							(start 0.2794 -0.1778)
							(mid 0.249642 -0.249642)
							(end 0.1778 -0.2794)
						)
					)
					(width 0)
					(fill yes)
				)
			)
		)
		(pad "2" smd custom
			(at 0 0.4445)
			(size 0.1397 0.1397)
			(layers "F.Cu" "F.Mask" "F.Paste")
			(net "BMC_I2C_SDA_10")
			(options
				(clearance outline)
				(anchor circle)
			)
			(primitives
				(gr_poly
					(pts
						(arc
							(start -0.1778 -0.2794)
							(mid -0.249642 -0.249642)
							(end -0.2794 -0.1778)
						)
						(arc
							(start -0.2794 0.1778)
							(mid -0.249642 0.249642)
							(end -0.1778 0.2794)
						)
						(arc
							(start 0.1778 0.2794)
							(mid 0.249642 0.249642)
							(end 0.2794 0.1778)
						)
						(arc
							(start 0.2794 -0.1778)
							(mid 0.249642 -0.249642)
							(end 0.1778 -0.2794)
						)
					)
					(width 0)
					(fill yes)
				)
			)
		)
	)
	(footprint ""
		(layer "F.Cu")
		(at 112.23117 -71.0946 90)
		(property "Reference" "U136"
			(at 0 0 90)
			(layer "F.SilkS")
			(hide yes)
			(effects
				(font
					(size 1.27 1.27)
				)
			)
		)
		(property "Value" "TMP75AIDGKR-GP"
			(at -0.1143 -9.1948 90)
			(unlocked yes)
			(layer "F.Fab")
			(hide yes)
			(effects
				(font
					(size 1.016 1.016)
					(thickness 0.1524)
				)
			)
		)
		(property "Device Type" "MSOP8-1H44"
			(at -0.1143 -10.795 90)
			(unlocked yes)
			(layer "F.Fab")
			(hide yes)
			(effects
				(font
					(size 1.016 1.016)
					(thickness 0.1524)
				)
			)
		)
		(duplicate_pad_numbers_are_jumpers no)
		(fp_line
			(start 1.0795 -1.016)
			(end -1.9558 -1.016)
			(stroke
				(width 0.1524)
				(type default)
			)
			(layer "F.SilkS")
		)
		(fp_line
			(start -1.9558 -1.016)
			(end -1.9558 1.016)
			(stroke
				(width 0.1524)
				(type default)
			)
			(layer "F.SilkS")
		)
		(fp_line
			(start -1.9558 -0.5461)
			(end -1.4478 -0.0381)
			(stroke
				(width 0.1524)
				(type default)
			)
			(layer "F.SilkS")
		)
		(fp_line
			(start -1.4478 -0.0381)
			(end -1.9558 0.4699)
			(stroke
				(width 0.1524)
				(type default)
			)
			(layer "F.SilkS")
		)
		(fp_line
			(start 1.0795 1.016)
			(end 1.0795 -1.016)
			(stroke
				(width 0.1524)
				(type default)
			)
			(layer "F.SilkS")
		)
		(fp_line
			(start -1.9558 1.016)
			(end 1.0795 1.016)
			(stroke
				(width 0.1524)
				(type default)
			)
			(layer "F.SilkS")
		)
		(fp_line
			(start -1.778 1.0922)
			(end -1.778 3.048)
			(stroke
				(width 0.508)
				(type default)
			)
			(layer "F.SilkS")
		)
		(fp_poly
			(pts
				(xy -1.1557 -1.016) (xy -1.1557 1.016) (xy 1.1557 1.016) (xy 1.1557 -1.016)
			)
			(stroke
				(width 0)
				(type default)
			)
			(fill yes)
			(layer "F.SilkS")
		)
		(fp_rect
			(start -1.4986 2.4511)
			(end 1.4986 -2.4511)
			(stroke
				(width 0)
				(type default)
			)
			(fill no)
			(layer "F.CrtYd")
		)
		(fp_poly
			(pts
				(xy -2.032 3.302) (xy -2.032 -3.302) (xy 2.032 -3.302) (xy 2.032 -2.1209) (xy 1.4986 -2.1209) (xy 1.4986 -2.4511)
				(xy -1.4986 -2.4511) (xy -1.4986 2.4511) (xy 1.4986 2.4511) (xy 1.4986 -2.1082) (xy 2.032 -2.1082)
				(xy 2.032 3.302)
			)
			(stroke
				(width 0)
				(type default)
			)
			(fill no)
			(layer "F.CrtYd")
		)
		(fp_rect
			(start -2.032 3.302)
			(end 2.032 -3.302)
			(stroke
				(width 0)
				(type default)
			)
			(fill no)
			(layer "F.Fab")
		)
		(pad "1" smd rect
			(at -0.97536 2.05486 90)
			(size 0.3556 1.524)
			(layers "F.Cu" "F.Mask" "F.Paste")
			(net "TEMP_4_SDA")
		)
		(pad "2" smd rect
			(at -0.32512 2.05486 90)
			(size 0.3556 1.524)
			(layers "F.Cu" "F.Mask" "F.Paste")
			(net "TEMP_4_SCL")
		)
		(pad "3" smd rect
			(at 0.32512 2.05486 90)
			(size 0.3556 1.524)
			(layers "F.Cu" "F.Mask" "F.Paste")
			(net "TEMP_4_ALERT")
		)
		(pad "4" smd rect
			(at 0.97536 2.05486 90)
			(size 0.3556 1.524)
			(layers "F.Cu" "F.Mask" "F.Paste")
			(net "GND")
		)
		(pad "5" smd rect
			(at 0.97536 -2.05486 90)
			(size 0.3556 1.524)
			(layers "F.Cu" "F.Mask" "F.Paste")
			(net "TEMP_4_A2")
		)
		(pad "6" smd rect
			(at 0.32512 -2.05486 90)
			(size 0.3556 1.524)
			(layers "F.Cu" "F.Mask" "F.Paste")
			(net "TEMP_4_A1")
		)
		(pad "7" smd rect
			(at -0.32512 -2.05486 90)
			(size 0.3556 1.524)
			(layers "F.Cu" "F.Mask" "F.Paste")
			(net "TEMP_4_A0")
		)
		(pad "8" smd rect
			(at -0.97536 -2.05486 90)
			(size 0.3556 1.524)
			(layers "F.Cu" "F.Mask" "F.Paste")
			(net "P3V3_STBY")
		)
	)
	(footprint ""
		(layer "F.Cu")
		(at 193.737992 -31.369 90)
		(property "Reference" "BC2"
			(at 0 0 90)
			(layer "F.SilkS")
			(hide yes)
			(effects
				(font
					(size 1.27 1.27)
				)
			)
		)
		(property "Value" "SC2D2U10V3KX-1GP"
			(at 0 -2.8194 90)
			(unlocked yes)
			(layer "F.Fab")
			(hide yes)
			(effects
				(font
					(size 1.016 1.016)
					(thickness 0.1524)
				)
			)
		)
		(property "Device Type" "C603H36"
			(at 0 -4.3434 90)
			(unlocked yes)
			(layer "F.Fab")
			(hide yes)
			(effects
				(font
					(size 1.016 1.016)
					(thickness 0.1524)
				)
			)
		)
		(duplicate_pad_numbers_are_jumpers no)
		(fp_line
			(start 0.508 0)
			(end -0.508 0)
			(stroke
				(width 0.2032)
				(type default)
			)
			(layer "F.SilkS")
		)
		(fp_rect
			(start -0.5842 1.3335)
			(end 0.5842 -1.3335)
			(stroke
				(width 0)
				(type default)
			)
			(fill no)
			(layer "F.CrtYd")
		)
		(fp_rect
			(start -0.5842 1.3335)
			(end 0.5842 -1.3335)
			(stroke
				(width 0)
				(type default)
			)
			(fill no)
			(layer "F.Fab")
		)
		(pad "1" smd custom
			(at 0 -0.762 90)
			(size 0.2159 0.2159)
			(layers "F.Cu" "F.Mask" "F.Paste")
			(net "PHY_DVDD")
			(options
				(clearance outline)
				(anchor circle)
			)
			(primitives
				(gr_poly
					(pts
						(arc
							(start -0.3302 -0.4318)
							(mid -0.402042 -0.402042)
							(end -0.4318 -0.3302)
						)
						(arc
							(start -0.4318 0.3302)
							(mid -0.402042 0.402042)
							(end -0.3302 0.4318)
						)
						(arc
							(start 0.3302 0.4318)
							(mid 0.402042 0.402042)
							(end 0.4318 0.3302)
						)
						(arc
							(start 0.4318 -0.3302)
							(mid 0.402042 -0.402042)
							(end 0.3302 -0.4318)
						)
					)
					(width 0)
					(fill yes)
				)
			)
		)
		(pad "2" smd custom
			(at 0 0.762 90)
			(size 0.2159 0.2159)
			(layers "F.Cu" "F.Mask" "F.Paste")
			(net "GND")
			(options
				(clearance outline)
				(anchor circle)
			)
			(primitives
				(gr_poly
					(pts
						(arc
							(start -0.3302 -0.4318)
							(mid -0.402042 -0.402042)
							(end -0.4318 -0.3302)
						)
						(arc
							(start -0.4318 0.3302)
							(mid -0.402042 0.402042)
							(end -0.3302 0.4318)
						)
						(arc
							(start 0.3302 0.4318)
							(mid 0.402042 0.402042)
							(end 0.4318 0.3302)
						)
						(arc
							(start 0.4318 -0.3302)
							(mid 0.402042 -0.402042)
							(end 0.3302 -0.4318)
						)
					)
					(width 0)
					(fill yes)
				)
			)
		)
	)
	(footprint ""
		(layer "F.Cu")
		(at 89.662 -225.806 -90)
		(property "Reference" "SR308"
			(at 0 0 270)
			(layer "F.SilkS")
			(hide yes)
			(effects
				(font
					(size 1.27 1.27)
				)
			)
		)
		(property "Value" "0R2J-2-GP"
			(at 0.064008 -3.993896 270)
			(unlocked yes)
			(layer "F.Fab")
			(hide yes)
			(effects
				(font
					(size 1.016 1.016)
					(thickness 0.1524)
				)
			)
		)
		(property "Device Type" "R402H16"
			(at 0.064008 -5.517896 270)
			(unlocked yes)
			(layer "F.Fab")
			(hide yes)
			(effects
				(font
					(size 1.016 1.016)
					(thickness 0.1524)
				)
			)
		)
		(duplicate_pad_numbers_are_jumpers no)
		(fp_line
			(start -0.508 -0.9398)
			(end -0.508 0.9398)
			(stroke
				(width 0.1524)
				(type default)
			)
			(layer "F.SilkS")
		)
		(fp_line
			(start 0.508 -0.9398)
			(end -0.508 -0.9398)
			(stroke
				(width 0.1524)
				(type default)
			)
			(layer "F.SilkS")
		)
		(fp_rect
			(start -0.508 0.9398)
			(end 0.508 -0.9398)
			(stroke
				(width 0)
				(type default)
			)
			(fill no)
			(layer "F.CrtYd")
		)
		(fp_rect
			(start -0.508 0.9398)
			(end 0.508 -0.9398)
			(stroke
				(width 0)
				(type default)
			)
			(fill no)
			(layer "F.Fab")
		)
		(pad "1" smd custom
			(at 0 -0.4445 270)
			(size 0.1397 0.1397)
			(layers "F.Cu" "F.Mask" "F.Paste")
			(net "I2C_IO_EXP_RESET#_FLT")
			(options
				(clearance outline)
				(anchor circle)
			)
			(primitives
				(gr_poly
					(pts
						(arc
							(start -0.1778 -0.2794)
							(mid -0.249642 -0.249642)
							(end -0.2794 -0.1778)
						)
						(arc
							(start -0.2794 0.1778)
							(mid -0.249642 0.249642)
							(end -0.1778 0.2794)
						)
						(arc
							(start 0.1778 0.2794)
							(mid 0.249642 0.249642)
							(end 0.2794 0.1778)
						)
						(arc
							(start 0.2794 -0.1778)
							(mid 0.249642 -0.249642)
							(end 0.1778 -0.2794)
						)
					)
					(width 0)
					(fill yes)
				)
			)
		)
		(pad "2" smd custom
			(at 0 0.4445 270)
			(size 0.1397 0.1397)
			(layers "F.Cu" "F.Mask" "F.Paste")
			(net "HDD_LED_RESET_N")
			(options
				(clearance outline)
				(anchor circle)
			)
			(primitives
				(gr_poly
					(pts
						(arc
							(start -0.1778 -0.2794)
							(mid -0.249642 -0.249642)
							(end -0.2794 -0.1778)
						)
						(arc
							(start -0.2794 0.1778)
							(mid -0.249642 0.249642)
							(end -0.1778 0.2794)
						)
						(arc
							(start 0.1778 0.2794)
							(mid 0.249642 0.249642)
							(end 0.2794 0.1778)
						)
						(arc
							(start 0.2794 -0.1778)
							(mid 0.249642 -0.249642)
							(end 0.1778 -0.2794)
						)
					)
					(width 0)
					(fill yes)
				)
			)
		)
	)
	(footprint ""
		(layer "F.Cu")
		(at 267.589 -71.882 90)
		(property "Reference" "C258"
			(at 0 0 90)
			(layer "F.SilkS")
			(hide yes)
			(effects
				(font
					(size 1.27 1.27)
				)
			)
		)
		(property "Value" "SC1U25V3KX-GP"
			(at 0 -2.8194 90)
			(unlocked yes)
			(layer "F.Fab")
			(hide yes)
			(effects
				(font
					(size 1.016 1.016)
					(thickness 0.1524)
				)
			)
		)
		(property "Device Type" "C603H36"
			(at 0 -4.3434 90)
			(unlocked yes)
			(layer "F.Fab")
			(hide yes)
			(effects
				(font
					(size 1.016 1.016)
					(thickness 0.1524)
				)
			)
		)
		(duplicate_pad_numbers_are_jumpers no)
		(fp_line
			(start 0.508 0)
			(end -0.508 0)
			(stroke
				(width 0.2032)
				(type default)
			)
			(layer "F.SilkS")
		)
		(fp_rect
			(start -0.5842 1.3335)
			(end 0.5842 -1.3335)
			(stroke
				(width 0)
				(type default)
			)
			(fill no)
			(layer "F.CrtYd")
		)
		(fp_rect
			(start -0.5842 1.3335)
			(end 0.5842 -1.3335)
			(stroke
				(width 0)
				(type default)
			)
			(fill no)
			(layer "F.Fab")
		)
		(pad "1" smd custom
			(at 0 -0.762 90)
			(size 0.2159 0.2159)
			(layers "F.Cu" "F.Mask" "F.Paste")
			(net "P12V_MSB")
			(options
				(clearance outline)
				(anchor circle)
			)
			(primitives
				(gr_poly
					(pts
						(arc
							(start -0.3302 -0.4318)
							(mid -0.402042 -0.402042)
							(end -0.4318 -0.3302)
						)
						(arc
							(start -0.4318 0.3302)
							(mid -0.402042 0.402042)
							(end -0.3302 0.4318)
						)
						(arc
							(start 0.3302 0.4318)
							(mid 0.402042 0.402042)
							(end 0.4318 0.3302)
						)
						(arc
							(start 0.4318 -0.3302)
							(mid 0.402042 -0.402042)
							(end 0.3302 -0.4318)
						)
					)
					(width 0)
					(fill yes)
				)
			)
		)
		(pad "2" smd custom
			(at 0 0.762 90)
			(size 0.2159 0.2159)
			(layers "F.Cu" "F.Mask" "F.Paste")
			(net "GND")
			(options
				(clearance outline)
				(anchor circle)
			)
			(primitives
				(gr_poly
					(pts
						(arc
							(start -0.3302 -0.4318)
							(mid -0.402042 -0.402042)
							(end -0.4318 -0.3302)
						)
						(arc
							(start -0.4318 0.3302)
							(mid -0.402042 0.402042)
							(end -0.3302 0.4318)
						)
						(arc
							(start 0.3302 0.4318)
							(mid 0.402042 0.402042)
							(end 0.4318 0.3302)
						)
						(arc
							(start 0.4318 -0.3302)
							(mid 0.402042 -0.402042)
							(end 0.3302 -0.4318)
						)
					)
					(width 0)
					(fill yes)
				)
			)
		)
	)
	(footprint ""
		(layer "F.Cu")
		(at 35.383216 -199.06488 -90)
		(property "Reference" "R568"
			(at 0 0 270)
			(layer "F.SilkS")
			(hide yes)
			(effects
				(font
					(size 1.27 1.27)
				)
			)
		)
		(property "Value" "0R2J-2-GP"
			(at 0.064008 -3.993896 270)
			(unlocked yes)
			(layer "F.Fab")
			(hide yes)
			(effects
				(font
					(size 1.016 1.016)
					(thickness 0.1524)
				)
			)
		)
		(property "Device Type" "R402H16"
			(at 0.064008 -5.517896 270)
			(unlocked yes)
			(layer "F.Fab")
			(hide yes)
			(effects
				(font
					(size 1.016 1.016)
					(thickness 0.1524)
				)
			)
		)
		(duplicate_pad_numbers_are_jumpers no)
		(fp_line
			(start -0.508 -0.9398)
			(end -0.508 0.9398)
			(stroke
				(width 0.1524)
				(type default)
			)
			(layer "F.SilkS")
		)
		(fp_line
			(start 0.508 -0.9398)
			(end -0.508 -0.9398)
			(stroke
				(width 0.1524)
				(type default)
			)
			(layer "F.SilkS")
		)
		(fp_rect
			(start -0.508 0.9398)
			(end 0.508 -0.9398)
			(stroke
				(width 0)
				(type default)
			)
			(fill no)
			(layer "F.CrtYd")
		)
		(fp_rect
			(start -0.508 0.9398)
			(end 0.508 -0.9398)
			(stroke
				(width 0)
				(type default)
			)
			(fill no)
			(layer "F.Fab")
		)
		(pad "1" smd custom
			(at 0 -0.4445 270)
			(size 0.1397 0.1397)
			(layers "F.Cu" "F.Mask" "F.Paste")
			(net "ADC_P1V5_E")
			(options
				(clearance outline)
				(anchor circle)
			)
			(primitives
				(gr_poly
					(pts
						(arc
							(start -0.1778 -0.2794)
							(mid -0.249642 -0.249642)
							(end -0.2794 -0.1778)
						)
						(arc
							(start -0.2794 0.1778)
							(mid -0.249642 0.249642)
							(end -0.1778 0.2794)
						)
						(arc
							(start 0.1778 0.2794)
							(mid 0.249642 0.249642)
							(end 0.2794 0.1778)
						)
						(arc
							(start 0.2794 -0.1778)
							(mid 0.249642 -0.249642)
							(end 0.1778 -0.2794)
						)
					)
					(width 0)
					(fill yes)
				)
			)
		)
		(pad "2" smd custom
			(at 0 0.4445 270)
			(size 0.1397 0.1397)
			(layers "F.Cu" "F.Mask" "F.Paste")
			(net "P1V5_E_SENSE")
			(options
				(clearance outline)
				(anchor circle)
			)
			(primitives
				(gr_poly
					(pts
						(arc
							(start -0.1778 -0.2794)
							(mid -0.249642 -0.249642)
							(end -0.2794 -0.1778)
						)
						(arc
							(start -0.2794 0.1778)
							(mid -0.249642 0.249642)
							(end -0.1778 0.2794)
						)
						(arc
							(start 0.1778 0.2794)
							(mid 0.249642 0.249642)
							(end 0.2794 0.1778)
						)
						(arc
							(start 0.2794 -0.1778)
							(mid 0.249642 -0.249642)
							(end 0.1778 -0.2794)
						)
					)
					(width 0)
					(fill yes)
				)
			)
		)
	)
	(footprint ""
		(layer "F.Cu")
		(at 323.85 -172.974 90)
		(property "Reference" "R435"
			(at 0 0 90)
			(layer "F.SilkS")
			(hide yes)
			(effects
				(font
					(size 1.27 1.27)
				)
			)
		)
		(property "Value" "0R2J-2-GP"
			(at 0.064008 -3.993896 90)
			(unlocked yes)
			(layer "F.Fab")
			(hide yes)
			(effects
				(font
					(size 1.016 1.016)
					(thickness 0.1524)
				)
			)
		)
		(property "Device Type" "R402H16"
			(at 0.064008 -5.517896 90)
			(unlocked yes)
			(layer "F.Fab")
			(hide yes)
			(effects
				(font
					(size 1.016 1.016)
					(thickness 0.1524)
				)
			)
		)
		(duplicate_pad_numbers_are_jumpers no)
		(fp_line
			(start 0.508 -0.9398)
			(end -0.508 -0.9398)
			(stroke
				(width 0.1524)
				(type default)
			)
			(layer "F.SilkS")
		)
		(fp_line
			(start -0.508 -0.9398)
			(end -0.508 0.9398)
			(stroke
				(width 0.1524)
				(type default)
			)
			(layer "F.SilkS")
		)
		(fp_rect
			(start -0.508 0.9398)
			(end 0.508 -0.9398)
			(stroke
				(width 0)
				(type default)
			)
			(fill no)
			(layer "F.CrtYd")
		)
		(fp_rect
			(start -0.508 0.9398)
			(end 0.508 -0.9398)
			(stroke
				(width 0)
				(type default)
			)
			(fill no)
			(layer "F.Fab")
		)
		(pad "1" smd custom
			(at 0 -0.4445 90)
			(size 0.1397 0.1397)
			(layers "F.Cu" "F.Mask" "F.Paste")
			(net "EXP_SMART_TX")
			(options
				(clearance outline)
				(anchor circle)
			)
			(primitives
				(gr_poly
					(pts
						(arc
							(start -0.1778 -0.2794)
							(mid -0.249642 -0.249642)
							(end -0.2794 -0.1778)
						)
						(arc
							(start -0.2794 0.1778)
							(mid -0.249642 0.249642)
							(end -0.1778 0.2794)
						)
						(arc
							(start 0.1778 0.2794)
							(mid 0.249642 0.249642)
							(end 0.2794 0.1778)
						)
						(arc
							(start 0.2794 -0.1778)
							(mid 0.249642 -0.249642)
							(end 0.1778 -0.2794)
						)
					)
					(width 0)
					(fill yes)
				)
			)
		)
		(pad "2" smd custom
			(at 0 0.4445 90)
			(size 0.1397 0.1397)
			(layers "F.Cu" "F.Mask" "F.Paste")
			(net "EXP_UART_TX_R")
			(options
				(clearance outline)
				(anchor circle)
			)
			(primitives
				(gr_poly
					(pts
						(arc
							(start -0.1778 -0.2794)
							(mid -0.249642 -0.249642)
							(end -0.2794 -0.1778)
						)
						(arc
							(start -0.2794 0.1778)
							(mid -0.249642 0.249642)
							(end -0.1778 0.2794)
						)
						(arc
							(start 0.1778 0.2794)
							(mid 0.249642 0.249642)
							(end 0.2794 0.1778)
						)
						(arc
							(start 0.2794 -0.1778)
							(mid 0.249642 -0.249642)
							(end 0.1778 -0.2794)
						)
					)
					(width 0)
					(fill yes)
				)
			)
		)
	)
	(footprint ""
		(layer "F.Cu")
		(at 114.82197 -78.359)
		(property "Reference" "STP106"
			(at 0 0 0)
			(layer "F.SilkS")
			(hide yes)
			(effects
				(font
					(size 1.27 1.27)
				)
			)
		)
		(property "Value" "TPAD28"
			(at 0.0127 -1.8034 0)
			(unlocked yes)
			(layer "F.Fab")
			(hide yes)
			(effects
				(font
					(size 1.016 1.016)
					(thickness 0.1524)
				)
			)
		)
		(property "Device Type" "TPAD28"
			(at 0.0127 -3.3274 0)
			(unlocked yes)
			(layer "F.Fab")
			(hide yes)
			(effects
				(font
					(size 1.016 1.016)
					(thickness 0.1524)
				)
			)
		)
		(duplicate_pad_numbers_are_jumpers no)
		(fp_poly
			(pts
				(arc
					(start 0.3556 0)
					(mid -0.3556 0)
					(end 0.3556 0)
				)
			)
			(stroke
				(width 0)
				(type default)
			)
			(fill no)
			(layer "F.CrtYd")
		)
		(fp_poly
			(pts
				(arc
					(start 0.6096 0)
					(mid -0.6096 0)
					(end 0.6096 0)
				)
			)
			(stroke
				(width 0)
				(type default)
			)
			(fill no)
			(layer "F.Fab")
		)
		(pad "1" smd circle
			(at 0 0)
			(size 0.7112 0.7112)
			(layers "F.Cu" "F.Mask" "F.Paste")
			(net "TEST_MUX_39")
		)
	)
	(footprint ""
		(layer "F.Cu")
		(at 52.08397 -134.62 90)
		(property "Reference" "U39"
			(at 0 0 90)
			(layer "F.SilkS")
			(hide yes)
			(effects
				(font
					(size 1.27 1.27)
				)
			)
		)
		(property "Value" "SN74LVC1G08DCKR-GP"
			(at -2.3368 -8.6868 90)
			(unlocked yes)
			(layer "F.Fab")
			(hide yes)
			(effects
				(font
					(size 1.016 1.016)
					(thickness 0.1524)
				)
			)
		)
		(property "Device Type" "SC70-5H44"
			(at -2.3114 -10.414 90)
			(unlocked yes)
			(layer "F.Fab")
			(hide yes)
			(effects
				(font
					(size 1.016 1.016)
					(thickness 0.1524)
				)
			)
		)
		(duplicate_pad_numbers_are_jumpers no)
		(fp_line
			(start 1.3843 -1.8034)
			(end 1.3843 -1.1176)
			(stroke
				(width 0.3302)
				(type default)
			)
			(layer "F.SilkS")
		)
		(fp_line
			(start 0.6604 -1.8034)
			(end 1.3843 -1.8034)
			(stroke
				(width 0.3302)
				(type default)
			)
			(layer "F.SilkS")
		)
		(fp_line
			(start 1.27 -1.7018)
			(end 1.27 1.7018)
			(stroke
				(width 0.1524)
				(type default)
			)
			(layer "F.SilkS")
		)
		(fp_line
			(start -1.27 -1.7018)
			(end 1.27 -1.7018)
			(stroke
				(width 0.1524)
				(type default)
			)
			(layer "F.SilkS")
		)
		(fp_line
			(start 1.27 1.7018)
			(end -1.27 1.7018)
			(stroke
				(width 0.1524)
				(type default)
			)
			(layer "F.SilkS")
		)
		(fp_line
			(start -1.27 1.7018)
			(end -1.27 -1.7018)
			(stroke
				(width 0.1524)
				(type default)
			)
			(layer "F.SilkS")
		)
		(fp_rect
			(start -1.524 1.9558)
			(end 1.524 -1.9558)
			(stroke
				(width 0)
				(type default)
			)
			(fill no)
			(layer "F.CrtYd")
		)
		(fp_poly
			(pts
				(xy -1.524 -1.9558) (xy 1.524 -1.9558) (xy 1.524 1.9558) (xy -1.524 1.9558)
			)
			(stroke
				(width 0)
				(type default)
			)
			(fill no)
			(layer "F.Fab")
		)
		(pad "1" smd rect
			(at 0.65024 -0.8255 90)
			(size 0.4064 1.2192)
			(layers "F.Cu" "F.Mask" "F.Paste")
			(net "RESET_AND_N")
		)
		(pad "2" smd rect
			(at 0 -0.8255 90)
			(size 0.4064 1.2192)
			(layers "F.Cu" "F.Mask" "F.Paste")
			(net "BMC_EXP_RESET_N")
		)
		(pad "3" smd rect
			(at -0.65024 -0.8255 90)
			(size 0.4064 1.2192)
			(layers "F.Cu" "F.Mask" "F.Paste")
			(net "GND")
		)
		(pad "4" smd rect
			(at -0.65024 0.8255 90)
			(size 0.4064 1.2192)
			(layers "F.Cu" "F.Mask" "F.Paste")
			(net "EXP_RST_1")
		)
		(pad "5" smd rect
			(at 0.65024 0.8255 90)
			(size 0.4064 1.2192)
			(layers "F.Cu" "F.Mask" "F.Paste")
			(net "P1V8_E")
		)
	)
	(footprint ""
		(layer "F.Cu")
		(at 319.660016 -88.650064 -90)
		(property "Reference" "BAT1"
			(at 0 0 270)
			(layer "F.SilkS")
			(hide yes)
			(effects
				(font
					(size 1.27 1.27)
				)
			)
		)
		(property "Value" "BAT-AAA-BAT-043-K01-GP"
			(at -10.2616 -6.7056 270)
			(unlocked yes)
			(layer "F.Fab")
			(hide yes)
			(effects
				(font
					(size 1.016 1.016)
					(thickness 0.1524)
				)
			)
		)
		(property "Device Type" "AAA-BAT-043-K01"
			(at -10.2616 -8.2296 270)
			(unlocked yes)
			(layer "F.Fab")
			(hide yes)
			(effects
				(font
					(size 1.016 1.016)
					(thickness 0.1524)
				)
			)
		)
		(duplicate_pad_numbers_are_jumpers no)
		(fp_line
			(start -5.38099 2.0574)
			(end -4.61899 2.0574)
			(stroke
				(width 0.1524)
				(type default)
			)
			(layer "F.SilkS")
		)
		(fp_line
			(start 4.61899 2.0574)
			(end 5.38099 2.0574)
			(stroke
				(width 0.1524)
				(type default)
			)
			(layer "F.SilkS")
		)
		(fp_line
			(start -4.99999 1.6764)
			(end -4.99999 2.4384)
			(stroke
				(width 0.1524)
				(type default)
			)
			(layer "F.SilkS")
		)
		(fp_line
			(start 4.99999 1.6764)
			(end 4.99999 2.4384)
			(stroke
				(width 0.1524)
				(type default)
			)
			(layer "F.SilkS")
		)
		(fp_line
			(start 10.7569 1.4732)
			(end 12.0269 1.4732)
			(stroke
				(width 0.4064)
				(type default)
			)
			(layer "F.SilkS")
		)
		(fp_line
			(start 12.0269 1.4732)
			(end 12.0269 0.2032)
			(stroke
				(width 0.4064)
				(type default)
			)
			(layer "F.SilkS")
		)
		(fp_line
			(start -11.8999 1.3462)
			(end -11.8999 -4.953)
			(stroke
				(width 0.1524)
				(type default)
			)
			(layer "F.SilkS")
		)
		(fp_line
			(start 11.8999 1.3462)
			(end -11.8999 1.3462)
			(stroke
				(width 0.1524)
				(type default)
			)
			(layer "F.SilkS")
		)
		(fp_line
			(start -11.8999 -4.953)
			(end 11.8999 -4.953)
			(stroke
				(width 0.1524)
				(type default)
			)
			(layer "F.SilkS")
		)
		(fp_line
			(start 11.8999 -4.953)
			(end 11.8999 1.3462)
			(stroke
				(width 0.1524)
				(type default)
			)
			(layer "F.SilkS")
		)
		(fp_line
			(start -0.381 -5.301234)
			(end 0.381 -5.301234)
			(stroke
				(width 0.1524)
				(type default)
			)
			(layer "F.SilkS")
		)
		(fp_circle
			(center -4.99999 0)
			(end -4.99999 -1.0922)
			(stroke
				(width 0.3048)
				(type default)
			)
			(fill no)
			(layer "F.SilkS")
		)
		(fp_circle
			(center 4.99999 0)
			(end 4.99999 -1.0922)
			(stroke
				(width 0.3048)
				(type default)
			)
			(fill no)
			(layer "F.SilkS")
		)
		(fp_circle
			(center 0 -3.599942)
			(end 0 -4.692142)
			(stroke
				(width 0.3048)
				(type default)
			)
			(fill no)
			(layer "F.SilkS")
		)
		(fp_rect
			(start -11.6459 1.0922)
			(end 11.6459 -4.699)
			(stroke
				(width 0)
				(type default)
			)
			(fill no)
			(layer "F.CrtYd")
		)
		(fp_poly
			(pts
				(xy -0.1016 -5.207) (xy -0.1016 -4.699) (xy 11.6459 -4.699) (xy 11.6459 1.0922) (xy -11.6459 1.0922)
				(xy -11.6459 -4.699) (xy -0.1143 -4.699) (xy -0.1143 -5.207) (xy -12.1539 -5.207) (xy -12.1539 1.6002)
				(xy 12.1539 1.6002) (xy 12.1539 -5.207)
			)
			(stroke
				(width 0)
				(type default)
			)
			(fill no)
			(layer "F.CrtYd")
		)
		(fp_rect
			(start -12.1539 1.6002)
			(end 12.1539 -5.207)
			(stroke
				(width 0)
				(type default)
			)
			(fill no)
			(layer "F.Fab")
		)
		(pad "1" thru_hole circle
			(at 4.99999 0 270)
			(size 1.4732 1.4732)
			(drill 1.0668)
			(layers "*.Cu" "*.Mask")
			(remove_unused_layers no)
			(net "P3V0_BAT")
			(clearance 0.1524)
			(thermal_gap 0.1524)
		)
		(pad "2" thru_hole circle
			(at 0 -3.599942 270)
			(size 1.4732 1.4732)
			(drill 1.0668)
			(layers "*.Cu" "*.Mask")
			(remove_unused_layers no)
			(net "GND")
			(clearance 0.1524)
			(thermal_gap 0.1524)
		)
		(pad "3" thru_hole circle
			(at -4.99999 0 270)
			(size 1.4732 1.4732)
			(drill 1.0668)
			(layers "*.Cu" "*.Mask")
			(remove_unused_layers no)
			(net "P3V0_BAT")
			(clearance 0.1524)
			(thermal_gap 0.1524)
		)
	)
	(footprint ""
		(layer "F.Cu")
		(at 204.793596 -111.906812)
		(property "Reference" "PC225"
			(at 0 0 0)
			(layer "F.SilkS")
			(hide yes)
			(effects
				(font
					(size 1.27 1.27)
				)
			)
		)
		(property "Value" "SCD1U16V2KX-3GP"
			(at 1.1811 -2.7051 0)
			(unlocked yes)
			(layer "F.Fab")
			(hide yes)
			(effects
				(font
					(size 1.016 1.016)
					(thickness 0.1524)
				)
			)
		)
		(property "Device Type" "C402H22"
			(at 1.1811 -4.2291 0)
			(unlocked yes)
			(layer "F.Fab")
			(hide yes)
			(effects
				(font
					(size 1.016 1.016)
					(thickness 0.1524)
				)
			)
		)
		(duplicate_pad_numbers_are_jumpers no)
		(fp_rect
			(start -0.4318 0.9525)
			(end 0.4318 -0.9525)
			(stroke
				(width 0)
				(type default)
			)
			(fill no)
			(layer "F.CrtYd")
		)
		(fp_rect
			(start -0.4318 0.9525)
			(end 0.4318 -0.9525)
			(stroke
				(width 0)
				(type default)
			)
			(fill no)
			(layer "F.Fab")
		)
		(pad "1" smd custom
			(at 0 -0.4445)
			(size 0.1524 0.1524)
			(layers "F.Cu" "F.Mask" "F.Paste")
			(net "P1V5_E_VIN")
			(options
				(clearance outline)
				(anchor circle)
			)
			(primitives
				(gr_poly
					(pts
						(arc
							(start 0.3048 -0.2032)
							(mid 0.275042 -0.275042)
							(end 0.2032 -0.3048)
						)
						(arc
							(start -0.2032 -0.3048)
							(mid -0.275042 -0.275042)
							(end -0.3048 -0.2032)
						)
						(arc
							(start -0.3048 0.2032)
							(mid -0.275042 0.275042)
							(end -0.2032 0.3048)
						)
						(arc
							(start 0.2032 0.3048)
							(mid 0.275042 0.275042)
							(end 0.3048 0.2032)
						)
					)
					(width 0)
					(fill yes)
				)
			)
		)
		(pad "2" smd custom
			(at 0 0.4445)
			(size 0.1524 0.1524)
			(layers "F.Cu" "F.Mask" "F.Paste")
			(net "GND")
			(options
				(clearance outline)
				(anchor circle)
			)
			(primitives
				(gr_poly
					(pts
						(arc
							(start 0.3048 -0.2032)
							(mid 0.275042 -0.275042)
							(end 0.2032 -0.3048)
						)
						(arc
							(start -0.2032 -0.3048)
							(mid -0.275042 -0.275042)
							(end -0.3048 -0.2032)
						)
						(arc
							(start -0.3048 0.2032)
							(mid -0.275042 0.275042)
							(end -0.2032 0.3048)
						)
						(arc
							(start 0.2032 0.3048)
							(mid 0.275042 0.275042)
							(end 0.3048 0.2032)
						)
					)
					(width 0)
					(fill yes)
				)
			)
		)
	)
	(footprint ""
		(layer "F.Cu")
		(at 89.662 -18.796 180)
		(property "Reference" "PC219"
			(at 0 0 180)
			(layer "F.SilkS")
			(hide yes)
			(effects
				(font
					(size 1.27 1.27)
				)
			)
		)
		(property "Value" "SCD1U50V3KX-GP"
			(at 0 -2.8194 180)
			(unlocked yes)
			(layer "F.Fab")
			(hide yes)
			(effects
				(font
					(size 1.016 1.016)
					(thickness 0.1524)
				)
			)
		)
		(property "Device Type" "C603H36"
			(at 0 -4.3434 180)
			(unlocked yes)
			(layer "F.Fab")
			(hide yes)
			(effects
				(font
					(size 1.016 1.016)
					(thickness 0.1524)
				)
			)
		)
		(duplicate_pad_numbers_are_jumpers no)
		(fp_line
			(start 0.508 0)
			(end -0.508 0)
			(stroke
				(width 0.2032)
				(type default)
			)
			(layer "F.SilkS")
		)
		(fp_rect
			(start -0.5842 1.3335)
			(end 0.5842 -1.3335)
			(stroke
				(width 0)
				(type default)
			)
			(fill no)
			(layer "F.CrtYd")
		)
		(fp_rect
			(start -0.5842 1.3335)
			(end 0.5842 -1.3335)
			(stroke
				(width 0)
				(type default)
			)
			(fill no)
			(layer "F.Fab")
		)
		(pad "1" smd custom
			(at 0 -0.762 180)
			(size 0.2159 0.2159)
			(layers "F.Cu" "F.Mask" "F.Paste")
			(net "VT235_VDES_RC")
			(options
				(clearance outline)
				(anchor circle)
			)
			(primitives
				(gr_poly
					(pts
						(arc
							(start -0.3302 -0.4318)
							(mid -0.402042 -0.402042)
							(end -0.4318 -0.3302)
						)
						(arc
							(start -0.4318 0.3302)
							(mid -0.402042 0.402042)
							(end -0.3302 0.4318)
						)
						(arc
							(start 0.3302 0.4318)
							(mid 0.402042 0.402042)
							(end 0.4318 0.3302)
						)
						(arc
							(start 0.4318 -0.3302)
							(mid 0.402042 -0.402042)
							(end 0.3302 -0.4318)
						)
					)
					(width 0)
					(fill yes)
				)
			)
		)
		(pad "2" smd custom
			(at 0 0.762 180)
			(size 0.2159 0.2159)
			(layers "F.Cu" "F.Mask" "F.Paste")
			(net "VT235_VDES_RCC")
			(options
				(clearance outline)
				(anchor circle)
			)
			(primitives
				(gr_poly
					(pts
						(arc
							(start -0.3302 -0.4318)
							(mid -0.402042 -0.402042)
							(end -0.4318 -0.3302)
						)
						(arc
							(start -0.4318 0.3302)
							(mid -0.402042 0.402042)
							(end -0.3302 0.4318)
						)
						(arc
							(start 0.3302 0.4318)
							(mid 0.402042 0.402042)
							(end 0.4318 0.3302)
						)
						(arc
							(start 0.4318 -0.3302)
							(mid 0.402042 -0.402042)
							(end 0.3302 -0.4318)
						)
					)
					(width 0)
					(fill yes)
				)
			)
		)
	)
	(footprint ""
		(layer "F.Cu")
		(at 276.987 -21.59 180)
		(property "Reference" "U22"
			(at 0 0 180)
			(layer "F.SilkS")
			(hide yes)
			(effects
				(font
					(size 1.27 1.27)
				)
			)
		)
		(property "Value" "AZC099-04S-1-GP"
			(at -0.0254 -11.9634 180)
			(unlocked yes)
			(layer "F.Fab")
			(hide yes)
			(effects
				(font
					(size 1.016 1.016)
					(thickness 0.1524)
				)
			)
		)
		(property "Device Type" "SOT-6H58"
			(at -0.0254 -13.5636 180)
			(unlocked yes)
			(layer "F.Fab")
			(hide yes)
			(effects
				(font
					(size 1.016 1.016)
					(thickness 0.1524)
				)
			)
		)
		(duplicate_pad_numbers_are_jumpers no)
		(fp_line
			(start 1.7145 0.5842)
			(end 1.7145 -0.5842)
			(stroke
				(width 0.1524)
				(type default)
			)
			(layer "F.SilkS")
		)
		(fp_line
			(start 1.7145 -0.5842)
			(end -1.9685 -0.5842)
			(stroke
				(width 0.1524)
				(type default)
			)
			(layer "F.SilkS")
		)
		(fp_line
			(start -1.5621 0)
			(end -1.9685 0.4064)
			(stroke
				(width 0.1524)
				(type default)
			)
			(layer "F.SilkS")
		)
		(fp_line
			(start -1.9685 0.5842)
			(end 1.7145 0.5842)
			(stroke
				(width 0.1524)
				(type default)
			)
			(layer "F.SilkS")
		)
		(fp_line
			(start -1.9685 0.5842)
			(end -1.9685 2.3622)
			(stroke
				(width 0.508)
				(type default)
			)
			(layer "F.SilkS")
		)
		(fp_line
			(start -1.9685 -0.4064)
			(end -1.5621 0)
			(stroke
				(width 0.1524)
				(type default)
			)
			(layer "F.SilkS")
		)
		(fp_line
			(start -1.9685 -0.5842)
			(end -1.9685 0.5842)
			(stroke
				(width 0.1524)
				(type default)
			)
			(layer "F.SilkS")
		)
		(fp_poly
			(pts
				(xy -1.27 -0.635) (xy 1.27 -0.635) (xy 1.27 0.635) (xy -1.27 0.635)
			)
			(stroke
				(width 0)
				(type default)
			)
			(fill yes)
			(layer "F.SilkS")
		)
		(fp_rect
			(start -1.9685 2.3622)
			(end 1.9685 -2.3622)
			(stroke
				(width 0)
				(type default)
			)
			(fill no)
			(layer "F.CrtYd")
		)
		(fp_poly
			(pts
				(xy -1.9685 -2.3622) (xy 1.9685 -2.3622) (xy 1.9685 2.3622) (xy -1.9685 2.3622)
			)
			(stroke
				(width 0)
				(type default)
			)
			(fill no)
			(layer "F.Fab")
		)
		(pad "1" smd rect
			(at -0.9525 1.3462 180)
			(size 0.5842 1.016)
			(layers "F.Cu" "F.Mask" "F.Paste")
			(net "USB_P1_F_DP1")
		)
		(pad "2" smd rect
			(at 0 1.3462 180)
			(size 0.5842 1.016)
			(layers "F.Cu" "F.Mask" "F.Paste")
			(net "GND")
		)
		(pad "3" smd rect
			(at 0.9525 1.3462 180)
			(size 0.5842 1.016)
			(layers "F.Cu" "F.Mask" "F.Paste")
			(net "Net_404")
		)
		(pad "4" smd rect
			(at 0.9525 -1.3462 180)
			(size 0.5842 1.016)
			(layers "F.Cu" "F.Mask" "F.Paste")
			(net "Net_405")
		)
		(pad "5" smd rect
			(at 0 -1.3462 180)
			(size 0.5842 1.016)
			(layers "F.Cu" "F.Mask" "F.Paste")
			(net "P5V_USB")
		)
		(pad "6" smd rect
			(at -0.9525 -1.3462 180)
			(size 0.5842 1.016)
			(layers "F.Cu" "F.Mask" "F.Paste")
			(net "USB_P1_F_DN1")
		)
	)
	(footprint ""
		(layer "F.Cu")
		(at 192.151 -225.806 -90)
		(property "Reference" "U175"
			(at 0 0 270)
			(layer "F.SilkS")
			(hide yes)
			(effects
				(font
					(size 1.27 1.27)
				)
			)
		)
		(property "Value" "TSLVC14APW-2-GP"
			(at 0.1016 -7.62 270)
			(unlocked yes)
			(layer "F.Fab")
			(hide yes)
			(effects
				(font
					(size 1.016 1.016)
					(thickness 0.1524)
				)
			)
		)
		(property "Device Type" "TSOIC14H44"
			(at 0.1016 -10.16 270)
			(unlocked yes)
			(layer "F.Fab")
			(hide yes)
			(effects
				(font
					(size 1.016 1.016)
					(thickness 0.1524)
				)
			)
		)
		(duplicate_pad_numbers_are_jumpers no)
		(fp_line
			(start -3.048 4.191)
			(end -3.048 1.397)
			(stroke
				(width 0.508)
				(type default)
			)
			(layer "F.SilkS")
		)
		(fp_line
			(start 2.159 1.778)
			(end 2.159 1.7526)
			(stroke
				(width 0.2032)
				(type default)
			)
			(layer "F.SilkS")
		)
		(fp_line
			(start 2.159 1.7526)
			(end -3.0734 1.7526)
			(stroke
				(width 0.2032)
				(type default)
			)
			(layer "F.SilkS")
		)
		(fp_line
			(start -2.032 0)
			(end -3.048 1.016)
			(stroke
				(width 0.2032)
				(type default)
			)
			(layer "F.SilkS")
		)
		(fp_line
			(start -2.032 0)
			(end -3.048 -1.016)
			(stroke
				(width 0.2032)
				(type default)
			)
			(layer "F.SilkS")
		)
		(fp_line
			(start -3.048 -1.778)
			(end -3.048 4.191)
			(stroke
				(width 0.2032)
				(type default)
			)
			(layer "F.SilkS")
		)
		(fp_line
			(start -3.048 -1.778)
			(end 2.159 -1.778)
			(stroke
				(width 0.2032)
				(type default)
			)
			(layer "F.SilkS")
		)
		(fp_line
			(start 2.159 -1.778)
			(end 2.159 1.778)
			(stroke
				(width 0.2032)
				(type default)
			)
			(layer "F.SilkS")
		)
		(fp_poly
			(pts
				(xy -2.2606 -1.8542) (xy 2.2606 -1.8542) (xy 2.2606 1.8542) (xy -2.2606 1.8542)
			)
			(stroke
				(width 0)
				(type default)
			)
			(fill yes)
			(layer "F.SilkS")
		)
		(fp_poly
			(pts
				(xy -3.048 -4.0894) (xy 3.048 -4.0894) (xy 3.048 4.0894) (xy -3.048 4.0894)
			)
			(stroke
				(width 0)
				(type default)
			)
			(fill no)
			(layer "F.CrtYd")
		)
		(fp_poly
			(pts
				(xy -3.048 -4.0894) (xy 3.048 -4.0894) (xy 3.048 4.0894) (xy -3.048 4.0894)
			)
			(stroke
				(width 0)
				(type default)
			)
			(fill no)
			(layer "F.Fab")
		)
		(pad "1" smd rect
			(at -1.94945 2.8194 270)
			(size 0.3556 1.524)
			(layers "F.Cu" "F.Mask" "F.Paste")
			(net "FP_PWRBTN_RC_N")
		)
		(pad "2" smd rect
			(at -1.30048 2.8194 270)
			(size 0.3556 1.524)
			(layers "F.Cu" "F.Mask" "F.Paste")
			(net "FP_PWRBTN")
		)
		(pad "3" smd rect
			(at -0.65024 2.8194 270)
			(size 0.3556 1.524)
			(layers "F.Cu" "F.Mask" "F.Paste")
			(net "FP_PWRBTN_R")
		)
		(pad "4" smd rect
			(at 0 2.8194 270)
			(size 0.3556 1.524)
			(layers "F.Cu" "F.Mask" "F.Paste")
			(net "PWRBTN_FP_N")
		)
		(pad "5" smd rect
			(at 0.65024 2.8194 270)
			(size 0.3556 1.524)
			(layers "F.Cu" "F.Mask" "F.Paste")
			(net "FP_RESET_RC_N")
		)
		(pad "6" smd rect
			(at 1.30048 2.8194 270)
			(size 0.3556 1.524)
			(layers "F.Cu" "F.Mask" "F.Paste")
			(net "FP_RETBTN")
		)
		(pad "7" smd rect
			(at 1.94945 2.8194 270)
			(size 0.3556 1.524)
			(layers "F.Cu" "F.Mask" "F.Paste")
			(net "GND")
		)
		(pad "8" smd rect
			(at 1.94945 -2.8194 270)
			(size 0.3556 1.524)
			(layers "F.Cu" "F.Mask" "F.Paste")
			(net "RSTBTN_FP_N")
		)
		(pad "9" smd rect
			(at 1.30048 -2.8194 270)
			(size 0.3556 1.524)
			(layers "F.Cu" "F.Mask" "F.Paste")
			(net "FP_RETBTN_R")
		)
		(pad "10" smd rect
			(at 0.65024 -2.8194 270)
			(size 0.3556 1.524)
			(layers "F.Cu" "F.Mask" "F.Paste")
			(net "Net_401")
		)
		(pad "11" smd rect
			(at 0 -2.8194 270)
			(size 0.3556 1.524)
			(layers "F.Cu" "F.Mask" "F.Paste")
			(net "Net_400")
		)
		(pad "12" smd rect
			(at -0.65024 -2.8194 270)
			(size 0.3556 1.524)
			(layers "F.Cu" "F.Mask" "F.Paste")
			(net "Net_399")
		)
		(pad "13" smd rect
			(at -1.30048 -2.8194 270)
			(size 0.3556 1.524)
			(layers "F.Cu" "F.Mask" "F.Paste")
			(net "Net_398")
		)
		(pad "14" smd rect
			(at -1.94945 -2.8194 270)
			(size 0.3556 1.524)
			(layers "F.Cu" "F.Mask" "F.Paste")
			(net "P3V3_STBY")
		)
	)
	(footprint ""
		(layer "F.Cu")
		(at 101.092 -221.488)
		(property "Reference" "R641"
			(at 0 0 0)
			(layer "F.SilkS")
			(hide yes)
			(effects
				(font
					(size 1.27 1.27)
				)
			)
		)
		(property "Value" "4K7R2F-GP"
			(at 0.064008 -3.993896 0)
			(unlocked yes)
			(layer "F.Fab")
			(hide yes)
			(effects
				(font
					(size 1.016 1.016)
					(thickness 0.1524)
				)
			)
		)
		(property "Device Type" "R402H16"
			(at 0.064008 -5.517896 0)
			(unlocked yes)
			(layer "F.Fab")
			(hide yes)
			(effects
				(font
					(size 1.016 1.016)
					(thickness 0.1524)
				)
			)
		)
		(duplicate_pad_numbers_are_jumpers no)
		(fp_line
			(start -0.508 -0.9398)
			(end -0.508 0.9398)
			(stroke
				(width 0.1524)
				(type default)
			)
			(layer "F.SilkS")
		)
		(fp_line
			(start 0.508 -0.9398)
			(end -0.508 -0.9398)
			(stroke
				(width 0.1524)
				(type default)
			)
			(layer "F.SilkS")
		)
		(fp_rect
			(start -0.508 0.9398)
			(end 0.508 -0.9398)
			(stroke
				(width 0)
				(type default)
			)
			(fill no)
			(layer "F.CrtYd")
		)
		(fp_rect
			(start -0.508 0.9398)
			(end 0.508 -0.9398)
			(stroke
				(width 0)
				(type default)
			)
			(fill no)
			(layer "F.Fab")
		)
		(pad "1" smd custom
			(at 0 -0.4445)
			(size 0.1397 0.1397)
			(layers "F.Cu" "F.Mask" "F.Paste")
			(net "IO_EXP_HDD_FAULT_A1")
			(options
				(clearance outline)
				(anchor circle)
			)
			(primitives
				(gr_poly
					(pts
						(arc
							(start -0.1778 -0.2794)
							(mid -0.249642 -0.249642)
							(end -0.2794 -0.1778)
						)
						(arc
							(start -0.2794 0.1778)
							(mid -0.249642 0.249642)
							(end -0.1778 0.2794)
						)
						(arc
							(start 0.1778 0.2794)
							(mid 0.249642 0.249642)
							(end 0.2794 0.1778)
						)
						(arc
							(start 0.2794 -0.1778)
							(mid 0.249642 -0.249642)
							(end 0.1778 -0.2794)
						)
					)
					(width 0)
					(fill yes)
				)
			)
		)
		(pad "2" smd custom
			(at 0 0.4445)
			(size 0.1397 0.1397)
			(layers "F.Cu" "F.Mask" "F.Paste")
			(net "GND")
			(options
				(clearance outline)
				(anchor circle)
			)
			(primitives
				(gr_poly
					(pts
						(arc
							(start -0.1778 -0.2794)
							(mid -0.249642 -0.249642)
							(end -0.2794 -0.1778)
						)
						(arc
							(start -0.2794 0.1778)
							(mid -0.249642 0.249642)
							(end -0.1778 0.2794)
						)
						(arc
							(start 0.1778 0.2794)
							(mid 0.249642 0.249642)
							(end 0.2794 0.1778)
						)
						(arc
							(start 0.2794 -0.1778)
							(mid 0.249642 -0.249642)
							(end 0.1778 -0.2794)
						)
					)
					(width 0)
					(fill yes)
				)
			)
		)
	)
	(footprint ""
		(layer "F.Cu")
		(at 79.888842 -128.951482 -90)
		(property "Reference" "SR786"
			(at 0 0 270)
			(layer "F.SilkS")
			(hide yes)
			(effects
				(font
					(size 1.27 1.27)
				)
			)
		)
		(property "Value" "4K75R2F-1-GP"
			(at 0.064008 -3.993896 270)
			(unlocked yes)
			(layer "F.Fab")
			(hide yes)
			(effects
				(font
					(size 1.016 1.016)
					(thickness 0.1524)
				)
			)
		)
		(property "Device Type" "R402H16"
			(at 0.064008 -5.517896 270)
			(unlocked yes)
			(layer "F.Fab")
			(hide yes)
			(effects
				(font
					(size 1.016 1.016)
					(thickness 0.1524)
				)
			)
		)
		(duplicate_pad_numbers_are_jumpers no)
		(fp_line
			(start -0.508 -0.9398)
			(end -0.508 0.9398)
			(stroke
				(width 0.1524)
				(type default)
			)
			(layer "F.SilkS")
		)
		(fp_line
			(start 0.508 -0.9398)
			(end -0.508 -0.9398)
			(stroke
				(width 0.1524)
				(type default)
			)
			(layer "F.SilkS")
		)
		(fp_rect
			(start -0.508 0.9398)
			(end 0.508 -0.9398)
			(stroke
				(width 0)
				(type default)
			)
			(fill no)
			(layer "F.CrtYd")
		)
		(fp_rect
			(start -0.508 0.9398)
			(end 0.508 -0.9398)
			(stroke
				(width 0)
				(type default)
			)
			(fill no)
			(layer "F.Fab")
		)
		(pad "1" smd custom
			(at 0 -0.4445 270)
			(size 0.1397 0.1397)
			(layers "F.Cu" "F.Mask" "F.Paste")
			(net "P1V8_E")
			(options
				(clearance outline)
				(anchor circle)
			)
			(primitives
				(gr_poly
					(pts
						(arc
							(start -0.1778 -0.2794)
							(mid -0.249642 -0.249642)
							(end -0.2794 -0.1778)
						)
						(arc
							(start -0.2794 0.1778)
							(mid -0.249642 0.249642)
							(end -0.1778 0.2794)
						)
						(arc
							(start 0.1778 0.2794)
							(mid 0.249642 0.249642)
							(end 0.2794 0.1778)
						)
						(arc
							(start 0.2794 -0.1778)
							(mid 0.249642 -0.249642)
							(end 0.1778 -0.2794)
						)
					)
					(width 0)
					(fill yes)
				)
			)
		)
		(pad "2" smd custom
			(at 0 0.4445 270)
			(size 0.1397 0.1397)
			(layers "F.Cu" "F.Mask" "F.Paste")
			(net "EXP_XM_NOR_CS_N")
			(options
				(clearance outline)
				(anchor circle)
			)
			(primitives
				(gr_poly
					(pts
						(arc
							(start -0.1778 -0.2794)
							(mid -0.249642 -0.249642)
							(end -0.2794 -0.1778)
						)
						(arc
							(start -0.2794 0.1778)
							(mid -0.249642 0.249642)
							(end -0.1778 0.2794)
						)
						(arc
							(start 0.1778 0.2794)
							(mid 0.249642 0.249642)
							(end 0.2794 0.1778)
						)
						(arc
							(start 0.2794 -0.1778)
							(mid 0.249642 -0.249642)
							(end 0.1778 -0.2794)
						)
					)
					(width 0)
					(fill yes)
				)
			)
		)
	)
	(footprint ""
		(layer "F.Cu")
		(at 318.008 -178.689 -90)
		(property "Reference" "R320"
			(at 0 0 270)
			(layer "F.SilkS")
			(hide yes)
			(effects
				(font
					(size 1.27 1.27)
				)
			)
		)
		(property "Value" "0R2J-2-GP"
			(at 0.064008 -3.993896 270)
			(unlocked yes)
			(layer "F.Fab")
			(hide yes)
			(effects
				(font
					(size 1.016 1.016)
					(thickness 0.1524)
				)
			)
		)
		(property "Device Type" "R402H16"
			(at 0.064008 -5.517896 270)
			(unlocked yes)
			(layer "F.Fab")
			(hide yes)
			(effects
				(font
					(size 1.016 1.016)
					(thickness 0.1524)
				)
			)
		)
		(duplicate_pad_numbers_are_jumpers no)
		(fp_line
			(start -0.508 -0.9398)
			(end -0.508 0.9398)
			(stroke
				(width 0.1524)
				(type default)
			)
			(layer "F.SilkS")
		)
		(fp_line
			(start 0.508 -0.9398)
			(end -0.508 -0.9398)
			(stroke
				(width 0.1524)
				(type default)
			)
			(layer "F.SilkS")
		)
		(fp_rect
			(start -0.508 0.9398)
			(end 0.508 -0.9398)
			(stroke
				(width 0)
				(type default)
			)
			(fill no)
			(layer "F.CrtYd")
		)
		(fp_rect
			(start -0.508 0.9398)
			(end 0.508 -0.9398)
			(stroke
				(width 0)
				(type default)
			)
			(fill no)
			(layer "F.Fab")
		)
		(pad "1" smd custom
			(at 0 -0.4445 270)
			(size 0.1397 0.1397)
			(layers "F.Cu" "F.Mask" "F.Paste")
			(net "ADC_P1V5_C")
			(options
				(clearance outline)
				(anchor circle)
			)
			(primitives
				(gr_poly
					(pts
						(arc
							(start -0.1778 -0.2794)
							(mid -0.249642 -0.249642)
							(end -0.2794 -0.1778)
						)
						(arc
							(start -0.2794 0.1778)
							(mid -0.249642 0.249642)
							(end -0.1778 0.2794)
						)
						(arc
							(start 0.1778 0.2794)
							(mid 0.249642 0.249642)
							(end 0.2794 0.1778)
						)
						(arc
							(start 0.2794 -0.1778)
							(mid 0.249642 -0.249642)
							(end 0.1778 -0.2794)
						)
					)
					(width 0)
					(fill yes)
				)
			)
		)
		(pad "2" smd custom
			(at 0 0.4445 270)
			(size 0.1397 0.1397)
			(layers "F.Cu" "F.Mask" "F.Paste")
			(net "ADC_P1V5_C_BMC")
			(options
				(clearance outline)
				(anchor circle)
			)
			(primitives
				(gr_poly
					(pts
						(arc
							(start -0.1778 -0.2794)
							(mid -0.249642 -0.249642)
							(end -0.2794 -0.1778)
						)
						(arc
							(start -0.2794 0.1778)
							(mid -0.249642 0.249642)
							(end -0.1778 0.2794)
						)
						(arc
							(start 0.1778 0.2794)
							(mid 0.249642 0.249642)
							(end 0.2794 0.1778)
						)
						(arc
							(start 0.2794 -0.1778)
							(mid 0.249642 -0.249642)
							(end 0.1778 -0.2794)
						)
					)
					(width 0)
					(fill yes)
				)
			)
		)
	)
	(footprint ""
		(layer "F.Cu")
		(at 264.033 -32.639 -90)
		(property "Reference" "PR56"
			(at 0 0 270)
			(layer "F.SilkS")
			(hide yes)
			(effects
				(font
					(size 1.27 1.27)
				)
			)
		)
		(property "Value" "0R2J-2-GP"
			(at 0.064008 -3.993896 270)
			(unlocked yes)
			(layer "F.Fab")
			(hide yes)
			(effects
				(font
					(size 1.016 1.016)
					(thickness 0.1524)
				)
			)
		)
		(property "Device Type" "R402H16"
			(at 0.064008 -5.517896 270)
			(unlocked yes)
			(layer "F.Fab")
			(hide yes)
			(effects
				(font
					(size 1.016 1.016)
					(thickness 0.1524)
				)
			)
		)
		(duplicate_pad_numbers_are_jumpers no)
		(fp_line
			(start -0.508 -0.9398)
			(end -0.508 0.9398)
			(stroke
				(width 0.1524)
				(type default)
			)
			(layer "F.SilkS")
		)
		(fp_line
			(start 0.508 -0.9398)
			(end -0.508 -0.9398)
			(stroke
				(width 0.1524)
				(type default)
			)
			(layer "F.SilkS")
		)
		(fp_rect
			(start -0.508 0.9398)
			(end 0.508 -0.9398)
			(stroke
				(width 0)
				(type default)
			)
			(fill no)
			(layer "F.CrtYd")
		)
		(fp_rect
			(start -0.508 0.9398)
			(end 0.508 -0.9398)
			(stroke
				(width 0)
				(type default)
			)
			(fill no)
			(layer "F.Fab")
		)
		(pad "1" smd custom
			(at 0 -0.4445 270)
			(size 0.1397 0.1397)
			(layers "F.Cu" "F.Mask" "F.Paste")
			(net "P1V8_STBY_ROVP")
			(options
				(clearance outline)
				(anchor circle)
			)
			(primitives
				(gr_poly
					(pts
						(arc
							(start -0.1778 -0.2794)
							(mid -0.249642 -0.249642)
							(end -0.2794 -0.1778)
						)
						(arc
							(start -0.2794 0.1778)
							(mid -0.249642 0.249642)
							(end -0.1778 0.2794)
						)
						(arc
							(start 0.1778 0.2794)
							(mid 0.249642 0.249642)
							(end 0.2794 0.1778)
						)
						(arc
							(start 0.2794 -0.1778)
							(mid 0.249642 -0.249642)
							(end 0.1778 -0.2794)
						)
					)
					(width 0)
					(fill yes)
				)
			)
		)
		(pad "2" smd custom
			(at 0 0.4445 270)
			(size 0.1397 0.1397)
			(layers "F.Cu" "F.Mask" "F.Paste")
			(net "AGND_P1V8_STBY")
			(options
				(clearance outline)
				(anchor circle)
			)
			(primitives
				(gr_poly
					(pts
						(arc
							(start -0.1778 -0.2794)
							(mid -0.249642 -0.249642)
							(end -0.2794 -0.1778)
						)
						(arc
							(start -0.2794 0.1778)
							(mid -0.249642 0.249642)
							(end -0.1778 0.2794)
						)
						(arc
							(start 0.1778 0.2794)
							(mid 0.249642 0.249642)
							(end 0.2794 0.1778)
						)
						(arc
							(start 0.2794 -0.1778)
							(mid 0.249642 -0.249642)
							(end 0.1778 -0.2794)
						)
					)
					(width 0)
					(fill yes)
				)
			)
		)
	)
	(footprint ""
		(layer "F.Cu")
		(at 95.70847 -110.617 -90)
		(property "Reference" "SR739"
			(at 0 0 270)
			(layer "F.SilkS")
			(hide yes)
			(effects
				(font
					(size 1.27 1.27)
				)
			)
		)
		(property "Value" "2K2R2F-GP"
			(at 0.064008 -3.993896 270)
			(unlocked yes)
			(layer "F.Fab")
			(hide yes)
			(effects
				(font
					(size 1.016 1.016)
					(thickness 0.1524)
				)
			)
		)
		(property "Device Type" "R402H16"
			(at 0.064008 -5.517896 270)
			(unlocked yes)
			(layer "F.Fab")
			(hide yes)
			(effects
				(font
					(size 1.016 1.016)
					(thickness 0.1524)
				)
			)
		)
		(duplicate_pad_numbers_are_jumpers no)
		(fp_line
			(start -0.508 -0.9398)
			(end -0.508 0.9398)
			(stroke
				(width 0.1524)
				(type default)
			)
			(layer "F.SilkS")
		)
		(fp_line
			(start 0.508 -0.9398)
			(end -0.508 -0.9398)
			(stroke
				(width 0.1524)
				(type default)
			)
			(layer "F.SilkS")
		)
		(fp_rect
			(start -0.508 0.9398)
			(end 0.508 -0.9398)
			(stroke
				(width 0)
				(type default)
			)
			(fill no)
			(layer "F.CrtYd")
		)
		(fp_rect
			(start -0.508 0.9398)
			(end 0.508 -0.9398)
			(stroke
				(width 0)
				(type default)
			)
			(fill no)
			(layer "F.Fab")
		)
		(pad "1" smd custom
			(at 0 -0.4445 270)
			(size 0.1397 0.1397)
			(layers "F.Cu" "F.Mask" "F.Paste")
			(net "EXP_I2C_SDA_2")
			(options
				(clearance outline)
				(anchor circle)
			)
			(primitives
				(gr_poly
					(pts
						(arc
							(start -0.1778 -0.2794)
							(mid -0.249642 -0.249642)
							(end -0.2794 -0.1778)
						)
						(arc
							(start -0.2794 0.1778)
							(mid -0.249642 0.249642)
							(end -0.1778 0.2794)
						)
						(arc
							(start 0.1778 0.2794)
							(mid 0.249642 0.249642)
							(end 0.2794 0.1778)
						)
						(arc
							(start 0.2794 -0.1778)
							(mid 0.249642 -0.249642)
							(end 0.1778 -0.2794)
						)
					)
					(width 0)
					(fill yes)
				)
			)
		)
		(pad "2" smd custom
			(at 0 0.4445 270)
			(size 0.1397 0.1397)
			(layers "F.Cu" "F.Mask" "F.Paste")
			(net "P1V8_E")
			(options
				(clearance outline)
				(anchor circle)
			)
			(primitives
				(gr_poly
					(pts
						(arc
							(start -0.1778 -0.2794)
							(mid -0.249642 -0.249642)
							(end -0.2794 -0.1778)
						)
						(arc
							(start -0.2794 0.1778)
							(mid -0.249642 0.249642)
							(end -0.1778 0.2794)
						)
						(arc
							(start 0.1778 0.2794)
							(mid 0.249642 0.249642)
							(end 0.2794 0.1778)
						)
						(arc
							(start 0.2794 -0.1778)
							(mid 0.249642 -0.249642)
							(end 0.1778 -0.2794)
						)
					)
					(width 0)
					(fill yes)
				)
			)
		)
	)
	(footprint ""
		(layer "F.Cu")
		(at 144.907 -96.647 90)
		(property "Reference" "SC1176"
			(at 0 0 90)
			(layer "F.SilkS")
			(hide yes)
			(effects
				(font
					(size 1.27 1.27)
				)
			)
		)
		(property "Value" "SC100U6D3V0MX-2GP"
			(at -0.00254 -4.78536 90)
			(unlocked yes)
			(layer "F.Fab")
			(hide yes)
			(effects
				(font
					(size 1.016 1.016)
					(thickness 0.1524)
				)
			)
		)
		(property "Device Type" "C1210H107"
			(at -0.00254 -6.38048 90)
			(unlocked yes)
			(layer "F.Fab")
			(hide yes)
			(effects
				(font
					(size 1.016 1.016)
					(thickness 0.1524)
				)
			)
		)
		(duplicate_pad_numbers_are_jumpers no)
		(fp_line
			(start 1.5748 -2.3368)
			(end -1.5748 -2.3368)
			(stroke
				(width 0.1524)
				(type default)
			)
			(layer "F.SilkS")
		)
		(fp_line
			(start -1.5748 -2.3368)
			(end -1.5748 -0.762)
			(stroke
				(width 0.1524)
				(type default)
			)
			(layer "F.SilkS")
		)
		(fp_line
			(start 1.5748 -0.762)
			(end 1.5748 -2.3368)
			(stroke
				(width 0.1524)
				(type default)
			)
			(layer "F.SilkS")
		)
		(fp_line
			(start -1.5748 0.762)
			(end -1.5748 2.3368)
			(stroke
				(width 0.1524)
				(type default)
			)
			(layer "F.SilkS")
		)
		(fp_line
			(start 1.5748 2.3368)
			(end 1.5748 0.762)
			(stroke
				(width 0.1524)
				(type default)
			)
			(layer "F.SilkS")
		)
		(fp_line
			(start -1.5748 2.3368)
			(end 1.5748 2.3368)
			(stroke
				(width 0.1524)
				(type default)
			)
			(layer "F.SilkS")
		)
		(fp_rect
			(start -1.651 2.413)
			(end 1.651 -2.413)
			(stroke
				(width 0)
				(type default)
			)
			(fill no)
			(layer "F.CrtYd")
		)
		(fp_poly
			(pts
				(xy 1.651 2.413) (xy 1.651 -2.413) (xy -1.651 -2.413) (xy -1.651 2.413)
			)
			(stroke
				(width 0)
				(type default)
			)
			(fill no)
			(layer "F.Fab")
		)
		(pad "1" smd rect
			(at 0 -1.4732 90)
			(size 2.794 1.397)
			(layers "F.Cu" "F.Mask" "F.Paste")
			(net "GND")
		)
		(pad "2" smd rect
			(at 0 1.4732 90)
			(size 2.794 1.397)
			(layers "F.Cu" "F.Mask" "F.Paste")
			(net "GB_VDDA")
		)
	)
	(footprint ""
		(layer "F.Cu")
		(at 170.932348 -115.941856 180)
		(property "Reference" "PU12"
			(at 0 0 180)
			(layer "F.SilkS")
			(hide yes)
			(effects
				(font
					(size 1.27 1.27)
				)
			)
		)
		(property "Value" "TPS53355DQPR-GP"
			(at 4.7498 -5.6896 180)
			(unlocked yes)
			(layer "F.Fab")
			(hide yes)
			(effects
				(font
					(size 1.016 1.016)
					(thickness 0.1524)
				)
			)
		)
		(property "Device Type" "QFN22G6050-G6133H60"
			(at 4.7498 -7.2136 180)
			(unlocked yes)
			(layer "F.Fab")
			(hide yes)
			(effects
				(font
					(size 1.016 1.016)
					(thickness 0.1524)
				)
			)
		)
		(duplicate_pad_numbers_are_jumpers no)
		(fp_line
			(start 3.556 3.5179)
			(end 3.556 2.2479)
			(stroke
				(width 0.1524)
				(type default)
			)
			(layer "F.SilkS")
		)
		(fp_line
			(start 2.286 3.5179)
			(end 3.556 3.5179)
			(stroke
				(width 0.1524)
				(type default)
			)
			(layer "F.SilkS")
		)
		(fp_line
			(start 1.500124 3.262122)
			(end 1.500124 4.024122)
			(stroke
				(width 0.1524)
				(type default)
			)
			(layer "F.SilkS")
		)
		(fp_line
			(start 0.500126 -3.262122)
			(end 0.500126 -3.770122)
			(stroke
				(width 0.1524)
				(type default)
			)
			(layer "F.SilkS")
		)
		(fp_line
			(start -0.999998 3.262122)
			(end -0.999998 3.770122)
			(stroke
				(width 0.1524)
				(type default)
			)
			(layer "F.SilkS")
		)
		(fp_line
			(start -1.999996 -3.262122)
			(end -1.999996 -4.024122)
			(stroke
				(width 0.1524)
				(type default)
			)
			(layer "F.SilkS")
		)
		(fp_line
			(start -2.286 -3.5179)
			(end -3.556 -3.5179)
			(stroke
				(width 0.1524)
				(type default)
			)
			(layer "F.SilkS")
		)
		(fp_line
			(start -3.556 3.5179)
			(end -2.286 3.5179)
			(stroke
				(width 0.1524)
				(type default)
			)
			(layer "F.SilkS")
		)
		(fp_line
			(start -3.556 2.2479)
			(end -3.556 3.5179)
			(stroke
				(width 0.1524)
				(type default)
			)
			(layer "F.SilkS")
		)
		(fp_line
			(start -3.556 -3.5179)
			(end -3.556 -2.2479)
			(stroke
				(width 0.1524)
				(type default)
			)
			(layer "F.SilkS")
		)
		(fp_poly
			(pts
				(xy 3.556 -3.5179) (xy 2.5273 -3.5179) (xy 3.556 -2.4892)
			)
			(stroke
				(width 0)
				(type default)
			)
			(fill yes)
			(layer "F.SilkS")
		)
		(fp_rect
			(start -2.9972 2.5019)
			(end 2.9972 -2.5019)
			(stroke
				(width 0)
				(type default)
			)
			(fill no)
			(layer "F.CrtYd")
		)
		(fp_poly
			(pts
				(xy 3.556 -2.5019) (xy -2.9972 -2.5019) (xy -2.9972 2.5019) (xy 2.9972 2.5019) (xy 2.9972 -2.4892)
				(xy 3.556 -2.4892) (xy 3.556 3.5179) (xy -3.556 3.5179) (xy -3.556 -3.5179) (xy 3.556 -3.5179)
			)
			(stroke
				(width 0)
				(type default)
			)
			(fill no)
			(layer "F.CrtYd")
		)
		(fp_rect
			(start -3.556 3.5179)
			(end 3.556 -3.5179)
			(stroke
				(width 0)
				(type default)
			)
			(fill no)
			(layer "F.Fab")
		)
		(pad "1" smd rect
			(at 2.500122 -2.449322 180)
			(size 0.3048 1.1176)
			(layers "F.Cu" "F.Mask" "F.Paste")
			(net "P0V9_E_VFB")
		)
		(pad "2" smd rect
			(at 1.999996 -2.449322 180)
			(size 0.3048 1.1176)
			(layers "F.Cu" "F.Mask" "F.Paste")
			(net "P0V9_E_EN")
		)
		(pad "3" smd rect
			(at 1.500124 -2.449322 180)
			(size 0.3048 1.1176)
			(layers "F.Cu" "F.Mask" "F.Paste")
			(net "P0V9_E_PG")
		)
		(pad "4" smd rect
			(at 0.999998 -2.449322 180)
			(size 0.3048 1.1176)
			(layers "F.Cu" "F.Mask" "F.Paste")
			(net "P0V9_E_VBST")
		)
		(pad "5" smd rect
			(at 0.500126 -2.449322 180)
			(size 0.3048 1.1176)
			(layers "F.Cu" "F.Mask" "F.Paste")
			(net "Net_1134")
		)
		(pad "6" smd rect
			(at 0 -2.449322 180)
			(size 0.3048 1.1176)
			(layers "F.Cu" "F.Mask" "F.Paste")
			(net "P0V9_E_LX")
		)
		(pad "7" smd rect
			(at -0.500126 -2.449322 180)
			(size 0.3048 1.1176)
			(layers "F.Cu" "F.Mask" "F.Paste")
			(net "P0V9_E_LX")
		)
		(pad "8" smd rect
			(at -0.999998 -2.449322 180)
			(size 0.3048 1.1176)
			(layers "F.Cu" "F.Mask" "F.Paste")
			(net "P0V9_E_LX")
		)
		(pad "9" smd rect
			(at -1.500124 -2.449322 180)
			(size 0.3048 1.1176)
			(layers "F.Cu" "F.Mask" "F.Paste")
			(net "P0V9_E_LX")
		)
		(pad "10" smd rect
			(at -1.999996 -2.449322 180)
			(size 0.3048 1.1176)
			(layers "F.Cu" "F.Mask" "F.Paste")
			(net "P0V9_E_LX")
		)
		(pad "11" smd rect
			(at -2.500122 -2.449322 180)
			(size 0.3048 1.1176)
			(layers "F.Cu" "F.Mask" "F.Paste")
			(net "P0V9_E_LX")
		)
		(pad "12" smd rect
			(at -2.500122 2.449322 180)
			(size 0.3048 1.1176)
			(layers "F.Cu" "F.Mask" "F.Paste")
			(net "P0V9_E_VIN")
		)
		(pad "13" smd rect
			(at -1.999996 2.449322 180)
			(size 0.3048 1.1176)
			(layers "F.Cu" "F.Mask" "F.Paste")
			(net "P0V9_E_VIN")
		)
		(pad "14" smd rect
			(at -1.500124 2.449322 180)
			(size 0.3048 1.1176)
			(layers "F.Cu" "F.Mask" "F.Paste")
			(net "P0V9_E_VIN")
		)
		(pad "15" smd rect
			(at -0.999998 2.449322 180)
			(size 0.3048 1.1176)
			(layers "F.Cu" "F.Mask" "F.Paste")
			(net "P0V9_E_VIN")
		)
		(pad "16" smd rect
			(at -0.500126 2.449322 180)
			(size 0.3048 1.1176)
			(layers "F.Cu" "F.Mask" "F.Paste")
			(net "P0V9_E_VIN")
		)
		(pad "17" smd rect
			(at 0 2.449322 180)
			(size 0.3048 1.1176)
			(layers "F.Cu" "F.Mask" "F.Paste")
			(net "P0V9_E_VIN")
		)
		(pad "18" smd rect
			(at 0.500126 2.449322 180)
			(size 0.3048 1.1176)
			(layers "F.Cu" "F.Mask" "F.Paste")
			(net "P0V9_E_VREG")
		)
		(pad "19" smd rect
			(at 0.999998 2.449322 180)
			(size 0.3048 1.1176)
			(layers "F.Cu" "F.Mask" "F.Paste")
			(net "P0V9_E_VDD")
		)
		(pad "20" smd rect
			(at 1.500124 2.449322 180)
			(size 0.3048 1.1176)
			(layers "F.Cu" "F.Mask" "F.Paste")
			(net "P0V9_E_MODE")
		)
		(pad "21" smd rect
			(at 1.999996 2.449322 180)
			(size 0.3048 1.1176)
			(layers "F.Cu" "F.Mask" "F.Paste")
			(net "P0V9_E_TRIP")
		)
		(pad "22" smd rect
			(at 2.500122 2.449322 180)
			(size 0.3048 1.1176)
			(layers "F.Cu" "F.Mask" "F.Paste")
			(net "P0V9_E_RF")
		)
		(pad "23" smd custom
			(at 0 0 180)
			(size 0.83185 0.83185)
			(layers "F.Cu" "F.Mask" "F.Paste")
			(net "GND")
			(options
				(clearance outline)
				(anchor circle)
			)
			(primitives
				(gr_poly
					(pts
						(xy -2.7813 1.6637) (xy -2.7813 1.2954) (xy -3.048 1.2954) (xy -3.048 0.9525) (xy -2.7813 0.9525)
						(xy -2.7813 -0.9525) (xy -3.048 -0.9525) (xy -3.048 -1.2954) (xy -2.7813 -1.2954) (xy -2.7813 -1.6637)
						(xy 2.7813 -1.6637) (xy 2.7813 -1.2954) (xy 3.048 -1.2954) (xy 3.048 -0.9525) (xy 2.7813 -0.9525)
						(xy 2.7813 0.9525) (xy 3.048 0.9525) (xy 3.048 1.2954) (xy 2.7813 1.2954) (xy 2.7813 1.6637)
					)
					(width 0)
					(fill yes)
				)
			)
		)
	)
	(footprint ""
		(layer "F.Cu")
		(at 19.762216 -195.12788 180)
		(property "Reference" "R642"
			(at 0 0 180)
			(layer "F.SilkS")
			(hide yes)
			(effects
				(font
					(size 1.27 1.27)
				)
			)
		)
		(property "Value" "4K7R2F-GP"
			(at 0.064008 -3.993896 180)
			(unlocked yes)
			(layer "F.Fab")
			(hide yes)
			(effects
				(font
					(size 1.016 1.016)
					(thickness 0.1524)
				)
			)
		)
		(property "Device Type" "R402H16"
			(at 0.064008 -5.517896 180)
			(unlocked yes)
			(layer "F.Fab")
			(hide yes)
			(effects
				(font
					(size 1.016 1.016)
					(thickness 0.1524)
				)
			)
		)
		(duplicate_pad_numbers_are_jumpers no)
		(fp_line
			(start 0.508 -0.9398)
			(end -0.508 -0.9398)
			(stroke
				(width 0.1524)
				(type default)
			)
			(layer "F.SilkS")
		)
		(fp_line
			(start -0.508 -0.9398)
			(end -0.508 0.9398)
			(stroke
				(width 0.1524)
				(type default)
			)
			(layer "F.SilkS")
		)
		(fp_rect
			(start -0.508 0.9398)
			(end 0.508 -0.9398)
			(stroke
				(width 0)
				(type default)
			)
			(fill no)
			(layer "F.CrtYd")
		)
		(fp_rect
			(start -0.508 0.9398)
			(end 0.508 -0.9398)
			(stroke
				(width 0)
				(type default)
			)
			(fill no)
			(layer "F.Fab")
		)
		(pad "1" smd custom
			(at 0 -0.4445 180)
			(size 0.1397 0.1397)
			(layers "F.Cu" "F.Mask" "F.Paste")
			(net "IO_EXP_HDD_PRE_A1")
			(options
				(clearance outline)
				(anchor circle)
			)
			(primitives
				(gr_poly
					(pts
						(arc
							(start -0.1778 -0.2794)
							(mid -0.249642 -0.249642)
							(end -0.2794 -0.1778)
						)
						(arc
							(start -0.2794 0.1778)
							(mid -0.249642 0.249642)
							(end -0.1778 0.2794)
						)
						(arc
							(start 0.1778 0.2794)
							(mid 0.249642 0.249642)
							(end 0.2794 0.1778)
						)
						(arc
							(start 0.2794 -0.1778)
							(mid 0.249642 -0.249642)
							(end 0.1778 -0.2794)
						)
					)
					(width 0)
					(fill yes)
				)
			)
		)
		(pad "2" smd custom
			(at 0 0.4445 180)
			(size 0.1397 0.1397)
			(layers "F.Cu" "F.Mask" "F.Paste")
			(net "GND")
			(options
				(clearance outline)
				(anchor circle)
			)
			(primitives
				(gr_poly
					(pts
						(arc
							(start -0.1778 -0.2794)
							(mid -0.249642 -0.249642)
							(end -0.2794 -0.1778)
						)
						(arc
							(start -0.2794 0.1778)
							(mid -0.249642 0.249642)
							(end -0.1778 0.2794)
						)
						(arc
							(start 0.1778 0.2794)
							(mid 0.249642 0.249642)
							(end 0.2794 0.1778)
						)
						(arc
							(start 0.2794 -0.1778)
							(mid 0.249642 -0.249642)
							(end 0.1778 -0.2794)
						)
					)
					(width 0)
					(fill yes)
				)
			)
		)
	)
	(footprint ""
		(layer "F.Cu")
		(at 41.54297 -134.62 90)
		(property "Reference" "SR915"
			(at 0 0 90)
			(layer "F.SilkS")
			(hide yes)
			(effects
				(font
					(size 1.27 1.27)
				)
			)
		)
		(property "Value" "10KR2F-2-GP"
			(at 0.064008 -3.993896 90)
			(unlocked yes)
			(layer "F.Fab")
			(hide yes)
			(effects
				(font
					(size 1.016 1.016)
					(thickness 0.1524)
				)
			)
		)
		(property "Device Type" "R402H16"
			(at 0.064008 -5.517896 90)
			(unlocked yes)
			(layer "F.Fab")
			(hide yes)
			(effects
				(font
					(size 1.016 1.016)
					(thickness 0.1524)
				)
			)
		)
		(duplicate_pad_numbers_are_jumpers no)
		(fp_line
			(start 0.508 -0.9398)
			(end -0.508 -0.9398)
			(stroke
				(width 0.1524)
				(type default)
			)
			(layer "F.SilkS")
		)
		(fp_line
			(start -0.508 -0.9398)
			(end -0.508 0.9398)
			(stroke
				(width 0.1524)
				(type default)
			)
			(layer "F.SilkS")
		)
		(fp_rect
			(start -0.508 0.9398)
			(end 0.508 -0.9398)
			(stroke
				(width 0)
				(type default)
			)
			(fill no)
			(layer "F.CrtYd")
		)
		(fp_rect
			(start -0.508 0.9398)
			(end 0.508 -0.9398)
			(stroke
				(width 0)
				(type default)
			)
			(fill no)
			(layer "F.Fab")
		)
		(pad "1" smd custom
			(at 0 -0.4445 90)
			(size 0.1397 0.1397)
			(layers "F.Cu" "F.Mask" "F.Paste")
			(net "P3V3_STBY_R5")
			(options
				(clearance outline)
				(anchor circle)
			)
			(primitives
				(gr_poly
					(pts
						(arc
							(start -0.1778 -0.2794)
							(mid -0.249642 -0.249642)
							(end -0.2794 -0.1778)
						)
						(arc
							(start -0.2794 0.1778)
							(mid -0.249642 0.249642)
							(end -0.1778 0.2794)
						)
						(arc
							(start 0.1778 0.2794)
							(mid 0.249642 0.249642)
							(end 0.2794 0.1778)
						)
						(arc
							(start 0.2794 -0.1778)
							(mid 0.249642 -0.249642)
							(end 0.1778 -0.2794)
						)
					)
					(width 0)
					(fill yes)
				)
			)
		)
		(pad "2" smd custom
			(at 0 0.4445 90)
			(size 0.1397 0.1397)
			(layers "F.Cu" "F.Mask" "F.Paste")
			(net "P3V3_STBY_G5")
			(options
				(clearance outline)
				(anchor circle)
			)
			(primitives
				(gr_poly
					(pts
						(arc
							(start -0.1778 -0.2794)
							(mid -0.249642 -0.249642)
							(end -0.2794 -0.1778)
						)
						(arc
							(start -0.2794 0.1778)
							(mid -0.249642 0.249642)
							(end -0.1778 0.2794)
						)
						(arc
							(start 0.1778 0.2794)
							(mid 0.249642 0.249642)
							(end 0.2794 0.1778)
						)
						(arc
							(start 0.2794 -0.1778)
							(mid 0.249642 -0.249642)
							(end 0.1778 -0.2794)
						)
					)
					(width 0)
					(fill yes)
				)
			)
		)
	)
	(footprint ""
		(layer "F.Cu")
		(at 98.660966 -64.008)
		(property "Reference" "SU57"
			(at 0 0 0)
			(layer "F.SilkS")
			(hide yes)
			(effects
				(font
					(size 1.27 1.27)
				)
			)
		)
		(property "Value" "TPS3808G18DRVT-GP-U"
			(at -2.7813 -0.4572 0)
			(unlocked yes)
			(layer "F.Fab")
			(hide yes)
			(effects
				(font
					(size 1.016 1.016)
					(thickness 0.1524)
				)
			)
		)
		(property "Device Type" "DFN6F2-G1711-UH32"
			(at -2.7813 -1.9812 0)
			(unlocked yes)
			(layer "F.Fab")
			(hide yes)
			(effects
				(font
					(size 1.016 1.016)
					(thickness 0.1524)
				)
			)
		)
		(duplicate_pad_numbers_are_jumpers no)
		(fp_line
			(start -1.5113 -1.7653)
			(end -0.7493 -1.7653)
			(stroke
				(width 0.1524)
				(type default)
			)
			(layer "F.SilkS")
		)
		(fp_line
			(start -1.5113 -1.0033)
			(end -1.5113 -1.7653)
			(stroke
				(width 0.1524)
				(type default)
			)
			(layer "F.SilkS")
		)
		(fp_line
			(start -1.5113 1.0033)
			(end -1.5113 1.7653)
			(stroke
				(width 0.1524)
				(type default)
			)
			(layer "F.SilkS")
		)
		(fp_line
			(start -1.5113 1.7653)
			(end -0.7493 1.7653)
			(stroke
				(width 0.1524)
				(type default)
			)
			(layer "F.SilkS")
		)
		(fp_line
			(start 0 1.5113)
			(end 0 2.0193)
			(stroke
				(width 0.1524)
				(type default)
			)
			(layer "F.SilkS")
		)
		(fp_line
			(start 1.5113 1.0033)
			(end 1.5113 1.7653)
			(stroke
				(width 0.1524)
				(type default)
			)
			(layer "F.SilkS")
		)
		(fp_line
			(start 1.5113 1.7653)
			(end 0.7493 1.7653)
			(stroke
				(width 0.1524)
				(type default)
			)
			(layer "F.SilkS")
		)
		(fp_poly
			(pts
				(xy 0.7493 -1.7653) (xy 1.5113 -1.0033) (xy 1.5113 -1.7653)
			)
			(stroke
				(width 0)
				(type default)
			)
			(fill yes)
			(layer "F.SilkS")
		)
		(fp_rect
			(start -1.0033 1.0033)
			(end 1.0033 -1.0033)
			(stroke
				(width 0)
				(type default)
			)
			(fill no)
			(layer "F.CrtYd")
		)
		(fp_poly
			(pts
				(xy -1.5113 1.7653) (xy -1.5113 -1.7653) (xy 1.5113 -1.7653) (xy 1.5113 0.99822) (xy 1.0033 0.99822)
				(xy 1.0033 -1.0033) (xy -1.0033 -1.0033) (xy -1.0033 1.0033) (xy 1.5113 1.0033) (xy 1.5113 1.7653)
			)
			(stroke
				(width 0)
				(type default)
			)
			(fill no)
			(layer "F.CrtYd")
		)
		(fp_rect
			(start -1.5113 1.7653)
			(end 1.5113 -1.7653)
			(stroke
				(width 0)
				(type default)
			)
			(fill no)
			(layer "F.Fab")
		)
		(pad "1" smd rect
			(at 0.649986 -1.1303)
			(size 0.4064 0.508)
			(drill
				(offset 0 0.127)
			)
			(layers "F.Cu" "F.Mask" "F.Paste")
			(net "P1V8_STBY")
		)
		(pad "2" smd rect
			(at 0 -1.1303)
			(size 0.4064 0.508)
			(drill
				(offset 0 0.127)
			)
			(layers "F.Cu" "F.Mask" "F.Paste")
			(net "PWRGD_P0V955_C")
		)
		(pad "3" smd rect
			(at -0.649986 -1.1303)
			(size 0.4064 0.508)
			(drill
				(offset 0 0.127)
			)
			(layers "F.Cu" "F.Mask" "F.Paste")
			(net "Net_8")
		)
		(pad "4" smd rect
			(at -0.649986 1.1303)
			(size 0.4064 0.508)
			(drill
				(offset 0 -0.127)
			)
			(layers "F.Cu" "F.Mask" "F.Paste")
			(net "IOC_VREF_SET")
		)
		(pad "5" smd rect
			(at 0 1.1303)
			(size 0.4064 0.508)
			(drill
				(offset 0 -0.127)
			)
			(layers "F.Cu" "F.Mask" "F.Paste")
			(net "GND")
		)
		(pad "6" smd rect
			(at 0.649986 1.1303)
			(size 0.4064 0.508)
			(drill
				(offset 0 -0.127)
			)
			(layers "F.Cu" "F.Mask" "F.Paste")
			(net "IOC_RESET#")
		)
		(pad "7" smd rect
			(at 0 0)
			(size 1.7018 1.0922)
			(layers "F.Cu" "F.Mask" "F.Paste")
			(net "GND")
		)
	)
	(footprint ""
		(layer "F.Cu")
		(at 191.516 -146.177 -90)
		(property "Reference" "SR738"
			(at 0 0 270)
			(layer "F.SilkS")
			(hide yes)
			(effects
				(font
					(size 1.27 1.27)
				)
			)
		)
		(property "Value" "2K2R2F-GP"
			(at 0.064008 -3.993896 270)
			(unlocked yes)
			(layer "F.Fab")
			(hide yes)
			(effects
				(font
					(size 1.016 1.016)
					(thickness 0.1524)
				)
			)
		)
		(property "Device Type" "R402H16"
			(at 0.064008 -5.517896 270)
			(unlocked yes)
			(layer "F.Fab")
			(hide yes)
			(effects
				(font
					(size 1.016 1.016)
					(thickness 0.1524)
				)
			)
		)
		(duplicate_pad_numbers_are_jumpers no)
		(fp_line
			(start -0.508 -0.9398)
			(end -0.508 0.9398)
			(stroke
				(width 0.1524)
				(type default)
			)
			(layer "F.SilkS")
		)
		(fp_line
			(start 0.508 -0.9398)
			(end -0.508 -0.9398)
			(stroke
				(width 0.1524)
				(type default)
			)
			(layer "F.SilkS")
		)
		(fp_rect
			(start -0.508 0.9398)
			(end 0.508 -0.9398)
			(stroke
				(width 0)
				(type default)
			)
			(fill no)
			(layer "F.CrtYd")
		)
		(fp_rect
			(start -0.508 0.9398)
			(end 0.508 -0.9398)
			(stroke
				(width 0)
				(type default)
			)
			(fill no)
			(layer "F.Fab")
		)
		(pad "1" smd custom
			(at 0 -0.4445 270)
			(size 0.1397 0.1397)
			(layers "F.Cu" "F.Mask" "F.Paste")
			(net "EXP_I2C_SCL_3")
			(options
				(clearance outline)
				(anchor circle)
			)
			(primitives
				(gr_poly
					(pts
						(arc
							(start -0.1778 -0.2794)
							(mid -0.249642 -0.249642)
							(end -0.2794 -0.1778)
						)
						(arc
							(start -0.2794 0.1778)
							(mid -0.249642 0.249642)
							(end -0.1778 0.2794)
						)
						(arc
							(start 0.1778 0.2794)
							(mid 0.249642 0.249642)
							(end 0.2794 0.1778)
						)
						(arc
							(start 0.2794 -0.1778)
							(mid 0.249642 -0.249642)
							(end 0.1778 -0.2794)
						)
					)
					(width 0)
					(fill yes)
				)
			)
		)
		(pad "2" smd custom
			(at 0 0.4445 270)
			(size 0.1397 0.1397)
			(layers "F.Cu" "F.Mask" "F.Paste")
			(net "P1V8_E")
			(options
				(clearance outline)
				(anchor circle)
			)
			(primitives
				(gr_poly
					(pts
						(arc
							(start -0.1778 -0.2794)
							(mid -0.249642 -0.249642)
							(end -0.2794 -0.1778)
						)
						(arc
							(start -0.2794 0.1778)
							(mid -0.249642 0.249642)
							(end -0.1778 0.2794)
						)
						(arc
							(start 0.1778 0.2794)
							(mid 0.249642 0.249642)
							(end 0.2794 0.1778)
						)
						(arc
							(start 0.2794 -0.1778)
							(mid 0.249642 -0.249642)
							(end 0.1778 -0.2794)
						)
					)
					(width 0)
					(fill yes)
				)
			)
		)
	)
	(footprint ""
		(layer "F.Cu")
		(at 252.984 -126.111 -90)
		(property "Reference" "R7904"
			(at 0 0 270)
			(layer "F.SilkS")
			(hide yes)
			(effects
				(font
					(size 1.27 1.27)
				)
			)
		)
		(property "Value" "0R2J-2-GP"
			(at 0.064008 -3.993896 270)
			(unlocked yes)
			(layer "F.Fab")
			(hide yes)
			(effects
				(font
					(size 1.016 1.016)
					(thickness 0.1524)
				)
			)
		)
		(property "Device Type" "R402H16"
			(at 0.064008 -5.517896 270)
			(unlocked yes)
			(layer "F.Fab")
			(hide yes)
			(effects
				(font
					(size 1.016 1.016)
					(thickness 0.1524)
				)
			)
		)
		(duplicate_pad_numbers_are_jumpers no)
		(fp_line
			(start -0.508 -0.9398)
			(end -0.508 0.9398)
			(stroke
				(width 0.1524)
				(type default)
			)
			(layer "F.SilkS")
		)
		(fp_line
			(start 0.508 -0.9398)
			(end -0.508 -0.9398)
			(stroke
				(width 0.1524)
				(type default)
			)
			(layer "F.SilkS")
		)
		(fp_rect
			(start -0.508 0.9398)
			(end 0.508 -0.9398)
			(stroke
				(width 0)
				(type default)
			)
			(fill no)
			(layer "F.CrtYd")
		)
		(fp_rect
			(start -0.508 0.9398)
			(end 0.508 -0.9398)
			(stroke
				(width 0)
				(type default)
			)
			(fill no)
			(layer "F.Fab")
		)
		(pad "1" smd custom
			(at 0 -0.4445 270)
			(size 0.1397 0.1397)
			(layers "F.Cu" "F.Mask" "F.Paste")
			(net "CPU_U193_PIN2_TX")
			(options
				(clearance outline)
				(anchor circle)
			)
			(primitives
				(gr_poly
					(pts
						(arc
							(start -0.1778 -0.2794)
							(mid -0.249642 -0.249642)
							(end -0.2794 -0.1778)
						)
						(arc
							(start -0.2794 0.1778)
							(mid -0.249642 0.249642)
							(end -0.1778 0.2794)
						)
						(arc
							(start 0.1778 0.2794)
							(mid 0.249642 0.249642)
							(end 0.2794 0.1778)
						)
						(arc
							(start 0.2794 -0.1778)
							(mid 0.249642 -0.249642)
							(end 0.1778 -0.2794)
						)
					)
					(width 0)
					(fill yes)
				)
			)
		)
		(pad "2" smd custom
			(at 0 0.4445 270)
			(size 0.1397 0.1397)
			(layers "F.Cu" "F.Mask" "F.Paste")
			(net "CPU_TXD")
			(options
				(clearance outline)
				(anchor circle)
			)
			(primitives
				(gr_poly
					(pts
						(arc
							(start -0.1778 -0.2794)
							(mid -0.249642 -0.249642)
							(end -0.2794 -0.1778)
						)
						(arc
							(start -0.2794 0.1778)
							(mid -0.249642 0.249642)
							(end -0.1778 0.2794)
						)
						(arc
							(start 0.1778 0.2794)
							(mid 0.249642 0.249642)
							(end 0.2794 0.1778)
						)
						(arc
							(start 0.2794 -0.1778)
							(mid 0.249642 -0.249642)
							(end 0.1778 -0.2794)
						)
					)
					(width 0)
					(fill yes)
				)
			)
		)
	)
	(footprint ""
		(layer "F.Cu")
		(at 93.853 -101.854)
		(property "Reference" "STP88"
			(at 0 0 0)
			(layer "F.SilkS")
			(hide yes)
			(effects
				(font
					(size 1.27 1.27)
				)
			)
		)
		(property "Value" "TPAD28"
			(at 0.0127 -1.8034 0)
			(unlocked yes)
			(layer "F.Fab")
			(hide yes)
			(effects
				(font
					(size 1.016 1.016)
					(thickness 0.1524)
				)
			)
		)
		(property "Device Type" "TPAD28"
			(at 0.0127 -3.3274 0)
			(unlocked yes)
			(layer "F.Fab")
			(hide yes)
			(effects
				(font
					(size 1.016 1.016)
					(thickness 0.1524)
				)
			)
		)
		(duplicate_pad_numbers_are_jumpers no)
		(fp_poly
			(pts
				(arc
					(start 0.3556 0)
					(mid -0.3556 0)
					(end 0.3556 0)
				)
			)
			(stroke
				(width 0)
				(type default)
			)
			(fill no)
			(layer "F.CrtYd")
		)
		(fp_poly
			(pts
				(arc
					(start 0.6096 0)
					(mid -0.6096 0)
					(end 0.6096 0)
				)
			)
			(stroke
				(width 0)
				(type default)
			)
			(fill no)
			(layer "F.Fab")
		)
		(pad "1" smd circle
			(at 0 0)
			(size 0.7112 0.7112)
			(layers "F.Cu" "F.Mask" "F.Paste")
			(net "UART_CTS")
		)
	)
	(footprint ""
		(layer "F.Cu")
		(at 190.871856 -119.770652 -90)
		(property "Reference" "PR172"
			(at 0 0 270)
			(layer "F.SilkS")
			(hide yes)
			(effects
				(font
					(size 1.27 1.27)
				)
			)
		)
		(property "Value" "0R2J-2-GP"
			(at 0.064008 -3.993896 270)
			(unlocked yes)
			(layer "F.Fab")
			(hide yes)
			(effects
				(font
					(size 1.016 1.016)
					(thickness 0.1524)
				)
			)
		)
		(property "Device Type" "R402H16"
			(at 0.064008 -5.517896 270)
			(unlocked yes)
			(layer "F.Fab")
			(hide yes)
			(effects
				(font
					(size 1.016 1.016)
					(thickness 0.1524)
				)
			)
		)
		(duplicate_pad_numbers_are_jumpers no)
		(fp_line
			(start -0.508 -0.9398)
			(end -0.508 0.9398)
			(stroke
				(width 0.1524)
				(type default)
			)
			(layer "F.SilkS")
		)
		(fp_line
			(start 0.508 -0.9398)
			(end -0.508 -0.9398)
			(stroke
				(width 0.1524)
				(type default)
			)
			(layer "F.SilkS")
		)
		(fp_rect
			(start -0.508 0.9398)
			(end 0.508 -0.9398)
			(stroke
				(width 0)
				(type default)
			)
			(fill no)
			(layer "F.CrtYd")
		)
		(fp_rect
			(start -0.508 0.9398)
			(end 0.508 -0.9398)
			(stroke
				(width 0)
				(type default)
			)
			(fill no)
			(layer "F.Fab")
		)
		(pad "1" smd custom
			(at 0 -0.4445 270)
			(size 0.1397 0.1397)
			(layers "F.Cu" "F.Mask" "F.Paste")
			(net "P3V3_STBY_B2")
			(options
				(clearance outline)
				(anchor circle)
			)
			(primitives
				(gr_poly
					(pts
						(arc
							(start -0.1778 -0.2794)
							(mid -0.249642 -0.249642)
							(end -0.2794 -0.1778)
						)
						(arc
							(start -0.2794 0.1778)
							(mid -0.249642 0.249642)
							(end -0.1778 0.2794)
						)
						(arc
							(start 0.1778 0.2794)
							(mid 0.249642 0.249642)
							(end 0.2794 0.1778)
						)
						(arc
							(start 0.2794 -0.1778)
							(mid 0.249642 -0.249642)
							(end 0.1778 -0.2794)
						)
					)
					(width 0)
					(fill yes)
				)
			)
		)
		(pad "2" smd custom
			(at 0 0.4445 270)
			(size 0.1397 0.1397)
			(layers "F.Cu" "F.Mask" "F.Paste")
			(net "P3V3_STBY_R2")
			(options
				(clearance outline)
				(anchor circle)
			)
			(primitives
				(gr_poly
					(pts
						(arc
							(start -0.1778 -0.2794)
							(mid -0.249642 -0.249642)
							(end -0.2794 -0.1778)
						)
						(arc
							(start -0.2794 0.1778)
							(mid -0.249642 0.249642)
							(end -0.1778 0.2794)
						)
						(arc
							(start 0.1778 0.2794)
							(mid 0.249642 0.249642)
							(end 0.2794 0.1778)
						)
						(arc
							(start 0.2794 -0.1778)
							(mid 0.249642 -0.249642)
							(end 0.1778 -0.2794)
						)
					)
					(width 0)
					(fill yes)
				)
			)
		)
	)
	(footprint ""
		(layer "F.Cu")
		(at 191.897 -20.955 -90)
		(property "Reference" "R687"
			(at 0 0 270)
			(layer "F.SilkS")
			(hide yes)
			(effects
				(font
					(size 1.27 1.27)
				)
			)
		)
		(property "Value" "0R2J-2-GP"
			(at 0.064008 -3.993896 270)
			(unlocked yes)
			(layer "F.Fab")
			(hide yes)
			(effects
				(font
					(size 1.016 1.016)
					(thickness 0.1524)
				)
			)
		)
		(property "Device Type" "R402H16"
			(at 0.064008 -5.517896 270)
			(unlocked yes)
			(layer "F.Fab")
			(hide yes)
			(effects
				(font
					(size 1.016 1.016)
					(thickness 0.1524)
				)
			)
		)
		(duplicate_pad_numbers_are_jumpers no)
		(fp_line
			(start -0.508 -0.9398)
			(end -0.508 0.9398)
			(stroke
				(width 0.1524)
				(type default)
			)
			(layer "F.SilkS")
		)
		(fp_line
			(start 0.508 -0.9398)
			(end -0.508 -0.9398)
			(stroke
				(width 0.1524)
				(type default)
			)
			(layer "F.SilkS")
		)
		(fp_rect
			(start -0.508 0.9398)
			(end 0.508 -0.9398)
			(stroke
				(width 0)
				(type default)
			)
			(fill no)
			(layer "F.CrtYd")
		)
		(fp_rect
			(start -0.508 0.9398)
			(end 0.508 -0.9398)
			(stroke
				(width 0)
				(type default)
			)
			(fill no)
			(layer "F.Fab")
		)
		(pad "1" smd custom
			(at 0 -0.4445 270)
			(size 0.1397 0.1397)
			(layers "F.Cu" "F.Mask" "F.Paste")
			(net "GND")
			(options
				(clearance outline)
				(anchor circle)
			)
			(primitives
				(gr_poly
					(pts
						(arc
							(start -0.1778 -0.2794)
							(mid -0.249642 -0.249642)
							(end -0.2794 -0.1778)
						)
						(arc
							(start -0.2794 0.1778)
							(mid -0.249642 0.249642)
							(end -0.1778 0.2794)
						)
						(arc
							(start 0.1778 0.2794)
							(mid 0.249642 0.249642)
							(end 0.2794 0.1778)
						)
						(arc
							(start 0.2794 -0.1778)
							(mid 0.249642 -0.249642)
							(end 0.1778 -0.2794)
						)
					)
					(width 0)
					(fill yes)
				)
			)
		)
		(pad "2" smd custom
			(at 0 0.4445 270)
			(size 0.1397 0.1397)
			(layers "F.Cu" "F.Mask" "F.Paste")
			(net "RMII_BMC_MDIO")
			(options
				(clearance outline)
				(anchor circle)
			)
			(primitives
				(gr_poly
					(pts
						(arc
							(start -0.1778 -0.2794)
							(mid -0.249642 -0.249642)
							(end -0.2794 -0.1778)
						)
						(arc
							(start -0.2794 0.1778)
							(mid -0.249642 0.249642)
							(end -0.1778 0.2794)
						)
						(arc
							(start 0.1778 0.2794)
							(mid 0.249642 0.249642)
							(end 0.2794 0.1778)
						)
						(arc
							(start 0.2794 -0.1778)
							(mid 0.249642 -0.249642)
							(end 0.1778 -0.2794)
						)
					)
					(width 0)
					(fill yes)
				)
			)
		)
	)
	(footprint ""
		(layer "F.Cu")
		(at 48.768 -213.36 -90)
		(property "Reference" "R2172"
			(at 0 0 270)
			(layer "F.SilkS")
			(hide yes)
			(effects
				(font
					(size 1.27 1.27)
				)
			)
		)
		(property "Value" "0R2J-2-GP"
			(at 0.064008 -3.993896 270)
			(unlocked yes)
			(layer "F.Fab")
			(hide yes)
			(effects
				(font
					(size 1.016 1.016)
					(thickness 0.1524)
				)
			)
		)
		(property "Device Type" "R402H16"
			(at 0.064008 -5.517896 270)
			(unlocked yes)
			(layer "F.Fab")
			(hide yes)
			(effects
				(font
					(size 1.016 1.016)
					(thickness 0.1524)
				)
			)
		)
		(duplicate_pad_numbers_are_jumpers no)
		(fp_line
			(start -0.508 -0.9398)
			(end -0.508 0.9398)
			(stroke
				(width 0.1524)
				(type default)
			)
			(layer "F.SilkS")
		)
		(fp_line
			(start 0.508 -0.9398)
			(end -0.508 -0.9398)
			(stroke
				(width 0.1524)
				(type default)
			)
			(layer "F.SilkS")
		)
		(fp_rect
			(start -0.508 0.9398)
			(end 0.508 -0.9398)
			(stroke
				(width 0)
				(type default)
			)
			(fill no)
			(layer "F.CrtYd")
		)
		(fp_rect
			(start -0.508 0.9398)
			(end 0.508 -0.9398)
			(stroke
				(width 0)
				(type default)
			)
			(fill no)
			(layer "F.Fab")
		)
		(pad "1" smd custom
			(at 0 -0.4445 270)
			(size 0.1397 0.1397)
			(layers "F.Cu" "F.Mask" "F.Paste")
			(net "MB0_CM_ADR2_R")
			(options
				(clearance outline)
				(anchor circle)
			)
			(primitives
				(gr_poly
					(pts
						(arc
							(start -0.1778 -0.2794)
							(mid -0.249642 -0.249642)
							(end -0.2794 -0.1778)
						)
						(arc
							(start -0.2794 0.1778)
							(mid -0.249642 0.249642)
							(end -0.1778 0.2794)
						)
						(arc
							(start 0.1778 0.2794)
							(mid 0.249642 0.249642)
							(end 0.2794 0.1778)
						)
						(arc
							(start 0.2794 -0.1778)
							(mid 0.249642 -0.249642)
							(end 0.1778 -0.2794)
						)
					)
					(width 0)
					(fill yes)
				)
			)
		)
		(pad "2" smd custom
			(at 0 0.4445 270)
			(size 0.1397 0.1397)
			(layers "F.Cu" "F.Mask" "F.Paste")
			(net "AGND_CURRENT_MON")
			(options
				(clearance outline)
				(anchor circle)
			)
			(primitives
				(gr_poly
					(pts
						(arc
							(start -0.1778 -0.2794)
							(mid -0.249642 -0.249642)
							(end -0.2794 -0.1778)
						)
						(arc
							(start -0.2794 0.1778)
							(mid -0.249642 0.249642)
							(end -0.1778 0.2794)
						)
						(arc
							(start 0.1778 0.2794)
							(mid 0.249642 0.249642)
							(end 0.2794 0.1778)
						)
						(arc
							(start 0.2794 -0.1778)
							(mid 0.249642 -0.249642)
							(end 0.1778 -0.2794)
						)
					)
					(width 0)
					(fill yes)
				)
			)
		)
	)
	(footprint ""
		(layer "F.Cu")
		(at 180.721 -17.78)
		(property "Reference" "C153"
			(at 0 0 0)
			(layer "F.SilkS")
			(hide yes)
			(effects
				(font
					(size 1.27 1.27)
				)
			)
		)
		(property "Value" "SC100P50V2JN-3GP"
			(at 1.1811 -2.7051 0)
			(unlocked yes)
			(layer "F.Fab")
			(hide yes)
			(effects
				(font
					(size 1.016 1.016)
					(thickness 0.1524)
				)
			)
		)
		(property "Device Type" "C402H22"
			(at 1.1811 -4.2291 0)
			(unlocked yes)
			(layer "F.Fab")
			(hide yes)
			(effects
				(font
					(size 1.016 1.016)
					(thickness 0.1524)
				)
			)
		)
		(duplicate_pad_numbers_are_jumpers no)
		(fp_rect
			(start -0.4318 0.9525)
			(end 0.4318 -0.9525)
			(stroke
				(width 0)
				(type default)
			)
			(fill no)
			(layer "F.CrtYd")
		)
		(fp_rect
			(start -0.4318 0.9525)
			(end 0.4318 -0.9525)
			(stroke
				(width 0)
				(type default)
			)
			(fill no)
			(layer "F.Fab")
		)
		(pad "1" smd custom
			(at 0 -0.4445)
			(size 0.1524 0.1524)
			(layers "F.Cu" "F.Mask" "F.Paste")
			(net "TEMP_SENSOR_DXP")
			(options
				(clearance outline)
				(anchor circle)
			)
			(primitives
				(gr_poly
					(pts
						(arc
							(start 0.3048 -0.2032)
							(mid 0.275042 -0.275042)
							(end 0.2032 -0.3048)
						)
						(arc
							(start -0.2032 -0.3048)
							(mid -0.275042 -0.275042)
							(end -0.3048 -0.2032)
						)
						(arc
							(start -0.3048 0.2032)
							(mid -0.275042 0.275042)
							(end -0.2032 0.3048)
						)
						(arc
							(start 0.2032 0.3048)
							(mid 0.275042 0.275042)
							(end 0.3048 0.2032)
						)
					)
					(width 0)
					(fill yes)
				)
			)
		)
		(pad "2" smd custom
			(at 0 0.4445)
			(size 0.1524 0.1524)
			(layers "F.Cu" "F.Mask" "F.Paste")
			(net "TEMP_SENSOR_DXN")
			(options
				(clearance outline)
				(anchor circle)
			)
			(primitives
				(gr_poly
					(pts
						(arc
							(start 0.3048 -0.2032)
							(mid 0.275042 -0.275042)
							(end 0.2032 -0.3048)
						)
						(arc
							(start -0.2032 -0.3048)
							(mid -0.275042 -0.275042)
							(end -0.3048 -0.2032)
						)
						(arc
							(start -0.3048 0.2032)
							(mid -0.275042 0.275042)
							(end -0.2032 0.3048)
						)
						(arc
							(start 0.2032 0.3048)
							(mid 0.275042 0.275042)
							(end 0.3048 0.2032)
						)
					)
					(width 0)
					(fill yes)
				)
			)
		)
	)
	(footprint ""
		(layer "F.Cu")
		(at 24.580088 -195.454016 180)
		(property "Reference" "SR269"
			(at 0 0 180)
			(layer "F.SilkS")
			(hide yes)
			(effects
				(font
					(size 1.27 1.27)
				)
			)
		)
		(property "Value" "4K7R2F-GP"
			(at 0.064008 -3.993896 180)
			(unlocked yes)
			(layer "F.Fab")
			(hide yes)
			(effects
				(font
					(size 1.016 1.016)
					(thickness 0.1524)
				)
			)
		)
		(property "Device Type" "R402H16"
			(at 0.064008 -5.517896 180)
			(unlocked yes)
			(layer "F.Fab")
			(hide yes)
			(effects
				(font
					(size 1.016 1.016)
					(thickness 0.1524)
				)
			)
		)
		(duplicate_pad_numbers_are_jumpers no)
		(fp_line
			(start 0.508 -0.9398)
			(end -0.508 -0.9398)
			(stroke
				(width 0.1524)
				(type default)
			)
			(layer "F.SilkS")
		)
		(fp_line
			(start -0.508 -0.9398)
			(end -0.508 0.9398)
			(stroke
				(width 0.1524)
				(type default)
			)
			(layer "F.SilkS")
		)
		(fp_rect
			(start -0.508 0.9398)
			(end 0.508 -0.9398)
			(stroke
				(width 0)
				(type default)
			)
			(fill no)
			(layer "F.CrtYd")
		)
		(fp_rect
			(start -0.508 0.9398)
			(end 0.508 -0.9398)
			(stroke
				(width 0)
				(type default)
			)
			(fill no)
			(layer "F.Fab")
		)
		(pad "1" smd custom
			(at 0 -0.4445 180)
			(size 0.1397 0.1397)
			(layers "F.Cu" "F.Mask" "F.Paste")
			(net "P1V8_E")
			(options
				(clearance outline)
				(anchor circle)
			)
			(primitives
				(gr_poly
					(pts
						(arc
							(start -0.1778 -0.2794)
							(mid -0.249642 -0.249642)
							(end -0.2794 -0.1778)
						)
						(arc
							(start -0.2794 0.1778)
							(mid -0.249642 0.249642)
							(end -0.1778 0.2794)
						)
						(arc
							(start 0.1778 0.2794)
							(mid 0.249642 0.249642)
							(end 0.2794 0.1778)
						)
						(arc
							(start 0.2794 -0.1778)
							(mid 0.249642 -0.249642)
							(end 0.1778 -0.2794)
						)
					)
					(width 0)
					(fill yes)
				)
			)
		)
		(pad "2" smd custom
			(at 0 0.4445 180)
			(size 0.1397 0.1397)
			(layers "F.Cu" "F.Mask" "F.Paste")
			(net "I2C_IO_EXP_RESET#_PRST")
			(options
				(clearance outline)
				(anchor circle)
			)
			(primitives
				(gr_poly
					(pts
						(arc
							(start -0.1778 -0.2794)
							(mid -0.249642 -0.249642)
							(end -0.2794 -0.1778)
						)
						(arc
							(start -0.2794 0.1778)
							(mid -0.249642 0.249642)
							(end -0.1778 0.2794)
						)
						(arc
							(start 0.1778 0.2794)
							(mid 0.249642 0.249642)
							(end 0.2794 0.1778)
						)
						(arc
							(start 0.2794 -0.1778)
							(mid 0.249642 -0.249642)
							(end 0.1778 -0.2794)
						)
					)
					(width 0)
					(fill yes)
				)
			)
		)
	)
	(footprint ""
		(layer "F.Cu")
		(at 140.716 -38.862 180)
		(property "Reference" "SR694"
			(at 0 0 180)
			(layer "F.SilkS")
			(hide yes)
			(effects
				(font
					(size 1.27 1.27)
				)
			)
		)
		(property "Value" "10KR2F-2-GP"
			(at 0.064008 -3.993896 180)
			(unlocked yes)
			(layer "F.Fab")
			(hide yes)
			(effects
				(font
					(size 1.016 1.016)
					(thickness 0.1524)
				)
			)
		)
		(property "Device Type" "R402H16"
			(at 0.064008 -5.517896 180)
			(unlocked yes)
			(layer "F.Fab")
			(hide yes)
			(effects
				(font
					(size 1.016 1.016)
					(thickness 0.1524)
				)
			)
		)
		(duplicate_pad_numbers_are_jumpers no)
		(fp_line
			(start 0.508 -0.9398)
			(end -0.508 -0.9398)
			(stroke
				(width 0.1524)
				(type default)
			)
			(layer "F.SilkS")
		)
		(fp_line
			(start -0.508 -0.9398)
			(end -0.508 0.9398)
			(stroke
				(width 0.1524)
				(type default)
			)
			(layer "F.SilkS")
		)
		(fp_rect
			(start -0.508 0.9398)
			(end 0.508 -0.9398)
			(stroke
				(width 0)
				(type default)
			)
			(fill no)
			(layer "F.CrtYd")
		)
		(fp_rect
			(start -0.508 0.9398)
			(end 0.508 -0.9398)
			(stroke
				(width 0)
				(type default)
			)
			(fill no)
			(layer "F.Fab")
		)
		(pad "1" smd custom
			(at 0 -0.4445 180)
			(size 0.1397 0.1397)
			(layers "F.Cu" "F.Mask" "F.Paste")
			(net "P1V8_C")
			(options
				(clearance outline)
				(anchor circle)
			)
			(primitives
				(gr_poly
					(pts
						(arc
							(start -0.1778 -0.2794)
							(mid -0.249642 -0.249642)
							(end -0.2794 -0.1778)
						)
						(arc
							(start -0.2794 0.1778)
							(mid -0.249642 0.249642)
							(end -0.1778 0.2794)
						)
						(arc
							(start 0.1778 0.2794)
							(mid 0.249642 0.249642)
							(end 0.2794 0.1778)
						)
						(arc
							(start 0.2794 -0.1778)
							(mid 0.249642 -0.249642)
							(end 0.1778 -0.2794)
						)
					)
					(width 0)
					(fill yes)
				)
			)
		)
		(pad "2" smd custom
			(at 0 0.4445 180)
			(size 0.1397 0.1397)
			(layers "F.Cu" "F.Mask" "F.Paste")
			(net "XM_WE_N")
			(options
				(clearance outline)
				(anchor circle)
			)
			(primitives
				(gr_poly
					(pts
						(arc
							(start -0.1778 -0.2794)
							(mid -0.249642 -0.249642)
							(end -0.2794 -0.1778)
						)
						(arc
							(start -0.2794 0.1778)
							(mid -0.249642 0.249642)
							(end -0.1778 0.2794)
						)
						(arc
							(start 0.1778 0.2794)
							(mid 0.249642 0.249642)
							(end 0.2794 0.1778)
						)
						(arc
							(start 0.2794 -0.1778)
							(mid 0.249642 -0.249642)
							(end 0.1778 -0.2794)
						)
					)
					(width 0)
					(fill yes)
				)
			)
		)
	)
	(footprint ""
		(layer "F.Cu")
		(at 191.697864 -28.520136 90)
		(property "Reference" "R377"
			(at 0 0 90)
			(layer "F.SilkS")
			(hide yes)
			(effects
				(font
					(size 1.27 1.27)
				)
			)
		)
		(property "Value" "33R2J-2-GP"
			(at 0.064008 -3.993896 90)
			(unlocked yes)
			(layer "F.Fab")
			(hide yes)
			(effects
				(font
					(size 1.016 1.016)
					(thickness 0.1524)
				)
			)
		)
		(property "Device Type" "R402H16"
			(at 0.064008 -5.517896 90)
			(unlocked yes)
			(layer "F.Fab")
			(hide yes)
			(effects
				(font
					(size 1.016 1.016)
					(thickness 0.1524)
				)
			)
		)
		(duplicate_pad_numbers_are_jumpers no)
		(fp_line
			(start 0.508 -0.9398)
			(end -0.508 -0.9398)
			(stroke
				(width 0.1524)
				(type default)
			)
			(layer "F.SilkS")
		)
		(fp_line
			(start -0.508 -0.9398)
			(end -0.508 0.9398)
			(stroke
				(width 0.1524)
				(type default)
			)
			(layer "F.SilkS")
		)
		(fp_rect
			(start -0.508 0.9398)
			(end 0.508 -0.9398)
			(stroke
				(width 0)
				(type default)
			)
			(fill no)
			(layer "F.CrtYd")
		)
		(fp_rect
			(start -0.508 0.9398)
			(end 0.508 -0.9398)
			(stroke
				(width 0)
				(type default)
			)
			(fill no)
			(layer "F.Fab")
		)
		(pad "1" smd custom
			(at 0 -0.4445 90)
			(size 0.1397 0.1397)
			(layers "F.Cu" "F.Mask" "F.Paste")
			(net "RMII_BMC_RX_ER_R")
			(options
				(clearance outline)
				(anchor circle)
			)
			(primitives
				(gr_poly
					(pts
						(arc
							(start -0.1778 -0.2794)
							(mid -0.249642 -0.249642)
							(end -0.2794 -0.1778)
						)
						(arc
							(start -0.2794 0.1778)
							(mid -0.249642 0.249642)
							(end -0.1778 0.2794)
						)
						(arc
							(start 0.1778 0.2794)
							(mid 0.249642 0.249642)
							(end 0.2794 0.1778)
						)
						(arc
							(start 0.2794 -0.1778)
							(mid 0.249642 -0.249642)
							(end 0.1778 -0.2794)
						)
					)
					(width 0)
					(fill yes)
				)
			)
		)
		(pad "2" smd custom
			(at 0 0.4445 90)
			(size 0.1397 0.1397)
			(layers "F.Cu" "F.Mask" "F.Paste")
			(net "RMII_BMC_RX_ER")
			(options
				(clearance outline)
				(anchor circle)
			)
			(primitives
				(gr_poly
					(pts
						(arc
							(start -0.1778 -0.2794)
							(mid -0.249642 -0.249642)
							(end -0.2794 -0.1778)
						)
						(arc
							(start -0.2794 0.1778)
							(mid -0.249642 0.249642)
							(end -0.1778 0.2794)
						)
						(arc
							(start 0.1778 0.2794)
							(mid 0.249642 0.249642)
							(end 0.2794 0.1778)
						)
						(arc
							(start 0.2794 -0.1778)
							(mid 0.249642 -0.249642)
							(end 0.1778 -0.2794)
						)
					)
					(width 0)
					(fill yes)
				)
			)
		)
	)
	(footprint ""
		(layer "F.Cu")
		(at 342.256872 -115.515136)
		(property "Reference" "PR6"
			(at 0 0 0)
			(layer "F.SilkS")
			(hide yes)
			(effects
				(font
					(size 1.27 1.27)
				)
			)
		)
		(property "Value" "10KR2F-2-GP"
			(at 0.064008 -3.993896 0)
			(unlocked yes)
			(layer "F.Fab")
			(hide yes)
			(effects
				(font
					(size 1.016 1.016)
					(thickness 0.1524)
				)
			)
		)
		(property "Device Type" "R402H16"
			(at 0.064008 -5.517896 0)
			(unlocked yes)
			(layer "F.Fab")
			(hide yes)
			(effects
				(font
					(size 1.016 1.016)
					(thickness 0.1524)
				)
			)
		)
		(duplicate_pad_numbers_are_jumpers no)
		(fp_line
			(start -0.508 -0.9398)
			(end -0.508 0.9398)
			(stroke
				(width 0.1524)
				(type default)
			)
			(layer "F.SilkS")
		)
		(fp_line
			(start 0.508 -0.9398)
			(end -0.508 -0.9398)
			(stroke
				(width 0.1524)
				(type default)
			)
			(layer "F.SilkS")
		)
		(fp_rect
			(start -0.508 0.9398)
			(end 0.508 -0.9398)
			(stroke
				(width 0)
				(type default)
			)
			(fill no)
			(layer "F.CrtYd")
		)
		(fp_rect
			(start -0.508 0.9398)
			(end 0.508 -0.9398)
			(stroke
				(width 0)
				(type default)
			)
			(fill no)
			(layer "F.Fab")
		)
		(pad "1" smd custom
			(at 0 -0.4445)
			(size 0.1397 0.1397)
			(layers "F.Cu" "F.Mask" "F.Paste")
			(net "AGND_P5V_STBY")
			(options
				(clearance outline)
				(anchor circle)
			)
			(primitives
				(gr_poly
					(pts
						(arc
							(start -0.1778 -0.2794)
							(mid -0.249642 -0.249642)
							(end -0.2794 -0.1778)
						)
						(arc
							(start -0.2794 0.1778)
							(mid -0.249642 0.249642)
							(end -0.1778 0.2794)
						)
						(arc
							(start 0.1778 0.2794)
							(mid 0.249642 0.249642)
							(end 0.2794 0.1778)
						)
						(arc
							(start 0.2794 -0.1778)
							(mid 0.249642 -0.249642)
							(end 0.1778 -0.2794)
						)
					)
					(width 0)
					(fill yes)
				)
			)
		)
		(pad "2" smd custom
			(at 0 0.4445)
			(size 0.1397 0.1397)
			(layers "F.Cu" "F.Mask" "F.Paste")
			(net "P5V_STBY_VFB")
			(options
				(clearance outline)
				(anchor circle)
			)
			(primitives
				(gr_poly
					(pts
						(arc
							(start -0.1778 -0.2794)
							(mid -0.249642 -0.249642)
							(end -0.2794 -0.1778)
						)
						(arc
							(start -0.2794 0.1778)
							(mid -0.249642 0.249642)
							(end -0.1778 0.2794)
						)
						(arc
							(start 0.1778 0.2794)
							(mid 0.249642 0.249642)
							(end 0.2794 0.1778)
						)
						(arc
							(start 0.2794 -0.1778)
							(mid 0.249642 -0.249642)
							(end 0.1778 -0.2794)
						)
					)
					(width 0)
					(fill yes)
				)
			)
		)
	)
	(footprint ""
		(layer "F.Cu")
		(at 111.89716 -27.94 -90)
		(property "Reference" "SR683"
			(at 0 0 270)
			(layer "F.SilkS")
			(hide yes)
			(effects
				(font
					(size 1.27 1.27)
				)
			)
		)
		(property "Value" "10KR2F-2-GP"
			(at 0.064008 -3.993896 270)
			(unlocked yes)
			(layer "F.Fab")
			(hide yes)
			(effects
				(font
					(size 1.016 1.016)
					(thickness 0.1524)
				)
			)
		)
		(property "Device Type" "R402H16"
			(at 0.064008 -5.517896 270)
			(unlocked yes)
			(layer "F.Fab")
			(hide yes)
			(effects
				(font
					(size 1.016 1.016)
					(thickness 0.1524)
				)
			)
		)
		(duplicate_pad_numbers_are_jumpers no)
		(fp_line
			(start -0.508 -0.9398)
			(end -0.508 0.9398)
			(stroke
				(width 0.1524)
				(type default)
			)
			(layer "F.SilkS")
		)
		(fp_line
			(start 0.508 -0.9398)
			(end -0.508 -0.9398)
			(stroke
				(width 0.1524)
				(type default)
			)
			(layer "F.SilkS")
		)
		(fp_rect
			(start -0.508 0.9398)
			(end 0.508 -0.9398)
			(stroke
				(width 0)
				(type default)
			)
			(fill no)
			(layer "F.CrtYd")
		)
		(fp_rect
			(start -0.508 0.9398)
			(end 0.508 -0.9398)
			(stroke
				(width 0)
				(type default)
			)
			(fill no)
			(layer "F.Fab")
		)
		(pad "1" smd custom
			(at 0 -0.4445 270)
			(size 0.1397 0.1397)
			(layers "F.Cu" "F.Mask" "F.Paste")
			(net "SYS_DBMODE3")
			(options
				(clearance outline)
				(anchor circle)
			)
			(primitives
				(gr_poly
					(pts
						(arc
							(start -0.1778 -0.2794)
							(mid -0.249642 -0.249642)
							(end -0.2794 -0.1778)
						)
						(arc
							(start -0.2794 0.1778)
							(mid -0.249642 0.249642)
							(end -0.1778 0.2794)
						)
						(arc
							(start 0.1778 0.2794)
							(mid 0.249642 0.249642)
							(end 0.2794 0.1778)
						)
						(arc
							(start 0.2794 -0.1778)
							(mid 0.249642 -0.249642)
							(end 0.1778 -0.2794)
						)
					)
					(width 0)
					(fill yes)
				)
			)
		)
		(pad "2" smd custom
			(at 0 0.4445 270)
			(size 0.1397 0.1397)
			(layers "F.Cu" "F.Mask" "F.Paste")
			(net "GND")
			(options
				(clearance outline)
				(anchor circle)
			)
			(primitives
				(gr_poly
					(pts
						(arc
							(start -0.1778 -0.2794)
							(mid -0.249642 -0.249642)
							(end -0.2794 -0.1778)
						)
						(arc
							(start -0.2794 0.1778)
							(mid -0.249642 0.249642)
							(end -0.1778 0.2794)
						)
						(arc
							(start 0.1778 0.2794)
							(mid 0.249642 0.249642)
							(end 0.2794 0.1778)
						)
						(arc
							(start 0.2794 -0.1778)
							(mid 0.249642 -0.249642)
							(end 0.1778 -0.2794)
						)
					)
					(width 0)
					(fill yes)
				)
			)
		)
	)
	(footprint ""
		(layer "F.Cu")
		(at 80.626966 -84.963 90)
		(property "Reference" "SR830"
			(at 0 0 90)
			(layer "F.SilkS")
			(hide yes)
			(effects
				(font
					(size 1.27 1.27)
				)
			)
		)
		(property "Value" "10R2F-L-GP"
			(at 0.064008 -3.993896 90)
			(unlocked yes)
			(layer "F.Fab")
			(hide yes)
			(effects
				(font
					(size 1.016 1.016)
					(thickness 0.1524)
				)
			)
		)
		(property "Device Type" "R402H14"
			(at 0.064008 -5.517896 90)
			(unlocked yes)
			(layer "F.Fab")
			(hide yes)
			(effects
				(font
					(size 1.016 1.016)
					(thickness 0.1524)
				)
			)
		)
		(duplicate_pad_numbers_are_jumpers no)
		(fp_line
			(start 0.508 -0.9398)
			(end -0.508 -0.9398)
			(stroke
				(width 0.1524)
				(type default)
			)
			(layer "F.SilkS")
		)
		(fp_line
			(start -0.508 -0.9398)
			(end -0.508 0.9398)
			(stroke
				(width 0.1524)
				(type default)
			)
			(layer "F.SilkS")
		)
		(fp_rect
			(start -0.508 0.9398)
			(end 0.508 -0.9398)
			(stroke
				(width 0)
				(type default)
			)
			(fill no)
			(layer "F.CrtYd")
		)
		(fp_rect
			(start -0.508 0.9398)
			(end 0.508 -0.9398)
			(stroke
				(width 0)
				(type default)
			)
			(fill no)
			(layer "F.Fab")
		)
		(pad "1" smd custom
			(at 0 -0.4445 90)
			(size 0.1397 0.1397)
			(layers "F.Cu" "F.Mask" "F.Paste")
			(net "P1V8_E")
			(options
				(clearance outline)
				(anchor circle)
			)
			(primitives
				(gr_poly
					(pts
						(arc
							(start -0.1778 -0.2794)
							(mid -0.249642 -0.249642)
							(end -0.2794 -0.1778)
						)
						(arc
							(start -0.2794 0.1778)
							(mid -0.249642 0.249642)
							(end -0.1778 0.2794)
						)
						(arc
							(start 0.1778 0.2794)
							(mid 0.249642 0.249642)
							(end 0.2794 0.1778)
						)
						(arc
							(start 0.2794 -0.1778)
							(mid 0.249642 -0.249642)
							(end 0.1778 -0.2794)
						)
					)
					(width 0)
					(fill yes)
				)
			)
		)
		(pad "2" smd custom
			(at 0 0.4445 90)
			(size 0.1397 0.1397)
			(layers "F.Cu" "F.Mask" "F.Paste")
			(net "PLLDDR_VDDA18")
			(options
				(clearance outline)
				(anchor circle)
			)
			(primitives
				(gr_poly
					(pts
						(arc
							(start -0.1778 -0.2794)
							(mid -0.249642 -0.249642)
							(end -0.2794 -0.1778)
						)
						(arc
							(start -0.2794 0.1778)
							(mid -0.249642 0.249642)
							(end -0.1778 0.2794)
						)
						(arc
							(start 0.1778 0.2794)
							(mid 0.249642 0.249642)
							(end 0.2794 0.1778)
						)
						(arc
							(start 0.2794 -0.1778)
							(mid 0.249642 -0.249642)
							(end 0.1778 -0.2794)
						)
					)
					(width 0)
					(fill yes)
				)
			)
		)
	)
	(footprint ""
		(layer "F.Cu")
		(at 258.699 -71.501 -90)
		(property "Reference" "C310"
			(at 0 0 270)
			(layer "F.SilkS")
			(hide yes)
			(effects
				(font
					(size 1.27 1.27)
				)
			)
		)
		(property "Value" "SCD1U25V2KX-2-GP"
			(at 1.1811 -2.7051 270)
			(unlocked yes)
			(layer "F.Fab")
			(hide yes)
			(effects
				(font
					(size 1.016 1.016)
					(thickness 0.1524)
				)
			)
		)
		(property "Device Type" "C402H22"
			(at 1.1811 -4.2291 270)
			(unlocked yes)
			(layer "F.Fab")
			(hide yes)
			(effects
				(font
					(size 1.016 1.016)
					(thickness 0.1524)
				)
			)
		)
		(duplicate_pad_numbers_are_jumpers no)
		(fp_rect
			(start -0.4318 0.9525)
			(end 0.4318 -0.9525)
			(stroke
				(width 0)
				(type default)
			)
			(fill no)
			(layer "F.CrtYd")
		)
		(fp_rect
			(start -0.4318 0.9525)
			(end 0.4318 -0.9525)
			(stroke
				(width 0)
				(type default)
			)
			(fill no)
			(layer "F.Fab")
		)
		(pad "1" smd custom
			(at 0 -0.4445 270)
			(size 0.1524 0.1524)
			(layers "F.Cu" "F.Mask" "F.Paste")
			(net "P12V_MSB")
			(options
				(clearance outline)
				(anchor circle)
			)
			(primitives
				(gr_poly
					(pts
						(arc
							(start 0.3048 -0.2032)
							(mid 0.275042 -0.275042)
							(end 0.2032 -0.3048)
						)
						(arc
							(start -0.2032 -0.3048)
							(mid -0.275042 -0.275042)
							(end -0.3048 -0.2032)
						)
						(arc
							(start -0.3048 0.2032)
							(mid -0.275042 0.275042)
							(end -0.2032 0.3048)
						)
						(arc
							(start 0.2032 0.3048)
							(mid 0.275042 0.275042)
							(end 0.3048 0.2032)
						)
					)
					(width 0)
					(fill yes)
				)
			)
		)
		(pad "2" smd custom
			(at 0 0.4445 270)
			(size 0.1524 0.1524)
			(layers "F.Cu" "F.Mask" "F.Paste")
			(net "GND")
			(options
				(clearance outline)
				(anchor circle)
			)
			(primitives
				(gr_poly
					(pts
						(arc
							(start 0.3048 -0.2032)
							(mid 0.275042 -0.275042)
							(end 0.2032 -0.3048)
						)
						(arc
							(start -0.2032 -0.3048)
							(mid -0.275042 -0.275042)
							(end -0.3048 -0.2032)
						)
						(arc
							(start -0.3048 0.2032)
							(mid -0.275042 0.275042)
							(end -0.2032 0.3048)
						)
						(arc
							(start 0.2032 0.3048)
							(mid 0.275042 0.275042)
							(end 0.3048 0.2032)
						)
					)
					(width 0)
					(fill yes)
				)
			)
		)
	)
	(footprint ""
		(layer "F.Cu")
		(at 219.828872 -179.904136 180)
		(property "Reference" "R493"
			(at 0 0 180)
			(layer "F.SilkS")
			(hide yes)
			(effects
				(font
					(size 1.27 1.27)
				)
			)
		)
		(property "Value" "4K7R2F-GP"
			(at 0.064008 -3.993896 180)
			(unlocked yes)
			(layer "F.Fab")
			(hide yes)
			(effects
				(font
					(size 1.016 1.016)
					(thickness 0.1524)
				)
			)
		)
		(property "Device Type" "R402H16"
			(at 0.064008 -5.517896 180)
			(unlocked yes)
			(layer "F.Fab")
			(hide yes)
			(effects
				(font
					(size 1.016 1.016)
					(thickness 0.1524)
				)
			)
		)
		(duplicate_pad_numbers_are_jumpers no)
		(fp_line
			(start 0.508 -0.9398)
			(end -0.508 -0.9398)
			(stroke
				(width 0.1524)
				(type default)
			)
			(layer "F.SilkS")
		)
		(fp_line
			(start -0.508 -0.9398)
			(end -0.508 0.9398)
			(stroke
				(width 0.1524)
				(type default)
			)
			(layer "F.SilkS")
		)
		(fp_rect
			(start -0.508 0.9398)
			(end 0.508 -0.9398)
			(stroke
				(width 0)
				(type default)
			)
			(fill no)
			(layer "F.CrtYd")
		)
		(fp_rect
			(start -0.508 0.9398)
			(end 0.508 -0.9398)
			(stroke
				(width 0)
				(type default)
			)
			(fill no)
			(layer "F.Fab")
		)
		(pad "1" smd custom
			(at 0 -0.4445 180)
			(size 0.1397 0.1397)
			(layers "F.Cu" "F.Mask" "F.Paste")
			(net "DIVIDER 1_IN_EXP")
			(options
				(clearance outline)
				(anchor circle)
			)
			(primitives
				(gr_poly
					(pts
						(arc
							(start -0.1778 -0.2794)
							(mid -0.249642 -0.249642)
							(end -0.2794 -0.1778)
						)
						(arc
							(start -0.2794 0.1778)
							(mid -0.249642 0.249642)
							(end -0.1778 0.2794)
						)
						(arc
							(start 0.1778 0.2794)
							(mid 0.249642 0.249642)
							(end 0.2794 0.1778)
						)
						(arc
							(start 0.2794 -0.1778)
							(mid 0.249642 -0.249642)
							(end 0.1778 -0.2794)
						)
					)
					(width 0)
					(fill yes)
				)
			)
		)
		(pad "2" smd custom
			(at 0 0.4445 180)
			(size 0.1397 0.1397)
			(layers "F.Cu" "F.Mask" "F.Paste")
			(net "DIVIDER 2_IN_EXP")
			(options
				(clearance outline)
				(anchor circle)
			)
			(primitives
				(gr_poly
					(pts
						(arc
							(start -0.1778 -0.2794)
							(mid -0.249642 -0.249642)
							(end -0.2794 -0.1778)
						)
						(arc
							(start -0.2794 0.1778)
							(mid -0.249642 0.249642)
							(end -0.1778 0.2794)
						)
						(arc
							(start 0.1778 0.2794)
							(mid 0.249642 0.249642)
							(end 0.2794 0.1778)
						)
						(arc
							(start 0.2794 -0.1778)
							(mid 0.249642 -0.249642)
							(end 0.1778 -0.2794)
						)
					)
					(width 0)
					(fill yes)
				)
			)
		)
	)
	(footprint ""
		(layer "F.Cu")
		(at 152.247092 -95.914464 -90)
		(property "Reference" "SL19"
			(at 0 0 270)
			(layer "F.SilkS")
			(hide yes)
			(effects
				(font
					(size 1.27 1.27)
				)
			)
		)
		(property "Value" "MPZ2012S300AT-GP"
			(at 0 -4.2418 270)
			(unlocked yes)
			(layer "F.Fab")
			(hide yes)
			(effects
				(font
					(size 1.016 1.016)
					(thickness 0.1524)
				)
			)
		)
		(property "Device Type" "L805H42"
			(at 0 -5.7912 270)
			(unlocked yes)
			(layer "F.Fab")
			(hide yes)
			(effects
				(font
					(size 1.016 1.016)
					(thickness 0.1524)
				)
			)
		)
		(duplicate_pad_numbers_are_jumpers no)
		(fp_line
			(start -0.889 1.7018)
			(end -0.889 -1.7018)
			(stroke
				(width 0.1524)
				(type default)
			)
			(layer "F.SilkS")
		)
		(fp_line
			(start 0.889 1.7018)
			(end -0.889 1.7018)
			(stroke
				(width 0.1524)
				(type default)
			)
			(layer "F.SilkS")
		)
		(fp_line
			(start -0.889 -1.7018)
			(end 0.889 -1.7018)
			(stroke
				(width 0.1524)
				(type default)
			)
			(layer "F.SilkS")
		)
		(fp_line
			(start 0.889 -1.7018)
			(end 0.889 1.7018)
			(stroke
				(width 0.1524)
				(type default)
			)
			(layer "F.SilkS")
		)
		(fp_rect
			(start -0.9652 1.778)
			(end 0.9652 -1.778)
			(stroke
				(width 0)
				(type default)
			)
			(fill no)
			(layer "F.CrtYd")
		)
		(fp_rect
			(start -0.9652 1.778)
			(end 0.9652 -1.778)
			(stroke
				(width 0)
				(type default)
			)
			(fill no)
			(layer "F.Fab")
		)
		(pad "1" smd rect
			(at 0 -0.9652 270)
			(size 1.397 1.143)
			(layers "F.Cu" "F.Mask" "F.Paste")
			(net "P0V9_E")
		)
		(pad "2" smd rect
			(at 0 0.9652 270)
			(size 1.397 1.143)
			(layers "F.Cu" "F.Mask" "F.Paste")
			(net "GB_VDDA")
		)
	)
	(footprint ""
		(layer "F.Cu")
		(at 222.758 -157.282388)
		(property "Reference" "Q17"
			(at 0 0 0)
			(layer "F.SilkS")
			(hide yes)
			(effects
				(font
					(size 1.27 1.27)
				)
			)
		)
		(property "Value" "2N7002A-7-GP"
			(at 0.127 -8.9662 0)
			(unlocked yes)
			(layer "F.Fab")
			(hide yes)
			(effects
				(font
					(size 1.016 1.016)
					(thickness 0.1524)
				)
			)
		)
		(property "Device Type" "SOT23DGS2D4H48"
			(at 0.127 -10.4902 0)
			(unlocked yes)
			(layer "F.Fab")
			(hide yes)
			(effects
				(font
					(size 1.016 1.016)
					(thickness 0.1524)
				)
			)
		)
		(duplicate_pad_numbers_are_jumpers no)
		(fp_line
			(start -1.651 -1.778)
			(end -1.651 1.778)
			(stroke
				(width 0.1524)
				(type default)
			)
			(layer "F.SilkS")
		)
		(fp_line
			(start -1.651 1.778)
			(end 1.651 1.778)
			(stroke
				(width 0.1524)
				(type default)
			)
			(layer "F.SilkS")
		)
		(fp_line
			(start 1.651 -1.778)
			(end -1.651 -1.778)
			(stroke
				(width 0.1524)
				(type default)
			)
			(layer "F.SilkS")
		)
		(fp_line
			(start 1.651 1.778)
			(end 1.651 -1.778)
			(stroke
				(width 0.1524)
				(type default)
			)
			(layer "F.SilkS")
		)
		(fp_poly
			(pts
				(xy -1.778 1.8796) (xy -1.778 -1.8796) (xy 1.778 -1.8796) (xy 1.778 1.8796)
			)
			(stroke
				(width 0)
				(type default)
			)
			(fill no)
			(layer "F.CrtYd")
		)
		(fp_poly
			(pts
				(xy -1.778 1.8796) (xy -1.778 -1.8796) (xy 1.778 -1.8796) (xy 1.778 1.8796)
			)
			(stroke
				(width 0)
				(type default)
			)
			(fill no)
			(layer "F.Fab")
		)
		(pad "D" smd custom
			(at 0 -0.9525)
			(size 0.1905 0.1905)
			(layers "F.Cu" "F.Mask" "F.Paste")
			(net "JTAG_DT")
			(options
				(clearance outline)
				(anchor circle)
			)
			(primitives
				(gr_poly
					(pts
						(arc
							(start -0.1778 0.5715)
							(mid -0.321484 0.511984)
							(end -0.381 0.3683)
						)
						(arc
							(start -0.381 -0.3683)
							(mid -0.321484 -0.511984)
							(end -0.1778 -0.5715)
						)
						(arc
							(start 0.1778 -0.5715)
							(mid 0.321484 -0.511984)
							(end 0.381 -0.3683)
						)
						(arc
							(start 0.381 0.3683)
							(mid 0.321484 0.511984)
							(end 0.1778 0.5715)
						)
					)
					(width 0)
					(fill yes)
				)
			)
		)
		(pad "G" smd custom
			(at -0.98425 0.9525)
			(size 0.1905 0.1905)
			(layers "F.Cu" "F.Mask" "F.Paste")
			(net "BMC_JTAG_L")
			(options
				(clearance outline)
				(anchor circle)
			)
			(primitives
				(gr_poly
					(pts
						(arc
							(start -0.1778 0.5715)
							(mid -0.321484 0.511984)
							(end -0.381 0.3683)
						)
						(arc
							(start -0.381 -0.3683)
							(mid -0.321484 -0.511984)
							(end -0.1778 -0.5715)
						)
						(arc
							(start 0.1778 -0.5715)
							(mid 0.321484 -0.511984)
							(end 0.381 -0.3683)
						)
						(arc
							(start 0.381 0.3683)
							(mid 0.321484 0.511984)
							(end 0.1778 0.5715)
						)
					)
					(width 0)
					(fill yes)
				)
			)
		)
		(pad "S" smd custom
			(at 0.98425 0.9525)
			(size 0.1905 0.1905)
			(layers "F.Cu" "F.Mask" "F.Paste")
			(net "GND")
			(options
				(clearance outline)
				(anchor circle)
			)
			(primitives
				(gr_poly
					(pts
						(arc
							(start -0.1778 0.5715)
							(mid -0.321484 0.511984)
							(end -0.381 0.3683)
						)
						(arc
							(start -0.381 -0.3683)
							(mid -0.321484 -0.511984)
							(end -0.1778 -0.5715)
						)
						(arc
							(start 0.1778 -0.5715)
							(mid 0.321484 -0.511984)
							(end 0.381 -0.3683)
						)
						(arc
							(start 0.381 0.3683)
							(mid 0.321484 0.511984)
							(end 0.1778 0.5715)
						)
					)
					(width 0)
					(fill yes)
				)
			)
		)
	)
	(footprint ""
		(layer "F.Cu")
		(at 348.390718 -143.233648)
		(property "Reference" "C158"
			(at 0 0 0)
			(layer "F.SilkS")
			(hide yes)
			(effects
				(font
					(size 1.27 1.27)
				)
			)
		)
		(property "Value" "SC1U10V2KX-4-GP"
			(at 1.1811 -2.7051 0)
			(unlocked yes)
			(layer "F.Fab")
			(hide yes)
			(effects
				(font
					(size 1.016 1.016)
					(thickness 0.1524)
				)
			)
		)
		(property "Device Type" "C402H22"
			(at 1.1811 -4.2291 0)
			(unlocked yes)
			(layer "F.Fab")
			(hide yes)
			(effects
				(font
					(size 1.016 1.016)
					(thickness 0.1524)
				)
			)
		)
		(duplicate_pad_numbers_are_jumpers no)
		(fp_rect
			(start -0.4318 0.9525)
			(end 0.4318 -0.9525)
			(stroke
				(width 0)
				(type default)
			)
			(fill no)
			(layer "F.CrtYd")
		)
		(fp_rect
			(start -0.4318 0.9525)
			(end 0.4318 -0.9525)
			(stroke
				(width 0)
				(type default)
			)
			(fill no)
			(layer "F.Fab")
		)
		(pad "1" smd custom
			(at 0 -0.4445)
			(size 0.1524 0.1524)
			(layers "F.Cu" "F.Mask" "F.Paste")
			(net "P3V3_STBY")
			(options
				(clearance outline)
				(anchor circle)
			)
			(primitives
				(gr_poly
					(pts
						(arc
							(start 0.3048 -0.2032)
							(mid 0.275042 -0.275042)
							(end 0.2032 -0.3048)
						)
						(arc
							(start -0.2032 -0.3048)
							(mid -0.275042 -0.275042)
							(end -0.3048 -0.2032)
						)
						(arc
							(start -0.3048 0.2032)
							(mid -0.275042 0.275042)
							(end -0.2032 0.3048)
						)
						(arc
							(start 0.2032 0.3048)
							(mid 0.275042 0.275042)
							(end 0.3048 0.2032)
						)
					)
					(width 0)
					(fill yes)
				)
			)
		)
		(pad "2" smd custom
			(at 0 0.4445)
			(size 0.1524 0.1524)
			(layers "F.Cu" "F.Mask" "F.Paste")
			(net "GND")
			(options
				(clearance outline)
				(anchor circle)
			)
			(primitives
				(gr_poly
					(pts
						(arc
							(start 0.3048 -0.2032)
							(mid 0.275042 -0.275042)
							(end 0.2032 -0.3048)
						)
						(arc
							(start -0.2032 -0.3048)
							(mid -0.275042 -0.275042)
							(end -0.3048 -0.2032)
						)
						(arc
							(start -0.3048 0.2032)
							(mid -0.275042 0.275042)
							(end -0.2032 0.3048)
						)
						(arc
							(start 0.2032 0.3048)
							(mid 0.275042 0.275042)
							(end 0.3048 0.2032)
						)
					)
					(width 0)
					(fill yes)
				)
			)
		)
	)
	(footprint ""
		(layer "F.Cu")
		(at 197.821296 -86.372192)
		(property "Reference" "SC1131"
			(at 0 0 0)
			(layer "F.SilkS")
			(hide yes)
			(effects
				(font
					(size 1.27 1.27)
				)
			)
		)
		(property "Value" "SC100U6D3V0MX-2GP"
			(at -0.00254 -4.78536 0)
			(unlocked yes)
			(layer "F.Fab")
			(hide yes)
			(effects
				(font
					(size 1.016 1.016)
					(thickness 0.1524)
				)
			)
		)
		(property "Device Type" "C1210H107"
			(at -0.00254 -6.38048 0)
			(unlocked yes)
			(layer "F.Fab")
			(hide yes)
			(effects
				(font
					(size 1.016 1.016)
					(thickness 0.1524)
				)
			)
		)
		(duplicate_pad_numbers_are_jumpers no)
		(fp_line
			(start -1.5748 -2.3368)
			(end -1.5748 -0.762)
			(stroke
				(width 0.1524)
				(type default)
			)
			(layer "F.SilkS")
		)
		(fp_line
			(start -1.5748 0.762)
			(end -1.5748 2.3368)
			(stroke
				(width 0.1524)
				(type default)
			)
			(layer "F.SilkS")
		)
		(fp_line
			(start -1.5748 2.3368)
			(end 1.5748 2.3368)
			(stroke
				(width 0.1524)
				(type default)
			)
			(layer "F.SilkS")
		)
		(fp_line
			(start 1.5748 -2.3368)
			(end -1.5748 -2.3368)
			(stroke
				(width 0.1524)
				(type default)
			)
			(layer "F.SilkS")
		)
		(fp_line
			(start 1.5748 -0.762)
			(end 1.5748 -2.3368)
			(stroke
				(width 0.1524)
				(type default)
			)
			(layer "F.SilkS")
		)
		(fp_line
			(start 1.5748 2.3368)
			(end 1.5748 0.762)
			(stroke
				(width 0.1524)
				(type default)
			)
			(layer "F.SilkS")
		)
		(fp_rect
			(start -1.651 2.413)
			(end 1.651 -2.413)
			(stroke
				(width 0)
				(type default)
			)
			(fill no)
			(layer "F.CrtYd")
		)
		(fp_poly
			(pts
				(xy 1.651 2.413) (xy 1.651 -2.413) (xy -1.651 -2.413) (xy -1.651 2.413)
			)
			(stroke
				(width 0)
				(type default)
			)
			(fill no)
			(layer "F.Fab")
		)
		(pad "1" smd rect
			(at 0 -1.4732)
			(size 2.794 1.397)
			(layers "F.Cu" "F.Mask" "F.Paste")
			(net "GND")
		)
		(pad "2" smd rect
			(at 0 1.4732)
			(size 2.794 1.397)
			(layers "F.Cu" "F.Mask" "F.Paste")
			(net "GB_VDDH2")
		)
	)
	(footprint ""
		(layer "F.Cu")
		(at 305.435 -184.785)
		(property "Reference" "TP113"
			(at 0 0 0)
			(layer "F.SilkS")
			(hide yes)
			(effects
				(font
					(size 1.27 1.27)
				)
			)
		)
		(property "Value" "TPAD28"
			(at 0.0127 -1.8034 0)
			(unlocked yes)
			(layer "F.Fab")
			(hide yes)
			(effects
				(font
					(size 1.016 1.016)
					(thickness 0.1524)
				)
			)
		)
		(property "Device Type" "TPAD28"
			(at 0.0127 -3.3274 0)
			(unlocked yes)
			(layer "F.Fab")
			(hide yes)
			(effects
				(font
					(size 1.016 1.016)
					(thickness 0.1524)
				)
			)
		)
		(duplicate_pad_numbers_are_jumpers no)
		(fp_poly
			(pts
				(arc
					(start 0.3556 0)
					(mid -0.3556 0)
					(end 0.3556 0)
				)
			)
			(stroke
				(width 0)
				(type default)
			)
			(fill no)
			(layer "F.CrtYd")
		)
		(fp_poly
			(pts
				(arc
					(start 0.6096 0)
					(mid -0.6096 0)
					(end 0.6096 0)
				)
			)
			(stroke
				(width 0)
				(type default)
			)
			(fill no)
			(layer "F.Fab")
		)
		(pad "1" smd circle
			(at 0 0)
			(size 0.7112 0.7112)
			(layers "F.Cu" "F.Mask" "F.Paste")
			(net "TP_BMC_GPIOM6")
		)
	)
	(footprint ""
		(layer "F.Cu")
		(at 179.052982 -24.929338)
		(property "Reference" "TP131"
			(at 0 0 0)
			(layer "F.SilkS")
			(hide yes)
			(effects
				(font
					(size 1.27 1.27)
				)
			)
		)
		(property "Value" "TPAD28"
			(at 0.0127 -1.8034 0)
			(unlocked yes)
			(layer "F.Fab")
			(hide yes)
			(effects
				(font
					(size 1.016 1.016)
					(thickness 0.1524)
				)
			)
		)
		(property "Device Type" "TPAD28"
			(at 0.0127 -3.3274 0)
			(unlocked yes)
			(layer "F.Fab")
			(hide yes)
			(effects
				(font
					(size 1.016 1.016)
					(thickness 0.1524)
				)
			)
		)
		(duplicate_pad_numbers_are_jumpers no)
		(fp_poly
			(pts
				(arc
					(start 0.3556 0)
					(mid -0.3556 0)
					(end 0.3556 0)
				)
			)
			(stroke
				(width 0)
				(type default)
			)
			(fill no)
			(layer "F.CrtYd")
		)
		(fp_poly
			(pts
				(arc
					(start 0.6096 0)
					(mid -0.6096 0)
					(end 0.6096 0)
				)
			)
			(stroke
				(width 0)
				(type default)
			)
			(fill no)
			(layer "F.Fab")
		)
		(pad "1" smd circle
			(at 0 0)
			(size 0.7112 0.7112)
			(layers "F.Cu" "F.Mask" "F.Paste")
			(net "NC_PHY_BMC_INTR_N")
		)
	)
	(footprint ""
		(layer "F.Cu")
		(at 204.597 -92.329)
		(property "Reference" "PG5"
			(at 0 0 0)
			(layer "F.SilkS")
			(hide yes)
			(effects
				(font
					(size 1.27 1.27)
				)
			)
		)
		(property "Value" "GAP-CLOSE-PWR-4-GP"
			(at -2.4638 -0.5461 0)
			(unlocked yes)
			(layer "F.Fab")
			(hide yes)
			(effects
				(font
					(size 1.016 1.016)
					(thickness 0.1524)
				)
			)
		)
		(property "Device Type" "GAP-CLOSE-PWR-4"
			(at -2.4638 -2.0701 0)
			(unlocked yes)
			(layer "F.Fab")
			(hide yes)
			(effects
				(font
					(size 1.016 1.016)
					(thickness 0.1524)
				)
			)
		)
		(duplicate_pad_numbers_are_jumpers no)
		(fp_rect
			(start -0.2794 0.254)
			(end 0.2794 -0.254)
			(stroke
				(width 0)
				(type default)
			)
			(fill no)
			(layer "F.CrtYd")
		)
		(fp_rect
			(start -0.2794 0.254)
			(end 0.2794 -0.254)
			(stroke
				(width 0)
				(type default)
			)
			(fill no)
			(layer "F.Fab")
		)
		(pad "1" smd rect
			(at -0.0635 0)
			(size 0.1778 0.254)
			(layers "F.Cu" "F.Mask" "F.Paste")
			(net "P1V5_E")
		)
		(pad "2" smd rect
			(at 0.0635 0)
			(size 0.1778 0.254)
			(layers "F.Cu" "F.Mask" "F.Paste")
			(net "P1V5_E_CC")
		)
	)
	(footprint ""
		(layer "F.Cu")
		(at 324.358 -182.372)
		(property "Reference" "R5767"
			(at 0 0 0)
			(layer "F.SilkS")
			(hide yes)
			(effects
				(font
					(size 1.27 1.27)
				)
			)
		)
		(property "Value" "1KR2F-3-GP"
			(at 0.064008 -3.993896 0)
			(unlocked yes)
			(layer "F.Fab")
			(hide yes)
			(effects
				(font
					(size 1.016 1.016)
					(thickness 0.1524)
				)
			)
		)
		(property "Device Type" "R402H16"
			(at 0.064008 -5.517896 0)
			(unlocked yes)
			(layer "F.Fab")
			(hide yes)
			(effects
				(font
					(size 1.016 1.016)
					(thickness 0.1524)
				)
			)
		)
		(duplicate_pad_numbers_are_jumpers no)
		(fp_line
			(start -0.508 -0.9398)
			(end -0.508 0.9398)
			(stroke
				(width 0.1524)
				(type default)
			)
			(layer "F.SilkS")
		)
		(fp_line
			(start 0.508 -0.9398)
			(end -0.508 -0.9398)
			(stroke
				(width 0.1524)
				(type default)
			)
			(layer "F.SilkS")
		)
		(fp_rect
			(start -0.508 0.9398)
			(end 0.508 -0.9398)
			(stroke
				(width 0)
				(type default)
			)
			(fill no)
			(layer "F.CrtYd")
		)
		(fp_rect
			(start -0.508 0.9398)
			(end 0.508 -0.9398)
			(stroke
				(width 0)
				(type default)
			)
			(fill no)
			(layer "F.Fab")
		)
		(pad "1" smd custom
			(at 0 -0.4445)
			(size 0.1397 0.1397)
			(layers "F.Cu" "F.Mask" "F.Paste")
			(net "ADC_P1V8_STBY")
			(options
				(clearance outline)
				(anchor circle)
			)
			(primitives
				(gr_poly
					(pts
						(arc
							(start -0.1778 -0.2794)
							(mid -0.249642 -0.249642)
							(end -0.2794 -0.1778)
						)
						(arc
							(start -0.2794 0.1778)
							(mid -0.249642 0.249642)
							(end -0.1778 0.2794)
						)
						(arc
							(start 0.1778 0.2794)
							(mid 0.249642 0.249642)
							(end 0.2794 0.1778)
						)
						(arc
							(start 0.2794 -0.1778)
							(mid 0.249642 -0.249642)
							(end 0.1778 -0.2794)
						)
					)
					(width 0)
					(fill yes)
				)
			)
		)
		(pad "2" smd custom
			(at 0 0.4445)
			(size 0.1397 0.1397)
			(layers "F.Cu" "F.Mask" "F.Paste")
			(net "GND")
			(options
				(clearance outline)
				(anchor circle)
			)
			(primitives
				(gr_poly
					(pts
						(arc
							(start -0.1778 -0.2794)
							(mid -0.249642 -0.249642)
							(end -0.2794 -0.1778)
						)
						(arc
							(start -0.2794 0.1778)
							(mid -0.249642 0.249642)
							(end -0.1778 0.2794)
						)
						(arc
							(start 0.1778 0.2794)
							(mid 0.249642 0.249642)
							(end 0.2794 0.1778)
						)
						(arc
							(start 0.2794 -0.1778)
							(mid 0.249642 -0.249642)
							(end 0.1778 -0.2794)
						)
					)
					(width 0)
					(fill yes)
				)
			)
		)
	)
	(footprint ""
		(layer "F.Cu")
		(at 171.226988 -32.621728 180)
		(property "Reference" "C236"
			(at 0 0 180)
			(layer "F.SilkS")
			(hide yes)
			(effects
				(font
					(size 1.27 1.27)
				)
			)
		)
		(property "Value" "SCD1U16V2KX-3GP"
			(at 1.1811 -2.7051 180)
			(unlocked yes)
			(layer "F.Fab")
			(hide yes)
			(effects
				(font
					(size 1.016 1.016)
					(thickness 0.1524)
				)
			)
		)
		(property "Device Type" "C402H22"
			(at 1.1811 -4.2291 180)
			(unlocked yes)
			(layer "F.Fab")
			(hide yes)
			(effects
				(font
					(size 1.016 1.016)
					(thickness 0.1524)
				)
			)
		)
		(duplicate_pad_numbers_are_jumpers no)
		(fp_rect
			(start -0.4318 0.9525)
			(end 0.4318 -0.9525)
			(stroke
				(width 0)
				(type default)
			)
			(fill no)
			(layer "F.CrtYd")
		)
		(fp_rect
			(start -0.4318 0.9525)
			(end 0.4318 -0.9525)
			(stroke
				(width 0)
				(type default)
			)
			(fill no)
			(layer "F.Fab")
		)
		(pad "1" smd custom
			(at 0 -0.4445 180)
			(size 0.1524 0.1524)
			(layers "F.Cu" "F.Mask" "F.Paste")
			(net "MOD_IMC_FAB_D_COP")
			(options
				(clearance outline)
				(anchor circle)
			)
			(primitives
				(gr_poly
					(pts
						(arc
							(start 0.3048 -0.2032)
							(mid 0.275042 -0.275042)
							(end 0.2032 -0.3048)
						)
						(arc
							(start -0.2032 -0.3048)
							(mid -0.275042 -0.275042)
							(end -0.3048 -0.2032)
						)
						(arc
							(start -0.3048 0.2032)
							(mid -0.275042 0.275042)
							(end -0.2032 0.3048)
						)
						(arc
							(start 0.2032 0.3048)
							(mid 0.275042 0.275042)
							(end 0.3048 0.2032)
						)
					)
					(width 0)
					(fill yes)
				)
			)
		)
		(pad "2" smd custom
			(at 0 0.4445 180)
			(size 0.1524 0.1524)
			(layers "F.Cu" "F.Mask" "F.Paste")
			(net "GND")
			(options
				(clearance outline)
				(anchor circle)
			)
			(primitives
				(gr_poly
					(pts
						(arc
							(start 0.3048 -0.2032)
							(mid 0.275042 -0.275042)
							(end 0.2032 -0.3048)
						)
						(arc
							(start -0.2032 -0.3048)
							(mid -0.275042 -0.275042)
							(end -0.3048 -0.2032)
						)
						(arc
							(start -0.3048 0.2032)
							(mid -0.275042 0.275042)
							(end -0.2032 0.3048)
						)
						(arc
							(start 0.2032 0.3048)
							(mid 0.275042 0.275042)
							(end 0.3048 0.2032)
						)
					)
					(width 0)
					(fill yes)
				)
			)
		)
	)
	(footprint ""
		(layer "F.Cu")
		(at 277.358094 -25.791668 90)
		(property "Reference" "L8"
			(at 0 0 90)
			(layer "F.SilkS")
			(hide yes)
			(effects
				(font
					(size 1.27 1.27)
				)
			)
		)
		(property "Value" "DLW21HN900SQ2LGP-U"
			(at -0.0889 -2.7813 90)
			(unlocked yes)
			(layer "F.Fab")
			(hide yes)
			(effects
				(font
					(size 1.016 1.016)
					(thickness 0.1524)
				)
			)
		)
		(property "Device Type" "L2012-4P-1MH40"
			(at -0.0889 -4.3053 90)
			(unlocked yes)
			(layer "F.Fab")
			(hide yes)
			(effects
				(font
					(size 1.016 1.016)
					(thickness 0.1524)
				)
			)
		)
		(duplicate_pad_numbers_are_jumpers no)
		(fp_line
			(start 1.5494 -1.0668)
			(end 1.5494 1.0668)
			(stroke
				(width 0.1524)
				(type default)
			)
			(layer "F.SilkS")
		)
		(fp_line
			(start -1.5494 -1.0668)
			(end 1.5494 -1.0668)
			(stroke
				(width 0.1524)
				(type default)
			)
			(layer "F.SilkS")
		)
		(fp_line
			(start 1.5494 1.0668)
			(end -1.5494 1.0668)
			(stroke
				(width 0.1524)
				(type default)
			)
			(layer "F.SilkS")
		)
		(fp_line
			(start -1.5494 1.0668)
			(end -1.5494 -1.0668)
			(stroke
				(width 0.1524)
				(type default)
			)
			(layer "F.SilkS")
		)
		(fp_line
			(start 1.0668 1.1811)
			(end 0.6858 1.1811)
			(stroke
				(width 0.3302)
				(type default)
			)
			(layer "F.SilkS")
		)
		(fp_poly
			(pts
				(xy 1.500124 1.768856) (xy 0.230124 1.768856) (xy 0.865124 1.133856)
			)
			(stroke
				(width 0)
				(type default)
			)
			(fill yes)
			(layer "F.SilkS")
		)
		(fp_rect
			(start -1.0033 0.5969)
			(end 1.0033 -0.5969)
			(stroke
				(width 0)
				(type default)
			)
			(fill no)
			(layer "F.CrtYd")
		)
		(fp_poly
			(pts
				(xy -1.8034 1.3208) (xy -1.8034 -1.3208) (xy 1.8034 -1.3208) (xy 1.8034 0.0508) (xy 1.0033 0.0508)
				(xy 1.0033 -0.5969) (xy -1.0033 -0.5969) (xy -1.0033 0.5969) (xy 1.0033 0.5969) (xy 1.0033 0.0762)
				(xy 1.8034 0.0762) (xy 1.8034 1.3208)
			)
			(stroke
				(width 0)
				(type default)
			)
			(fill no)
			(layer "F.CrtYd")
		)
		(fp_rect
			(start -1.8034 1.3208)
			(end 1.8034 -1.3208)
			(stroke
				(width 0)
				(type default)
			)
			(fill no)
			(layer "F.Fab")
		)
		(pad "1" smd rect
			(at 0.8382 0.4826 90)
			(size 0.9144 0.6604)
			(layers "F.Cu" "F.Mask" "F.Paste")
			(net "USB_DP_R")
		)
		(pad "2" smd rect
			(at -0.8382 0.4826 90)
			(size 0.9144 0.6604)
			(layers "F.Cu" "F.Mask" "F.Paste")
			(net "USB_P1_F_DP1")
		)
		(pad "3" smd rect
			(at -0.8382 -0.4826 90)
			(size 0.9144 0.6604)
			(layers "F.Cu" "F.Mask" "F.Paste")
			(net "USB_P1_F_DN1")
		)
		(pad "4" smd rect
			(at 0.8382 -0.4826 90)
			(size 0.9144 0.6604)
			(layers "F.Cu" "F.Mask" "F.Paste")
			(net "USB_DN_R")
		)
		(zone
			(layer "F.Cu")
			(hatch none 0.5)
			(connect_pads
				(clearance 0)
			)
			(min_thickness 0.25)
			(keepout
				(tracks not_allowed)
				(vias allowed)
				(pads allowed)
				(copperpour not_allowed)
				(footprints allowed)
			)
			(placement
				(enabled no)
				(sheetname "")
			)
			(fill
				(thermal_gap 0.5)
				(thermal_bridge_width 0.5)
				(island_removal_mode 0)
			)
			(polygon
				(pts
					(xy 278.170894 -25.410668) (xy 277.510494 -25.410668) (xy 277.510494 -24.496268) (xy 277.205694 -24.496268)
					(xy 277.205694 -25.410668) (xy 276.545294 -25.410668) (xy 276.545294 -26.172668) (xy 277.205694 -26.172668)
					(xy 277.205694 -27.087068) (xy 277.510494 -27.087068) (xy 277.510494 -26.172668) (xy 278.170894 -26.172668)
				)
			)
		)
		(zone
			(layer "F.Cu")
			(hatch none 0.5)
			(connect_pads
				(clearance 0)
			)
			(min_thickness 0.25)
			(keepout
				(tracks allowed)
				(vias not_allowed)
				(pads allowed)
				(copperpour not_allowed)
				(footprints allowed)
			)
			(placement
				(enabled no)
				(sheetname "")
			)
			(fill
				(thermal_gap 0.5)
				(thermal_bridge_width 0.5)
				(island_removal_mode 0)
			)
			(polygon
				(pts
					(xy 278.170894 -25.410668) (xy 277.510494 -25.410668) (xy 277.510494 -24.496268) (xy 277.205694 -24.496268)
					(xy 277.205694 -25.410668) (xy 276.545294 -25.410668) (xy 276.545294 -26.172668) (xy 277.205694 -26.172668)
					(xy 277.205694 -27.087068) (xy 277.510494 -27.087068) (xy 277.510494 -26.172668) (xy 278.170894 -26.172668)
				)
			)
		)
	)
	(footprint ""
		(layer "F.Cu")
		(at 173.778164 -22.490176 90)
		(property "Reference" "R398"
			(at 0 0 90)
			(layer "F.SilkS")
			(hide yes)
			(effects
				(font
					(size 1.27 1.27)
				)
			)
		)
		(property "Value" "49D9R5F-2-GP"
			(at 0 -8.9535 90)
			(unlocked yes)
			(layer "F.Fab")
			(hide yes)
			(effects
				(font
					(size 1.27 1.016)
					(thickness 0.1524)
				)
			)
		)
		(property "Device Type" "R805H24"
			(at 0 -10.6299 90)
			(unlocked yes)
			(layer "F.Fab")
			(hide yes)
			(effects
				(font
					(size 1.27 1.016)
					(thickness 0.1524)
				)
			)
		)
		(duplicate_pad_numbers_are_jumpers no)
		(fp_line
			(start 0.889 -1.7018)
			(end -0.889 -1.7018)
			(stroke
				(width 0.1524)
				(type default)
			)
			(layer "F.SilkS")
		)
		(fp_line
			(start 0.889 -1.7018)
			(end 0.889 -0.381)
			(stroke
				(width 0.1524)
				(type default)
			)
			(layer "F.SilkS")
		)
		(fp_line
			(start -0.889 -1.7018)
			(end -0.889 0.2794)
			(stroke
				(width 0.1524)
				(type default)
			)
			(layer "F.SilkS")
		)
		(fp_line
			(start -0.889 0.0762)
			(end -0.889 1.7018)
			(stroke
				(width 0.1524)
				(type default)
			)
			(layer "F.SilkS")
		)
		(fp_line
			(start 0.889 1.7018)
			(end 0.889 -0.508)
			(stroke
				(width 0.1524)
				(type default)
			)
			(layer "F.SilkS")
		)
		(fp_line
			(start -0.889 1.7018)
			(end 0.889 1.7018)
			(stroke
				(width 0.1524)
				(type default)
			)
			(layer "F.SilkS")
		)
		(fp_poly
			(pts
				(xy 0.9652 -1.778) (xy 0.9652 1.778) (xy -0.9652 1.778) (xy -0.9652 -1.778)
			)
			(stroke
				(width 0)
				(type default)
			)
			(fill no)
			(layer "F.CrtYd")
		)
		(fp_rect
			(start -0.9652 1.778)
			(end 0.9652 -1.778)
			(stroke
				(width 0)
				(type default)
			)
			(fill no)
			(layer "F.Fab")
		)
		(pad "1" smd rect
			(at 0 -0.9652 90)
			(size 1.397 1.143)
			(layers "F.Cu" "F.Mask" "F.Paste")
			(net "P3V3_STBY")
		)
		(pad "2" smd rect
			(at 0 0.9652 90)
			(size 1.397 1.143)
			(layers "F.Cu" "F.Mask" "F.Paste")
			(net "BCM5221_TX_C_DP")
		)
	)
	(footprint ""
		(layer "F.Cu")
		(at 6.300216 -214.68588 -90)
		(property "Reference" "R623"
			(at 0 0 270)
			(layer "F.SilkS")
			(hide yes)
			(effects
				(font
					(size 1.27 1.27)
				)
			)
		)
		(property "Value" "10KR2F-2-GP"
			(at 0.064008 -3.993896 270)
			(unlocked yes)
			(layer "F.Fab")
			(hide yes)
			(effects
				(font
					(size 1.016 1.016)
					(thickness 0.1524)
				)
			)
		)
		(property "Device Type" "R402H16"
			(at 0.064008 -5.517896 270)
			(unlocked yes)
			(layer "F.Fab")
			(hide yes)
			(effects
				(font
					(size 1.016 1.016)
					(thickness 0.1524)
				)
			)
		)
		(duplicate_pad_numbers_are_jumpers no)
		(fp_line
			(start -0.508 -0.9398)
			(end -0.508 0.9398)
			(stroke
				(width 0.1524)
				(type default)
			)
			(layer "F.SilkS")
		)
		(fp_line
			(start 0.508 -0.9398)
			(end -0.508 -0.9398)
			(stroke
				(width 0.1524)
				(type default)
			)
			(layer "F.SilkS")
		)
		(fp_rect
			(start -0.508 0.9398)
			(end 0.508 -0.9398)
			(stroke
				(width 0)
				(type default)
			)
			(fill no)
			(layer "F.CrtYd")
		)
		(fp_rect
			(start -0.508 0.9398)
			(end 0.508 -0.9398)
			(stroke
				(width 0)
				(type default)
			)
			(fill no)
			(layer "F.Fab")
		)
		(pad "1" smd custom
			(at 0 -0.4445 270)
			(size 0.1397 0.1397)
			(layers "F.Cu" "F.Mask" "F.Paste")
			(net "PRSNT_AND_3")
			(options
				(clearance outline)
				(anchor circle)
			)
			(primitives
				(gr_poly
					(pts
						(arc
							(start -0.1778 -0.2794)
							(mid -0.249642 -0.249642)
							(end -0.2794 -0.1778)
						)
						(arc
							(start -0.2794 0.1778)
							(mid -0.249642 0.249642)
							(end -0.1778 0.2794)
						)
						(arc
							(start 0.1778 0.2794)
							(mid 0.249642 0.249642)
							(end 0.2794 0.1778)
						)
						(arc
							(start 0.2794 -0.1778)
							(mid 0.249642 -0.249642)
							(end 0.1778 -0.2794)
						)
					)
					(width 0)
					(fill yes)
				)
			)
		)
		(pad "2" smd custom
			(at 0 0.4445 270)
			(size 0.1397 0.1397)
			(layers "F.Cu" "F.Mask" "F.Paste")
			(net "GND")
			(options
				(clearance outline)
				(anchor circle)
			)
			(primitives
				(gr_poly
					(pts
						(arc
							(start -0.1778 -0.2794)
							(mid -0.249642 -0.249642)
							(end -0.2794 -0.1778)
						)
						(arc
							(start -0.2794 0.1778)
							(mid -0.249642 0.249642)
							(end -0.1778 0.2794)
						)
						(arc
							(start 0.1778 0.2794)
							(mid 0.249642 0.249642)
							(end 0.2794 0.1778)
						)
						(arc
							(start 0.2794 -0.1778)
							(mid 0.249642 -0.249642)
							(end 0.1778 -0.2794)
						)
					)
					(width 0)
					(fill yes)
				)
			)
		)
	)
	(footprint ""
		(layer "F.Cu")
		(at 340.868 -110.871)
		(property "Reference" "PU1"
			(at 0 0 0)
			(layer "F.SilkS")
			(hide yes)
			(effects
				(font
					(size 1.27 1.27)
				)
			)
		)
		(property "Value" "TPS53312RGTR-GP"
			(at 4.9784 -6.9342 0)
			(unlocked yes)
			(layer "F.Fab")
			(hide yes)
			(effects
				(font
					(size 1.016 1.016)
					(thickness 0.1524)
				)
			)
		)
		(property "Device Type" "QFN16G3-G1D7H40"
			(at 4.9784 -8.4582 0)
			(unlocked yes)
			(layer "F.Fab")
			(hide yes)
			(effects
				(font
					(size 1.016 1.016)
					(thickness 0.1524)
				)
			)
		)
		(duplicate_pad_numbers_are_jumpers no)
		(fp_line
			(start -2.5146 -2.5146)
			(end -2.5146 -1.2446)
			(stroke
				(width 0.1524)
				(type default)
			)
			(layer "F.SilkS")
		)
		(fp_line
			(start -2.5146 1.2446)
			(end -2.5146 2.5146)
			(stroke
				(width 0.1524)
				(type default)
			)
			(layer "F.SilkS")
		)
		(fp_line
			(start -2.5146 2.5146)
			(end -1.2446 2.5146)
			(stroke
				(width 0.1524)
				(type default)
			)
			(layer "F.SilkS")
		)
		(fp_line
			(start -2.262124 -0.750062)
			(end -2.770124 -0.750062)
			(stroke
				(width 0.1524)
				(type default)
			)
			(layer "F.SilkS")
		)
		(fp_line
			(start -1.2446 -2.5146)
			(end -2.5146 -2.5146)
			(stroke
				(width 0.1524)
				(type default)
			)
			(layer "F.SilkS")
		)
		(fp_line
			(start -0.249936 2.262124)
			(end -0.249936 3.024124)
			(stroke
				(width 0.1524)
				(type default)
			)
			(layer "F.SilkS")
		)
		(fp_line
			(start 1.2446 2.5146)
			(end 2.5146 2.5146)
			(stroke
				(width 0.1524)
				(type default)
			)
			(layer "F.SilkS")
		)
		(fp_line
			(start 2.262124 -0.249936)
			(end 2.770124 -0.249936)
			(stroke
				(width 0.1524)
				(type default)
			)
			(layer "F.SilkS")
		)
		(fp_line
			(start 2.5146 2.5146)
			(end 2.5146 1.2446)
			(stroke
				(width 0.1524)
				(type default)
			)
			(layer "F.SilkS")
		)
		(fp_poly
			(pts
				(xy 2.5146 -2.5146) (xy 1.2446 -2.5146) (xy 2.5146 -1.2446)
			)
			(stroke
				(width 0)
				(type default)
			)
			(fill yes)
			(layer "F.SilkS")
		)
		(fp_rect
			(start -1.4986 1.4986)
			(end 1.4986 -1.4986)
			(stroke
				(width 0)
				(type default)
			)
			(fill no)
			(layer "F.CrtYd")
		)
		(fp_poly
			(pts
				(xy 2.5146 -1.4986) (xy -1.4986 -1.4986) (xy -1.4986 1.4986) (xy 1.4986 1.4986) (xy 1.4986 -1.4859)
				(xy 2.5146 -1.4859) (xy 2.5146 2.5146) (xy -2.5146 2.5146) (xy -2.5146 -2.5146) (xy 2.5146 -2.5146)
			)
			(stroke
				(width 0)
				(type default)
			)
			(fill no)
			(layer "F.CrtYd")
		)
		(fp_rect
			(start -2.5146 2.5146)
			(end 2.5146 -2.5146)
			(stroke
				(width 0)
				(type default)
			)
			(fill no)
			(layer "F.Fab")
		)
		(pad "1" smd rect
			(at 0.750062 -1.550924)
			(size 0.3048 0.9144)
			(layers "F.Cu" "F.Mask" "F.Paste")
			(net "P5V_STBY_VFB")
		)
		(pad "2" smd rect
			(at 0.249936 -1.538224)
			(size 0.3048 0.9398)
			(layers "F.Cu" "F.Mask" "F.Paste")
			(net "P5V_STBY_VRG5")
		)
		(pad "3" smd rect
			(at -0.249936 -1.538224)
			(size 0.3048 0.9398)
			(layers "F.Cu" "F.Mask" "F.Paste")
			(net "P5V_STBY_SS")
		)
		(pad "4" smd rect
			(at -0.750062 -1.550924)
			(size 0.3048 0.9144)
			(layers "F.Cu" "F.Mask" "F.Paste")
			(net "AGND_P5V_STBY")
		)
		(pad "5" smd rect
			(at -1.550924 -0.750062)
			(size 0.9144 0.3048)
			(layers "F.Cu" "F.Mask" "F.Paste")
			(net "P5V_STBY_PG")
		)
		(pad "6" smd rect
			(at -1.538224 -0.249936)
			(size 0.9398 0.3048)
			(layers "F.Cu" "F.Mask" "F.Paste")
			(net "P5V_STBY_EN_R")
		)
		(pad "7" smd rect
			(at -1.538224 0.249936)
			(size 0.9398 0.3048)
			(layers "F.Cu" "F.Mask" "F.Paste")
			(net "GND")
		)
		(pad "8" smd rect
			(at -1.550924 0.750062)
			(size 0.9144 0.3048)
			(layers "F.Cu" "F.Mask" "F.Paste")
			(net "GND")
		)
		(pad "9" smd rect
			(at -0.750062 1.550924)
			(size 0.3048 0.9144)
			(layers "F.Cu" "F.Mask" "F.Paste")
			(net "P5V_STBY_SW")
		)
		(pad "10" smd rect
			(at -0.249936 1.538224)
			(size 0.3048 0.9398)
			(layers "F.Cu" "F.Mask" "F.Paste")
			(net "P5V_STBY_SW")
		)
		(pad "11" smd rect
			(at 0.249936 1.538224)
			(size 0.3048 0.9398)
			(layers "F.Cu" "F.Mask" "F.Paste")
			(net "P5V_STBY_SW")
		)
		(pad "12" smd rect
			(at 0.750062 1.550924)
			(size 0.3048 0.9144)
			(layers "F.Cu" "F.Mask" "F.Paste")
			(net "P5V_STBY_VBST")
		)
		(pad "13" smd rect
			(at 1.550924 0.750062)
			(size 0.9144 0.3048)
			(layers "F.Cu" "F.Mask" "F.Paste")
			(net "P5V_STBY_VIN")
		)
		(pad "14" smd rect
			(at 1.538224 0.249936)
			(size 0.9398 0.3048)
			(layers "F.Cu" "F.Mask" "F.Paste")
			(net "P5V_STBY_VIN")
		)
		(pad "15" smd rect
			(at 1.538224 -0.249936)
			(size 0.9398 0.3048)
			(layers "F.Cu" "F.Mask" "F.Paste")
			(net "P5V_STBY_VCC")
		)
		(pad "16" smd rect
			(at 1.550924 -0.750062)
			(size 0.9144 0.3048)
			(layers "F.Cu" "F.Mask" "F.Paste")
			(net "P5V_STBY_VO")
		)
		(pad "17" smd rect
			(at 0 0)
			(size 1.6764 1.6764)
			(layers "F.Cu" "F.Mask" "F.Paste")
			(net "GND")
		)
	)
	(footprint ""
		(layer "F.Cu")
		(at 301.371 -97.028)
		(property "Reference" "U134"
			(at 0 0 0)
			(layer "F.SilkS")
			(hide yes)
			(effects
				(font
					(size 1.27 1.27)
				)
			)
		)
		(property "Value" "TMP75AIDGKR-GP"
			(at -0.1143 -9.1948 0)
			(unlocked yes)
			(layer "F.Fab")
			(hide yes)
			(effects
				(font
					(size 1.016 1.016)
					(thickness 0.1524)
				)
			)
		)
		(property "Device Type" "MSOP8-1H44"
			(at -0.1143 -10.795 0)
			(unlocked yes)
			(layer "F.Fab")
			(hide yes)
			(effects
				(font
					(size 1.016 1.016)
					(thickness 0.1524)
				)
			)
		)
		(duplicate_pad_numbers_are_jumpers no)
		(fp_line
			(start -1.9558 -1.016)
			(end -1.9558 1.016)
			(stroke
				(width 0.1524)
				(type default)
			)
			(layer "F.SilkS")
		)
		(fp_line
			(start -1.9558 -0.5461)
			(end -1.4478 -0.0381)
			(stroke
				(width 0.1524)
				(type default)
			)
			(layer "F.SilkS")
		)
		(fp_line
			(start -1.9558 1.016)
			(end 1.0795 1.016)
			(stroke
				(width 0.1524)
				(type default)
			)
			(layer "F.SilkS")
		)
		(fp_line
			(start -1.778 1.0922)
			(end -1.778 3.048)
			(stroke
				(width 0.508)
				(type default)
			)
			(layer "F.SilkS")
		)
		(fp_line
			(start -1.4478 -0.0381)
			(end -1.9558 0.4699)
			(stroke
				(width 0.1524)
				(type default)
			)
			(layer "F.SilkS")
		)
		(fp_line
			(start 1.0795 -1.016)
			(end -1.9558 -1.016)
			(stroke
				(width 0.1524)
				(type default)
			)
			(layer "F.SilkS")
		)
		(fp_line
			(start 1.0795 1.016)
			(end 1.0795 -1.016)
			(stroke
				(width 0.1524)
				(type default)
			)
			(layer "F.SilkS")
		)
		(fp_poly
			(pts
				(xy -1.1557 -1.016) (xy -1.1557 1.016) (xy 1.1557 1.016) (xy 1.1557 -1.016)
			)
			(stroke
				(width 0)
				(type default)
			)
			(fill yes)
			(layer "F.SilkS")
		)
		(fp_rect
			(start -1.4986 2.4511)
			(end 1.4986 -2.4511)
			(stroke
				(width 0)
				(type default)
			)
			(fill no)
			(layer "F.CrtYd")
		)
		(fp_poly
			(pts
				(xy -2.032 3.302) (xy -2.032 -3.302) (xy 2.032 -3.302) (xy 2.032 -2.1209) (xy 1.4986 -2.1209) (xy 1.4986 -2.4511)
				(xy -1.4986 -2.4511) (xy -1.4986 2.4511) (xy 1.4986 2.4511) (xy 1.4986 -2.1082) (xy 2.032 -2.1082)
				(xy 2.032 3.302)
			)
			(stroke
				(width 0)
				(type default)
			)
			(fill no)
			(layer "F.CrtYd")
		)
		(fp_rect
			(start -2.032 3.302)
			(end 2.032 -3.302)
			(stroke
				(width 0)
				(type default)
			)
			(fill no)
			(layer "F.Fab")
		)
		(pad "1" smd rect
			(at -0.97536 2.05486)
			(size 0.3556 1.524)
			(layers "F.Cu" "F.Mask" "F.Paste")
			(net "TEMP_2_SDA")
		)
		(pad "2" smd rect
			(at -0.32512 2.05486)
			(size 0.3556 1.524)
			(layers "F.Cu" "F.Mask" "F.Paste")
			(net "TEMP_2_SCL")
		)
		(pad "3" smd rect
			(at 0.32512 2.05486)
			(size 0.3556 1.524)
			(layers "F.Cu" "F.Mask" "F.Paste")
			(net "TEMP_2_ALERT")
		)
		(pad "4" smd rect
			(at 0.97536 2.05486)
			(size 0.3556 1.524)
			(layers "F.Cu" "F.Mask" "F.Paste")
			(net "GND")
		)
		(pad "5" smd rect
			(at 0.97536 -2.05486)
			(size 0.3556 1.524)
			(layers "F.Cu" "F.Mask" "F.Paste")
			(net "TEMP_2_A2")
		)
		(pad "6" smd rect
			(at 0.32512 -2.05486)
			(size 0.3556 1.524)
			(layers "F.Cu" "F.Mask" "F.Paste")
			(net "TEMP_2_A1")
		)
		(pad "7" smd rect
			(at -0.32512 -2.05486)
			(size 0.3556 1.524)
			(layers "F.Cu" "F.Mask" "F.Paste")
			(net "TEMP_2_A0")
		)
		(pad "8" smd rect
			(at -0.97536 -2.05486)
			(size 0.3556 1.524)
			(layers "F.Cu" "F.Mask" "F.Paste")
			(net "P3V3_STBY")
		)
	)
	(footprint ""
		(layer "F.Cu")
		(at 186.554872 -194.051936 -90)
		(property "Reference" "R429"
			(at 0 0 270)
			(layer "F.SilkS")
			(hide yes)
			(effects
				(font
					(size 1.27 1.27)
				)
			)
		)
		(property "Value" "2KR2F-3-GP"
			(at 0.064008 -3.993896 270)
			(unlocked yes)
			(layer "F.Fab")
			(hide yes)
			(effects
				(font
					(size 1.016 1.016)
					(thickness 0.1524)
				)
			)
		)
		(property "Device Type" "R402H16"
			(at 0.064008 -5.517896 270)
			(unlocked yes)
			(layer "F.Fab")
			(hide yes)
			(effects
				(font
					(size 1.016 1.016)
					(thickness 0.1524)
				)
			)
		)
		(duplicate_pad_numbers_are_jumpers no)
		(fp_line
			(start -0.508 -0.9398)
			(end -0.508 0.9398)
			(stroke
				(width 0.1524)
				(type default)
			)
			(layer "F.SilkS")
		)
		(fp_line
			(start 0.508 -0.9398)
			(end -0.508 -0.9398)
			(stroke
				(width 0.1524)
				(type default)
			)
			(layer "F.SilkS")
		)
		(fp_rect
			(start -0.508 0.9398)
			(end 0.508 -0.9398)
			(stroke
				(width 0)
				(type default)
			)
			(fill no)
			(layer "F.CrtYd")
		)
		(fp_rect
			(start -0.508 0.9398)
			(end 0.508 -0.9398)
			(stroke
				(width 0)
				(type default)
			)
			(fill no)
			(layer "F.Fab")
		)
		(pad "1" smd custom
			(at 0 -0.4445 270)
			(size 0.1397 0.1397)
			(layers "F.Cu" "F.Mask" "F.Paste")
			(net "P3V3_STBY")
			(options
				(clearance outline)
				(anchor circle)
			)
			(primitives
				(gr_poly
					(pts
						(arc
							(start -0.1778 -0.2794)
							(mid -0.249642 -0.249642)
							(end -0.2794 -0.1778)
						)
						(arc
							(start -0.2794 0.1778)
							(mid -0.249642 0.249642)
							(end -0.1778 0.2794)
						)
						(arc
							(start 0.1778 0.2794)
							(mid 0.249642 0.249642)
							(end 0.2794 0.1778)
						)
						(arc
							(start 0.2794 -0.1778)
							(mid 0.249642 -0.249642)
							(end 0.1778 -0.2794)
						)
					)
					(width 0)
					(fill yes)
				)
			)
		)
		(pad "2" smd custom
			(at 0 0.4445 270)
			(size 0.1397 0.1397)
			(layers "F.Cu" "F.Mask" "F.Paste")
			(net "SAS_I2C_C_BUF_SDA")
			(options
				(clearance outline)
				(anchor circle)
			)
			(primitives
				(gr_poly
					(pts
						(arc
							(start -0.1778 -0.2794)
							(mid -0.249642 -0.249642)
							(end -0.2794 -0.1778)
						)
						(arc
							(start -0.2794 0.1778)
							(mid -0.249642 0.249642)
							(end -0.1778 0.2794)
						)
						(arc
							(start 0.1778 0.2794)
							(mid 0.249642 0.249642)
							(end 0.2794 0.1778)
						)
						(arc
							(start 0.2794 -0.1778)
							(mid 0.249642 -0.249642)
							(end 0.1778 -0.2794)
						)
					)
					(width 0)
					(fill yes)
				)
			)
		)
	)
	(footprint ""
		(layer "F.Cu")
		(at 103.886 -232.537 90)
		(property "Reference" "R595"
			(at 0 0 90)
			(layer "F.SilkS")
			(hide yes)
			(effects
				(font
					(size 1.27 1.27)
				)
			)
		)
		(property "Value" "0R2J-2-GP"
			(at 0.064008 -3.993896 90)
			(unlocked yes)
			(layer "F.Fab")
			(hide yes)
			(effects
				(font
					(size 1.016 1.016)
					(thickness 0.1524)
				)
			)
		)
		(property "Device Type" "R402H16"
			(at 0.064008 -5.517896 90)
			(unlocked yes)
			(layer "F.Fab")
			(hide yes)
			(effects
				(font
					(size 1.016 1.016)
					(thickness 0.1524)
				)
			)
		)
		(duplicate_pad_numbers_are_jumpers no)
		(fp_line
			(start 0.508 -0.9398)
			(end -0.508 -0.9398)
			(stroke
				(width 0.1524)
				(type default)
			)
			(layer "F.SilkS")
		)
		(fp_line
			(start -0.508 -0.9398)
			(end -0.508 0.9398)
			(stroke
				(width 0.1524)
				(type default)
			)
			(layer "F.SilkS")
		)
		(fp_rect
			(start -0.508 0.9398)
			(end 0.508 -0.9398)
			(stroke
				(width 0)
				(type default)
			)
			(fill no)
			(layer "F.CrtYd")
		)
		(fp_rect
			(start -0.508 0.9398)
			(end 0.508 -0.9398)
			(stroke
				(width 0)
				(type default)
			)
			(fill no)
			(layer "F.Fab")
		)
		(pad "1" smd custom
			(at 0 -0.4445 90)
			(size 0.1397 0.1397)
			(layers "F.Cu" "F.Mask" "F.Paste")
			(net "SAS_FAULT_LED6")
			(options
				(clearance outline)
				(anchor circle)
			)
			(primitives
				(gr_poly
					(pts
						(arc
							(start -0.1778 -0.2794)
							(mid -0.249642 -0.249642)
							(end -0.2794 -0.1778)
						)
						(arc
							(start -0.2794 0.1778)
							(mid -0.249642 0.249642)
							(end -0.1778 0.2794)
						)
						(arc
							(start 0.1778 0.2794)
							(mid 0.249642 0.249642)
							(end 0.2794 0.1778)
						)
						(arc
							(start 0.2794 -0.1778)
							(mid 0.249642 -0.249642)
							(end 0.1778 -0.2794)
						)
					)
					(width 0)
					(fill yes)
				)
			)
		)
		(pad "2" smd custom
			(at 0 0.4445 90)
			(size 0.1397 0.1397)
			(layers "F.Cu" "F.Mask" "F.Paste")
			(net "SAS_HDD_LED_6")
			(options
				(clearance outline)
				(anchor circle)
			)
			(primitives
				(gr_poly
					(pts
						(arc
							(start -0.1778 -0.2794)
							(mid -0.249642 -0.249642)
							(end -0.2794 -0.1778)
						)
						(arc
							(start -0.2794 0.1778)
							(mid -0.249642 0.249642)
							(end -0.1778 0.2794)
						)
						(arc
							(start 0.1778 0.2794)
							(mid 0.249642 0.249642)
							(end 0.2794 0.1778)
						)
						(arc
							(start 0.2794 -0.1778)
							(mid 0.249642 -0.249642)
							(end 0.1778 -0.2794)
						)
					)
					(width 0)
					(fill yes)
				)
			)
		)
	)
	(footprint ""
		(layer "F.Cu")
		(at 167.989504 -24.184356 180)
		(property "Reference" "R413"
			(at 0 0 180)
			(layer "F.SilkS")
			(hide yes)
			(effects
				(font
					(size 1.27 1.27)
				)
			)
		)
		(property "Value" "0R2J-2-GP"
			(at 0.064008 -3.993896 180)
			(unlocked yes)
			(layer "F.Fab")
			(hide yes)
			(effects
				(font
					(size 1.016 1.016)
					(thickness 0.1524)
				)
			)
		)
		(property "Device Type" "R402H16"
			(at 0.064008 -5.517896 180)
			(unlocked yes)
			(layer "F.Fab")
			(hide yes)
			(effects
				(font
					(size 1.016 1.016)
					(thickness 0.1524)
				)
			)
		)
		(duplicate_pad_numbers_are_jumpers no)
		(fp_line
			(start 0.508 -0.9398)
			(end -0.508 -0.9398)
			(stroke
				(width 0.1524)
				(type default)
			)
			(layer "F.SilkS")
		)
		(fp_line
			(start -0.508 -0.9398)
			(end -0.508 0.9398)
			(stroke
				(width 0.1524)
				(type default)
			)
			(layer "F.SilkS")
		)
		(fp_rect
			(start -0.508 0.9398)
			(end 0.508 -0.9398)
			(stroke
				(width 0)
				(type default)
			)
			(fill no)
			(layer "F.CrtYd")
		)
		(fp_rect
			(start -0.508 0.9398)
			(end 0.508 -0.9398)
			(stroke
				(width 0)
				(type default)
			)
			(fill no)
			(layer "F.Fab")
		)
		(pad "1" smd custom
			(at 0 -0.4445 180)
			(size 0.1397 0.1397)
			(layers "F.Cu" "F.Mask" "F.Paste")
			(net "RJ45_GND_1")
			(options
				(clearance outline)
				(anchor circle)
			)
			(primitives
				(gr_poly
					(pts
						(arc
							(start -0.1778 -0.2794)
							(mid -0.249642 -0.249642)
							(end -0.2794 -0.1778)
						)
						(arc
							(start -0.2794 0.1778)
							(mid -0.249642 0.249642)
							(end -0.1778 0.2794)
						)
						(arc
							(start 0.1778 0.2794)
							(mid 0.249642 0.249642)
							(end 0.2794 0.1778)
						)
						(arc
							(start 0.2794 -0.1778)
							(mid 0.249642 -0.249642)
							(end 0.1778 -0.2794)
						)
					)
					(width 0)
					(fill yes)
				)
			)
		)
		(pad "2" smd custom
			(at 0 0.4445 180)
			(size 0.1397 0.1397)
			(layers "F.Cu" "F.Mask" "F.Paste")
			(net "GND")
			(options
				(clearance outline)
				(anchor circle)
			)
			(primitives
				(gr_poly
					(pts
						(arc
							(start -0.1778 -0.2794)
							(mid -0.249642 -0.249642)
							(end -0.2794 -0.1778)
						)
						(arc
							(start -0.2794 0.1778)
							(mid -0.249642 0.249642)
							(end -0.1778 0.2794)
						)
						(arc
							(start 0.1778 0.2794)
							(mid 0.249642 0.249642)
							(end 0.2794 0.1778)
						)
						(arc
							(start 0.2794 -0.1778)
							(mid 0.249642 -0.249642)
							(end 0.1778 -0.2794)
						)
					)
					(width 0)
					(fill yes)
				)
			)
		)
	)
	(footprint ""
		(layer "F.Cu")
		(at 331.161136 -197.366128 180)
		(property "Reference" "R192"
			(at 0 0 180)
			(layer "F.SilkS")
			(hide yes)
			(effects
				(font
					(size 1.27 1.27)
				)
			)
		)
		(property "Value" "8K2R2J-3-GP"
			(at 0.064008 -3.993896 180)
			(unlocked yes)
			(layer "F.Fab")
			(hide yes)
			(effects
				(font
					(size 1.016 1.016)
					(thickness 0.1524)
				)
			)
		)
		(property "Device Type" "R402H16"
			(at 0.064008 -5.517896 180)
			(unlocked yes)
			(layer "F.Fab")
			(hide yes)
			(effects
				(font
					(size 1.016 1.016)
					(thickness 0.1524)
				)
			)
		)
		(duplicate_pad_numbers_are_jumpers no)
		(fp_line
			(start 0.508 -0.9398)
			(end -0.508 -0.9398)
			(stroke
				(width 0.1524)
				(type default)
			)
			(layer "F.SilkS")
		)
		(fp_line
			(start -0.508 -0.9398)
			(end -0.508 0.9398)
			(stroke
				(width 0.1524)
				(type default)
			)
			(layer "F.SilkS")
		)
		(fp_rect
			(start -0.508 0.9398)
			(end 0.508 -0.9398)
			(stroke
				(width 0)
				(type default)
			)
			(fill no)
			(layer "F.CrtYd")
		)
		(fp_rect
			(start -0.508 0.9398)
			(end 0.508 -0.9398)
			(stroke
				(width 0)
				(type default)
			)
			(fill no)
			(layer "F.Fab")
		)
		(pad "1" smd custom
			(at 0 -0.4445 180)
			(size 0.1397 0.1397)
			(layers "F.Cu" "F.Mask" "F.Paste")
			(net "P3V3_STBY")
			(options
				(clearance outline)
				(anchor circle)
			)
			(primitives
				(gr_poly
					(pts
						(arc
							(start -0.1778 -0.2794)
							(mid -0.249642 -0.249642)
							(end -0.2794 -0.1778)
						)
						(arc
							(start -0.2794 0.1778)
							(mid -0.249642 0.249642)
							(end -0.1778 0.2794)
						)
						(arc
							(start 0.1778 0.2794)
							(mid 0.249642 0.249642)
							(end 0.2794 0.1778)
						)
						(arc
							(start 0.2794 -0.1778)
							(mid 0.249642 -0.249642)
							(end 0.1778 -0.2794)
						)
					)
					(width 0)
					(fill yes)
				)
			)
		)
		(pad "2" smd custom
			(at 0 0.4445 180)
			(size 0.1397 0.1397)
			(layers "F.Cu" "F.Mask" "F.Paste")
			(net "EEPROM_A0_R")
			(options
				(clearance outline)
				(anchor circle)
			)
			(primitives
				(gr_poly
					(pts
						(arc
							(start -0.1778 -0.2794)
							(mid -0.249642 -0.249642)
							(end -0.2794 -0.1778)
						)
						(arc
							(start -0.2794 0.1778)
							(mid -0.249642 0.249642)
							(end -0.1778 0.2794)
						)
						(arc
							(start 0.1778 0.2794)
							(mid 0.249642 0.249642)
							(end 0.2794 0.1778)
						)
						(arc
							(start 0.2794 -0.1778)
							(mid 0.249642 -0.249642)
							(end 0.1778 -0.2794)
						)
					)
					(width 0)
					(fill yes)
				)
			)
		)
	)
	(footprint ""
		(layer "F.Cu")
		(at 76.816966 -85.344 -90)
		(property "Reference" "SC1227"
			(at 0 0 270)
			(layer "F.SilkS")
			(hide yes)
			(effects
				(font
					(size 1.27 1.27)
				)
			)
		)
		(property "Value" "SCD1U6D3V1KX-GP"
			(at -2.8321 -1.7399 270)
			(unlocked yes)
			(layer "F.Fab")
			(hide yes)
			(effects
				(font
					(size 1.016 1.016)
					(thickness 0.1524)
				)
			)
		)
		(property "Device Type" "C0201H13"
			(at -2.8321 -3.2639 270)
			(unlocked yes)
			(layer "F.Fab")
			(hide yes)
			(effects
				(font
					(size 1.016 1.016)
					(thickness 0.1524)
				)
			)
		)
		(duplicate_pad_numbers_are_jumpers no)
		(fp_rect
			(start -0.2794 0.6477)
			(end 0.2794 -0.6477)
			(stroke
				(width 0)
				(type default)
			)
			(fill no)
			(layer "F.CrtYd")
		)
		(fp_rect
			(start -0.2794 0.6477)
			(end 0.2794 -0.6477)
			(stroke
				(width 0)
				(type default)
			)
			(fill no)
			(layer "F.Fab")
		)
		(pad "1" smd custom
			(at 0 -0.2794 270)
			(size 0.0762 0.0762)
			(layers "F.Cu" "F.Mask" "F.Paste")
			(net "P1V8_E")
			(options
				(clearance outline)
				(anchor circle)
			)
			(primitives
				(gr_poly
					(pts
						(arc
							(start 0.1524 -0.127)
							(mid 0.137521 -0.162921)
							(end 0.1016 -0.1778)
						)
						(arc
							(start -0.1016 -0.1778)
							(mid -0.137521 -0.162921)
							(end -0.1524 -0.127)
						)
						(arc
							(start -0.1524 0.127)
							(mid -0.137521 0.162921)
							(end -0.1016 0.1778)
						)
						(arc
							(start 0.1016 0.1778)
							(mid 0.137521 0.162921)
							(end 0.1524 0.127)
						)
					)
					(width 0)
					(fill yes)
				)
			)
		)
		(pad "2" smd custom
			(at 0 0.2794 270)
			(size 0.0762 0.0762)
			(layers "F.Cu" "F.Mask" "F.Paste")
			(net "GND")
			(options
				(clearance outline)
				(anchor circle)
			)
			(primitives
				(gr_poly
					(pts
						(arc
							(start 0.1524 -0.127)
							(mid 0.137521 -0.162921)
							(end 0.1016 -0.1778)
						)
						(arc
							(start -0.1016 -0.1778)
							(mid -0.137521 -0.162921)
							(end -0.1524 -0.127)
						)
						(arc
							(start -0.1524 0.127)
							(mid -0.137521 0.162921)
							(end -0.1016 0.1778)
						)
						(arc
							(start 0.1016 0.1778)
							(mid 0.137521 0.162921)
							(end 0.1524 0.127)
						)
					)
					(width 0)
					(fill yes)
				)
			)
		)
	)
	(footprint ""
		(layer "F.Cu")
		(at 150.622 -92.456 180)
		(property "Reference" "SC1170"
			(at 0 0 180)
			(layer "F.SilkS")
			(hide yes)
			(effects
				(font
					(size 1.27 1.27)
				)
			)
		)
		(property "Value" "SC100U6D3V0MX-2GP"
			(at -0.00254 -4.78536 180)
			(unlocked yes)
			(layer "F.Fab")
			(hide yes)
			(effects
				(font
					(size 1.016 1.016)
					(thickness 0.1524)
				)
			)
		)
		(property "Device Type" "C1210H107"
			(at -0.00254 -6.38048 180)
			(unlocked yes)
			(layer "F.Fab")
			(hide yes)
			(effects
				(font
					(size 1.016 1.016)
					(thickness 0.1524)
				)
			)
		)
		(duplicate_pad_numbers_are_jumpers no)
		(fp_line
			(start 1.5748 2.3368)
			(end 1.5748 0.762)
			(stroke
				(width 0.1524)
				(type default)
			)
			(layer "F.SilkS")
		)
		(fp_line
			(start 1.5748 -0.762)
			(end 1.5748 -2.3368)
			(stroke
				(width 0.1524)
				(type default)
			)
			(layer "F.SilkS")
		)
		(fp_line
			(start 1.5748 -2.3368)
			(end -1.5748 -2.3368)
			(stroke
				(width 0.1524)
				(type default)
			)
			(layer "F.SilkS")
		)
		(fp_line
			(start -1.5748 2.3368)
			(end 1.5748 2.3368)
			(stroke
				(width 0.1524)
				(type default)
			)
			(layer "F.SilkS")
		)
		(fp_line
			(start -1.5748 0.762)
			(end -1.5748 2.3368)
			(stroke
				(width 0.1524)
				(type default)
			)
			(layer "F.SilkS")
		)
		(fp_line
			(start -1.5748 -2.3368)
			(end -1.5748 -0.762)
			(stroke
				(width 0.1524)
				(type default)
			)
			(layer "F.SilkS")
		)
		(fp_rect
			(start -1.651 2.413)
			(end 1.651 -2.413)
			(stroke
				(width 0)
				(type default)
			)
			(fill no)
			(layer "F.CrtYd")
		)
		(fp_poly
			(pts
				(xy 1.651 2.413) (xy 1.651 -2.413) (xy -1.651 -2.413) (xy -1.651 2.413)
			)
			(stroke
				(width 0)
				(type default)
			)
			(fill no)
			(layer "F.Fab")
		)
		(pad "1" smd rect
			(at 0 -1.4732 180)
			(size 2.794 1.397)
			(layers "F.Cu" "F.Mask" "F.Paste")
			(net "GND")
		)
		(pad "2" smd rect
			(at 0 1.4732 180)
			(size 2.794 1.397)
			(layers "F.Cu" "F.Mask" "F.Paste")
			(net "GB_VDDA")
		)
	)
	(footprint ""
		(layer "F.Cu")
		(at 105.16997 -76.454)
		(property "Reference" "SR803"
			(at 0 0 0)
			(layer "F.SilkS")
			(hide yes)
			(effects
				(font
					(size 1.27 1.27)
				)
			)
		)
		(property "Value" "4K75R2F-1-GP"
			(at 0.064008 -3.993896 0)
			(unlocked yes)
			(layer "F.Fab")
			(hide yes)
			(effects
				(font
					(size 1.016 1.016)
					(thickness 0.1524)
				)
			)
		)
		(property "Device Type" "R402H16"
			(at 0.064008 -5.517896 0)
			(unlocked yes)
			(layer "F.Fab")
			(hide yes)
			(effects
				(font
					(size 1.016 1.016)
					(thickness 0.1524)
				)
			)
		)
		(duplicate_pad_numbers_are_jumpers no)
		(fp_line
			(start -0.508 -0.9398)
			(end -0.508 0.9398)
			(stroke
				(width 0.1524)
				(type default)
			)
			(layer "F.SilkS")
		)
		(fp_line
			(start 0.508 -0.9398)
			(end -0.508 -0.9398)
			(stroke
				(width 0.1524)
				(type default)
			)
			(layer "F.SilkS")
		)
		(fp_rect
			(start -0.508 0.9398)
			(end 0.508 -0.9398)
			(stroke
				(width 0)
				(type default)
			)
			(fill no)
			(layer "F.CrtYd")
		)
		(fp_rect
			(start -0.508 0.9398)
			(end 0.508 -0.9398)
			(stroke
				(width 0)
				(type default)
			)
			(fill no)
			(layer "F.Fab")
		)
		(pad "1" smd custom
			(at 0 -0.4445)
			(size 0.1397 0.1397)
			(layers "F.Cu" "F.Mask" "F.Paste")
			(net "LSI_TRST_N")
			(options
				(clearance outline)
				(anchor circle)
			)
			(primitives
				(gr_poly
					(pts
						(arc
							(start -0.1778 -0.2794)
							(mid -0.249642 -0.249642)
							(end -0.2794 -0.1778)
						)
						(arc
							(start -0.2794 0.1778)
							(mid -0.249642 0.249642)
							(end -0.1778 0.2794)
						)
						(arc
							(start 0.1778 0.2794)
							(mid 0.249642 0.249642)
							(end 0.2794 0.1778)
						)
						(arc
							(start 0.2794 -0.1778)
							(mid 0.249642 -0.249642)
							(end 0.1778 -0.2794)
						)
					)
					(width 0)
					(fill yes)
				)
			)
		)
		(pad "2" smd custom
			(at 0 0.4445)
			(size 0.1397 0.1397)
			(layers "F.Cu" "F.Mask" "F.Paste")
			(net "GND")
			(options
				(clearance outline)
				(anchor circle)
			)
			(primitives
				(gr_poly
					(pts
						(arc
							(start -0.1778 -0.2794)
							(mid -0.249642 -0.249642)
							(end -0.2794 -0.1778)
						)
						(arc
							(start -0.2794 0.1778)
							(mid -0.249642 0.249642)
							(end -0.1778 0.2794)
						)
						(arc
							(start 0.1778 0.2794)
							(mid 0.249642 0.249642)
							(end 0.2794 0.1778)
						)
						(arc
							(start 0.2794 -0.1778)
							(mid 0.249642 -0.249642)
							(end 0.1778 -0.2794)
						)
					)
					(width 0)
					(fill yes)
				)
			)
		)
	)
	(footprint ""
		(layer "F.Cu")
		(at 223.72828 -88.86952 180)
		(property "Reference" "SC1297"
			(at 0 0 180)
			(layer "F.SilkS")
			(hide yes)
			(effects
				(font
					(size 1.27 1.27)
				)
			)
		)
		(property "Value" "SCD1U16V2KX-3GP"
			(at 1.1811 -2.7051 180)
			(unlocked yes)
			(layer "F.Fab")
			(hide yes)
			(effects
				(font
					(size 1.016 1.016)
					(thickness 0.1524)
				)
			)
		)
		(property "Device Type" "C402H22"
			(at 1.1811 -4.2291 180)
			(unlocked yes)
			(layer "F.Fab")
			(hide yes)
			(effects
				(font
					(size 1.016 1.016)
					(thickness 0.1524)
				)
			)
		)
		(duplicate_pad_numbers_are_jumpers no)
		(fp_rect
			(start -0.4318 0.9525)
			(end 0.4318 -0.9525)
			(stroke
				(width 0)
				(type default)
			)
			(fill no)
			(layer "F.CrtYd")
		)
		(fp_rect
			(start -0.4318 0.9525)
			(end 0.4318 -0.9525)
			(stroke
				(width 0)
				(type default)
			)
			(fill no)
			(layer "F.Fab")
		)
		(pad "1" smd custom
			(at 0 -0.4445 180)
			(size 0.1524 0.1524)
			(layers "F.Cu" "F.Mask" "F.Paste")
			(net "P3V3_STBY")
			(options
				(clearance outline)
				(anchor circle)
			)
			(primitives
				(gr_poly
					(pts
						(arc
							(start 0.3048 -0.2032)
							(mid 0.275042 -0.275042)
							(end 0.2032 -0.3048)
						)
						(arc
							(start -0.2032 -0.3048)
							(mid -0.275042 -0.275042)
							(end -0.3048 -0.2032)
						)
						(arc
							(start -0.3048 0.2032)
							(mid -0.275042 0.275042)
							(end -0.2032 0.3048)
						)
						(arc
							(start 0.2032 0.3048)
							(mid 0.275042 0.275042)
							(end 0.3048 0.2032)
						)
					)
					(width 0)
					(fill yes)
				)
			)
		)
		(pad "2" smd custom
			(at 0 0.4445 180)
			(size 0.1524 0.1524)
			(layers "F.Cu" "F.Mask" "F.Paste")
			(net "GND")
			(options
				(clearance outline)
				(anchor circle)
			)
			(primitives
				(gr_poly
					(pts
						(arc
							(start 0.3048 -0.2032)
							(mid 0.275042 -0.275042)
							(end 0.2032 -0.3048)
						)
						(arc
							(start -0.2032 -0.3048)
							(mid -0.275042 -0.275042)
							(end -0.3048 -0.2032)
						)
						(arc
							(start -0.3048 0.2032)
							(mid -0.275042 0.275042)
							(end -0.2032 0.3048)
						)
						(arc
							(start 0.2032 0.3048)
							(mid 0.275042 0.275042)
							(end 0.3048 0.2032)
						)
					)
					(width 0)
					(fill yes)
				)
			)
		)
	)
	(footprint ""
		(layer "F.Cu")
		(at 167.503348 -125.085856 180)
		(property "Reference" "PC190"
			(at 0 0 180)
			(layer "F.SilkS")
			(hide yes)
			(effects
				(font
					(size 1.27 1.27)
				)
			)
		)
		(property "Value" "SC1U16V3KX-2GP"
			(at 0 -2.8194 180)
			(unlocked yes)
			(layer "F.Fab")
			(hide yes)
			(effects
				(font
					(size 1.016 1.016)
					(thickness 0.1524)
				)
			)
		)
		(property "Device Type" "C603H36"
			(at 0 -4.3434 180)
			(unlocked yes)
			(layer "F.Fab")
			(hide yes)
			(effects
				(font
					(size 1.016 1.016)
					(thickness 0.1524)
				)
			)
		)
		(duplicate_pad_numbers_are_jumpers no)
		(fp_line
			(start 0.508 0)
			(end -0.508 0)
			(stroke
				(width 0.2032)
				(type default)
			)
			(layer "F.SilkS")
		)
		(fp_rect
			(start -0.5842 1.3335)
			(end 0.5842 -1.3335)
			(stroke
				(width 0)
				(type default)
			)
			(fill no)
			(layer "F.CrtYd")
		)
		(fp_rect
			(start -0.5842 1.3335)
			(end 0.5842 -1.3335)
			(stroke
				(width 0)
				(type default)
			)
			(fill no)
			(layer "F.Fab")
		)
		(pad "1" smd custom
			(at 0 -0.762 180)
			(size 0.2159 0.2159)
			(layers "F.Cu" "F.Mask" "F.Paste")
			(net "P0V9_E_VREG")
			(options
				(clearance outline)
				(anchor circle)
			)
			(primitives
				(gr_poly
					(pts
						(arc
							(start -0.3302 -0.4318)
							(mid -0.402042 -0.402042)
							(end -0.4318 -0.3302)
						)
						(arc
							(start -0.4318 0.3302)
							(mid -0.402042 0.402042)
							(end -0.3302 0.4318)
						)
						(arc
							(start 0.3302 0.4318)
							(mid 0.402042 0.402042)
							(end 0.4318 0.3302)
						)
						(arc
							(start 0.4318 -0.3302)
							(mid 0.402042 -0.402042)
							(end 0.3302 -0.4318)
						)
					)
					(width 0)
					(fill yes)
				)
			)
		)
		(pad "2" smd custom
			(at 0 0.762 180)
			(size 0.2159 0.2159)
			(layers "F.Cu" "F.Mask" "F.Paste")
			(net "GND")
			(options
				(clearance outline)
				(anchor circle)
			)
			(primitives
				(gr_poly
					(pts
						(arc
							(start -0.3302 -0.4318)
							(mid -0.402042 -0.402042)
							(end -0.4318 -0.3302)
						)
						(arc
							(start -0.4318 0.3302)
							(mid -0.402042 0.402042)
							(end -0.3302 0.4318)
						)
						(arc
							(start 0.3302 0.4318)
							(mid 0.402042 0.402042)
							(end 0.4318 0.3302)
						)
						(arc
							(start 0.4318 -0.3302)
							(mid 0.402042 -0.402042)
							(end 0.3302 -0.4318)
						)
					)
					(width 0)
					(fill yes)
				)
			)
		)
	)
	(footprint ""
		(layer "F.Cu")
		(at 208.915 -103.124 180)
		(property "Reference" "PR122"
			(at 0 0 180)
			(layer "F.SilkS")
			(hide yes)
			(effects
				(font
					(size 1.27 1.27)
				)
			)
		)
		(property "Value" "4K22R2F-GP"
			(at 0.064008 -3.993896 180)
			(unlocked yes)
			(layer "F.Fab")
			(hide yes)
			(effects
				(font
					(size 1.016 1.016)
					(thickness 0.1524)
				)
			)
		)
		(property "Device Type" "R402H16"
			(at 0.064008 -5.517896 180)
			(unlocked yes)
			(layer "F.Fab")
			(hide yes)
			(effects
				(font
					(size 1.016 1.016)
					(thickness 0.1524)
				)
			)
		)
		(duplicate_pad_numbers_are_jumpers no)
		(fp_line
			(start 0.508 -0.9398)
			(end -0.508 -0.9398)
			(stroke
				(width 0.1524)
				(type default)
			)
			(layer "F.SilkS")
		)
		(fp_line
			(start -0.508 -0.9398)
			(end -0.508 0.9398)
			(stroke
				(width 0.1524)
				(type default)
			)
			(layer "F.SilkS")
		)
		(fp_rect
			(start -0.508 0.9398)
			(end 0.508 -0.9398)
			(stroke
				(width 0)
				(type default)
			)
			(fill no)
			(layer "F.CrtYd")
		)
		(fp_rect
			(start -0.508 0.9398)
			(end 0.508 -0.9398)
			(stroke
				(width 0)
				(type default)
			)
			(fill no)
			(layer "F.Fab")
		)
		(pad "1" smd custom
			(at 0 -0.4445 180)
			(size 0.1397 0.1397)
			(layers "F.Cu" "F.Mask" "F.Paste")
			(net "P1V5_C")
			(options
				(clearance outline)
				(anchor circle)
			)
			(primitives
				(gr_poly
					(pts
						(arc
							(start -0.1778 -0.2794)
							(mid -0.249642 -0.249642)
							(end -0.2794 -0.1778)
						)
						(arc
							(start -0.2794 0.1778)
							(mid -0.249642 0.249642)
							(end -0.1778 0.2794)
						)
						(arc
							(start 0.1778 0.2794)
							(mid 0.249642 0.249642)
							(end 0.2794 0.1778)
						)
						(arc
							(start 0.2794 -0.1778)
							(mid 0.249642 -0.249642)
							(end 0.1778 -0.2794)
						)
					)
					(width 0)
					(fill yes)
				)
			)
		)
		(pad "2" smd custom
			(at 0 0.4445 180)
			(size 0.1397 0.1397)
			(layers "F.Cu" "F.Mask" "F.Paste")
			(net "TPS74801_1V5_C_FB")
			(options
				(clearance outline)
				(anchor circle)
			)
			(primitives
				(gr_poly
					(pts
						(arc
							(start -0.1778 -0.2794)
							(mid -0.249642 -0.249642)
							(end -0.2794 -0.1778)
						)
						(arc
							(start -0.2794 0.1778)
							(mid -0.249642 0.249642)
							(end -0.1778 0.2794)
						)
						(arc
							(start 0.1778 0.2794)
							(mid 0.249642 0.249642)
							(end 0.2794 0.1778)
						)
						(arc
							(start 0.2794 -0.1778)
							(mid 0.249642 -0.249642)
							(end 0.1778 -0.2794)
						)
					)
					(width 0)
					(fill yes)
				)
			)
		)
	)
	(footprint ""
		(layer "F.Cu")
		(at 250.00204 -50.039778)
		(property "Reference" "SC1064"
			(at 0 0 0)
			(layer "F.SilkS")
			(hide yes)
			(effects
				(font
					(size 1.27 1.27)
				)
			)
		)
		(property "Value" "SCD1U16V2KX-3GP"
			(at 1.1811 -2.7051 0)
			(unlocked yes)
			(layer "F.Fab")
			(hide yes)
			(effects
				(font
					(size 1.016 1.016)
					(thickness 0.1524)
				)
			)
		)
		(property "Device Type" "C402H22"
			(at 1.1811 -4.2291 0)
			(unlocked yes)
			(layer "F.Fab")
			(hide yes)
			(effects
				(font
					(size 1.016 1.016)
					(thickness 0.1524)
				)
			)
		)
		(duplicate_pad_numbers_are_jumpers no)
		(fp_rect
			(start -0.4318 0.9525)
			(end 0.4318 -0.9525)
			(stroke
				(width 0)
				(type default)
			)
			(fill no)
			(layer "F.CrtYd")
		)
		(fp_rect
			(start -0.4318 0.9525)
			(end 0.4318 -0.9525)
			(stroke
				(width 0)
				(type default)
			)
			(fill no)
			(layer "F.Fab")
		)
		(pad "1" smd custom
			(at 0 -0.4445)
			(size 0.1524 0.1524)
			(layers "F.Cu" "F.Mask" "F.Paste")
			(net "P1V8_C")
			(options
				(clearance outline)
				(anchor circle)
			)
			(primitives
				(gr_poly
					(pts
						(arc
							(start 0.3048 -0.2032)
							(mid 0.275042 -0.275042)
							(end 0.2032 -0.3048)
						)
						(arc
							(start -0.2032 -0.3048)
							(mid -0.275042 -0.275042)
							(end -0.3048 -0.2032)
						)
						(arc
							(start -0.3048 0.2032)
							(mid -0.275042 0.275042)
							(end -0.2032 0.3048)
						)
						(arc
							(start 0.2032 0.3048)
							(mid 0.275042 0.275042)
							(end 0.3048 0.2032)
						)
					)
					(width 0)
					(fill yes)
				)
			)
		)
		(pad "2" smd custom
			(at 0 0.4445)
			(size 0.1524 0.1524)
			(layers "F.Cu" "F.Mask" "F.Paste")
			(net "GND")
			(options
				(clearance outline)
				(anchor circle)
			)
			(primitives
				(gr_poly
					(pts
						(arc
							(start 0.3048 -0.2032)
							(mid 0.275042 -0.275042)
							(end 0.2032 -0.3048)
						)
						(arc
							(start -0.2032 -0.3048)
							(mid -0.275042 -0.275042)
							(end -0.3048 -0.2032)
						)
						(arc
							(start -0.3048 0.2032)
							(mid -0.275042 0.275042)
							(end -0.2032 0.3048)
						)
						(arc
							(start 0.2032 0.3048)
							(mid 0.275042 0.275042)
							(end 0.3048 0.2032)
						)
					)
					(width 0)
					(fill yes)
				)
			)
		)
	)
	(footprint ""
		(layer "F.Cu")
		(at 14.936216 -181.91988 180)
		(property "Reference" "R654"
			(at 0 0 180)
			(layer "F.SilkS")
			(hide yes)
			(effects
				(font
					(size 1.27 1.27)
				)
			)
		)
		(property "Value" "4K7R2F-GP"
			(at 0.064008 -3.993896 180)
			(unlocked yes)
			(layer "F.Fab")
			(hide yes)
			(effects
				(font
					(size 1.016 1.016)
					(thickness 0.1524)
				)
			)
		)
		(property "Device Type" "R402H16"
			(at 0.064008 -5.517896 180)
			(unlocked yes)
			(layer "F.Fab")
			(hide yes)
			(effects
				(font
					(size 1.016 1.016)
					(thickness 0.1524)
				)
			)
		)
		(duplicate_pad_numbers_are_jumpers no)
		(fp_line
			(start 0.508 -0.9398)
			(end -0.508 -0.9398)
			(stroke
				(width 0.1524)
				(type default)
			)
			(layer "F.SilkS")
		)
		(fp_line
			(start -0.508 -0.9398)
			(end -0.508 0.9398)
			(stroke
				(width 0.1524)
				(type default)
			)
			(layer "F.SilkS")
		)
		(fp_rect
			(start -0.508 0.9398)
			(end 0.508 -0.9398)
			(stroke
				(width 0)
				(type default)
			)
			(fill no)
			(layer "F.CrtYd")
		)
		(fp_rect
			(start -0.508 0.9398)
			(end 0.508 -0.9398)
			(stroke
				(width 0)
				(type default)
			)
			(fill no)
			(layer "F.Fab")
		)
		(pad "1" smd custom
			(at 0 -0.4445 180)
			(size 0.1397 0.1397)
			(layers "F.Cu" "F.Mask" "F.Paste")
			(net "P3V3_STBY")
			(options
				(clearance outline)
				(anchor circle)
			)
			(primitives
				(gr_poly
					(pts
						(arc
							(start -0.1778 -0.2794)
							(mid -0.249642 -0.249642)
							(end -0.2794 -0.1778)
						)
						(arc
							(start -0.2794 0.1778)
							(mid -0.249642 0.249642)
							(end -0.1778 0.2794)
						)
						(arc
							(start 0.1778 0.2794)
							(mid 0.249642 0.249642)
							(end 0.2794 0.1778)
						)
						(arc
							(start 0.2794 -0.1778)
							(mid 0.249642 -0.249642)
							(end 0.1778 -0.2794)
						)
					)
					(width 0)
					(fill yes)
				)
			)
		)
		(pad "2" smd custom
			(at 0 0.4445 180)
			(size 0.1397 0.1397)
			(layers "F.Cu" "F.Mask" "F.Paste")
			(net "IO_EXP_HDD_PRE_A2")
			(options
				(clearance outline)
				(anchor circle)
			)
			(primitives
				(gr_poly
					(pts
						(arc
							(start -0.1778 -0.2794)
							(mid -0.249642 -0.249642)
							(end -0.2794 -0.1778)
						)
						(arc
							(start -0.2794 0.1778)
							(mid -0.249642 0.249642)
							(end -0.1778 0.2794)
						)
						(arc
							(start 0.1778 0.2794)
							(mid 0.249642 0.249642)
							(end 0.2794 0.1778)
						)
						(arc
							(start 0.2794 -0.1778)
							(mid 0.249642 -0.249642)
							(end 0.1778 -0.2794)
						)
					)
					(width 0)
					(fill yes)
				)
			)
		)
	)
	(footprint ""
		(layer "F.Cu")
		(at 101.727 -68.9356 -90)
		(property "Reference" "SL3"
			(at 0 0 270)
			(layer "F.SilkS")
			(hide yes)
			(effects
				(font
					(size 1.27 1.27)
				)
			)
		)
		(property "Value" "MPZ2012S601AT-GP"
			(at 0 -4.2418 270)
			(unlocked yes)
			(layer "F.Fab")
			(hide yes)
			(effects
				(font
					(size 1.016 1.016)
					(thickness 0.1524)
				)
			)
		)
		(property "Device Type" "L805H42"
			(at 0 -5.7912 270)
			(unlocked yes)
			(layer "F.Fab")
			(hide yes)
			(effects
				(font
					(size 1.016 1.016)
					(thickness 0.1524)
				)
			)
		)
		(duplicate_pad_numbers_are_jumpers no)
		(fp_line
			(start -0.889 1.7018)
			(end -0.889 -1.7018)
			(stroke
				(width 0.1524)
				(type default)
			)
			(layer "F.SilkS")
		)
		(fp_line
			(start 0.889 1.7018)
			(end -0.889 1.7018)
			(stroke
				(width 0.1524)
				(type default)
			)
			(layer "F.SilkS")
		)
		(fp_line
			(start -0.889 -1.7018)
			(end 0.889 -1.7018)
			(stroke
				(width 0.1524)
				(type default)
			)
			(layer "F.SilkS")
		)
		(fp_line
			(start 0.889 -1.7018)
			(end 0.889 1.7018)
			(stroke
				(width 0.1524)
				(type default)
			)
			(layer "F.SilkS")
		)
		(fp_rect
			(start -0.9652 1.778)
			(end 0.9652 -1.778)
			(stroke
				(width 0)
				(type default)
			)
			(fill no)
			(layer "F.CrtYd")
		)
		(fp_rect
			(start -0.9652 1.778)
			(end 0.9652 -1.778)
			(stroke
				(width 0)
				(type default)
			)
			(fill no)
			(layer "F.Fab")
		)
		(pad "1" smd rect
			(at 0 -0.9652 270)
			(size 1.397 1.143)
			(layers "F.Cu" "F.Mask" "F.Paste")
			(net "HM40ADC_VDDA")
		)
		(pad "2" smd rect
			(at 0 0.9652 270)
			(size 1.397 1.143)
			(layers "F.Cu" "F.Mask" "F.Paste")
			(net "P1V8_C")
		)
	)
	(footprint ""
		(layer "F.Cu")
		(at 109.05617 -77.7494)
		(property "Reference" "STP66"
			(at 0 0 0)
			(layer "F.SilkS")
			(hide yes)
			(effects
				(font
					(size 1.27 1.27)
				)
			)
		)
		(property "Value" "TPAD28"
			(at 0.0127 -1.8034 0)
			(unlocked yes)
			(layer "F.Fab")
			(hide yes)
			(effects
				(font
					(size 1.016 1.016)
					(thickness 0.1524)
				)
			)
		)
		(property "Device Type" "TPAD28"
			(at 0.0127 -3.3274 0)
			(unlocked yes)
			(layer "F.Fab")
			(hide yes)
			(effects
				(font
					(size 1.016 1.016)
					(thickness 0.1524)
				)
			)
		)
		(duplicate_pad_numbers_are_jumpers no)
		(fp_poly
			(pts
				(arc
					(start 0.3556 0)
					(mid -0.3556 0)
					(end 0.3556 0)
				)
			)
			(stroke
				(width 0)
				(type default)
			)
			(fill no)
			(layer "F.CrtYd")
		)
		(fp_poly
			(pts
				(arc
					(start 0.6096 0)
					(mid -0.6096 0)
					(end 0.6096 0)
				)
			)
			(stroke
				(width 0)
				(type default)
			)
			(fill no)
			(layer "F.Fab")
		)
		(pad "1" smd circle
			(at 0 0)
			(size 0.7112 0.7112)
			(layers "F.Cu" "F.Mask" "F.Paste")
			(net "EXP_TEST_MUX28")
		)
	)
	(footprint ""
		(layer "F.Cu")
		(at 89.154 -231.775 180)
		(property "Reference" "R662"
			(at 0 0 180)
			(layer "F.SilkS")
			(hide yes)
			(effects
				(font
					(size 1.27 1.27)
				)
			)
		)
		(property "Value" "0R2J-2-GP"
			(at 0.064008 -3.993896 180)
			(unlocked yes)
			(layer "F.Fab")
			(hide yes)
			(effects
				(font
					(size 1.016 1.016)
					(thickness 0.1524)
				)
			)
		)
		(property "Device Type" "R402H16"
			(at 0.064008 -5.517896 180)
			(unlocked yes)
			(layer "F.Fab")
			(hide yes)
			(effects
				(font
					(size 1.016 1.016)
					(thickness 0.1524)
				)
			)
		)
		(duplicate_pad_numbers_are_jumpers no)
		(fp_line
			(start 0.508 -0.9398)
			(end -0.508 -0.9398)
			(stroke
				(width 0.1524)
				(type default)
			)
			(layer "F.SilkS")
		)
		(fp_line
			(start -0.508 -0.9398)
			(end -0.508 0.9398)
			(stroke
				(width 0.1524)
				(type default)
			)
			(layer "F.SilkS")
		)
		(fp_rect
			(start -0.508 0.9398)
			(end 0.508 -0.9398)
			(stroke
				(width 0)
				(type default)
			)
			(fill no)
			(layer "F.CrtYd")
		)
		(fp_rect
			(start -0.508 0.9398)
			(end 0.508 -0.9398)
			(stroke
				(width 0)
				(type default)
			)
			(fill no)
			(layer "F.Fab")
		)
		(pad "1" smd custom
			(at 0 -0.4445 180)
			(size 0.1397 0.1397)
			(layers "F.Cu" "F.Mask" "F.Paste")
			(net "SAS_FAULT_LED13")
			(options
				(clearance outline)
				(anchor circle)
			)
			(primitives
				(gr_poly
					(pts
						(arc
							(start -0.1778 -0.2794)
							(mid -0.249642 -0.249642)
							(end -0.2794 -0.1778)
						)
						(arc
							(start -0.2794 0.1778)
							(mid -0.249642 0.249642)
							(end -0.1778 0.2794)
						)
						(arc
							(start 0.1778 0.2794)
							(mid 0.249642 0.249642)
							(end 0.2794 0.1778)
						)
						(arc
							(start 0.2794 -0.1778)
							(mid 0.249642 -0.249642)
							(end 0.1778 -0.2794)
						)
					)
					(width 0)
					(fill yes)
				)
			)
		)
		(pad "2" smd custom
			(at 0 0.4445 180)
			(size 0.1397 0.1397)
			(layers "F.Cu" "F.Mask" "F.Paste")
			(net "SAS_HDD_LED_13")
			(options
				(clearance outline)
				(anchor circle)
			)
			(primitives
				(gr_poly
					(pts
						(arc
							(start -0.1778 -0.2794)
							(mid -0.249642 -0.249642)
							(end -0.2794 -0.1778)
						)
						(arc
							(start -0.2794 0.1778)
							(mid -0.249642 0.249642)
							(end -0.1778 0.2794)
						)
						(arc
							(start 0.1778 0.2794)
							(mid 0.249642 0.249642)
							(end 0.2794 0.1778)
						)
						(arc
							(start 0.2794 -0.1778)
							(mid 0.249642 -0.249642)
							(end 0.1778 -0.2794)
						)
					)
					(width 0)
					(fill yes)
				)
			)
		)
	)
	(footprint ""
		(layer "F.Cu")
		(at 114.82197 -114.3 180)
		(property "Reference" "SC1075"
			(at 0 0 180)
			(layer "F.SilkS")
			(hide yes)
			(effects
				(font
					(size 1.27 1.27)
				)
			)
		)
		(property "Value" "SCD01U10V1KX-GP"
			(at -2.8321 -1.7399 180)
			(unlocked yes)
			(layer "F.Fab")
			(hide yes)
			(effects
				(font
					(size 1.016 1.016)
					(thickness 0.1524)
				)
			)
		)
		(property "Device Type" "C0201H13"
			(at -2.8321 -3.2639 180)
			(unlocked yes)
			(layer "F.Fab")
			(hide yes)
			(effects
				(font
					(size 1.016 1.016)
					(thickness 0.1524)
				)
			)
		)
		(duplicate_pad_numbers_are_jumpers no)
		(fp_rect
			(start -0.2794 0.6477)
			(end 0.2794 -0.6477)
			(stroke
				(width 0)
				(type default)
			)
			(fill no)
			(layer "F.CrtYd")
		)
		(fp_rect
			(start -0.2794 0.6477)
			(end 0.2794 -0.6477)
			(stroke
				(width 0)
				(type default)
			)
			(fill no)
			(layer "F.Fab")
		)
		(pad "1" smd custom
			(at 0 -0.2794 180)
			(size 0.0762 0.0762)
			(layers "F.Cu" "F.Mask" "F.Paste")
			(net "SAS_HDD_TX4_P")
			(options
				(clearance outline)
				(anchor circle)
			)
			(primitives
				(gr_poly
					(pts
						(arc
							(start 0.1524 -0.127)
							(mid 0.137521 -0.162921)
							(end 0.1016 -0.1778)
						)
						(arc
							(start -0.1016 -0.1778)
							(mid -0.137521 -0.162921)
							(end -0.1524 -0.127)
						)
						(arc
							(start -0.1524 0.127)
							(mid -0.137521 0.162921)
							(end -0.1016 0.1778)
						)
						(arc
							(start 0.1016 0.1778)
							(mid 0.137521 0.162921)
							(end 0.1524 0.127)
						)
					)
					(width 0)
					(fill yes)
				)
			)
		)
		(pad "2" smd custom
			(at 0 0.2794 180)
			(size 0.0762 0.0762)
			(layers "F.Cu" "F.Mask" "F.Paste")
			(net "SAS_HDD_REDV_TX8_P")
			(options
				(clearance outline)
				(anchor circle)
			)
			(primitives
				(gr_poly
					(pts
						(arc
							(start 0.1524 -0.127)
							(mid 0.137521 -0.162921)
							(end 0.1016 -0.1778)
						)
						(arc
							(start -0.1016 -0.1778)
							(mid -0.137521 -0.162921)
							(end -0.1524 -0.127)
						)
						(arc
							(start -0.1524 0.127)
							(mid -0.137521 0.162921)
							(end -0.1016 0.1778)
						)
						(arc
							(start 0.1016 0.1778)
							(mid 0.137521 0.162921)
							(end 0.1524 0.127)
						)
					)
					(width 0)
					(fill yes)
				)
			)
		)
	)
	(footprint ""
		(layer "F.Cu")
		(at 302.768 -191.897)
		(property "Reference" "R173"
			(at 0 0 0)
			(layer "F.SilkS")
			(hide yes)
			(effects
				(font
					(size 1.27 1.27)
				)
			)
		)
		(property "Value" "4K7R2F-GP"
			(at 0.064008 -3.993896 0)
			(unlocked yes)
			(layer "F.Fab")
			(hide yes)
			(effects
				(font
					(size 1.016 1.016)
					(thickness 0.1524)
				)
			)
		)
		(property "Device Type" "R402H16"
			(at 0.064008 -5.517896 0)
			(unlocked yes)
			(layer "F.Fab")
			(hide yes)
			(effects
				(font
					(size 1.016 1.016)
					(thickness 0.1524)
				)
			)
		)
		(duplicate_pad_numbers_are_jumpers no)
		(fp_line
			(start -0.508 -0.9398)
			(end -0.508 0.9398)
			(stroke
				(width 0.1524)
				(type default)
			)
			(layer "F.SilkS")
		)
		(fp_line
			(start 0.508 -0.9398)
			(end -0.508 -0.9398)
			(stroke
				(width 0.1524)
				(type default)
			)
			(layer "F.SilkS")
		)
		(fp_rect
			(start -0.508 0.9398)
			(end 0.508 -0.9398)
			(stroke
				(width 0)
				(type default)
			)
			(fill no)
			(layer "F.CrtYd")
		)
		(fp_rect
			(start -0.508 0.9398)
			(end 0.508 -0.9398)
			(stroke
				(width 0)
				(type default)
			)
			(fill no)
			(layer "F.Fab")
		)
		(pad "1" smd custom
			(at 0 -0.4445)
			(size 0.1397 0.1397)
			(layers "F.Cu" "F.Mask" "F.Paste")
			(net "P3V3_STBY")
			(options
				(clearance outline)
				(anchor circle)
			)
			(primitives
				(gr_poly
					(pts
						(arc
							(start -0.1778 -0.2794)
							(mid -0.249642 -0.249642)
							(end -0.2794 -0.1778)
						)
						(arc
							(start -0.2794 0.1778)
							(mid -0.249642 0.249642)
							(end -0.1778 0.2794)
						)
						(arc
							(start 0.1778 0.2794)
							(mid 0.249642 0.249642)
							(end 0.2794 0.1778)
						)
						(arc
							(start 0.2794 -0.1778)
							(mid 0.249642 -0.249642)
							(end 0.1778 -0.2794)
						)
					)
					(width 0)
					(fill yes)
				)
			)
		)
		(pad "2" smd custom
			(at 0 0.4445)
			(size 0.1397 0.1397)
			(layers "F.Cu" "F.Mask" "F.Paste")
			(net "UART COUNT")
			(options
				(clearance outline)
				(anchor circle)
			)
			(primitives
				(gr_poly
					(pts
						(arc
							(start -0.1778 -0.2794)
							(mid -0.249642 -0.249642)
							(end -0.2794 -0.1778)
						)
						(arc
							(start -0.2794 0.1778)
							(mid -0.249642 0.249642)
							(end -0.1778 0.2794)
						)
						(arc
							(start 0.1778 0.2794)
							(mid 0.249642 0.249642)
							(end 0.2794 0.1778)
						)
						(arc
							(start 0.2794 -0.1778)
							(mid 0.249642 -0.249642)
							(end 0.1778 -0.2794)
						)
					)
					(width 0)
					(fill yes)
				)
			)
		)
	)
	(footprint ""
		(layer "F.Cu")
		(at 109.48797 -114.3 180)
		(property "Reference" "SC1081"
			(at 0 0 180)
			(layer "F.SilkS")
			(hide yes)
			(effects
				(font
					(size 1.27 1.27)
				)
			)
		)
		(property "Value" "SCD01U10V1KX-GP"
			(at -2.8321 -1.7399 180)
			(unlocked yes)
			(layer "F.Fab")
			(hide yes)
			(effects
				(font
					(size 1.016 1.016)
					(thickness 0.1524)
				)
			)
		)
		(property "Device Type" "C0201H13"
			(at -2.8321 -3.2639 180)
			(unlocked yes)
			(layer "F.Fab")
			(hide yes)
			(effects
				(font
					(size 1.016 1.016)
					(thickness 0.1524)
				)
			)
		)
		(duplicate_pad_numbers_are_jumpers no)
		(fp_rect
			(start -0.2794 0.6477)
			(end 0.2794 -0.6477)
			(stroke
				(width 0)
				(type default)
			)
			(fill no)
			(layer "F.CrtYd")
		)
		(fp_rect
			(start -0.2794 0.6477)
			(end 0.2794 -0.6477)
			(stroke
				(width 0)
				(type default)
			)
			(fill no)
			(layer "F.Fab")
		)
		(pad "1" smd custom
			(at 0 -0.2794 180)
			(size 0.0762 0.0762)
			(layers "F.Cu" "F.Mask" "F.Paste")
			(net "SAS_HDD_TX7_P")
			(options
				(clearance outline)
				(anchor circle)
			)
			(primitives
				(gr_poly
					(pts
						(arc
							(start 0.1524 -0.127)
							(mid 0.137521 -0.162921)
							(end 0.1016 -0.1778)
						)
						(arc
							(start -0.1016 -0.1778)
							(mid -0.137521 -0.162921)
							(end -0.1524 -0.127)
						)
						(arc
							(start -0.1524 0.127)
							(mid -0.137521 0.162921)
							(end -0.1016 0.1778)
						)
						(arc
							(start 0.1016 0.1778)
							(mid 0.137521 0.162921)
							(end 0.1524 0.127)
						)
					)
					(width 0)
					(fill yes)
				)
			)
		)
		(pad "2" smd custom
			(at 0 0.2794 180)
			(size 0.0762 0.0762)
			(layers "F.Cu" "F.Mask" "F.Paste")
			(net "SAS_EXP_GF_TX_DP11")
			(options
				(clearance outline)
				(anchor circle)
			)
			(primitives
				(gr_poly
					(pts
						(arc
							(start 0.1524 -0.127)
							(mid 0.137521 -0.162921)
							(end 0.1016 -0.1778)
						)
						(arc
							(start -0.1016 -0.1778)
							(mid -0.137521 -0.162921)
							(end -0.1524 -0.127)
						)
						(arc
							(start -0.1524 0.127)
							(mid -0.137521 0.162921)
							(end -0.1016 0.1778)
						)
						(arc
							(start 0.1016 0.1778)
							(mid 0.137521 0.162921)
							(end 0.1524 0.127)
						)
					)
					(width 0)
					(fill yes)
				)
			)
		)
	)
	(footprint ""
		(layer "F.Cu")
		(at 87.757 -224.663 -90)
		(property "Reference" "SR783"
			(at 0 0 270)
			(layer "F.SilkS")
			(hide yes)
			(effects
				(font
					(size 1.27 1.27)
				)
			)
		)
		(property "Value" "4K7R2F-GP"
			(at 0.064008 -3.993896 270)
			(unlocked yes)
			(layer "F.Fab")
			(hide yes)
			(effects
				(font
					(size 1.016 1.016)
					(thickness 0.1524)
				)
			)
		)
		(property "Device Type" "R402H16"
			(at 0.064008 -5.517896 270)
			(unlocked yes)
			(layer "F.Fab")
			(hide yes)
			(effects
				(font
					(size 1.016 1.016)
					(thickness 0.1524)
				)
			)
		)
		(duplicate_pad_numbers_are_jumpers no)
		(fp_line
			(start -0.508 -0.9398)
			(end -0.508 0.9398)
			(stroke
				(width 0.1524)
				(type default)
			)
			(layer "F.SilkS")
		)
		(fp_line
			(start 0.508 -0.9398)
			(end -0.508 -0.9398)
			(stroke
				(width 0.1524)
				(type default)
			)
			(layer "F.SilkS")
		)
		(fp_rect
			(start -0.508 0.9398)
			(end 0.508 -0.9398)
			(stroke
				(width 0)
				(type default)
			)
			(fill no)
			(layer "F.CrtYd")
		)
		(fp_rect
			(start -0.508 0.9398)
			(end 0.508 -0.9398)
			(stroke
				(width 0)
				(type default)
			)
			(fill no)
			(layer "F.Fab")
		)
		(pad "1" smd custom
			(at 0 -0.4445 270)
			(size 0.1397 0.1397)
			(layers "F.Cu" "F.Mask" "F.Paste")
			(net "EXP_SCL_L_0")
			(options
				(clearance outline)
				(anchor circle)
			)
			(primitives
				(gr_poly
					(pts
						(arc
							(start -0.1778 -0.2794)
							(mid -0.249642 -0.249642)
							(end -0.2794 -0.1778)
						)
						(arc
							(start -0.2794 0.1778)
							(mid -0.249642 0.249642)
							(end -0.1778 0.2794)
						)
						(arc
							(start 0.1778 0.2794)
							(mid 0.249642 0.249642)
							(end 0.2794 0.1778)
						)
						(arc
							(start 0.2794 -0.1778)
							(mid 0.249642 -0.249642)
							(end 0.1778 -0.2794)
						)
					)
					(width 0)
					(fill yes)
				)
			)
		)
		(pad "2" smd custom
			(at 0 0.4445 270)
			(size 0.1397 0.1397)
			(layers "F.Cu" "F.Mask" "F.Paste")
			(net "P3V3_STBY")
			(options
				(clearance outline)
				(anchor circle)
			)
			(primitives
				(gr_poly
					(pts
						(arc
							(start -0.1778 -0.2794)
							(mid -0.249642 -0.249642)
							(end -0.2794 -0.1778)
						)
						(arc
							(start -0.2794 0.1778)
							(mid -0.249642 0.249642)
							(end -0.1778 0.2794)
						)
						(arc
							(start 0.1778 0.2794)
							(mid 0.249642 0.249642)
							(end 0.2794 0.1778)
						)
						(arc
							(start 0.2794 -0.1778)
							(mid 0.249642 -0.249642)
							(end 0.1778 -0.2794)
						)
					)
					(width 0)
					(fill yes)
				)
			)
		)
	)
	(footprint ""
		(layer "F.Cu")
		(at 275.082 -44.958)
		(property "Reference" "PL4"
			(at 0 0 0)
			(layer "F.SilkS")
			(hide yes)
			(effects
				(font
					(size 1.27 1.27)
				)
			)
		)
		(property "Value" "BLM21PG220SN1DGP"
			(at 0.0254 -5.6896 0)
			(unlocked yes)
			(layer "F.Fab")
			(hide yes)
			(effects
				(font
					(size 1.016 1.016)
					(thickness 0.1524)
				)
			)
		)
		(property "Device Type" "L20125H42"
			(at 0.0254 -7.5946 0)
			(unlocked yes)
			(layer "F.Fab")
			(hide yes)
			(effects
				(font
					(size 1.016 1.016)
					(thickness 0.1524)
				)
			)
		)
		(duplicate_pad_numbers_are_jumpers no)
		(fp_line
			(start -0.9144 -1.7018)
			(end -0.9144 1.7018)
			(stroke
				(width 0.1524)
				(type default)
			)
			(layer "F.SilkS")
		)
		(fp_line
			(start -0.9144 1.7018)
			(end 0.9144 1.7018)
			(stroke
				(width 0.1524)
				(type default)
			)
			(layer "F.SilkS")
		)
		(fp_line
			(start 0.9144 -1.7018)
			(end -0.9144 -1.7018)
			(stroke
				(width 0.1524)
				(type default)
			)
			(layer "F.SilkS")
		)
		(fp_line
			(start 0.9144 1.7018)
			(end 0.9144 -1.7018)
			(stroke
				(width 0.1524)
				(type default)
			)
			(layer "F.SilkS")
		)
		(fp_rect
			(start -1.0033 1.778)
			(end 1.0033 -1.778)
			(stroke
				(width 0)
				(type default)
			)
			(fill no)
			(layer "F.CrtYd")
		)
		(fp_poly
			(pts
				(xy -1.0033 -1.778) (xy 1.0033 -1.778) (xy 1.0033 1.778) (xy -1.0033 1.778)
			)
			(stroke
				(width 0)
				(type default)
			)
			(fill no)
			(layer "F.Fab")
		)
		(pad "1" smd rect
			(at 0 -0.9652)
			(size 1.397 1.143)
			(layers "F.Cu" "F.Mask" "F.Paste")
			(net "P12V")
		)
		(pad "2" smd rect
			(at 0 0.9652)
			(size 1.397 1.143)
			(layers "F.Cu" "F.Mask" "F.Paste")
			(net "P1V8_STBY_VIN")
		)
	)
	(footprint ""
		(layer "F.Cu")
		(at 88.2904 -3.683)
		(property "Reference" "PC196"
			(at 0 0 0)
			(layer "F.SilkS")
			(hide yes)
			(effects
				(font
					(size 1.27 1.27)
				)
			)
		)
		(property "Value" "SC22U6D3V6KX-2-GP"
			(at -0.0762 -5.1308 0)
			(unlocked yes)
			(layer "F.Fab")
			(hide yes)
			(effects
				(font
					(size 1.016 1.016)
					(thickness 0.1524)
				)
			)
		)
		(property "Device Type" "C1206H71"
			(at -0.127 -6.6548 0)
			(unlocked yes)
			(layer "F.Fab")
			(hide yes)
			(effects
				(font
					(size 1.016 1.016)
					(thickness 0.1524)
				)
			)
		)
		(duplicate_pad_numbers_are_jumpers no)
		(fp_line
			(start -1.016 -2.2352)
			(end 1.016 -2.2352)
			(stroke
				(width 0.1524)
				(type default)
			)
			(layer "F.SilkS")
		)
		(fp_line
			(start -1.016 -0.8382)
			(end -1.016 -2.2352)
			(stroke
				(width 0.1524)
				(type default)
			)
			(layer "F.SilkS")
		)
		(fp_line
			(start -1.016 2.2352)
			(end -1.016 0.8382)
			(stroke
				(width 0.1524)
				(type default)
			)
			(layer "F.SilkS")
		)
		(fp_line
			(start 1.016 -2.2352)
			(end 1.016 -0.8382)
			(stroke
				(width 0.1524)
				(type default)
			)
			(layer "F.SilkS")
		)
		(fp_line
			(start 1.016 0.8382)
			(end 1.016 2.2352)
			(stroke
				(width 0.1524)
				(type default)
			)
			(layer "F.SilkS")
		)
		(fp_line
			(start 1.016 2.2352)
			(end -1.016 2.2352)
			(stroke
				(width 0.1524)
				(type default)
			)
			(layer "F.SilkS")
		)
		(fp_rect
			(start -1.0922 2.3114)
			(end 1.0922 -2.3114)
			(stroke
				(width 0)
				(type default)
			)
			(fill no)
			(layer "F.CrtYd")
		)
		(fp_poly
			(pts
				(xy 1.0922 -2.3114) (xy 1.0922 2.3114) (xy -1.0922 2.3114) (xy -1.0922 -2.3114)
			)
			(stroke
				(width 0)
				(type default)
			)
			(fill no)
			(layer "F.Fab")
		)
		(pad "1" smd rect
			(at 0 -1.397)
			(size 1.651 1.27)
			(layers "F.Cu" "F.Mask" "F.Paste")
			(net "P0V955_C")
		)
		(pad "2" smd rect
			(at 0 1.397)
			(size 1.651 1.27)
			(layers "F.Cu" "F.Mask" "F.Paste")
			(net "GND")
		)
	)
	(footprint ""
		(layer "F.Cu")
		(at 194.760596 -112.033812 -90)
		(property "Reference" "PC231"
			(at 0 0 270)
			(layer "F.SilkS")
			(hide yes)
			(effects
				(font
					(size 1.27 1.27)
				)
			)
		)
		(property "Value" "SC2K2P50V3KX-GP"
			(at 0 -2.8194 270)
			(unlocked yes)
			(layer "F.Fab")
			(hide yes)
			(effects
				(font
					(size 1.016 1.016)
					(thickness 0.1524)
				)
			)
		)
		(property "Device Type" "C603"
			(at 0 -4.3434 270)
			(unlocked yes)
			(layer "F.Fab")
			(hide yes)
			(effects
				(font
					(size 1.016 1.016)
					(thickness 0.1524)
				)
			)
		)
		(duplicate_pad_numbers_are_jumpers no)
		(fp_line
			(start 0.508 0)
			(end -0.508 0)
			(stroke
				(width 0.2032)
				(type default)
			)
			(layer "F.SilkS")
		)
		(fp_rect
			(start -0.5842 1.3335)
			(end 0.5842 -1.3335)
			(stroke
				(width 0)
				(type default)
			)
			(fill no)
			(layer "F.CrtYd")
		)
		(fp_rect
			(start -0.5842 1.3335)
			(end 0.5842 -1.3335)
			(stroke
				(width 0)
				(type default)
			)
			(fill no)
			(layer "F.Fab")
		)
		(pad "1" smd custom
			(at 0 -0.762 270)
			(size 0.2159 0.2159)
			(layers "F.Cu" "F.Mask" "F.Paste")
			(net "P1V5_E_SW")
			(options
				(clearance outline)
				(anchor circle)
			)
			(primitives
				(gr_poly
					(pts
						(arc
							(start -0.3302 -0.4318)
							(mid -0.402042 -0.402042)
							(end -0.4318 -0.3302)
						)
						(arc
							(start -0.4318 0.3302)
							(mid -0.402042 0.402042)
							(end -0.3302 0.4318)
						)
						(arc
							(start 0.3302 0.4318)
							(mid 0.402042 0.402042)
							(end 0.4318 0.3302)
						)
						(arc
							(start 0.4318 -0.3302)
							(mid 0.402042 -0.402042)
							(end 0.3302 -0.4318)
						)
					)
					(width 0)
					(fill yes)
				)
			)
		)
		(pad "2" smd custom
			(at 0 0.762 270)
			(size 0.2159 0.2159)
			(layers "F.Cu" "F.Mask" "F.Paste")
			(net "P1V5_E_SNB")
			(options
				(clearance outline)
				(anchor circle)
			)
			(primitives
				(gr_poly
					(pts
						(arc
							(start -0.3302 -0.4318)
							(mid -0.402042 -0.402042)
							(end -0.4318 -0.3302)
						)
						(arc
							(start -0.4318 0.3302)
							(mid -0.402042 0.402042)
							(end -0.3302 0.4318)
						)
						(arc
							(start 0.3302 0.4318)
							(mid 0.402042 0.402042)
							(end 0.4318 0.3302)
						)
						(arc
							(start 0.4318 -0.3302)
							(mid 0.402042 -0.402042)
							(end 0.3302 -0.4318)
						)
					)
					(width 0)
					(fill yes)
				)
			)
		)
	)
	(footprint ""
		(layer "F.Cu")
		(at 226.568 -21.463 -90)
		(property "Reference" "R5774"
			(at 0 0 270)
			(layer "F.SilkS")
			(hide yes)
			(effects
				(font
					(size 1.27 1.27)
				)
			)
		)
		(property "Value" "330R1210J-GP"
			(at 0.0889 -6.9977 270)
			(unlocked yes)
			(layer "F.Fab")
			(hide yes)
			(effects
				(font
					(size 1.016 1.016)
					(thickness 0.1524)
				)
			)
		)
		(property "Device Type" "R1210H24"
			(at 0.0635 -8.636 270)
			(unlocked yes)
			(layer "F.Fab")
			(hide yes)
			(effects
				(font
					(size 1.016 1.016)
					(thickness 0.1524)
				)
			)
		)
		(duplicate_pad_numbers_are_jumpers no)
		(fp_line
			(start -1.651 2.413)
			(end -1.651 -2.413)
			(stroke
				(width 0.1524)
				(type default)
			)
			(layer "F.SilkS")
		)
		(fp_line
			(start 1.651 2.413)
			(end -1.651 2.413)
			(stroke
				(width 0.1524)
				(type default)
			)
			(layer "F.SilkS")
		)
		(fp_line
			(start -1.651 -2.413)
			(end 1.651 -2.413)
			(stroke
				(width 0.1524)
				(type default)
			)
			(layer "F.SilkS")
		)
		(fp_line
			(start 1.651 -2.413)
			(end 1.651 2.413)
			(stroke
				(width 0.1524)
				(type default)
			)
			(layer "F.SilkS")
		)
		(fp_poly
			(pts
				(xy -1.651 -2.413) (xy 1.651 -2.413) (xy 1.651 2.413) (xy -1.651 2.413)
			)
			(stroke
				(width 0)
				(type default)
			)
			(fill no)
			(layer "F.CrtYd")
		)
		(fp_poly
			(pts
				(xy -1.651 -2.413) (xy 1.651 -2.413) (xy 1.651 2.413) (xy -1.651 2.413)
			)
			(stroke
				(width 0)
				(type default)
			)
			(fill no)
			(layer "F.Fab")
		)
		(pad "1" smd rect
			(at 0 -1.4732 270)
			(size 2.794 1.397)
			(layers "F.Cu" "F.Mask" "F.Paste")
			(net "P5V_STBY")
		)
		(pad "2" smd rect
			(at 0 1.4732 270)
			(size 2.794 1.397)
			(layers "F.Cu" "F.Mask" "F.Paste")
			(net "LED_PWR_N_R")
		)
	)
	(footprint ""
		(layer "F.Cu")
		(at 266.446 -236.22 -90)
		(property "Reference" "C86"
			(at 0 0 270)
			(layer "F.SilkS")
			(hide yes)
			(effects
				(font
					(size 1.27 1.27)
				)
			)
		)
		(property "Value" "SCD1U16V2KX-3GP"
			(at 1.1811 -2.7051 270)
			(unlocked yes)
			(layer "F.Fab")
			(hide yes)
			(effects
				(font
					(size 1.016 1.016)
					(thickness 0.1524)
				)
			)
		)
		(property "Device Type" "C402H22"
			(at 1.1811 -4.2291 270)
			(unlocked yes)
			(layer "F.Fab")
			(hide yes)
			(effects
				(font
					(size 1.016 1.016)
					(thickness 0.1524)
				)
			)
		)
		(duplicate_pad_numbers_are_jumpers no)
		(fp_rect
			(start -0.4318 0.9525)
			(end 0.4318 -0.9525)
			(stroke
				(width 0)
				(type default)
			)
			(fill no)
			(layer "F.CrtYd")
		)
		(fp_rect
			(start -0.4318 0.9525)
			(end 0.4318 -0.9525)
			(stroke
				(width 0)
				(type default)
			)
			(fill no)
			(layer "F.Fab")
		)
		(pad "1" smd custom
			(at 0 -0.4445 270)
			(size 0.1524 0.1524)
			(layers "F.Cu" "F.Mask" "F.Paste")
			(net "P1V8_STBY")
			(options
				(clearance outline)
				(anchor circle)
			)
			(primitives
				(gr_poly
					(pts
						(arc
							(start 0.3048 -0.2032)
							(mid 0.275042 -0.275042)
							(end 0.2032 -0.3048)
						)
						(arc
							(start -0.2032 -0.3048)
							(mid -0.275042 -0.275042)
							(end -0.3048 -0.2032)
						)
						(arc
							(start -0.3048 0.2032)
							(mid -0.275042 0.275042)
							(end -0.2032 0.3048)
						)
						(arc
							(start 0.2032 0.3048)
							(mid 0.275042 0.275042)
							(end 0.3048 0.2032)
						)
					)
					(width 0)
					(fill yes)
				)
			)
		)
		(pad "2" smd custom
			(at 0 0.4445 270)
			(size 0.1524 0.1524)
			(layers "F.Cu" "F.Mask" "F.Paste")
			(net "GND")
			(options
				(clearance outline)
				(anchor circle)
			)
			(primitives
				(gr_poly
					(pts
						(arc
							(start 0.3048 -0.2032)
							(mid 0.275042 -0.275042)
							(end 0.2032 -0.3048)
						)
						(arc
							(start -0.2032 -0.3048)
							(mid -0.275042 -0.275042)
							(end -0.3048 -0.2032)
						)
						(arc
							(start -0.3048 0.2032)
							(mid -0.275042 0.275042)
							(end -0.2032 0.3048)
						)
						(arc
							(start 0.2032 0.3048)
							(mid 0.275042 0.275042)
							(end 0.3048 0.2032)
						)
					)
					(width 0)
					(fill yes)
				)
			)
		)
	)
	(footprint ""
		(layer "F.Cu")
		(at 107.88777 -69.9008 -90)
		(property "Reference" "R585"
			(at 0 0 270)
			(layer "F.SilkS")
			(hide yes)
			(effects
				(font
					(size 1.27 1.27)
				)
			)
		)
		(property "Value" "4K7R2F-GP"
			(at 0.064008 -3.993896 270)
			(unlocked yes)
			(layer "F.Fab")
			(hide yes)
			(effects
				(font
					(size 1.016 1.016)
					(thickness 0.1524)
				)
			)
		)
		(property "Device Type" "R402H16"
			(at 0.064008 -5.517896 270)
			(unlocked yes)
			(layer "F.Fab")
			(hide yes)
			(effects
				(font
					(size 1.016 1.016)
					(thickness 0.1524)
				)
			)
		)
		(duplicate_pad_numbers_are_jumpers no)
		(fp_line
			(start -0.508 -0.9398)
			(end -0.508 0.9398)
			(stroke
				(width 0.1524)
				(type default)
			)
			(layer "F.SilkS")
		)
		(fp_line
			(start 0.508 -0.9398)
			(end -0.508 -0.9398)
			(stroke
				(width 0.1524)
				(type default)
			)
			(layer "F.SilkS")
		)
		(fp_rect
			(start -0.508 0.9398)
			(end 0.508 -0.9398)
			(stroke
				(width 0)
				(type default)
			)
			(fill no)
			(layer "F.CrtYd")
		)
		(fp_rect
			(start -0.508 0.9398)
			(end 0.508 -0.9398)
			(stroke
				(width 0)
				(type default)
			)
			(fill no)
			(layer "F.Fab")
		)
		(pad "1" smd custom
			(at 0 -0.4445 270)
			(size 0.1397 0.1397)
			(layers "F.Cu" "F.Mask" "F.Paste")
			(net "TEMP_4_A0")
			(options
				(clearance outline)
				(anchor circle)
			)
			(primitives
				(gr_poly
					(pts
						(arc
							(start -0.1778 -0.2794)
							(mid -0.249642 -0.249642)
							(end -0.2794 -0.1778)
						)
						(arc
							(start -0.2794 0.1778)
							(mid -0.249642 0.249642)
							(end -0.1778 0.2794)
						)
						(arc
							(start 0.1778 0.2794)
							(mid 0.249642 0.249642)
							(end 0.2794 0.1778)
						)
						(arc
							(start 0.2794 -0.1778)
							(mid 0.249642 -0.249642)
							(end 0.1778 -0.2794)
						)
					)
					(width 0)
					(fill yes)
				)
			)
		)
		(pad "2" smd custom
			(at 0 0.4445 270)
			(size 0.1397 0.1397)
			(layers "F.Cu" "F.Mask" "F.Paste")
			(net "GND")
			(options
				(clearance outline)
				(anchor circle)
			)
			(primitives
				(gr_poly
					(pts
						(arc
							(start -0.1778 -0.2794)
							(mid -0.249642 -0.249642)
							(end -0.2794 -0.1778)
						)
						(arc
							(start -0.2794 0.1778)
							(mid -0.249642 0.249642)
							(end -0.1778 0.2794)
						)
						(arc
							(start 0.1778 0.2794)
							(mid 0.249642 0.249642)
							(end 0.2794 0.1778)
						)
						(arc
							(start 0.2794 -0.1778)
							(mid 0.249642 -0.249642)
							(end 0.1778 -0.2794)
						)
					)
					(width 0)
					(fill yes)
				)
			)
		)
	)
	(footprint ""
		(layer "F.Cu")
		(at 277.994872 -219.274136 -90)
		(property "Reference" "PC88"
			(at 0 0 270)
			(layer "F.SilkS")
			(hide yes)
			(effects
				(font
					(size 1.27 1.27)
				)
			)
		)
		(property "Value" "SCD1U16V2KX-3GP"
			(at 1.1811 -2.7051 270)
			(unlocked yes)
			(layer "F.Fab")
			(hide yes)
			(effects
				(font
					(size 1.016 1.016)
					(thickness 0.1524)
				)
			)
		)
		(property "Device Type" "C402H22"
			(at 1.1811 -4.2291 270)
			(unlocked yes)
			(layer "F.Fab")
			(hide yes)
			(effects
				(font
					(size 1.016 1.016)
					(thickness 0.1524)
				)
			)
		)
		(duplicate_pad_numbers_are_jumpers no)
		(fp_rect
			(start -0.4318 0.9525)
			(end 0.4318 -0.9525)
			(stroke
				(width 0)
				(type default)
			)
			(fill no)
			(layer "F.CrtYd")
		)
		(fp_rect
			(start -0.4318 0.9525)
			(end 0.4318 -0.9525)
			(stroke
				(width 0)
				(type default)
			)
			(fill no)
			(layer "F.Fab")
		)
		(pad "1" smd custom
			(at 0 -0.4445 270)
			(size 0.1524 0.1524)
			(layers "F.Cu" "F.Mask" "F.Paste")
			(net "TPS74801_1V53_STBY_BIAS")
			(options
				(clearance outline)
				(anchor circle)
			)
			(primitives
				(gr_poly
					(pts
						(arc
							(start 0.3048 -0.2032)
							(mid 0.275042 -0.275042)
							(end 0.2032 -0.3048)
						)
						(arc
							(start -0.2032 -0.3048)
							(mid -0.275042 -0.275042)
							(end -0.3048 -0.2032)
						)
						(arc
							(start -0.3048 0.2032)
							(mid -0.275042 0.275042)
							(end -0.2032 0.3048)
						)
						(arc
							(start 0.2032 0.3048)
							(mid 0.275042 0.275042)
							(end 0.3048 0.2032)
						)
					)
					(width 0)
					(fill yes)
				)
			)
		)
		(pad "2" smd custom
			(at 0 0.4445 270)
			(size 0.1524 0.1524)
			(layers "F.Cu" "F.Mask" "F.Paste")
			(net "GND")
			(options
				(clearance outline)
				(anchor circle)
			)
			(primitives
				(gr_poly
					(pts
						(arc
							(start 0.3048 -0.2032)
							(mid 0.275042 -0.275042)
							(end 0.2032 -0.3048)
						)
						(arc
							(start -0.2032 -0.3048)
							(mid -0.275042 -0.275042)
							(end -0.3048 -0.2032)
						)
						(arc
							(start -0.3048 0.2032)
							(mid -0.275042 0.275042)
							(end -0.2032 0.3048)
						)
						(arc
							(start 0.2032 0.3048)
							(mid 0.275042 0.275042)
							(end 0.3048 0.2032)
						)
					)
					(width 0)
					(fill yes)
				)
			)
		)
	)
	(footprint ""
		(layer "F.Cu")
		(at 291.973 -207.772 90)
		(property "Reference" "R232"
			(at 0 0 90)
			(layer "F.SilkS")
			(hide yes)
			(effects
				(font
					(size 1.27 1.27)
				)
			)
		)
		(property "Value" "1KR2F-3-GP"
			(at 0.064008 -3.993896 90)
			(unlocked yes)
			(layer "F.Fab")
			(hide yes)
			(effects
				(font
					(size 1.016 1.016)
					(thickness 0.1524)
				)
			)
		)
		(property "Device Type" "R402H16"
			(at 0.064008 -5.517896 90)
			(unlocked yes)
			(layer "F.Fab")
			(hide yes)
			(effects
				(font
					(size 1.016 1.016)
					(thickness 0.1524)
				)
			)
		)
		(duplicate_pad_numbers_are_jumpers no)
		(fp_line
			(start 0.508 -0.9398)
			(end -0.508 -0.9398)
			(stroke
				(width 0.1524)
				(type default)
			)
			(layer "F.SilkS")
		)
		(fp_line
			(start -0.508 -0.9398)
			(end -0.508 0.9398)
			(stroke
				(width 0.1524)
				(type default)
			)
			(layer "F.SilkS")
		)
		(fp_rect
			(start -0.508 0.9398)
			(end 0.508 -0.9398)
			(stroke
				(width 0)
				(type default)
			)
			(fill no)
			(layer "F.CrtYd")
		)
		(fp_rect
			(start -0.508 0.9398)
			(end 0.508 -0.9398)
			(stroke
				(width 0)
				(type default)
			)
			(fill no)
			(layer "F.Fab")
		)
		(pad "1" smd custom
			(at 0 -0.4445 90)
			(size 0.1397 0.1397)
			(layers "F.Cu" "F.Mask" "F.Paste")
			(net "DDR_VREF")
			(options
				(clearance outline)
				(anchor circle)
			)
			(primitives
				(gr_poly
					(pts
						(arc
							(start -0.1778 -0.2794)
							(mid -0.249642 -0.249642)
							(end -0.2794 -0.1778)
						)
						(arc
							(start -0.2794 0.1778)
							(mid -0.249642 0.249642)
							(end -0.1778 0.2794)
						)
						(arc
							(start 0.1778 0.2794)
							(mid 0.249642 0.249642)
							(end 0.2794 0.1778)
						)
						(arc
							(start 0.2794 -0.1778)
							(mid 0.249642 -0.249642)
							(end 0.1778 -0.2794)
						)
					)
					(width 0)
					(fill yes)
				)
			)
		)
		(pad "2" smd custom
			(at 0 0.4445 90)
			(size 0.1397 0.1397)
			(layers "F.Cu" "F.Mask" "F.Paste")
			(net "GND")
			(options
				(clearance outline)
				(anchor circle)
			)
			(primitives
				(gr_poly
					(pts
						(arc
							(start -0.1778 -0.2794)
							(mid -0.249642 -0.249642)
							(end -0.2794 -0.1778)
						)
						(arc
							(start -0.2794 0.1778)
							(mid -0.249642 0.249642)
							(end -0.1778 0.2794)
						)
						(arc
							(start 0.1778 0.2794)
							(mid 0.249642 0.249642)
							(end 0.2794 0.1778)
						)
						(arc
							(start 0.2794 -0.1778)
							(mid 0.249642 -0.249642)
							(end 0.1778 -0.2794)
						)
					)
					(width 0)
					(fill yes)
				)
			)
		)
	)
	(footprint ""
		(layer "F.Cu")
		(at 11.126216 -211.63788 -90)
		(property "Reference" "Q92"
			(at 0 0 270)
			(layer "F.SilkS")
			(hide yes)
			(effects
				(font
					(size 1.27 1.27)
				)
			)
		)
		(property "Value" "2N7002A-7-GP"
			(at 0.127 -8.9662 270)
			(unlocked yes)
			(layer "F.Fab")
			(hide yes)
			(effects
				(font
					(size 1.016 1.016)
					(thickness 0.1524)
				)
			)
		)
		(property "Device Type" "SOT23DGS2D4H48"
			(at 0.127 -10.4902 270)
			(unlocked yes)
			(layer "F.Fab")
			(hide yes)
			(effects
				(font
					(size 1.016 1.016)
					(thickness 0.1524)
				)
			)
		)
		(duplicate_pad_numbers_are_jumpers no)
		(fp_line
			(start -1.651 1.778)
			(end 1.651 1.778)
			(stroke
				(width 0.1524)
				(type default)
			)
			(layer "F.SilkS")
		)
		(fp_line
			(start 1.651 1.778)
			(end 1.651 -1.778)
			(stroke
				(width 0.1524)
				(type default)
			)
			(layer "F.SilkS")
		)
		(fp_line
			(start -1.651 -1.778)
			(end -1.651 1.778)
			(stroke
				(width 0.1524)
				(type default)
			)
			(layer "F.SilkS")
		)
		(fp_line
			(start 1.651 -1.778)
			(end -1.651 -1.778)
			(stroke
				(width 0.1524)
				(type default)
			)
			(layer "F.SilkS")
		)
		(fp_poly
			(pts
				(xy -1.778 1.8796) (xy -1.778 -1.8796) (xy 1.778 -1.8796) (xy 1.778 1.8796)
			)
			(stroke
				(width 0)
				(type default)
			)
			(fill no)
			(layer "F.CrtYd")
		)
		(fp_poly
			(pts
				(xy -1.778 1.8796) (xy -1.778 -1.8796) (xy 1.778 -1.8796) (xy 1.778 1.8796)
			)
			(stroke
				(width 0)
				(type default)
			)
			(fill no)
			(layer "F.Fab")
		)
		(pad "D" smd custom
			(at 0 -0.9525 270)
			(size 0.1905 0.1905)
			(layers "F.Cu" "F.Mask" "F.Paste")
			(net "PCIE_MATED#")
			(options
				(clearance outline)
				(anchor circle)
			)
			(primitives
				(gr_poly
					(pts
						(arc
							(start -0.1778 0.5715)
							(mid -0.321484 0.511984)
							(end -0.381 0.3683)
						)
						(arc
							(start -0.381 -0.3683)
							(mid -0.321484 -0.511984)
							(end -0.1778 -0.5715)
						)
						(arc
							(start 0.1778 -0.5715)
							(mid 0.321484 -0.511984)
							(end 0.381 -0.3683)
						)
						(arc
							(start 0.381 0.3683)
							(mid 0.321484 0.511984)
							(end 0.1778 0.5715)
						)
					)
					(width 0)
					(fill yes)
				)
			)
		)
		(pad "G" smd custom
			(at -0.98425 0.9525 270)
			(size 0.1905 0.1905)
			(layers "F.Cu" "F.Mask" "F.Paste")
			(net "MATED#")
			(options
				(clearance outline)
				(anchor circle)
			)
			(primitives
				(gr_poly
					(pts
						(arc
							(start -0.1778 0.5715)
							(mid -0.321484 0.511984)
							(end -0.381 0.3683)
						)
						(arc
							(start -0.381 -0.3683)
							(mid -0.321484 -0.511984)
							(end -0.1778 -0.5715)
						)
						(arc
							(start 0.1778 -0.5715)
							(mid 0.321484 -0.511984)
							(end 0.381 -0.3683)
						)
						(arc
							(start 0.381 0.3683)
							(mid 0.321484 0.511984)
							(end 0.1778 0.5715)
						)
					)
					(width 0)
					(fill yes)
				)
			)
		)
		(pad "S" smd custom
			(at 0.98425 0.9525 270)
			(size 0.1905 0.1905)
			(layers "F.Cu" "F.Mask" "F.Paste")
			(net "GND")
			(options
				(clearance outline)
				(anchor circle)
			)
			(primitives
				(gr_poly
					(pts
						(arc
							(start -0.1778 0.5715)
							(mid -0.321484 0.511984)
							(end -0.381 0.3683)
						)
						(arc
							(start -0.381 -0.3683)
							(mid -0.321484 -0.511984)
							(end -0.1778 -0.5715)
						)
						(arc
							(start 0.1778 -0.5715)
							(mid 0.321484 -0.511984)
							(end 0.381 -0.3683)
						)
						(arc
							(start 0.381 0.3683)
							(mid 0.321484 0.511984)
							(end 0.1778 0.5715)
						)
					)
					(width 0)
					(fill yes)
				)
			)
		)
	)
	(footprint ""
		(layer "F.Cu")
		(at 308.60238 -144.40154 -90)
		(property "Reference" "R7789"
			(at 0 0 270)
			(layer "F.SilkS")
			(hide yes)
			(effects
				(font
					(size 1.27 1.27)
				)
			)
		)
		(property "Value" "49D9R2F-GP"
			(at 0.064008 -3.993896 270)
			(unlocked yes)
			(layer "F.Fab")
			(hide yes)
			(effects
				(font
					(size 1.016 1.016)
					(thickness 0.1524)
				)
			)
		)
		(property "Device Type" "R402H16"
			(at 0.064008 -5.517896 270)
			(unlocked yes)
			(layer "F.Fab")
			(hide yes)
			(effects
				(font
					(size 1.016 1.016)
					(thickness 0.1524)
				)
			)
		)
		(duplicate_pad_numbers_are_jumpers no)
		(fp_line
			(start -0.508 -0.9398)
			(end -0.508 0.9398)
			(stroke
				(width 0.1524)
				(type default)
			)
			(layer "F.SilkS")
		)
		(fp_line
			(start 0.508 -0.9398)
			(end -0.508 -0.9398)
			(stroke
				(width 0.1524)
				(type default)
			)
			(layer "F.SilkS")
		)
		(fp_rect
			(start -0.508 0.9398)
			(end 0.508 -0.9398)
			(stroke
				(width 0)
				(type default)
			)
			(fill no)
			(layer "F.CrtYd")
		)
		(fp_rect
			(start -0.508 0.9398)
			(end 0.508 -0.9398)
			(stroke
				(width 0)
				(type default)
			)
			(fill no)
			(layer "F.Fab")
		)
		(pad "1" smd custom
			(at 0 -0.4445 270)
			(size 0.1397 0.1397)
			(layers "F.Cu" "F.Mask" "F.Paste")
			(net "OSC_OE")
			(options
				(clearance outline)
				(anchor circle)
			)
			(primitives
				(gr_poly
					(pts
						(arc
							(start -0.1778 -0.2794)
							(mid -0.249642 -0.249642)
							(end -0.2794 -0.1778)
						)
						(arc
							(start -0.2794 0.1778)
							(mid -0.249642 0.249642)
							(end -0.1778 0.2794)
						)
						(arc
							(start 0.1778 0.2794)
							(mid 0.249642 0.249642)
							(end 0.2794 0.1778)
						)
						(arc
							(start 0.2794 -0.1778)
							(mid 0.249642 -0.249642)
							(end 0.1778 -0.2794)
						)
					)
					(width 0)
					(fill yes)
				)
			)
		)
		(pad "2" smd custom
			(at 0 0.4445 270)
			(size 0.1397 0.1397)
			(layers "F.Cu" "F.Mask" "F.Paste")
			(net "P3V3_STBY")
			(options
				(clearance outline)
				(anchor circle)
			)
			(primitives
				(gr_poly
					(pts
						(arc
							(start -0.1778 -0.2794)
							(mid -0.249642 -0.249642)
							(end -0.2794 -0.1778)
						)
						(arc
							(start -0.2794 0.1778)
							(mid -0.249642 0.249642)
							(end -0.1778 0.2794)
						)
						(arc
							(start 0.1778 0.2794)
							(mid 0.249642 0.249642)
							(end 0.2794 0.1778)
						)
						(arc
							(start 0.2794 -0.1778)
							(mid 0.249642 -0.249642)
							(end 0.1778 -0.2794)
						)
					)
					(width 0)
					(fill yes)
				)
			)
		)
	)
	(footprint ""
		(layer "F.Cu")
		(at 270.637 -16.764 180)
		(property "Reference" "C238"
			(at 0 0 180)
			(layer "F.SilkS")
			(hide yes)
			(effects
				(font
					(size 1.27 1.27)
				)
			)
		)
		(property "Value" "SCD1U16V2JX-1-GP"
			(at 1.1811 -2.7051 180)
			(unlocked yes)
			(layer "F.Fab")
			(hide yes)
			(effects
				(font
					(size 1.016 1.016)
					(thickness 0.1524)
				)
			)
		)
		(property "Device Type" "C402H22"
			(at 1.1811 -4.2291 180)
			(unlocked yes)
			(layer "F.Fab")
			(hide yes)
			(effects
				(font
					(size 1.016 1.016)
					(thickness 0.1524)
				)
			)
		)
		(duplicate_pad_numbers_are_jumpers no)
		(fp_rect
			(start -0.4318 0.9525)
			(end 0.4318 -0.9525)
			(stroke
				(width 0)
				(type default)
			)
			(fill no)
			(layer "F.CrtYd")
		)
		(fp_rect
			(start -0.4318 0.9525)
			(end 0.4318 -0.9525)
			(stroke
				(width 0)
				(type default)
			)
			(fill no)
			(layer "F.Fab")
		)
		(pad "1" smd custom
			(at 0 -0.4445 180)
			(size 0.1524 0.1524)
			(layers "F.Cu" "F.Mask" "F.Paste")
			(net "P5V_USB")
			(options
				(clearance outline)
				(anchor circle)
			)
			(primitives
				(gr_poly
					(pts
						(arc
							(start 0.3048 -0.2032)
							(mid 0.275042 -0.275042)
							(end 0.2032 -0.3048)
						)
						(arc
							(start -0.2032 -0.3048)
							(mid -0.275042 -0.275042)
							(end -0.3048 -0.2032)
						)
						(arc
							(start -0.3048 0.2032)
							(mid -0.275042 0.275042)
							(end -0.2032 0.3048)
						)
						(arc
							(start 0.2032 0.3048)
							(mid 0.275042 0.275042)
							(end 0.3048 0.2032)
						)
					)
					(width 0)
					(fill yes)
				)
			)
		)
		(pad "2" smd custom
			(at 0 0.4445 180)
			(size 0.1524 0.1524)
			(layers "F.Cu" "F.Mask" "F.Paste")
			(net "GND")
			(options
				(clearance outline)
				(anchor circle)
			)
			(primitives
				(gr_poly
					(pts
						(arc
							(start 0.3048 -0.2032)
							(mid 0.275042 -0.275042)
							(end 0.2032 -0.3048)
						)
						(arc
							(start -0.2032 -0.3048)
							(mid -0.275042 -0.275042)
							(end -0.3048 -0.2032)
						)
						(arc
							(start -0.3048 0.2032)
							(mid -0.275042 0.275042)
							(end -0.2032 0.3048)
						)
						(arc
							(start 0.2032 0.3048)
							(mid 0.275042 0.275042)
							(end 0.3048 0.2032)
						)
					)
					(width 0)
					(fill yes)
				)
			)
		)
	)
	(footprint ""
		(layer "F.Cu")
		(at 323.600064 -9.800082 90)
		(property "Reference" "LED6"
			(at 0 0 90)
			(layer "F.SilkS")
			(hide yes)
			(effects
				(font
					(size 1.27 1.27)
				)
			)
		)
		(property "Value" "LED-R-46-GP"
			(at -2.5527 1.6256 90)
			(unlocked yes)
			(layer "F.Fab")
			(hide yes)
			(effects
				(font
					(size 1.016 1.016)
					(thickness 0.1524)
				)
			)
		)
		(property "Device Type" "LED3215AKH52"
			(at -2.5527 0.1016 90)
			(unlocked yes)
			(layer "F.Fab")
			(hide yes)
			(effects
				(font
					(size 1.016 1.016)
					(thickness 0.1524)
				)
			)
		)
		(duplicate_pad_numbers_are_jumpers no)
		(fp_line
			(start 1.1303 -2.2479)
			(end -1.1303 -2.2479)
			(stroke
				(width 0.1524)
				(type default)
			)
			(layer "F.SilkS")
		)
		(fp_line
			(start -1.1303 -2.2479)
			(end -1.1303 2.2479)
			(stroke
				(width 0.1524)
				(type default)
			)
			(layer "F.SilkS")
		)
		(fp_line
			(start 1.1303 2.2479)
			(end 1.1303 -2.2479)
			(stroke
				(width 0.1524)
				(type default)
			)
			(layer "F.SilkS")
		)
		(fp_line
			(start -1.1303 2.2479)
			(end 1.1303 2.2479)
			(stroke
				(width 0.1524)
				(type default)
			)
			(layer "F.SilkS")
		)
		(fp_line
			(start -1.1303 2.4257)
			(end 1.1303 2.4257)
			(stroke
				(width 0.508)
				(type default)
			)
			(layer "F.SilkS")
		)
		(fp_rect
			(start -1.3843 2.6797)
			(end 1.3843 -2.3241)
			(stroke
				(width 0)
				(type default)
			)
			(fill no)
			(layer "F.CrtYd")
		)
		(fp_rect
			(start -1.3843 2.6797)
			(end 1.3843 -2.3241)
			(stroke
				(width 0)
				(type default)
			)
			(fill no)
			(layer "F.Fab")
		)
		(pad "A" smd rect
			(at 0 -1.36779 90)
			(size 1.7526 1.2446)
			(layers "F.Cu" "F.Mask" "F.Paste")
			(net "LED_SL_SW_ON")
		)
		(pad "K" smd rect
			(at 0 1.36779 90)
			(size 1.7526 1.2446)
			(layers "F.Cu" "F.Mask" "F.Paste")
			(net "DEBUG_LED_SW")
		)
	)
	(footprint ""
		(layer "F.Cu")
		(at 194.1576 -36.6522 -90)
		(property "Reference" "R620"
			(at 0 0 270)
			(layer "F.SilkS")
			(hide yes)
			(effects
				(font
					(size 1.27 1.27)
				)
			)
		)
		(property "Value" "0R2J-2-GP"
			(at 0.064008 -3.993896 270)
			(unlocked yes)
			(layer "F.Fab")
			(hide yes)
			(effects
				(font
					(size 1.016 1.016)
					(thickness 0.1524)
				)
			)
		)
		(property "Device Type" "R402H16"
			(at 0.064008 -5.517896 270)
			(unlocked yes)
			(layer "F.Fab")
			(hide yes)
			(effects
				(font
					(size 1.016 1.016)
					(thickness 0.1524)
				)
			)
		)
		(duplicate_pad_numbers_are_jumpers no)
		(fp_line
			(start -0.508 -0.9398)
			(end -0.508 0.9398)
			(stroke
				(width 0.1524)
				(type default)
			)
			(layer "F.SilkS")
		)
		(fp_line
			(start 0.508 -0.9398)
			(end -0.508 -0.9398)
			(stroke
				(width 0.1524)
				(type default)
			)
			(layer "F.SilkS")
		)
		(fp_rect
			(start -0.508 0.9398)
			(end 0.508 -0.9398)
			(stroke
				(width 0)
				(type default)
			)
			(fill no)
			(layer "F.CrtYd")
		)
		(fp_rect
			(start -0.508 0.9398)
			(end 0.508 -0.9398)
			(stroke
				(width 0)
				(type default)
			)
			(fill no)
			(layer "F.Fab")
		)
		(pad "1" smd custom
			(at 0 -0.4445 270)
			(size 0.1397 0.1397)
			(layers "F.Cu" "F.Mask" "F.Paste")
			(net "GND")
			(options
				(clearance outline)
				(anchor circle)
			)
			(primitives
				(gr_poly
					(pts
						(arc
							(start -0.1778 -0.2794)
							(mid -0.249642 -0.249642)
							(end -0.2794 -0.1778)
						)
						(arc
							(start -0.2794 0.1778)
							(mid -0.249642 0.249642)
							(end -0.1778 0.2794)
						)
						(arc
							(start 0.1778 0.2794)
							(mid 0.249642 0.249642)
							(end 0.2794 0.1778)
						)
						(arc
							(start 0.2794 -0.1778)
							(mid 0.249642 -0.249642)
							(end 0.1778 -0.2794)
						)
					)
					(width 0)
					(fill yes)
				)
			)
		)
		(pad "2" smd custom
			(at 0 0.4445 270)
			(size 0.1397 0.1397)
			(layers "F.Cu" "F.Mask" "F.Paste")
			(net "RMII_BMC_PHY_TXD1")
			(options
				(clearance outline)
				(anchor circle)
			)
			(primitives
				(gr_poly
					(pts
						(arc
							(start -0.1778 -0.2794)
							(mid -0.249642 -0.249642)
							(end -0.2794 -0.1778)
						)
						(arc
							(start -0.2794 0.1778)
							(mid -0.249642 0.249642)
							(end -0.1778 0.2794)
						)
						(arc
							(start 0.1778 0.2794)
							(mid 0.249642 0.249642)
							(end 0.2794 0.1778)
						)
						(arc
							(start 0.2794 -0.1778)
							(mid 0.249642 -0.249642)
							(end 0.1778 -0.2794)
						)
					)
					(width 0)
					(fill yes)
				)
			)
		)
	)
	(footprint ""
		(layer "F.Cu")
		(at 131.318 -90.424 90)
		(property "Reference" "SC1103"
			(at 0 0 90)
			(layer "F.SilkS")
			(hide yes)
			(effects
				(font
					(size 1.27 1.27)
				)
			)
		)
		(property "Value" "SCD01U10V1KX-GP"
			(at -2.8321 -1.7399 90)
			(unlocked yes)
			(layer "F.Fab")
			(hide yes)
			(effects
				(font
					(size 1.016 1.016)
					(thickness 0.1524)
				)
			)
		)
		(property "Device Type" "C0201H13"
			(at -2.8321 -3.2639 90)
			(unlocked yes)
			(layer "F.Fab")
			(hide yes)
			(effects
				(font
					(size 1.016 1.016)
					(thickness 0.1524)
				)
			)
		)
		(duplicate_pad_numbers_are_jumpers no)
		(fp_rect
			(start -0.2794 0.6477)
			(end 0.2794 -0.6477)
			(stroke
				(width 0)
				(type default)
			)
			(fill no)
			(layer "F.CrtYd")
		)
		(fp_rect
			(start -0.2794 0.6477)
			(end 0.2794 -0.6477)
			(stroke
				(width 0)
				(type default)
			)
			(fill no)
			(layer "F.Fab")
		)
		(pad "1" smd custom
			(at 0 -0.2794 90)
			(size 0.0762 0.0762)
			(layers "F.Cu" "F.Mask" "F.Paste")
			(net "3X24_SAS_TX18_N")
			(options
				(clearance outline)
				(anchor circle)
			)
			(primitives
				(gr_poly
					(pts
						(arc
							(start 0.1524 -0.127)
							(mid 0.137521 -0.162921)
							(end 0.1016 -0.1778)
						)
						(arc
							(start -0.1016 -0.1778)
							(mid -0.137521 -0.162921)
							(end -0.1524 -0.127)
						)
						(arc
							(start -0.1524 0.127)
							(mid -0.137521 0.162921)
							(end -0.1016 0.1778)
						)
						(arc
							(start 0.1016 0.1778)
							(mid 0.137521 0.162921)
							(end 0.1524 0.127)
						)
					)
					(width 0)
					(fill yes)
				)
			)
		)
		(pad "2" smd custom
			(at 0 0.2794 90)
			(size 0.0762 0.0762)
			(layers "F.Cu" "F.Mask" "F.Paste")
			(net "SAS_EXP2CONN_TX_N_22")
			(options
				(clearance outline)
				(anchor circle)
			)
			(primitives
				(gr_poly
					(pts
						(arc
							(start 0.1524 -0.127)
							(mid 0.137521 -0.162921)
							(end 0.1016 -0.1778)
						)
						(arc
							(start -0.1016 -0.1778)
							(mid -0.137521 -0.162921)
							(end -0.1524 -0.127)
						)
						(arc
							(start -0.1524 0.127)
							(mid -0.137521 0.162921)
							(end -0.1016 0.1778)
						)
						(arc
							(start 0.1016 0.1778)
							(mid 0.137521 0.162921)
							(end 0.1524 0.127)
						)
					)
					(width 0)
					(fill yes)
				)
			)
		)
	)
	(footprint ""
		(layer "F.Cu")
		(at 336.804 -217.3605)
		(property "Reference" "R183"
			(at 0 0 0)
			(layer "F.SilkS")
			(hide yes)
			(effects
				(font
					(size 1.27 1.27)
				)
			)
		)
		(property "Value" "0R2J-2-GP"
			(at 0.064008 -3.993896 0)
			(unlocked yes)
			(layer "F.Fab")
			(hide yes)
			(effects
				(font
					(size 1.016 1.016)
					(thickness 0.1524)
				)
			)
		)
		(property "Device Type" "R402H16"
			(at 0.064008 -5.517896 0)
			(unlocked yes)
			(layer "F.Fab")
			(hide yes)
			(effects
				(font
					(size 1.016 1.016)
					(thickness 0.1524)
				)
			)
		)
		(duplicate_pad_numbers_are_jumpers no)
		(fp_line
			(start -0.508 -0.9398)
			(end -0.508 0.9398)
			(stroke
				(width 0.1524)
				(type default)
			)
			(layer "F.SilkS")
		)
		(fp_line
			(start 0.508 -0.9398)
			(end -0.508 -0.9398)
			(stroke
				(width 0.1524)
				(type default)
			)
			(layer "F.SilkS")
		)
		(fp_rect
			(start -0.508 0.9398)
			(end 0.508 -0.9398)
			(stroke
				(width 0)
				(type default)
			)
			(fill no)
			(layer "F.CrtYd")
		)
		(fp_rect
			(start -0.508 0.9398)
			(end 0.508 -0.9398)
			(stroke
				(width 0)
				(type default)
			)
			(fill no)
			(layer "F.Fab")
		)
		(pad "1" smd custom
			(at 0 -0.4445)
			(size 0.1397 0.1397)
			(layers "F.Cu" "F.Mask" "F.Paste")
			(net "VOL_SEN_SCL")
			(options
				(clearance outline)
				(anchor circle)
			)
			(primitives
				(gr_poly
					(pts
						(arc
							(start -0.1778 -0.2794)
							(mid -0.249642 -0.249642)
							(end -0.2794 -0.1778)
						)
						(arc
							(start -0.2794 0.1778)
							(mid -0.249642 0.249642)
							(end -0.1778 0.2794)
						)
						(arc
							(start 0.1778 0.2794)
							(mid 0.249642 0.249642)
							(end 0.2794 0.1778)
						)
						(arc
							(start 0.2794 -0.1778)
							(mid 0.249642 -0.249642)
							(end 0.1778 -0.2794)
						)
					)
					(width 0)
					(fill yes)
				)
			)
		)
		(pad "2" smd custom
			(at 0 0.4445)
			(size 0.1397 0.1397)
			(layers "F.Cu" "F.Mask" "F.Paste")
			(net "BMC_I2C_A_SCL")
			(options
				(clearance outline)
				(anchor circle)
			)
			(primitives
				(gr_poly
					(pts
						(arc
							(start -0.1778 -0.2794)
							(mid -0.249642 -0.249642)
							(end -0.2794 -0.1778)
						)
						(arc
							(start -0.2794 0.1778)
							(mid -0.249642 0.249642)
							(end -0.1778 0.2794)
						)
						(arc
							(start 0.1778 0.2794)
							(mid 0.249642 0.249642)
							(end 0.2794 0.1778)
						)
						(arc
							(start 0.2794 -0.1778)
							(mid 0.249642 -0.249642)
							(end 0.1778 -0.2794)
						)
					)
					(width 0)
					(fill yes)
				)
			)
		)
	)
	(footprint ""
		(layer "F.Cu")
		(at 289.433 -156.972 -90)
		(property "Reference" "R421"
			(at 0 0 270)
			(layer "F.SilkS")
			(hide yes)
			(effects
				(font
					(size 1.27 1.27)
				)
			)
		)
		(property "Value" "2K2R2J-2-GP"
			(at 0.064008 -3.993896 270)
			(unlocked yes)
			(layer "F.Fab")
			(hide yes)
			(effects
				(font
					(size 1.016 1.016)
					(thickness 0.1524)
				)
			)
		)
		(property "Device Type" "R402H16"
			(at 0.064008 -5.517896 270)
			(unlocked yes)
			(layer "F.Fab")
			(hide yes)
			(effects
				(font
					(size 1.016 1.016)
					(thickness 0.1524)
				)
			)
		)
		(duplicate_pad_numbers_are_jumpers no)
		(fp_line
			(start -0.508 -0.9398)
			(end -0.508 0.9398)
			(stroke
				(width 0.1524)
				(type default)
			)
			(layer "F.SilkS")
		)
		(fp_line
			(start 0.508 -0.9398)
			(end -0.508 -0.9398)
			(stroke
				(width 0.1524)
				(type default)
			)
			(layer "F.SilkS")
		)
		(fp_rect
			(start -0.508 0.9398)
			(end 0.508 -0.9398)
			(stroke
				(width 0)
				(type default)
			)
			(fill no)
			(layer "F.CrtYd")
		)
		(fp_rect
			(start -0.508 0.9398)
			(end 0.508 -0.9398)
			(stroke
				(width 0)
				(type default)
			)
			(fill no)
			(layer "F.Fab")
		)
		(pad "1" smd custom
			(at 0 -0.4445 270)
			(size 0.1397 0.1397)
			(layers "F.Cu" "F.Mask" "F.Paste")
			(net "P3V3_STBY")
			(options
				(clearance outline)
				(anchor circle)
			)
			(primitives
				(gr_poly
					(pts
						(arc
							(start -0.1778 -0.2794)
							(mid -0.249642 -0.249642)
							(end -0.2794 -0.1778)
						)
						(arc
							(start -0.2794 0.1778)
							(mid -0.249642 0.249642)
							(end -0.1778 0.2794)
						)
						(arc
							(start 0.1778 0.2794)
							(mid 0.249642 0.249642)
							(end 0.2794 0.1778)
						)
						(arc
							(start 0.2794 -0.1778)
							(mid 0.249642 -0.249642)
							(end 0.1778 -0.2794)
						)
					)
					(width 0)
					(fill yes)
				)
			)
		)
		(pad "2" smd custom
			(at 0 0.4445 270)
			(size 0.1397 0.1397)
			(layers "F.Cu" "F.Mask" "F.Paste")
			(net "CPU_BMC_UART_TX")
			(options
				(clearance outline)
				(anchor circle)
			)
			(primitives
				(gr_poly
					(pts
						(arc
							(start -0.1778 -0.2794)
							(mid -0.249642 -0.249642)
							(end -0.2794 -0.1778)
						)
						(arc
							(start -0.2794 0.1778)
							(mid -0.249642 0.249642)
							(end -0.1778 0.2794)
						)
						(arc
							(start 0.1778 0.2794)
							(mid 0.249642 0.249642)
							(end 0.2794 0.1778)
						)
						(arc
							(start 0.2794 -0.1778)
							(mid 0.249642 -0.249642)
							(end 0.1778 -0.2794)
						)
					)
					(width 0)
					(fill yes)
				)
			)
		)
	)
	(footprint ""
		(layer "F.Cu")
		(at 85.452966 -84.074 180)
		(property "Reference" "SC1155"
			(at 0 0 180)
			(layer "F.SilkS")
			(hide yes)
			(effects
				(font
					(size 1.27 1.27)
				)
			)
		)
		(property "Value" "SC10U6D3V5KX-4GP"
			(at -0.0762 -6.1214 180)
			(unlocked yes)
			(layer "F.Fab")
			(hide yes)
			(effects
				(font
					(size 1.016 1.016)
					(thickness 0.1524)
				)
			)
		)
		(property "Device Type" "C805H58"
			(at -0.0762 -8.1534 180)
			(unlocked yes)
			(layer "F.Fab")
			(hide yes)
			(effects
				(font
					(size 1.016 1.016)
					(thickness 0.1524)
				)
			)
		)
		(duplicate_pad_numbers_are_jumpers no)
		(fp_line
			(start 0.635 0)
			(end -0.635 0)
			(stroke
				(width 0.508)
				(type default)
			)
			(layer "F.SilkS")
		)
		(fp_rect
			(start -0.9652 1.778)
			(end 0.9652 -1.778)
			(stroke
				(width 0)
				(type default)
			)
			(fill no)
			(layer "F.CrtYd")
		)
		(fp_poly
			(pts
				(xy -0.9652 -1.778) (xy 0.9652 -1.778) (xy 0.9652 1.778) (xy -0.9652 1.778)
			)
			(stroke
				(width 0)
				(type default)
			)
			(fill no)
			(layer "F.Fab")
		)
		(pad "1" smd rect
			(at 0 -0.9652 180)
			(size 1.397 1.143)
			(layers "F.Cu" "F.Mask" "F.Paste")
			(net "PLLDDR_VDDA18")
		)
		(pad "2" smd rect
			(at 0 0.9652 180)
			(size 1.397 1.143)
			(layers "F.Cu" "F.Mask" "F.Paste")
			(net "GND")
		)
	)
	(footprint ""
		(layer "F.Cu")
		(at 174.107348 -121.783856 90)
		(property "Reference" "PC169"
			(at 0 0 90)
			(layer "F.SilkS")
			(hide yes)
			(effects
				(font
					(size 1.27 1.27)
				)
			)
		)
		(property "Value" "SC22U25V5MX-GP"
			(at -0.0762 -6.1214 90)
			(unlocked yes)
			(layer "F.Fab")
			(hide yes)
			(effects
				(font
					(size 1.016 1.016)
					(thickness 0.1524)
				)
			)
		)
		(property "Device Type" "C805H58"
			(at -0.0762 -8.1534 90)
			(unlocked yes)
			(layer "F.Fab")
			(hide yes)
			(effects
				(font
					(size 1.016 1.016)
					(thickness 0.1524)
				)
			)
		)
		(duplicate_pad_numbers_are_jumpers no)
		(fp_line
			(start 0.635 0)
			(end -0.635 0)
			(stroke
				(width 0.508)
				(type default)
			)
			(layer "F.SilkS")
		)
		(fp_rect
			(start -0.9652 1.778)
			(end 0.9652 -1.778)
			(stroke
				(width 0)
				(type default)
			)
			(fill no)
			(layer "F.CrtYd")
		)
		(fp_poly
			(pts
				(xy -0.9652 -1.778) (xy 0.9652 -1.778) (xy 0.9652 1.778) (xy -0.9652 1.778)
			)
			(stroke
				(width 0)
				(type default)
			)
			(fill no)
			(layer "F.Fab")
		)
		(pad "1" smd rect
			(at 0 -0.9652 90)
			(size 1.397 1.143)
			(layers "F.Cu" "F.Mask" "F.Paste")
			(net "P0V9_E_VIN")
		)
		(pad "2" smd rect
			(at 0 0.9652 90)
			(size 1.397 1.143)
			(layers "F.Cu" "F.Mask" "F.Paste")
			(net "GND")
		)
	)
	(footprint ""
		(layer "F.Cu")
		(at 284.0482 -191.77)
		(property "Reference" "C183"
			(at 0 0 0)
			(layer "F.SilkS")
			(hide yes)
			(effects
				(font
					(size 1.27 1.27)
				)
			)
		)
		(property "Value" "SCD1U16V2KX-3GP"
			(at 1.1811 -2.7051 0)
			(unlocked yes)
			(layer "F.Fab")
			(hide yes)
			(effects
				(font
					(size 1.016 1.016)
					(thickness 0.1524)
				)
			)
		)
		(property "Device Type" "C402H22"
			(at 1.1811 -4.2291 0)
			(unlocked yes)
			(layer "F.Fab")
			(hide yes)
			(effects
				(font
					(size 1.016 1.016)
					(thickness 0.1524)
				)
			)
		)
		(duplicate_pad_numbers_are_jumpers no)
		(fp_rect
			(start -0.4318 0.9525)
			(end 0.4318 -0.9525)
			(stroke
				(width 0)
				(type default)
			)
			(fill no)
			(layer "F.CrtYd")
		)
		(fp_rect
			(start -0.4318 0.9525)
			(end 0.4318 -0.9525)
			(stroke
				(width 0)
				(type default)
			)
			(fill no)
			(layer "F.Fab")
		)
		(pad "1" smd custom
			(at 0 -0.4445)
			(size 0.1524 0.1524)
			(layers "F.Cu" "F.Mask" "F.Paste")
			(net "P1V53_STBY")
			(options
				(clearance outline)
				(anchor circle)
			)
			(primitives
				(gr_poly
					(pts
						(arc
							(start 0.3048 -0.2032)
							(mid 0.275042 -0.275042)
							(end 0.2032 -0.3048)
						)
						(arc
							(start -0.2032 -0.3048)
							(mid -0.275042 -0.275042)
							(end -0.3048 -0.2032)
						)
						(arc
							(start -0.3048 0.2032)
							(mid -0.275042 0.275042)
							(end -0.2032 0.3048)
						)
						(arc
							(start 0.2032 0.3048)
							(mid 0.275042 0.275042)
							(end 0.3048 0.2032)
						)
					)
					(width 0)
					(fill yes)
				)
			)
		)
		(pad "2" smd custom
			(at 0 0.4445)
			(size 0.1524 0.1524)
			(layers "F.Cu" "F.Mask" "F.Paste")
			(net "GND")
			(options
				(clearance outline)
				(anchor circle)
			)
			(primitives
				(gr_poly
					(pts
						(arc
							(start 0.3048 -0.2032)
							(mid 0.275042 -0.275042)
							(end 0.2032 -0.3048)
						)
						(arc
							(start -0.2032 -0.3048)
							(mid -0.275042 -0.275042)
							(end -0.3048 -0.2032)
						)
						(arc
							(start -0.3048 0.2032)
							(mid -0.275042 0.275042)
							(end -0.2032 0.3048)
						)
						(arc
							(start 0.2032 0.3048)
							(mid 0.275042 0.275042)
							(end 0.3048 0.2032)
						)
					)
					(width 0)
					(fill yes)
				)
			)
		)
	)
	(footprint ""
		(layer "F.Cu")
		(at 41.03497 -139.827 90)
		(property "Reference" "SR916"
			(at 0 0 90)
			(layer "F.SilkS")
			(hide yes)
			(effects
				(font
					(size 1.27 1.27)
				)
			)
		)
		(property "Value" "4K7R2F-GP"
			(at 0.064008 -3.993896 90)
			(unlocked yes)
			(layer "F.Fab")
			(hide yes)
			(effects
				(font
					(size 1.016 1.016)
					(thickness 0.1524)
				)
			)
		)
		(property "Device Type" "R402H16"
			(at 0.064008 -5.517896 90)
			(unlocked yes)
			(layer "F.Fab")
			(hide yes)
			(effects
				(font
					(size 1.016 1.016)
					(thickness 0.1524)
				)
			)
		)
		(duplicate_pad_numbers_are_jumpers no)
		(fp_line
			(start 0.508 -0.9398)
			(end -0.508 -0.9398)
			(stroke
				(width 0.1524)
				(type default)
			)
			(layer "F.SilkS")
		)
		(fp_line
			(start -0.508 -0.9398)
			(end -0.508 0.9398)
			(stroke
				(width 0.1524)
				(type default)
			)
			(layer "F.SilkS")
		)
		(fp_rect
			(start -0.508 0.9398)
			(end 0.508 -0.9398)
			(stroke
				(width 0)
				(type default)
			)
			(fill no)
			(layer "F.CrtYd")
		)
		(fp_rect
			(start -0.508 0.9398)
			(end 0.508 -0.9398)
			(stroke
				(width 0)
				(type default)
			)
			(fill no)
			(layer "F.Fab")
		)
		(pad "1" smd custom
			(at 0 -0.4445 90)
			(size 0.1397 0.1397)
			(layers "F.Cu" "F.Mask" "F.Paste")
			(net "P3V3_STBY")
			(options
				(clearance outline)
				(anchor circle)
			)
			(primitives
				(gr_poly
					(pts
						(arc
							(start -0.1778 -0.2794)
							(mid -0.249642 -0.249642)
							(end -0.2794 -0.1778)
						)
						(arc
							(start -0.2794 0.1778)
							(mid -0.249642 0.249642)
							(end -0.1778 0.2794)
						)
						(arc
							(start 0.1778 0.2794)
							(mid 0.249642 0.249642)
							(end 0.2794 0.1778)
						)
						(arc
							(start 0.2794 -0.1778)
							(mid 0.249642 -0.249642)
							(end 0.1778 -0.2794)
						)
					)
					(width 0)
					(fill yes)
				)
			)
		)
		(pad "2" smd custom
			(at 0 0.4445 90)
			(size 0.1397 0.1397)
			(layers "F.Cu" "F.Mask" "F.Paste")
			(net "BMC_RST_EXPANDER")
			(options
				(clearance outline)
				(anchor circle)
			)
			(primitives
				(gr_poly
					(pts
						(arc
							(start -0.1778 -0.2794)
							(mid -0.249642 -0.249642)
							(end -0.2794 -0.1778)
						)
						(arc
							(start -0.2794 0.1778)
							(mid -0.249642 0.249642)
							(end -0.1778 0.2794)
						)
						(arc
							(start 0.1778 0.2794)
							(mid 0.249642 0.249642)
							(end 0.2794 0.1778)
						)
						(arc
							(start 0.2794 -0.1778)
							(mid 0.249642 -0.249642)
							(end 0.1778 -0.2794)
						)
					)
					(width 0)
					(fill yes)
				)
			)
		)
	)
	(footprint ""
		(layer "F.Cu")
		(at 200.279 -167.64 180)
		(property "Reference" "C321"
			(at 0 0 180)
			(layer "F.SilkS")
			(hide yes)
			(effects
				(font
					(size 1.27 1.27)
				)
			)
		)
		(property "Value" "SCD1U16V2KX-3GP"
			(at 1.1811 -2.7051 180)
			(unlocked yes)
			(layer "F.Fab")
			(hide yes)
			(effects
				(font
					(size 1.016 1.016)
					(thickness 0.1524)
				)
			)
		)
		(property "Device Type" "C402H22"
			(at 1.1811 -4.2291 180)
			(unlocked yes)
			(layer "F.Fab")
			(hide yes)
			(effects
				(font
					(size 1.016 1.016)
					(thickness 0.1524)
				)
			)
		)
		(duplicate_pad_numbers_are_jumpers no)
		(fp_rect
			(start -0.4318 0.9525)
			(end 0.4318 -0.9525)
			(stroke
				(width 0)
				(type default)
			)
			(fill no)
			(layer "F.CrtYd")
		)
		(fp_rect
			(start -0.4318 0.9525)
			(end 0.4318 -0.9525)
			(stroke
				(width 0)
				(type default)
			)
			(fill no)
			(layer "F.Fab")
		)
		(pad "1" smd custom
			(at 0 -0.4445 180)
			(size 0.1524 0.1524)
			(layers "F.Cu" "F.Mask" "F.Paste")
			(net "P3V3_B")
			(options
				(clearance outline)
				(anchor circle)
			)
			(primitives
				(gr_poly
					(pts
						(arc
							(start 0.3048 -0.2032)
							(mid 0.275042 -0.275042)
							(end 0.2032 -0.3048)
						)
						(arc
							(start -0.2032 -0.3048)
							(mid -0.275042 -0.275042)
							(end -0.3048 -0.2032)
						)
						(arc
							(start -0.3048 0.2032)
							(mid -0.275042 0.275042)
							(end -0.2032 0.3048)
						)
						(arc
							(start 0.2032 0.3048)
							(mid 0.275042 0.275042)
							(end 0.3048 0.2032)
						)
					)
					(width 0)
					(fill yes)
				)
			)
		)
		(pad "2" smd custom
			(at 0 0.4445 180)
			(size 0.1524 0.1524)
			(layers "F.Cu" "F.Mask" "F.Paste")
			(net "GND")
			(options
				(clearance outline)
				(anchor circle)
			)
			(primitives
				(gr_poly
					(pts
						(arc
							(start 0.3048 -0.2032)
							(mid 0.275042 -0.275042)
							(end 0.2032 -0.3048)
						)
						(arc
							(start -0.2032 -0.3048)
							(mid -0.275042 -0.275042)
							(end -0.3048 -0.2032)
						)
						(arc
							(start -0.3048 0.2032)
							(mid -0.275042 0.275042)
							(end -0.2032 0.3048)
						)
						(arc
							(start 0.2032 0.3048)
							(mid 0.275042 0.275042)
							(end 0.3048 0.2032)
						)
					)
					(width 0)
					(fill yes)
				)
			)
		)
	)
	(footprint ""
		(layer "F.Cu")
		(at 208.407 -99.06 -90)
		(property "Reference" "PC143"
			(at 0 0 270)
			(layer "F.SilkS")
			(hide yes)
			(effects
				(font
					(size 1.27 1.27)
				)
			)
		)
		(property "Value" "SC10U6D3V5KX-1GP"
			(at -0.0762 -6.1214 270)
			(unlocked yes)
			(layer "F.Fab")
			(hide yes)
			(effects
				(font
					(size 1.016 1.016)
					(thickness 0.1524)
				)
			)
		)
		(property "Device Type" "C805H54"
			(at -0.0762 -8.1534 270)
			(unlocked yes)
			(layer "F.Fab")
			(hide yes)
			(effects
				(font
					(size 1.016 1.016)
					(thickness 0.1524)
				)
			)
		)
		(duplicate_pad_numbers_are_jumpers no)
		(fp_line
			(start 0.635 0)
			(end -0.635 0)
			(stroke
				(width 0.508)
				(type default)
			)
			(layer "F.SilkS")
		)
		(fp_rect
			(start -0.9652 1.778)
			(end 0.9652 -1.778)
			(stroke
				(width 0)
				(type default)
			)
			(fill no)
			(layer "F.CrtYd")
		)
		(fp_poly
			(pts
				(xy -0.9652 -1.778) (xy 0.9652 -1.778) (xy 0.9652 1.778) (xy -0.9652 1.778)
			)
			(stroke
				(width 0)
				(type default)
			)
			(fill no)
			(layer "F.Fab")
		)
		(pad "1" smd rect
			(at 0 -0.9652 270)
			(size 1.397 1.143)
			(layers "F.Cu" "F.Mask" "F.Paste")
			(net "P1V5_C")
		)
		(pad "2" smd rect
			(at 0 0.9652 270)
			(size 1.397 1.143)
			(layers "F.Cu" "F.Mask" "F.Paste")
			(net "GND")
		)
	)
	(footprint ""
		(layer "F.Cu")
		(at 180.721 -144.272 -90)
		(property "Reference" "SC1295"
			(at 0 0 270)
			(layer "F.SilkS")
			(hide yes)
			(effects
				(font
					(size 1.27 1.27)
				)
			)
		)
		(property "Value" "SCD1U16V2KX-3GP"
			(at 1.1811 -2.7051 270)
			(unlocked yes)
			(layer "F.Fab")
			(hide yes)
			(effects
				(font
					(size 1.016 1.016)
					(thickness 0.1524)
				)
			)
		)
		(property "Device Type" "C402H22"
			(at 1.1811 -4.2291 270)
			(unlocked yes)
			(layer "F.Fab")
			(hide yes)
			(effects
				(font
					(size 1.016 1.016)
					(thickness 0.1524)
				)
			)
		)
		(duplicate_pad_numbers_are_jumpers no)
		(fp_rect
			(start -0.4318 0.9525)
			(end 0.4318 -0.9525)
			(stroke
				(width 0)
				(type default)
			)
			(fill no)
			(layer "F.CrtYd")
		)
		(fp_rect
			(start -0.4318 0.9525)
			(end 0.4318 -0.9525)
			(stroke
				(width 0)
				(type default)
			)
			(fill no)
			(layer "F.Fab")
		)
		(pad "1" smd custom
			(at 0 -0.4445 270)
			(size 0.1524 0.1524)
			(layers "F.Cu" "F.Mask" "F.Paste")
			(net "EXP_I2C_VREF_3")
			(options
				(clearance outline)
				(anchor circle)
			)
			(primitives
				(gr_poly
					(pts
						(arc
							(start 0.3048 -0.2032)
							(mid 0.275042 -0.275042)
							(end 0.2032 -0.3048)
						)
						(arc
							(start -0.2032 -0.3048)
							(mid -0.275042 -0.275042)
							(end -0.3048 -0.2032)
						)
						(arc
							(start -0.3048 0.2032)
							(mid -0.275042 0.275042)
							(end -0.2032 0.3048)
						)
						(arc
							(start 0.2032 0.3048)
							(mid 0.275042 0.275042)
							(end 0.3048 0.2032)
						)
					)
					(width 0)
					(fill yes)
				)
			)
		)
		(pad "2" smd custom
			(at 0 0.4445 270)
			(size 0.1524 0.1524)
			(layers "F.Cu" "F.Mask" "F.Paste")
			(net "GND")
			(options
				(clearance outline)
				(anchor circle)
			)
			(primitives
				(gr_poly
					(pts
						(arc
							(start 0.3048 -0.2032)
							(mid 0.275042 -0.275042)
							(end 0.2032 -0.3048)
						)
						(arc
							(start -0.2032 -0.3048)
							(mid -0.275042 -0.275042)
							(end -0.3048 -0.2032)
						)
						(arc
							(start -0.3048 0.2032)
							(mid -0.275042 0.275042)
							(end -0.2032 0.3048)
						)
						(arc
							(start 0.2032 0.3048)
							(mid 0.275042 0.275042)
							(end 0.3048 0.2032)
						)
					)
					(width 0)
					(fill yes)
				)
			)
		)
	)
	(footprint ""
		(layer "F.Cu")
		(at 178.816 -221.869)
		(property "Reference" "U172"
			(at 0 0 0)
			(layer "F.SilkS")
			(hide yes)
			(effects
				(font
					(size 1.27 1.27)
				)
			)
		)
		(property "Value" "SN74LVC1G08DCKR-GP"
			(at -2.3368 -8.6868 0)
			(unlocked yes)
			(layer "F.Fab")
			(hide yes)
			(effects
				(font
					(size 1.016 1.016)
					(thickness 0.1524)
				)
			)
		)
		(property "Device Type" "SC70-5H44"
			(at -2.3114 -10.414 0)
			(unlocked yes)
			(layer "F.Fab")
			(hide yes)
			(effects
				(font
					(size 1.016 1.016)
					(thickness 0.1524)
				)
			)
		)
		(duplicate_pad_numbers_are_jumpers no)
		(fp_line
			(start -1.27 -1.7018)
			(end 1.27 -1.7018)
			(stroke
				(width 0.1524)
				(type default)
			)
			(layer "F.SilkS")
		)
		(fp_line
			(start -1.27 1.7018)
			(end -1.27 -1.7018)
			(stroke
				(width 0.1524)
				(type default)
			)
			(layer "F.SilkS")
		)
		(fp_line
			(start 0.6604 -1.8034)
			(end 1.3843 -1.8034)
			(stroke
				(width 0.3302)
				(type default)
			)
			(layer "F.SilkS")
		)
		(fp_line
			(start 1.27 -1.7018)
			(end 1.27 1.7018)
			(stroke
				(width 0.1524)
				(type default)
			)
			(layer "F.SilkS")
		)
		(fp_line
			(start 1.27 1.7018)
			(end -1.27 1.7018)
			(stroke
				(width 0.1524)
				(type default)
			)
			(layer "F.SilkS")
		)
		(fp_line
			(start 1.3843 -1.8034)
			(end 1.3843 -1.1176)
			(stroke
				(width 0.3302)
				(type default)
			)
			(layer "F.SilkS")
		)
		(fp_rect
			(start -1.524 1.9558)
			(end 1.524 -1.9558)
			(stroke
				(width 0)
				(type default)
			)
			(fill no)
			(layer "F.CrtYd")
		)
		(fp_poly
			(pts
				(xy -1.524 -1.9558) (xy 1.524 -1.9558) (xy 1.524 1.9558) (xy -1.524 1.9558)
			)
			(stroke
				(width 0)
				(type default)
			)
			(fill no)
			(layer "F.Fab")
		)
		(pad "1" smd rect
			(at 0.65024 -0.8255)
			(size 0.4064 1.2192)
			(layers "F.Cu" "F.Mask" "F.Paste")
			(net "PWRBTN_OUT_N")
		)
		(pad "2" smd rect
			(at 0 -0.8255)
			(size 0.4064 1.2192)
			(layers "F.Cu" "F.Mask" "F.Paste")
			(net "BMC_PWRBTN_N")
		)
		(pad "3" smd rect
			(at -0.65024 -0.8255)
			(size 0.4064 1.2192)
			(layers "F.Cu" "F.Mask" "F.Paste")
			(net "GND")
		)
		(pad "4" smd rect
			(at -0.65024 0.8255)
			(size 0.4064 1.2192)
			(layers "F.Cu" "F.Mask" "F.Paste")
			(net "PMU_PWRBTN_N")
		)
		(pad "5" smd rect
			(at 0.65024 0.8255)
			(size 0.4064 1.2192)
			(layers "F.Cu" "F.Mask" "F.Paste")
			(net "P3V3_STBY")
		)
	)
	(footprint ""
		(layer "F.Cu")
		(at 327.787 -92.202 -90)
		(property "Reference" "PC35"
			(at 0 0 270)
			(layer "F.SilkS")
			(hide yes)
			(effects
				(font
					(size 1.27 1.27)
				)
			)
		)
		(property "Value" "SCD1U16V3KX-3GP"
			(at 0 -2.8194 270)
			(unlocked yes)
			(layer "F.Fab")
			(hide yes)
			(effects
				(font
					(size 1.016 1.016)
					(thickness 0.1524)
				)
			)
		)
		(property "Device Type" "C603H36"
			(at 0 -4.3434 270)
			(unlocked yes)
			(layer "F.Fab")
			(hide yes)
			(effects
				(font
					(size 1.016 1.016)
					(thickness 0.1524)
				)
			)
		)
		(duplicate_pad_numbers_are_jumpers no)
		(fp_line
			(start 0.508 0)
			(end -0.508 0)
			(stroke
				(width 0.2032)
				(type default)
			)
			(layer "F.SilkS")
		)
		(fp_rect
			(start -0.5842 1.3335)
			(end 0.5842 -1.3335)
			(stroke
				(width 0)
				(type default)
			)
			(fill no)
			(layer "F.CrtYd")
		)
		(fp_rect
			(start -0.5842 1.3335)
			(end 0.5842 -1.3335)
			(stroke
				(width 0)
				(type default)
			)
			(fill no)
			(layer "F.Fab")
		)
		(pad "1" smd custom
			(at 0 -0.762 270)
			(size 0.2159 0.2159)
			(layers "F.Cu" "F.Mask" "F.Paste")
			(net "P3V3_STBY")
			(options
				(clearance outline)
				(anchor circle)
			)
			(primitives
				(gr_poly
					(pts
						(arc
							(start -0.3302 -0.4318)
							(mid -0.402042 -0.402042)
							(end -0.4318 -0.3302)
						)
						(arc
							(start -0.4318 0.3302)
							(mid -0.402042 0.402042)
							(end -0.3302 0.4318)
						)
						(arc
							(start 0.3302 0.4318)
							(mid 0.402042 0.402042)
							(end 0.4318 0.3302)
						)
						(arc
							(start 0.4318 -0.3302)
							(mid 0.402042 -0.402042)
							(end 0.3302 -0.4318)
						)
					)
					(width 0)
					(fill yes)
				)
			)
		)
		(pad "2" smd custom
			(at 0 0.762 270)
			(size 0.2159 0.2159)
			(layers "F.Cu" "F.Mask" "F.Paste")
			(net "GND")
			(options
				(clearance outline)
				(anchor circle)
			)
			(primitives
				(gr_poly
					(pts
						(arc
							(start -0.3302 -0.4318)
							(mid -0.402042 -0.402042)
							(end -0.4318 -0.3302)
						)
						(arc
							(start -0.4318 0.3302)
							(mid -0.402042 0.402042)
							(end -0.3302 0.4318)
						)
						(arc
							(start 0.3302 0.4318)
							(mid 0.402042 0.402042)
							(end 0.4318 0.3302)
						)
						(arc
							(start 0.4318 -0.3302)
							(mid 0.402042 -0.402042)
							(end 0.3302 -0.4318)
						)
					)
					(width 0)
					(fill yes)
				)
			)
		)
	)
	(footprint ""
		(layer "F.Cu")
		(at 107.88777 -71.9328 90)
		(property "Reference" "R586"
			(at 0 0 90)
			(layer "F.SilkS")
			(hide yes)
			(effects
				(font
					(size 1.27 1.27)
				)
			)
		)
		(property "Value" "4K7R2F-GP"
			(at 0.064008 -3.993896 90)
			(unlocked yes)
			(layer "F.Fab")
			(hide yes)
			(effects
				(font
					(size 1.016 1.016)
					(thickness 0.1524)
				)
			)
		)
		(property "Device Type" "R402H16"
			(at 0.064008 -5.517896 90)
			(unlocked yes)
			(layer "F.Fab")
			(hide yes)
			(effects
				(font
					(size 1.016 1.016)
					(thickness 0.1524)
				)
			)
		)
		(duplicate_pad_numbers_are_jumpers no)
		(fp_line
			(start 0.508 -0.9398)
			(end -0.508 -0.9398)
			(stroke
				(width 0.1524)
				(type default)
			)
			(layer "F.SilkS")
		)
		(fp_line
			(start -0.508 -0.9398)
			(end -0.508 0.9398)
			(stroke
				(width 0.1524)
				(type default)
			)
			(layer "F.SilkS")
		)
		(fp_rect
			(start -0.508 0.9398)
			(end 0.508 -0.9398)
			(stroke
				(width 0)
				(type default)
			)
			(fill no)
			(layer "F.CrtYd")
		)
		(fp_rect
			(start -0.508 0.9398)
			(end 0.508 -0.9398)
			(stroke
				(width 0)
				(type default)
			)
			(fill no)
			(layer "F.Fab")
		)
		(pad "1" smd custom
			(at 0 -0.4445 90)
			(size 0.1397 0.1397)
			(layers "F.Cu" "F.Mask" "F.Paste")
			(net "P3V3_STBY")
			(options
				(clearance outline)
				(anchor circle)
			)
			(primitives
				(gr_poly
					(pts
						(arc
							(start -0.1778 -0.2794)
							(mid -0.249642 -0.249642)
							(end -0.2794 -0.1778)
						)
						(arc
							(start -0.2794 0.1778)
							(mid -0.249642 0.249642)
							(end -0.1778 0.2794)
						)
						(arc
							(start 0.1778 0.2794)
							(mid 0.249642 0.249642)
							(end 0.2794 0.1778)
						)
						(arc
							(start 0.2794 -0.1778)
							(mid 0.249642 -0.249642)
							(end 0.1778 -0.2794)
						)
					)
					(width 0)
					(fill yes)
				)
			)
		)
		(pad "2" smd custom
			(at 0 0.4445 90)
			(size 0.1397 0.1397)
			(layers "F.Cu" "F.Mask" "F.Paste")
			(net "TEMP_4_A1")
			(options
				(clearance outline)
				(anchor circle)
			)
			(primitives
				(gr_poly
					(pts
						(arc
							(start -0.1778 -0.2794)
							(mid -0.249642 -0.249642)
							(end -0.2794 -0.1778)
						)
						(arc
							(start -0.2794 0.1778)
							(mid -0.249642 0.249642)
							(end -0.1778 0.2794)
						)
						(arc
							(start 0.1778 0.2794)
							(mid 0.249642 0.249642)
							(end 0.2794 0.1778)
						)
						(arc
							(start 0.2794 -0.1778)
							(mid 0.249642 -0.249642)
							(end 0.1778 -0.2794)
						)
					)
					(width 0)
					(fill yes)
				)
			)
		)
	)
	(footprint ""
		(layer "F.Cu")
		(at 340.516718 -158.473648 90)
		(property "Reference" "R547"
			(at 0 0 90)
			(layer "F.SilkS")
			(hide yes)
			(effects
				(font
					(size 1.27 1.27)
				)
			)
		)
		(property "Value" "4K7R2F-GP"
			(at 0.064008 -3.993896 90)
			(unlocked yes)
			(layer "F.Fab")
			(hide yes)
			(effects
				(font
					(size 1.016 1.016)
					(thickness 0.1524)
				)
			)
		)
		(property "Device Type" "R402H16"
			(at 0.064008 -5.517896 90)
			(unlocked yes)
			(layer "F.Fab")
			(hide yes)
			(effects
				(font
					(size 1.016 1.016)
					(thickness 0.1524)
				)
			)
		)
		(duplicate_pad_numbers_are_jumpers no)
		(fp_line
			(start 0.508 -0.9398)
			(end -0.508 -0.9398)
			(stroke
				(width 0.1524)
				(type default)
			)
			(layer "F.SilkS")
		)
		(fp_line
			(start -0.508 -0.9398)
			(end -0.508 0.9398)
			(stroke
				(width 0.1524)
				(type default)
			)
			(layer "F.SilkS")
		)
		(fp_rect
			(start -0.508 0.9398)
			(end 0.508 -0.9398)
			(stroke
				(width 0)
				(type default)
			)
			(fill no)
			(layer "F.CrtYd")
		)
		(fp_rect
			(start -0.508 0.9398)
			(end 0.508 -0.9398)
			(stroke
				(width 0)
				(type default)
			)
			(fill no)
			(layer "F.Fab")
		)
		(pad "1" smd custom
			(at 0 -0.4445 90)
			(size 0.1397 0.1397)
			(layers "F.Cu" "F.Mask" "F.Paste")
			(net "USB_EN_2")
			(options
				(clearance outline)
				(anchor circle)
			)
			(primitives
				(gr_poly
					(pts
						(arc
							(start -0.1778 -0.2794)
							(mid -0.249642 -0.249642)
							(end -0.2794 -0.1778)
						)
						(arc
							(start -0.2794 0.1778)
							(mid -0.249642 0.249642)
							(end -0.1778 0.2794)
						)
						(arc
							(start 0.1778 0.2794)
							(mid 0.249642 0.249642)
							(end 0.2794 0.1778)
						)
						(arc
							(start 0.2794 -0.1778)
							(mid 0.249642 -0.249642)
							(end 0.1778 -0.2794)
						)
					)
					(width 0)
					(fill yes)
				)
			)
		)
		(pad "2" smd custom
			(at 0 0.4445 90)
			(size 0.1397 0.1397)
			(layers "F.Cu" "F.Mask" "F.Paste")
			(net "GND")
			(options
				(clearance outline)
				(anchor circle)
			)
			(primitives
				(gr_poly
					(pts
						(arc
							(start -0.1778 -0.2794)
							(mid -0.249642 -0.249642)
							(end -0.2794 -0.1778)
						)
						(arc
							(start -0.2794 0.1778)
							(mid -0.249642 0.249642)
							(end -0.1778 0.2794)
						)
						(arc
							(start 0.1778 0.2794)
							(mid 0.249642 0.249642)
							(end 0.2794 0.1778)
						)
						(arc
							(start 0.2794 -0.1778)
							(mid 0.249642 -0.249642)
							(end 0.1778 -0.2794)
						)
					)
					(width 0)
					(fill yes)
				)
			)
		)
	)
	(footprint ""
		(layer "F.Cu")
		(at 317.290958 -61.341 -90)
		(property "Reference" "R254"
			(at 0 0 270)
			(layer "F.SilkS")
			(hide yes)
			(effects
				(font
					(size 1.27 1.27)
				)
			)
		)
		(property "Value" "0R2J-2-GP"
			(at 0.064008 -3.993896 270)
			(unlocked yes)
			(layer "F.Fab")
			(hide yes)
			(effects
				(font
					(size 1.016 1.016)
					(thickness 0.1524)
				)
			)
		)
		(property "Device Type" "R402H16"
			(at 0.064008 -5.517896 270)
			(unlocked yes)
			(layer "F.Fab")
			(hide yes)
			(effects
				(font
					(size 1.016 1.016)
					(thickness 0.1524)
				)
			)
		)
		(duplicate_pad_numbers_are_jumpers no)
		(fp_line
			(start -0.508 -0.9398)
			(end -0.508 0.9398)
			(stroke
				(width 0.1524)
				(type default)
			)
			(layer "F.SilkS")
		)
		(fp_line
			(start 0.508 -0.9398)
			(end -0.508 -0.9398)
			(stroke
				(width 0.1524)
				(type default)
			)
			(layer "F.SilkS")
		)
		(fp_rect
			(start -0.508 0.9398)
			(end 0.508 -0.9398)
			(stroke
				(width 0)
				(type default)
			)
			(fill no)
			(layer "F.CrtYd")
		)
		(fp_rect
			(start -0.508 0.9398)
			(end 0.508 -0.9398)
			(stroke
				(width 0)
				(type default)
			)
			(fill no)
			(layer "F.Fab")
		)
		(pad "1" smd custom
			(at 0 -0.4445 270)
			(size 0.1397 0.1397)
			(layers "F.Cu" "F.Mask" "F.Paste")
			(net "BMC_MBC_I2C_E_SCL")
			(options
				(clearance outline)
				(anchor circle)
			)
			(primitives
				(gr_poly
					(pts
						(arc
							(start -0.1778 -0.2794)
							(mid -0.249642 -0.249642)
							(end -0.2794 -0.1778)
						)
						(arc
							(start -0.2794 0.1778)
							(mid -0.249642 0.249642)
							(end -0.1778 0.2794)
						)
						(arc
							(start 0.1778 0.2794)
							(mid 0.249642 0.249642)
							(end 0.2794 0.1778)
						)
						(arc
							(start 0.2794 -0.1778)
							(mid 0.249642 -0.249642)
							(end 0.1778 -0.2794)
						)
					)
					(width 0)
					(fill yes)
				)
			)
		)
		(pad "2" smd custom
			(at 0 0.4445 270)
			(size 0.1397 0.1397)
			(layers "F.Cu" "F.Mask" "F.Paste")
			(net "I2C_BMC_MSB_CLK_R")
			(options
				(clearance outline)
				(anchor circle)
			)
			(primitives
				(gr_poly
					(pts
						(arc
							(start -0.1778 -0.2794)
							(mid -0.249642 -0.249642)
							(end -0.2794 -0.1778)
						)
						(arc
							(start -0.2794 0.1778)
							(mid -0.249642 0.249642)
							(end -0.1778 0.2794)
						)
						(arc
							(start 0.1778 0.2794)
							(mid 0.249642 0.249642)
							(end 0.2794 0.1778)
						)
						(arc
							(start 0.2794 -0.1778)
							(mid 0.249642 -0.249642)
							(end 0.1778 -0.2794)
						)
					)
					(width 0)
					(fill yes)
				)
			)
		)
	)
	(footprint ""
		(layer "F.Cu")
		(at 107.88777 -70.9168 90)
		(property "Reference" "R592"
			(at 0 0 90)
			(layer "F.SilkS")
			(hide yes)
			(effects
				(font
					(size 1.27 1.27)
				)
			)
		)
		(property "Value" "4K7R2F-GP"
			(at 0.064008 -3.993896 90)
			(unlocked yes)
			(layer "F.Fab")
			(hide yes)
			(effects
				(font
					(size 1.016 1.016)
					(thickness 0.1524)
				)
			)
		)
		(property "Device Type" "R402H16"
			(at 0.064008 -5.517896 90)
			(unlocked yes)
			(layer "F.Fab")
			(hide yes)
			(effects
				(font
					(size 1.016 1.016)
					(thickness 0.1524)
				)
			)
		)
		(duplicate_pad_numbers_are_jumpers no)
		(fp_line
			(start 0.508 -0.9398)
			(end -0.508 -0.9398)
			(stroke
				(width 0.1524)
				(type default)
			)
			(layer "F.SilkS")
		)
		(fp_line
			(start -0.508 -0.9398)
			(end -0.508 0.9398)
			(stroke
				(width 0.1524)
				(type default)
			)
			(layer "F.SilkS")
		)
		(fp_rect
			(start -0.508 0.9398)
			(end 0.508 -0.9398)
			(stroke
				(width 0)
				(type default)
			)
			(fill no)
			(layer "F.CrtYd")
		)
		(fp_rect
			(start -0.508 0.9398)
			(end 0.508 -0.9398)
			(stroke
				(width 0)
				(type default)
			)
			(fill no)
			(layer "F.Fab")
		)
		(pad "1" smd custom
			(at 0 -0.4445 90)
			(size 0.1397 0.1397)
			(layers "F.Cu" "F.Mask" "F.Paste")
			(net "P3V3_STBY")
			(options
				(clearance outline)
				(anchor circle)
			)
			(primitives
				(gr_poly
					(pts
						(arc
							(start -0.1778 -0.2794)
							(mid -0.249642 -0.249642)
							(end -0.2794 -0.1778)
						)
						(arc
							(start -0.2794 0.1778)
							(mid -0.249642 0.249642)
							(end -0.1778 0.2794)
						)
						(arc
							(start 0.1778 0.2794)
							(mid 0.249642 0.249642)
							(end 0.2794 0.1778)
						)
						(arc
							(start 0.2794 -0.1778)
							(mid 0.249642 -0.249642)
							(end 0.1778 -0.2794)
						)
					)
					(width 0)
					(fill yes)
				)
			)
		)
		(pad "2" smd custom
			(at 0 0.4445 90)
			(size 0.1397 0.1397)
			(layers "F.Cu" "F.Mask" "F.Paste")
			(net "TEMP_4_A0")
			(options
				(clearance outline)
				(anchor circle)
			)
			(primitives
				(gr_poly
					(pts
						(arc
							(start -0.1778 -0.2794)
							(mid -0.249642 -0.249642)
							(end -0.2794 -0.1778)
						)
						(arc
							(start -0.2794 0.1778)
							(mid -0.249642 0.249642)
							(end -0.1778 0.2794)
						)
						(arc
							(start 0.1778 0.2794)
							(mid 0.249642 0.249642)
							(end 0.2794 0.1778)
						)
						(arc
							(start 0.2794 -0.1778)
							(mid 0.249642 -0.249642)
							(end 0.1778 -0.2794)
						)
					)
					(width 0)
					(fill yes)
				)
			)
		)
	)
	(footprint ""
		(layer "F.Cu")
		(at 165.1 -115.062 90)
		(property "Reference" "PR161"
			(at 0 0 90)
			(layer "F.SilkS")
			(hide yes)
			(effects
				(font
					(size 1.27 1.27)
				)
			)
		)
		(property "Value" "4K87R2F-GP"
			(at 0.064008 -3.993896 90)
			(unlocked yes)
			(layer "F.Fab")
			(hide yes)
			(effects
				(font
					(size 1.016 1.016)
					(thickness 0.1524)
				)
			)
		)
		(property "Device Type" "R402H16"
			(at 0.064008 -5.517896 90)
			(unlocked yes)
			(layer "F.Fab")
			(hide yes)
			(effects
				(font
					(size 1.016 1.016)
					(thickness 0.1524)
				)
			)
		)
		(duplicate_pad_numbers_are_jumpers no)
		(fp_line
			(start 0.508 -0.9398)
			(end -0.508 -0.9398)
			(stroke
				(width 0.1524)
				(type default)
			)
			(layer "F.SilkS")
		)
		(fp_line
			(start -0.508 -0.9398)
			(end -0.508 0.9398)
			(stroke
				(width 0.1524)
				(type default)
			)
			(layer "F.SilkS")
		)
		(fp_rect
			(start -0.508 0.9398)
			(end 0.508 -0.9398)
			(stroke
				(width 0)
				(type default)
			)
			(fill no)
			(layer "F.CrtYd")
		)
		(fp_rect
			(start -0.508 0.9398)
			(end 0.508 -0.9398)
			(stroke
				(width 0)
				(type default)
			)
			(fill no)
			(layer "F.Fab")
		)
		(pad "1" smd custom
			(at 0 -0.4445 90)
			(size 0.1397 0.1397)
			(layers "F.Cu" "F.Mask" "F.Paste")
			(net "P0V9_E_VFB_R")
			(options
				(clearance outline)
				(anchor circle)
			)
			(primitives
				(gr_poly
					(pts
						(arc
							(start -0.1778 -0.2794)
							(mid -0.249642 -0.249642)
							(end -0.2794 -0.1778)
						)
						(arc
							(start -0.2794 0.1778)
							(mid -0.249642 0.249642)
							(end -0.1778 0.2794)
						)
						(arc
							(start 0.1778 0.2794)
							(mid 0.249642 0.249642)
							(end 0.2794 0.1778)
						)
						(arc
							(start 0.2794 -0.1778)
							(mid 0.249642 -0.249642)
							(end 0.1778 -0.2794)
						)
					)
					(width 0)
					(fill yes)
				)
			)
		)
		(pad "2" smd custom
			(at 0 0.4445 90)
			(size 0.1397 0.1397)
			(layers "F.Cu" "F.Mask" "F.Paste")
			(net "P0V9_E_VFB")
			(options
				(clearance outline)
				(anchor circle)
			)
			(primitives
				(gr_poly
					(pts
						(arc
							(start -0.1778 -0.2794)
							(mid -0.249642 -0.249642)
							(end -0.2794 -0.1778)
						)
						(arc
							(start -0.2794 0.1778)
							(mid -0.249642 0.249642)
							(end -0.1778 0.2794)
						)
						(arc
							(start 0.1778 0.2794)
							(mid 0.249642 0.249642)
							(end 0.2794 0.1778)
						)
						(arc
							(start 0.2794 -0.1778)
							(mid 0.249642 -0.249642)
							(end 0.1778 -0.2794)
						)
					)
					(width 0)
					(fill yes)
				)
			)
		)
	)
	(footprint ""
		(layer "F.Cu")
		(at 121.29897 -114.3 180)
		(property "Reference" "SC1067"
			(at 0 0 180)
			(layer "F.SilkS")
			(hide yes)
			(effects
				(font
					(size 1.27 1.27)
				)
			)
		)
		(property "Value" "SCD01U10V1KX-GP"
			(at -2.8321 -1.7399 180)
			(unlocked yes)
			(layer "F.Fab")
			(hide yes)
			(effects
				(font
					(size 1.016 1.016)
					(thickness 0.1524)
				)
			)
		)
		(property "Device Type" "C0201H13"
			(at -2.8321 -3.2639 180)
			(unlocked yes)
			(layer "F.Fab")
			(hide yes)
			(effects
				(font
					(size 1.016 1.016)
					(thickness 0.1524)
				)
			)
		)
		(duplicate_pad_numbers_are_jumpers no)
		(fp_rect
			(start -0.2794 0.6477)
			(end 0.2794 -0.6477)
			(stroke
				(width 0)
				(type default)
			)
			(fill no)
			(layer "F.CrtYd")
		)
		(fp_rect
			(start -0.2794 0.6477)
			(end 0.2794 -0.6477)
			(stroke
				(width 0)
				(type default)
			)
			(fill no)
			(layer "F.Fab")
		)
		(pad "1" smd custom
			(at 0 -0.2794 180)
			(size 0.0762 0.0762)
			(layers "F.Cu" "F.Mask" "F.Paste")
			(net "SAS_HDD_TX0_N")
			(options
				(clearance outline)
				(anchor circle)
			)
			(primitives
				(gr_poly
					(pts
						(arc
							(start 0.1524 -0.127)
							(mid 0.137521 -0.162921)
							(end 0.1016 -0.1778)
						)
						(arc
							(start -0.1016 -0.1778)
							(mid -0.137521 -0.162921)
							(end -0.1524 -0.127)
						)
						(arc
							(start -0.1524 0.127)
							(mid -0.137521 0.162921)
							(end -0.1016 0.1778)
						)
						(arc
							(start 0.1016 0.1778)
							(mid 0.137521 0.162921)
							(end 0.1524 0.127)
						)
					)
					(width 0)
					(fill yes)
				)
			)
		)
		(pad "2" smd custom
			(at 0 0.2794 180)
			(size 0.0762 0.0762)
			(layers "F.Cu" "F.Mask" "F.Paste")
			(net "SAS_EXP_GF_TX_DN4")
			(options
				(clearance outline)
				(anchor circle)
			)
			(primitives
				(gr_poly
					(pts
						(arc
							(start 0.1524 -0.127)
							(mid 0.137521 -0.162921)
							(end 0.1016 -0.1778)
						)
						(arc
							(start -0.1016 -0.1778)
							(mid -0.137521 -0.162921)
							(end -0.1524 -0.127)
						)
						(arc
							(start -0.1524 0.127)
							(mid -0.137521 0.162921)
							(end -0.1016 0.1778)
						)
						(arc
							(start 0.1016 0.1778)
							(mid 0.137521 0.162921)
							(end 0.1524 0.127)
						)
					)
					(width 0)
					(fill yes)
				)
			)
		)
	)
	(footprint ""
		(layer "F.Cu")
		(at 284.988 -156.464)
		(property "Reference" "R23"
			(at 0 0 0)
			(layer "F.SilkS")
			(hide yes)
			(effects
				(font
					(size 1.27 1.27)
				)
			)
		)
		(property "Value" "10KR2F-2-GP"
			(at 0.064008 -3.993896 0)
			(unlocked yes)
			(layer "F.Fab")
			(hide yes)
			(effects
				(font
					(size 1.016 1.016)
					(thickness 0.1524)
				)
			)
		)
		(property "Device Type" "R402H16"
			(at 0.064008 -5.517896 0)
			(unlocked yes)
			(layer "F.Fab")
			(hide yes)
			(effects
				(font
					(size 1.016 1.016)
					(thickness 0.1524)
				)
			)
		)
		(duplicate_pad_numbers_are_jumpers no)
		(fp_line
			(start -0.508 -0.9398)
			(end -0.508 0.9398)
			(stroke
				(width 0.1524)
				(type default)
			)
			(layer "F.SilkS")
		)
		(fp_line
			(start 0.508 -0.9398)
			(end -0.508 -0.9398)
			(stroke
				(width 0.1524)
				(type default)
			)
			(layer "F.SilkS")
		)
		(fp_rect
			(start -0.508 0.9398)
			(end 0.508 -0.9398)
			(stroke
				(width 0)
				(type default)
			)
			(fill no)
			(layer "F.CrtYd")
		)
		(fp_rect
			(start -0.508 0.9398)
			(end 0.508 -0.9398)
			(stroke
				(width 0)
				(type default)
			)
			(fill no)
			(layer "F.Fab")
		)
		(pad "1" smd custom
			(at 0 -0.4445)
			(size 0.1397 0.1397)
			(layers "F.Cu" "F.Mask" "F.Paste")
			(net "BMC_LSI_BOARD")
			(options
				(clearance outline)
				(anchor circle)
			)
			(primitives
				(gr_poly
					(pts
						(arc
							(start -0.1778 -0.2794)
							(mid -0.249642 -0.249642)
							(end -0.2794 -0.1778)
						)
						(arc
							(start -0.2794 0.1778)
							(mid -0.249642 0.249642)
							(end -0.1778 0.2794)
						)
						(arc
							(start 0.1778 0.2794)
							(mid 0.249642 0.249642)
							(end 0.2794 0.1778)
						)
						(arc
							(start 0.2794 -0.1778)
							(mid 0.249642 -0.249642)
							(end 0.1778 -0.2794)
						)
					)
					(width 0)
					(fill yes)
				)
			)
		)
		(pad "2" smd custom
			(at 0 0.4445)
			(size 0.1397 0.1397)
			(layers "F.Cu" "F.Mask" "F.Paste")
			(net "P3V3_STBY")
			(options
				(clearance outline)
				(anchor circle)
			)
			(primitives
				(gr_poly
					(pts
						(arc
							(start -0.1778 -0.2794)
							(mid -0.249642 -0.249642)
							(end -0.2794 -0.1778)
						)
						(arc
							(start -0.2794 0.1778)
							(mid -0.249642 0.249642)
							(end -0.1778 0.2794)
						)
						(arc
							(start 0.1778 0.2794)
							(mid 0.249642 0.249642)
							(end 0.2794 0.1778)
						)
						(arc
							(start 0.2794 -0.1778)
							(mid 0.249642 -0.249642)
							(end 0.1778 -0.2794)
						)
					)
					(width 0)
					(fill yes)
				)
			)
		)
	)
	(footprint ""
		(layer "F.Cu")
		(at 108.966 -239.141 90)
		(property "Reference" "SR948"
			(at 0 0 90)
			(layer "F.SilkS")
			(hide yes)
			(effects
				(font
					(size 1.27 1.27)
				)
			)
		)
		(property "Value" "4K7R2F-GP"
			(at 0.064008 -3.993896 90)
			(unlocked yes)
			(layer "F.Fab")
			(hide yes)
			(effects
				(font
					(size 1.016 1.016)
					(thickness 0.1524)
				)
			)
		)
		(property "Device Type" "R402H16"
			(at 0.064008 -5.517896 90)
			(unlocked yes)
			(layer "F.Fab")
			(hide yes)
			(effects
				(font
					(size 1.016 1.016)
					(thickness 0.1524)
				)
			)
		)
		(duplicate_pad_numbers_are_jumpers no)
		(fp_line
			(start 0.508 -0.9398)
			(end -0.508 -0.9398)
			(stroke
				(width 0.1524)
				(type default)
			)
			(layer "F.SilkS")
		)
		(fp_line
			(start -0.508 -0.9398)
			(end -0.508 0.9398)
			(stroke
				(width 0.1524)
				(type default)
			)
			(layer "F.SilkS")
		)
		(fp_rect
			(start -0.508 0.9398)
			(end 0.508 -0.9398)
			(stroke
				(width 0)
				(type default)
			)
			(fill no)
			(layer "F.CrtYd")
		)
		(fp_rect
			(start -0.508 0.9398)
			(end 0.508 -0.9398)
			(stroke
				(width 0)
				(type default)
			)
			(fill no)
			(layer "F.Fab")
		)
		(pad "1" smd custom
			(at 0 -0.4445 90)
			(size 0.1397 0.1397)
			(layers "F.Cu" "F.Mask" "F.Paste")
			(net "SAS_FAULT_LED7")
			(options
				(clearance outline)
				(anchor circle)
			)
			(primitives
				(gr_poly
					(pts
						(arc
							(start -0.1778 -0.2794)
							(mid -0.249642 -0.249642)
							(end -0.2794 -0.1778)
						)
						(arc
							(start -0.2794 0.1778)
							(mid -0.249642 0.249642)
							(end -0.1778 0.2794)
						)
						(arc
							(start 0.1778 0.2794)
							(mid 0.249642 0.249642)
							(end 0.2794 0.1778)
						)
						(arc
							(start 0.2794 -0.1778)
							(mid 0.249642 -0.249642)
							(end 0.1778 -0.2794)
						)
					)
					(width 0)
					(fill yes)
				)
			)
		)
		(pad "2" smd custom
			(at 0 0.4445 90)
			(size 0.1397 0.1397)
			(layers "F.Cu" "F.Mask" "F.Paste")
			(net "P3V3_STBY")
			(options
				(clearance outline)
				(anchor circle)
			)
			(primitives
				(gr_poly
					(pts
						(arc
							(start -0.1778 -0.2794)
							(mid -0.249642 -0.249642)
							(end -0.2794 -0.1778)
						)
						(arc
							(start -0.2794 0.1778)
							(mid -0.249642 0.249642)
							(end -0.1778 0.2794)
						)
						(arc
							(start 0.1778 0.2794)
							(mid 0.249642 0.249642)
							(end 0.2794 0.1778)
						)
						(arc
							(start 0.2794 -0.1778)
							(mid 0.249642 -0.249642)
							(end 0.1778 -0.2794)
						)
					)
					(width 0)
					(fill yes)
				)
			)
		)
	)
	(footprint ""
		(layer "F.Cu")
		(at 101.99497 -78.613)
		(property "Reference" "STP146"
			(at 0 0 0)
			(layer "F.SilkS")
			(hide yes)
			(effects
				(font
					(size 1.27 1.27)
				)
			)
		)
		(property "Value" "TPAD28"
			(at 0.0127 -1.8034 0)
			(unlocked yes)
			(layer "F.Fab")
			(hide yes)
			(effects
				(font
					(size 1.016 1.016)
					(thickness 0.1524)
				)
			)
		)
		(property "Device Type" "TPAD28"
			(at 0.0127 -3.3274 0)
			(unlocked yes)
			(layer "F.Fab")
			(hide yes)
			(effects
				(font
					(size 1.016 1.016)
					(thickness 0.1524)
				)
			)
		)
		(duplicate_pad_numbers_are_jumpers no)
		(fp_poly
			(pts
				(arc
					(start 0.3556 0)
					(mid -0.3556 0)
					(end 0.3556 0)
				)
			)
			(stroke
				(width 0)
				(type default)
			)
			(fill no)
			(layer "F.CrtYd")
		)
		(fp_poly
			(pts
				(arc
					(start 0.6096 0)
					(mid -0.6096 0)
					(end 0.6096 0)
				)
			)
			(stroke
				(width 0)
				(type default)
			)
			(fill no)
			(layer "F.Fab")
		)
		(pad "1" smd circle
			(at 0 0)
			(size 0.7112 0.7112)
			(layers "F.Cu" "F.Mask" "F.Paste")
			(net "JTAG_EXP_TDO_R")
		)
	)
	(footprint ""
		(layer "F.Cu")
		(at 92.27947 -106.426 90)
		(property "Reference" "SR818"
			(at 0 0 90)
			(layer "F.SilkS")
			(hide yes)
			(effects
				(font
					(size 1.27 1.27)
				)
			)
		)
		(property "Value" "4K75R2F-1-GP"
			(at 0.064008 -3.993896 90)
			(unlocked yes)
			(layer "F.Fab")
			(hide yes)
			(effects
				(font
					(size 1.016 1.016)
					(thickness 0.1524)
				)
			)
		)
		(property "Device Type" "R402H16"
			(at 0.064008 -5.517896 90)
			(unlocked yes)
			(layer "F.Fab")
			(hide yes)
			(effects
				(font
					(size 1.016 1.016)
					(thickness 0.1524)
				)
			)
		)
		(duplicate_pad_numbers_are_jumpers no)
		(fp_line
			(start 0.508 -0.9398)
			(end -0.508 -0.9398)
			(stroke
				(width 0.1524)
				(type default)
			)
			(layer "F.SilkS")
		)
		(fp_line
			(start -0.508 -0.9398)
			(end -0.508 0.9398)
			(stroke
				(width 0.1524)
				(type default)
			)
			(layer "F.SilkS")
		)
		(fp_rect
			(start -0.508 0.9398)
			(end 0.508 -0.9398)
			(stroke
				(width 0)
				(type default)
			)
			(fill no)
			(layer "F.CrtYd")
		)
		(fp_rect
			(start -0.508 0.9398)
			(end 0.508 -0.9398)
			(stroke
				(width 0)
				(type default)
			)
			(fill no)
			(layer "F.Fab")
		)
		(pad "1" smd custom
			(at 0 -0.4445 90)
			(size 0.1397 0.1397)
			(layers "F.Cu" "F.Mask" "F.Paste")
			(net "P1V8_E")
			(options
				(clearance outline)
				(anchor circle)
			)
			(primitives
				(gr_poly
					(pts
						(arc
							(start -0.1778 -0.2794)
							(mid -0.249642 -0.249642)
							(end -0.2794 -0.1778)
						)
						(arc
							(start -0.2794 0.1778)
							(mid -0.249642 0.249642)
							(end -0.1778 0.2794)
						)
						(arc
							(start 0.1778 0.2794)
							(mid 0.249642 0.249642)
							(end 0.2794 0.1778)
						)
						(arc
							(start 0.2794 -0.1778)
							(mid 0.249642 -0.249642)
							(end 0.1778 -0.2794)
						)
					)
					(width 0)
					(fill yes)
				)
			)
		)
		(pad "2" smd custom
			(at 0 0.4445 90)
			(size 0.1397 0.1397)
			(layers "F.Cu" "F.Mask" "F.Paste")
			(net "SAS_SMART_RX")
			(options
				(clearance outline)
				(anchor circle)
			)
			(primitives
				(gr_poly
					(pts
						(arc
							(start -0.1778 -0.2794)
							(mid -0.249642 -0.249642)
							(end -0.2794 -0.1778)
						)
						(arc
							(start -0.2794 0.1778)
							(mid -0.249642 0.249642)
							(end -0.1778 0.2794)
						)
						(arc
							(start 0.1778 0.2794)
							(mid 0.249642 0.249642)
							(end 0.2794 0.1778)
						)
						(arc
							(start 0.2794 -0.1778)
							(mid 0.249642 -0.249642)
							(end 0.1778 -0.2794)
						)
					)
					(width 0)
					(fill yes)
				)
			)
		)
	)
	(footprint ""
		(layer "F.Cu")
		(at 152.019 -55.499 90)
		(property "Reference" "SR700"
			(at 0 0 90)
			(layer "F.SilkS")
			(hide yes)
			(effects
				(font
					(size 1.27 1.27)
				)
			)
		)
		(property "Value" "10KR2F-2-GP"
			(at 0.064008 -3.993896 90)
			(unlocked yes)
			(layer "F.Fab")
			(hide yes)
			(effects
				(font
					(size 1.016 1.016)
					(thickness 0.1524)
				)
			)
		)
		(property "Device Type" "R402H16"
			(at 0.064008 -5.517896 90)
			(unlocked yes)
			(layer "F.Fab")
			(hide yes)
			(effects
				(font
					(size 1.016 1.016)
					(thickness 0.1524)
				)
			)
		)
		(duplicate_pad_numbers_are_jumpers no)
		(fp_line
			(start 0.508 -0.9398)
			(end -0.508 -0.9398)
			(stroke
				(width 0.1524)
				(type default)
			)
			(layer "F.SilkS")
		)
		(fp_line
			(start -0.508 -0.9398)
			(end -0.508 0.9398)
			(stroke
				(width 0.1524)
				(type default)
			)
			(layer "F.SilkS")
		)
		(fp_rect
			(start -0.508 0.9398)
			(end 0.508 -0.9398)
			(stroke
				(width 0)
				(type default)
			)
			(fill no)
			(layer "F.CrtYd")
		)
		(fp_rect
			(start -0.508 0.9398)
			(end 0.508 -0.9398)
			(stroke
				(width 0)
				(type default)
			)
			(fill no)
			(layer "F.Fab")
		)
		(pad "1" smd custom
			(at 0 -0.4445 90)
			(size 0.1397 0.1397)
			(layers "F.Cu" "F.Mask" "F.Paste")
			(net "XM_ADDR_6")
			(options
				(clearance outline)
				(anchor circle)
			)
			(primitives
				(gr_poly
					(pts
						(arc
							(start -0.1778 -0.2794)
							(mid -0.249642 -0.249642)
							(end -0.2794 -0.1778)
						)
						(arc
							(start -0.2794 0.1778)
							(mid -0.249642 0.249642)
							(end -0.1778 0.2794)
						)
						(arc
							(start 0.1778 0.2794)
							(mid 0.249642 0.249642)
							(end 0.2794 0.1778)
						)
						(arc
							(start 0.2794 -0.1778)
							(mid 0.249642 -0.249642)
							(end 0.1778 -0.2794)
						)
					)
					(width 0)
					(fill yes)
				)
			)
		)
		(pad "2" smd custom
			(at 0 0.4445 90)
			(size 0.1397 0.1397)
			(layers "F.Cu" "F.Mask" "F.Paste")
			(net "GND")
			(options
				(clearance outline)
				(anchor circle)
			)
			(primitives
				(gr_poly
					(pts
						(arc
							(start -0.1778 -0.2794)
							(mid -0.249642 -0.249642)
							(end -0.2794 -0.1778)
						)
						(arc
							(start -0.2794 0.1778)
							(mid -0.249642 0.249642)
							(end -0.1778 0.2794)
						)
						(arc
							(start 0.1778 0.2794)
							(mid 0.249642 0.249642)
							(end 0.2794 0.1778)
						)
						(arc
							(start 0.2794 -0.1778)
							(mid 0.249642 -0.249642)
							(end 0.1778 -0.2794)
						)
					)
					(width 0)
					(fill yes)
				)
			)
		)
	)
	(footprint ""
		(layer "F.Cu")
		(at 14.99997 -94.799912)
		(property "Reference" "CN1"
			(at 0 0 0)
			(layer "F.SilkS")
			(hide yes)
			(effects
				(font
					(size 1.27 1.27)
				)
			)
		)
		(property "Value" "MLX-CONN26-GP"
			(at -8.128 -14.6812 0)
			(unlocked yes)
			(layer "F.Fab")
			(hide yes)
			(effects
				(font
					(size 1.016 1.016)
					(thickness 0.1524)
				)
			)
		)
		(property "Device Type" "75586-0009"
			(at -8.128 -16.2052 0)
			(unlocked yes)
			(layer "F.Fab")
			(hide yes)
			(effects
				(font
					(size 1.016 1.016)
					(thickness 0.1524)
				)
			)
		)
		(duplicate_pad_numbers_are_jumpers no)
		(fp_line
			(start -7.0358 -8.8646)
			(end 7.0358 -8.8646)
			(stroke
				(width 0.1524)
				(type default)
			)
			(layer "F.SilkS")
		)
		(fp_line
			(start -7.0358 3.1496)
			(end -7.0358 -8.8646)
			(stroke
				(width 0.1524)
				(type default)
			)
			(layer "F.SilkS")
		)
		(fp_line
			(start 7.0358 -8.8646)
			(end 7.0358 3.1496)
			(stroke
				(width 0.1524)
				(type default)
			)
			(layer "F.SilkS")
		)
		(fp_line
			(start 7.0358 3.1496)
			(end -7.0358 3.1496)
			(stroke
				(width 0.1524)
				(type default)
			)
			(layer "F.SilkS")
		)
		(fp_rect
			(start -7.2898 3.4036)
			(end 7.2898 -9.1186)
			(stroke
				(width 0)
				(type default)
			)
			(fill no)
			(layer "F.CrtYd")
		)
		(fp_poly
			(pts
				(xy -7.2898 -9.1186) (xy 7.2898 -9.1186) (xy 7.2898 3.4036) (xy -7.2898 3.4036)
			)
			(stroke
				(width 0)
				(type default)
			)
			(fill no)
			(layer "F.Fab")
		)
		(pad "" np_thru_hole circle
			(at -5.99948 0)
			(size 0.254 0.254)
			(drill 1.5494)
			(layers "*.Cu" "*.Mask")
			(clearance 1.0033)
			(thermal_gap 1.0033)
		)
		(pad "" np_thru_hole circle
			(at 5.99948 0)
			(size 0.254 0.254)
			(drill 1.5494)
			(layers "*.Cu" "*.Mask")
			(clearance 1.0033)
			(thermal_gap 1.0033)
		)
		(pad "A1" smd oval
			(at -4.59994 -5.18033)
			(size 0.3556 1.8034)
			(layers "F.Cu" "F.Mask" "F.Paste")
			(net "GND")
		)
		(pad "A2" smd oval
			(at -3.79984 -5.18033)
			(size 0.3556 1.8034)
			(layers "F.Cu" "F.Mask" "F.Paste")
			(net "SAS_EXT_CONN_RX16_P")
		)
		(pad "A3" smd oval
			(at -2.99974 -5.18033)
			(size 0.3556 1.8034)
			(layers "F.Cu" "F.Mask" "F.Paste")
			(net "SAS_EXT_CONN_RX16_N")
		)
		(pad "A4" smd oval
			(at -2.19964 -5.18033)
			(size 0.3556 1.8034)
			(layers "F.Cu" "F.Mask" "F.Paste")
			(net "GND")
		)
		(pad "A5" smd oval
			(at -1.39954 -5.18033)
			(size 0.3556 1.8034)
			(layers "F.Cu" "F.Mask" "F.Paste")
			(net "SAS_EXT_CONN_RX17_P")
		)
		(pad "A6" smd oval
			(at -0.59944 -5.18033)
			(size 0.3556 1.8034)
			(layers "F.Cu" "F.Mask" "F.Paste")
			(net "SAS_EXT_CONN_RX17_N")
		)
		(pad "A7" smd oval
			(at 0.19939 -5.18033)
			(size 0.3556 1.8034)
			(layers "F.Cu" "F.Mask" "F.Paste")
			(net "GND")
		)
		(pad "A8" smd oval
			(at 0.99949 -5.18033)
			(size 0.3556 1.8034)
			(layers "F.Cu" "F.Mask" "F.Paste")
			(net "SAS_EXT_CONN_RX18_P")
		)
		(pad "A9" smd oval
			(at 1.79959 -5.18033)
			(size 0.3556 1.8034)
			(layers "F.Cu" "F.Mask" "F.Paste")
			(net "SAS_EXT_CONN_RX18_N")
		)
		(pad "A10" smd oval
			(at 2.59969 -5.18033)
			(size 0.3556 1.8034)
			(layers "F.Cu" "F.Mask" "F.Paste")
			(net "GND")
		)
		(pad "A11" smd oval
			(at 3.39979 -5.18033)
			(size 0.3556 1.8034)
			(layers "F.Cu" "F.Mask" "F.Paste")
			(net "SAS_EXT_CONN_RX19_P")
		)
		(pad "A12" smd oval
			(at 4.19989 -5.18033)
			(size 0.3556 1.8034)
			(layers "F.Cu" "F.Mask" "F.Paste")
			(net "SAS_EXT_CONN_RX19_N")
		)
		(pad "A13" smd oval
			(at 4.99999 -5.18033)
			(size 0.3556 1.8034)
			(layers "F.Cu" "F.Mask" "F.Paste")
			(net "GND")
		)
		(pad "B1" smd oval
			(at -4.99999 -7.68985)
			(size 0.3556 1.8034)
			(layers "F.Cu" "F.Mask" "F.Paste")
			(net "GND")
		)
		(pad "B2" smd oval
			(at -4.19989 -7.68985)
			(size 0.3556 1.8034)
			(layers "F.Cu" "F.Mask" "F.Paste")
			(net "IOC_RAID_TX_P4")
		)
		(pad "B3" smd oval
			(at -3.39979 -7.68985)
			(size 0.3556 1.8034)
			(layers "F.Cu" "F.Mask" "F.Paste")
			(net "IOC_RAID_TX_N4")
		)
		(pad "B4" smd oval
			(at -2.59969 -7.68985)
			(size 0.3556 1.8034)
			(layers "F.Cu" "F.Mask" "F.Paste")
			(net "GND")
		)
		(pad "B5" smd oval
			(at -1.79959 -7.68985)
			(size 0.3556 1.8034)
			(layers "F.Cu" "F.Mask" "F.Paste")
			(net "IOC_RAID_TX_P5")
		)
		(pad "B6" smd oval
			(at -0.99949 -7.68985)
			(size 0.3556 1.8034)
			(layers "F.Cu" "F.Mask" "F.Paste")
			(net "IOC_RAID_TX_N5")
		)
		(pad "B7" smd oval
			(at -0.19939 -7.68985)
			(size 0.3556 1.8034)
			(layers "F.Cu" "F.Mask" "F.Paste")
			(net "GND")
		)
		(pad "B8" smd oval
			(at 0.59944 -7.68985)
			(size 0.3556 1.8034)
			(layers "F.Cu" "F.Mask" "F.Paste")
			(net "IOC_RAID_TX_P6")
		)
		(pad "B9" smd oval
			(at 1.39954 -7.68985)
			(size 0.3556 1.8034)
			(layers "F.Cu" "F.Mask" "F.Paste")
			(net "IOC_RAID_TX_N6")
		)
		(pad "B10" smd oval
			(at 2.19964 -7.68985)
			(size 0.3556 1.8034)
			(layers "F.Cu" "F.Mask" "F.Paste")
			(net "GND")
		)
		(pad "B11" smd oval
			(at 2.99974 -7.68985)
			(size 0.3556 1.8034)
			(layers "F.Cu" "F.Mask" "F.Paste")
			(net "IOC_RAID_TX_P7")
		)
		(pad "B12" smd oval
			(at 3.79984 -7.68985)
			(size 0.3556 1.8034)
			(layers "F.Cu" "F.Mask" "F.Paste")
			(net "IOC_RAID_TX_N7")
		)
		(pad "B13" smd oval
			(at 4.59994 -7.68985)
			(size 0.3556 1.8034)
			(layers "F.Cu" "F.Mask" "F.Paste")
			(net "GND")
		)
		(zone
			(layer "F.Cu")
			(hatch none 0.5)
			(connect_pads
				(clearance 0)
			)
			(min_thickness 0.25)
			(keepout
				(tracks allowed)
				(vias not_allowed)
				(pads allowed)
				(copperpour not_allowed)
				(footprints allowed)
			)
			(placement
				(enabled no)
				(sheetname "")
			)
			(fill
				(thermal_gap 0.5)
				(thermal_bridge_width 0.5)
				(island_removal_mode 0)
			)
			(polygon
				(pts
					(xy 8.05053 -91.650312) (xy 9.88949 -91.650312) (xy 9.88949 -93.109542) (xy 8.05053 -93.109542)
				)
			)
		)
		(zone
			(layer "F.Cu")
			(hatch none 0.5)
			(connect_pads
				(clearance 0)
			)
			(min_thickness 0.25)
			(keepout
				(tracks not_allowed)
				(vias allowed)
				(pads allowed)
				(copperpour not_allowed)
				(footprints allowed)
			)
			(placement
				(enabled no)
				(sheetname "")
			)
			(fill
				(thermal_gap 0.5)
				(thermal_bridge_width 0.5)
				(island_removal_mode 0)
			)
			(polygon
				(pts
					(xy 8.05053 -91.650312) (xy 9.88949 -91.650312) (xy 9.88949 -93.109542) (xy 8.05053 -93.109542)
				)
			)
		)
		(zone
			(layer "F.Cu")
			(hatch none 0.5)
			(connect_pads
				(clearance 0)
			)
			(min_thickness 0.25)
			(keepout
				(tracks allowed)
				(vias not_allowed)
				(pads allowed)
				(copperpour not_allowed)
				(footprints allowed)
			)
			(placement
				(enabled no)
				(sheetname "")
			)
			(fill
				(thermal_gap 0.5)
				(thermal_bridge_width 0.5)
				(island_removal_mode 0)
			)
			(polygon
				(pts
					(xy 20.11045 -91.650312) (xy 21.94941 -91.650312) (xy 21.94941 -93.109542) (xy 20.11045 -93.109542)
				)
			)
		)
		(zone
			(layer "F.Cu")
			(hatch none 0.5)
			(connect_pads
				(clearance 0)
			)
			(min_thickness 0.25)
			(keepout
				(tracks not_allowed)
				(vias allowed)
				(pads allowed)
				(copperpour not_allowed)
				(footprints allowed)
			)
			(placement
				(enabled no)
				(sheetname "")
			)
			(fill
				(thermal_gap 0.5)
				(thermal_bridge_width 0.5)
				(island_removal_mode 0)
			)
			(polygon
				(pts
					(xy 20.11045 -91.650312) (xy 21.94941 -91.650312) (xy 21.94941 -93.109542) (xy 20.11045 -93.109542)
				)
			)
		)
		(zone
			(layers "F.Cu" "B.Cu" "In1.Cu" "In2.Cu" "In3.Cu" "In4.Cu" "In5.Cu" "In6.Cu")
			(hatch none 0.5)
			(connect_pads
				(clearance 0)
			)
			(min_thickness 0.25)
			(keepout
				(tracks not_allowed)
				(vias allowed)
				(pads allowed)
				(copperpour not_allowed)
				(footprints allowed)
			)
			(placement
				(enabled no)
				(sheetname "")
			)
			(fill
				(thermal_gap 0.5)
				(thermal_bridge_width 0.5)
				(island_removal_mode 0)
			)
			(polygon
				(pts
					(arc
						(start 10.07999 -94.799912)
						(mid 7.92099 -94.799912)
						(end 10.07999 -94.799912)
					)
				)
			)
		)
		(zone
			(layers "F.Cu" "B.Cu" "In1.Cu" "In2.Cu" "In3.Cu" "In4.Cu" "In5.Cu" "In6.Cu")
			(hatch none 0.5)
			(connect_pads
				(clearance 0)
			)
			(min_thickness 0.25)
			(keepout
				(tracks not_allowed)
				(vias allowed)
				(pads allowed)
				(copperpour not_allowed)
				(footprints allowed)
			)
			(placement
				(enabled no)
				(sheetname "")
			)
			(fill
				(thermal_gap 0.5)
				(thermal_bridge_width 0.5)
				(island_removal_mode 0)
			)
			(polygon
				(pts
					(arc
						(start 22.07895 -94.799912)
						(mid 19.91995 -94.799912)
						(end 22.07895 -94.799912)
					)
				)
			)
		)
	)
	(footprint ""
		(layer "F.Cu")
		(at 81.024222 -114.394742 -90)
		(property "Reference" "SC1284"
			(at 0 0 270)
			(layer "F.SilkS")
			(hide yes)
			(effects
				(font
					(size 1.27 1.27)
				)
			)
		)
		(property "Value" "SCD1U16V2KX-3GP"
			(at 1.1811 -2.7051 270)
			(unlocked yes)
			(layer "F.Fab")
			(hide yes)
			(effects
				(font
					(size 1.016 1.016)
					(thickness 0.1524)
				)
			)
		)
		(property "Device Type" "C402H22"
			(at 1.1811 -4.2291 270)
			(unlocked yes)
			(layer "F.Fab")
			(hide yes)
			(effects
				(font
					(size 1.016 1.016)
					(thickness 0.1524)
				)
			)
		)
		(duplicate_pad_numbers_are_jumpers no)
		(fp_rect
			(start -0.4318 0.9525)
			(end 0.4318 -0.9525)
			(stroke
				(width 0)
				(type default)
			)
			(fill no)
			(layer "F.CrtYd")
		)
		(fp_rect
			(start -0.4318 0.9525)
			(end 0.4318 -0.9525)
			(stroke
				(width 0)
				(type default)
			)
			(fill no)
			(layer "F.Fab")
		)
		(pad "1" smd custom
			(at 0 -0.4445 270)
			(size 0.1524 0.1524)
			(layers "F.Cu" "F.Mask" "F.Paste")
			(net "EXP_I2C_VREF_1")
			(options
				(clearance outline)
				(anchor circle)
			)
			(primitives
				(gr_poly
					(pts
						(arc
							(start 0.3048 -0.2032)
							(mid 0.275042 -0.275042)
							(end 0.2032 -0.3048)
						)
						(arc
							(start -0.2032 -0.3048)
							(mid -0.275042 -0.275042)
							(end -0.3048 -0.2032)
						)
						(arc
							(start -0.3048 0.2032)
							(mid -0.275042 0.275042)
							(end -0.2032 0.3048)
						)
						(arc
							(start 0.2032 0.3048)
							(mid 0.275042 0.275042)
							(end 0.3048 0.2032)
						)
					)
					(width 0)
					(fill yes)
				)
			)
		)
		(pad "2" smd custom
			(at 0 0.4445 270)
			(size 0.1524 0.1524)
			(layers "F.Cu" "F.Mask" "F.Paste")
			(net "GND")
			(options
				(clearance outline)
				(anchor circle)
			)
			(primitives
				(gr_poly
					(pts
						(arc
							(start 0.3048 -0.2032)
							(mid 0.275042 -0.275042)
							(end 0.2032 -0.3048)
						)
						(arc
							(start -0.2032 -0.3048)
							(mid -0.275042 -0.275042)
							(end -0.3048 -0.2032)
						)
						(arc
							(start -0.3048 0.2032)
							(mid -0.275042 0.275042)
							(end -0.2032 0.3048)
						)
						(arc
							(start 0.2032 0.3048)
							(mid 0.275042 0.275042)
							(end 0.3048 0.2032)
						)
					)
					(width 0)
					(fill yes)
				)
			)
		)
	)
	(footprint ""
		(layer "F.Cu")
		(at 344.021918 -157.838648)
		(property "Reference" "R227"
			(at 0 0 0)
			(layer "F.SilkS")
			(hide yes)
			(effects
				(font
					(size 1.27 1.27)
				)
			)
		)
		(property "Value" "4K7R2F-GP"
			(at 0.064008 -3.993896 0)
			(unlocked yes)
			(layer "F.Fab")
			(hide yes)
			(effects
				(font
					(size 1.016 1.016)
					(thickness 0.1524)
				)
			)
		)
		(property "Device Type" "R402H16"
			(at 0.064008 -5.517896 0)
			(unlocked yes)
			(layer "F.Fab")
			(hide yes)
			(effects
				(font
					(size 1.016 1.016)
					(thickness 0.1524)
				)
			)
		)
		(duplicate_pad_numbers_are_jumpers no)
		(fp_line
			(start -0.508 -0.9398)
			(end -0.508 0.9398)
			(stroke
				(width 0.1524)
				(type default)
			)
			(layer "F.SilkS")
		)
		(fp_line
			(start 0.508 -0.9398)
			(end -0.508 -0.9398)
			(stroke
				(width 0.1524)
				(type default)
			)
			(layer "F.SilkS")
		)
		(fp_rect
			(start -0.508 0.9398)
			(end 0.508 -0.9398)
			(stroke
				(width 0)
				(type default)
			)
			(fill no)
			(layer "F.CrtYd")
		)
		(fp_rect
			(start -0.508 0.9398)
			(end 0.508 -0.9398)
			(stroke
				(width 0)
				(type default)
			)
			(fill no)
			(layer "F.Fab")
		)
		(pad "1" smd custom
			(at 0 -0.4445)
			(size 0.1397 0.1397)
			(layers "F.Cu" "F.Mask" "F.Paste")
			(net "P3V3_STBY")
			(options
				(clearance outline)
				(anchor circle)
			)
			(primitives
				(gr_poly
					(pts
						(arc
							(start -0.1778 -0.2794)
							(mid -0.249642 -0.249642)
							(end -0.2794 -0.1778)
						)
						(arc
							(start -0.2794 0.1778)
							(mid -0.249642 0.249642)
							(end -0.1778 0.2794)
						)
						(arc
							(start 0.1778 0.2794)
							(mid 0.249642 0.249642)
							(end 0.2794 0.1778)
						)
						(arc
							(start 0.2794 -0.1778)
							(mid 0.249642 -0.249642)
							(end 0.1778 -0.2794)
						)
					)
					(width 0)
					(fill yes)
				)
			)
		)
		(pad "2" smd custom
			(at 0 0.4445)
			(size 0.1397 0.1397)
			(layers "F.Cu" "F.Mask" "F.Paste")
			(net "USB_EN_1")
			(options
				(clearance outline)
				(anchor circle)
			)
			(primitives
				(gr_poly
					(pts
						(arc
							(start -0.1778 -0.2794)
							(mid -0.249642 -0.249642)
							(end -0.2794 -0.1778)
						)
						(arc
							(start -0.2794 0.1778)
							(mid -0.249642 0.249642)
							(end -0.1778 0.2794)
						)
						(arc
							(start 0.1778 0.2794)
							(mid 0.249642 0.249642)
							(end 0.2794 0.1778)
						)
						(arc
							(start 0.2794 -0.1778)
							(mid 0.249642 -0.249642)
							(end 0.1778 -0.2794)
						)
					)
					(width 0)
					(fill yes)
				)
			)
		)
	)
	(footprint ""
		(layer "F.Cu")
		(at 190.554864 -31.695136 180)
		(property "Reference" "C224"
			(at 0 0 180)
			(layer "F.SilkS")
			(hide yes)
			(effects
				(font
					(size 1.27 1.27)
				)
			)
		)
		(property "Value" "SCD01U16V2KX-3GP"
			(at 1.1811 -2.7051 180)
			(unlocked yes)
			(layer "F.Fab")
			(hide yes)
			(effects
				(font
					(size 1.016 1.016)
					(thickness 0.1524)
				)
			)
		)
		(property "Device Type" "C402H22"
			(at 1.1811 -4.2291 180)
			(unlocked yes)
			(layer "F.Fab")
			(hide yes)
			(effects
				(font
					(size 1.016 1.016)
					(thickness 0.1524)
				)
			)
		)
		(duplicate_pad_numbers_are_jumpers no)
		(fp_rect
			(start -0.4318 0.9525)
			(end 0.4318 -0.9525)
			(stroke
				(width 0)
				(type default)
			)
			(fill no)
			(layer "F.CrtYd")
		)
		(fp_rect
			(start -0.4318 0.9525)
			(end 0.4318 -0.9525)
			(stroke
				(width 0)
				(type default)
			)
			(fill no)
			(layer "F.Fab")
		)
		(pad "1" smd custom
			(at 0 -0.4445 180)
			(size 0.1524 0.1524)
			(layers "F.Cu" "F.Mask" "F.Paste")
			(net "PHY_DVDD")
			(options
				(clearance outline)
				(anchor circle)
			)
			(primitives
				(gr_poly
					(pts
						(arc
							(start 0.3048 -0.2032)
							(mid 0.275042 -0.275042)
							(end 0.2032 -0.3048)
						)
						(arc
							(start -0.2032 -0.3048)
							(mid -0.275042 -0.275042)
							(end -0.3048 -0.2032)
						)
						(arc
							(start -0.3048 0.2032)
							(mid -0.275042 0.275042)
							(end -0.2032 0.3048)
						)
						(arc
							(start 0.2032 0.3048)
							(mid 0.275042 0.275042)
							(end 0.3048 0.2032)
						)
					)
					(width 0)
					(fill yes)
				)
			)
		)
		(pad "2" smd custom
			(at 0 0.4445 180)
			(size 0.1524 0.1524)
			(layers "F.Cu" "F.Mask" "F.Paste")
			(net "GND")
			(options
				(clearance outline)
				(anchor circle)
			)
			(primitives
				(gr_poly
					(pts
						(arc
							(start 0.3048 -0.2032)
							(mid 0.275042 -0.275042)
							(end 0.2032 -0.3048)
						)
						(arc
							(start -0.2032 -0.3048)
							(mid -0.275042 -0.275042)
							(end -0.3048 -0.2032)
						)
						(arc
							(start -0.3048 0.2032)
							(mid -0.275042 0.275042)
							(end -0.2032 0.3048)
						)
						(arc
							(start 0.2032 0.3048)
							(mid 0.275042 0.275042)
							(end 0.3048 0.2032)
						)
					)
					(width 0)
					(fill yes)
				)
			)
		)
	)
	(footprint ""
		(layer "F.Cu")
		(at 69.596 -231.902 180)
		(property "Reference" "R2118"
			(at 0 0 180)
			(layer "F.SilkS")
			(hide yes)
			(effects
				(font
					(size 1.27 1.27)
				)
			)
		)
		(property "Value" "1MR3J-L-GP"
			(at -0.0254 -2.5146 180)
			(unlocked yes)
			(layer "F.Fab")
			(hide yes)
			(effects
				(font
					(size 1.016 1.016)
					(thickness 0.1524)
				)
			)
		)
		(property "Device Type" "R603H22"
			(at -0.0254 -4.0386 180)
			(unlocked yes)
			(layer "F.Fab")
			(hide yes)
			(effects
				(font
					(size 1.016 1.016)
					(thickness 0.1524)
				)
			)
		)
		(duplicate_pad_numbers_are_jumpers no)
		(fp_line
			(start 0.2032 0)
			(end 0.4826 0)
			(stroke
				(width 0.2032)
				(type default)
			)
			(layer "F.SilkS")
		)
		(fp_line
			(start -0.4826 0)
			(end -0.2032 0)
			(stroke
				(width 0.2032)
				(type default)
			)
			(layer "F.SilkS")
		)
		(fp_rect
			(start -0.5842 1.3335)
			(end 0.5842 -1.3335)
			(stroke
				(width 0)
				(type default)
			)
			(fill no)
			(layer "F.CrtYd")
		)
		(fp_rect
			(start -0.5842 1.3335)
			(end 0.5842 -1.3335)
			(stroke
				(width 0)
				(type default)
			)
			(fill no)
			(layer "F.Fab")
		)
		(pad "1" smd custom
			(at 0 -0.762 180)
			(size 0.2159 0.2159)
			(layers "F.Cu" "F.Mask" "F.Paste")
			(net "MB0_CM_GATE_R")
			(options
				(clearance outline)
				(anchor circle)
			)
			(primitives
				(gr_poly
					(pts
						(arc
							(start -0.3302 -0.4318)
							(mid -0.402042 -0.402042)
							(end -0.4318 -0.3302)
						)
						(arc
							(start -0.4318 0.3302)
							(mid -0.402042 0.402042)
							(end -0.3302 0.4318)
						)
						(arc
							(start 0.3302 0.4318)
							(mid 0.402042 0.402042)
							(end 0.4318 0.3302)
						)
						(arc
							(start 0.4318 -0.3302)
							(mid 0.402042 -0.402042)
							(end 0.3302 -0.4318)
						)
					)
					(width 0)
					(fill yes)
				)
			)
		)
		(pad "2" smd custom
			(at 0 0.762 180)
			(size 0.2159 0.2159)
			(layers "F.Cu" "F.Mask" "F.Paste")
			(net "GND")
			(options
				(clearance outline)
				(anchor circle)
			)
			(primitives
				(gr_poly
					(pts
						(arc
							(start -0.3302 -0.4318)
							(mid -0.402042 -0.402042)
							(end -0.4318 -0.3302)
						)
						(arc
							(start -0.4318 0.3302)
							(mid -0.402042 0.402042)
							(end -0.3302 0.4318)
						)
						(arc
							(start 0.3302 0.4318)
							(mid 0.402042 0.402042)
							(end 0.4318 0.3302)
						)
						(arc
							(start 0.4318 -0.3302)
							(mid 0.402042 -0.402042)
							(end 0.3302 -0.4318)
						)
					)
					(width 0)
					(fill yes)
				)
			)
		)
	)
	(footprint ""
		(layer "F.Cu")
		(at 343.056718 -158.219648 180)
		(property "Reference" "C162"
			(at 0 0 180)
			(layer "F.SilkS")
			(hide yes)
			(effects
				(font
					(size 1.27 1.27)
				)
			)
		)
		(property "Value" "SC1U10V2KX-4-GP"
			(at 1.1811 -2.7051 180)
			(unlocked yes)
			(layer "F.Fab")
			(hide yes)
			(effects
				(font
					(size 1.016 1.016)
					(thickness 0.1524)
				)
			)
		)
		(property "Device Type" "C402H22"
			(at 1.1811 -4.2291 180)
			(unlocked yes)
			(layer "F.Fab")
			(hide yes)
			(effects
				(font
					(size 1.016 1.016)
					(thickness 0.1524)
				)
			)
		)
		(duplicate_pad_numbers_are_jumpers no)
		(fp_rect
			(start -0.4318 0.9525)
			(end 0.4318 -0.9525)
			(stroke
				(width 0)
				(type default)
			)
			(fill no)
			(layer "F.CrtYd")
		)
		(fp_rect
			(start -0.4318 0.9525)
			(end 0.4318 -0.9525)
			(stroke
				(width 0)
				(type default)
			)
			(fill no)
			(layer "F.Fab")
		)
		(pad "1" smd custom
			(at 0 -0.4445 180)
			(size 0.1524 0.1524)
			(layers "F.Cu" "F.Mask" "F.Paste")
			(net "CRFILT")
			(options
				(clearance outline)
				(anchor circle)
			)
			(primitives
				(gr_poly
					(pts
						(arc
							(start 0.3048 -0.2032)
							(mid 0.275042 -0.275042)
							(end 0.2032 -0.3048)
						)
						(arc
							(start -0.2032 -0.3048)
							(mid -0.275042 -0.275042)
							(end -0.3048 -0.2032)
						)
						(arc
							(start -0.3048 0.2032)
							(mid -0.275042 0.275042)
							(end -0.2032 0.3048)
						)
						(arc
							(start 0.2032 0.3048)
							(mid 0.275042 0.275042)
							(end 0.3048 0.2032)
						)
					)
					(width 0)
					(fill yes)
				)
			)
		)
		(pad "2" smd custom
			(at 0 0.4445 180)
			(size 0.1524 0.1524)
			(layers "F.Cu" "F.Mask" "F.Paste")
			(net "GND")
			(options
				(clearance outline)
				(anchor circle)
			)
			(primitives
				(gr_poly
					(pts
						(arc
							(start 0.3048 -0.2032)
							(mid 0.275042 -0.275042)
							(end 0.2032 -0.3048)
						)
						(arc
							(start -0.2032 -0.3048)
							(mid -0.275042 -0.275042)
							(end -0.3048 -0.2032)
						)
						(arc
							(start -0.3048 0.2032)
							(mid -0.275042 0.275042)
							(end -0.2032 0.3048)
						)
						(arc
							(start 0.2032 0.3048)
							(mid 0.275042 0.275042)
							(end 0.3048 0.2032)
						)
					)
					(width 0)
					(fill yes)
				)
			)
		)
	)
	(footprint ""
		(layer "F.Cu")
		(at 195.199 -217.932 90)
		(property "Reference" "R221"
			(at 0 0 90)
			(layer "F.SilkS")
			(hide yes)
			(effects
				(font
					(size 1.27 1.27)
				)
			)
		)
		(property "Value" "10KR2F-2-GP"
			(at 0.064008 -3.993896 90)
			(unlocked yes)
			(layer "F.Fab")
			(hide yes)
			(effects
				(font
					(size 1.016 1.016)
					(thickness 0.1524)
				)
			)
		)
		(property "Device Type" "R402H16"
			(at 0.064008 -5.517896 90)
			(unlocked yes)
			(layer "F.Fab")
			(hide yes)
			(effects
				(font
					(size 1.016 1.016)
					(thickness 0.1524)
				)
			)
		)
		(duplicate_pad_numbers_are_jumpers no)
		(fp_line
			(start 0.508 -0.9398)
			(end -0.508 -0.9398)
			(stroke
				(width 0.1524)
				(type default)
			)
			(layer "F.SilkS")
		)
		(fp_line
			(start -0.508 -0.9398)
			(end -0.508 0.9398)
			(stroke
				(width 0.1524)
				(type default)
			)
			(layer "F.SilkS")
		)
		(fp_rect
			(start -0.508 0.9398)
			(end 0.508 -0.9398)
			(stroke
				(width 0)
				(type default)
			)
			(fill no)
			(layer "F.CrtYd")
		)
		(fp_rect
			(start -0.508 0.9398)
			(end 0.508 -0.9398)
			(stroke
				(width 0)
				(type default)
			)
			(fill no)
			(layer "F.Fab")
		)
		(pad "1" smd custom
			(at 0 -0.4445 90)
			(size 0.1397 0.1397)
			(layers "F.Cu" "F.Mask" "F.Paste")
			(net "P3V3_STBY")
			(options
				(clearance outline)
				(anchor circle)
			)
			(primitives
				(gr_poly
					(pts
						(arc
							(start -0.1778 -0.2794)
							(mid -0.249642 -0.249642)
							(end -0.2794 -0.1778)
						)
						(arc
							(start -0.2794 0.1778)
							(mid -0.249642 0.249642)
							(end -0.1778 0.2794)
						)
						(arc
							(start 0.1778 0.2794)
							(mid 0.249642 0.249642)
							(end 0.2794 0.1778)
						)
						(arc
							(start 0.2794 -0.1778)
							(mid 0.249642 -0.249642)
							(end 0.1778 -0.2794)
						)
					)
					(width 0)
					(fill yes)
				)
			)
		)
		(pad "2" smd custom
			(at 0 0.4445 90)
			(size 0.1397 0.1397)
			(layers "F.Cu" "F.Mask" "F.Paste")
			(net "RSTBTN_OUT_N")
			(options
				(clearance outline)
				(anchor circle)
			)
			(primitives
				(gr_poly
					(pts
						(arc
							(start -0.1778 -0.2794)
							(mid -0.249642 -0.249642)
							(end -0.2794 -0.1778)
						)
						(arc
							(start -0.2794 0.1778)
							(mid -0.249642 0.249642)
							(end -0.1778 0.2794)
						)
						(arc
							(start 0.1778 0.2794)
							(mid 0.249642 0.249642)
							(end 0.2794 0.1778)
						)
						(arc
							(start 0.2794 -0.1778)
							(mid 0.249642 -0.249642)
							(end 0.1778 -0.2794)
						)
					)
					(width 0)
					(fill yes)
				)
			)
		)
	)
	(footprint ""
		(layer "F.Cu")
		(at 238.6203 -113.9698 -90)
		(property "Reference" "SC1299"
			(at 0 0 270)
			(layer "F.SilkS")
			(hide yes)
			(effects
				(font
					(size 1.27 1.27)
				)
			)
		)
		(property "Value" "SCD1U16V2KX-3GP"
			(at 1.1811 -2.7051 270)
			(unlocked yes)
			(layer "F.Fab")
			(hide yes)
			(effects
				(font
					(size 1.016 1.016)
					(thickness 0.1524)
				)
			)
		)
		(property "Device Type" "C402H22"
			(at 1.1811 -4.2291 270)
			(unlocked yes)
			(layer "F.Fab")
			(hide yes)
			(effects
				(font
					(size 1.016 1.016)
					(thickness 0.1524)
				)
			)
		)
		(duplicate_pad_numbers_are_jumpers no)
		(fp_rect
			(start -0.4318 0.9525)
			(end 0.4318 -0.9525)
			(stroke
				(width 0)
				(type default)
			)
			(fill no)
			(layer "F.CrtYd")
		)
		(fp_rect
			(start -0.4318 0.9525)
			(end 0.4318 -0.9525)
			(stroke
				(width 0)
				(type default)
			)
			(fill no)
			(layer "F.Fab")
		)
		(pad "1" smd custom
			(at 0 -0.4445 270)
			(size 0.1524 0.1524)
			(layers "F.Cu" "F.Mask" "F.Paste")
			(net "P3V3_STBY")
			(options
				(clearance outline)
				(anchor circle)
			)
			(primitives
				(gr_poly
					(pts
						(arc
							(start 0.3048 -0.2032)
							(mid 0.275042 -0.275042)
							(end 0.2032 -0.3048)
						)
						(arc
							(start -0.2032 -0.3048)
							(mid -0.275042 -0.275042)
							(end -0.3048 -0.2032)
						)
						(arc
							(start -0.3048 0.2032)
							(mid -0.275042 0.275042)
							(end -0.2032 0.3048)
						)
						(arc
							(start 0.2032 0.3048)
							(mid 0.275042 0.275042)
							(end 0.3048 0.2032)
						)
					)
					(width 0)
					(fill yes)
				)
			)
		)
		(pad "2" smd custom
			(at 0 0.4445 270)
			(size 0.1524 0.1524)
			(layers "F.Cu" "F.Mask" "F.Paste")
			(net "GND")
			(options
				(clearance outline)
				(anchor circle)
			)
			(primitives
				(gr_poly
					(pts
						(arc
							(start 0.3048 -0.2032)
							(mid 0.275042 -0.275042)
							(end 0.2032 -0.3048)
						)
						(arc
							(start -0.2032 -0.3048)
							(mid -0.275042 -0.275042)
							(end -0.3048 -0.2032)
						)
						(arc
							(start -0.3048 0.2032)
							(mid -0.275042 0.275042)
							(end -0.2032 0.3048)
						)
						(arc
							(start 0.2032 0.3048)
							(mid 0.275042 0.275042)
							(end 0.3048 0.2032)
						)
					)
					(width 0)
					(fill yes)
				)
			)
		)
	)
	(footprint ""
		(layer "F.Cu")
		(at 264.033 -44.958)
		(property "Reference" "PR50"
			(at 0 0 0)
			(layer "F.SilkS")
			(hide yes)
			(effects
				(font
					(size 1.27 1.27)
				)
			)
		)
		(property "Value" "100KR2F-L1-GP"
			(at 0.064008 -3.993896 0)
			(unlocked yes)
			(layer "F.Fab")
			(hide yes)
			(effects
				(font
					(size 1.016 1.016)
					(thickness 0.1524)
				)
			)
		)
		(property "Device Type" "R402H16"
			(at 0.064008 -5.517896 0)
			(unlocked yes)
			(layer "F.Fab")
			(hide yes)
			(effects
				(font
					(size 1.016 1.016)
					(thickness 0.1524)
				)
			)
		)
		(duplicate_pad_numbers_are_jumpers no)
		(fp_line
			(start -0.508 -0.9398)
			(end -0.508 0.9398)
			(stroke
				(width 0.1524)
				(type default)
			)
			(layer "F.SilkS")
		)
		(fp_line
			(start 0.508 -0.9398)
			(end -0.508 -0.9398)
			(stroke
				(width 0.1524)
				(type default)
			)
			(layer "F.SilkS")
		)
		(fp_rect
			(start -0.508 0.9398)
			(end 0.508 -0.9398)
			(stroke
				(width 0)
				(type default)
			)
			(fill no)
			(layer "F.CrtYd")
		)
		(fp_rect
			(start -0.508 0.9398)
			(end 0.508 -0.9398)
			(stroke
				(width 0)
				(type default)
			)
			(fill no)
			(layer "F.Fab")
		)
		(pad "1" smd custom
			(at 0 -0.4445)
			(size 0.1397 0.1397)
			(layers "F.Cu" "F.Mask" "F.Paste")
			(net "AGND_P1V8_STBY")
			(options
				(clearance outline)
				(anchor circle)
			)
			(primitives
				(gr_poly
					(pts
						(arc
							(start -0.1778 -0.2794)
							(mid -0.249642 -0.249642)
							(end -0.2794 -0.1778)
						)
						(arc
							(start -0.2794 0.1778)
							(mid -0.249642 0.249642)
							(end -0.1778 0.2794)
						)
						(arc
							(start 0.1778 0.2794)
							(mid 0.249642 0.249642)
							(end 0.2794 0.1778)
						)
						(arc
							(start 0.2794 -0.1778)
							(mid 0.249642 -0.249642)
							(end 0.1778 -0.2794)
						)
					)
					(width 0)
					(fill yes)
				)
			)
		)
		(pad "2" smd custom
			(at 0 0.4445)
			(size 0.1397 0.1397)
			(layers "F.Cu" "F.Mask" "F.Paste")
			(net "P1V8_STBY_MODE")
			(options
				(clearance outline)
				(anchor circle)
			)
			(primitives
				(gr_poly
					(pts
						(arc
							(start -0.1778 -0.2794)
							(mid -0.249642 -0.249642)
							(end -0.2794 -0.1778)
						)
						(arc
							(start -0.2794 0.1778)
							(mid -0.249642 0.249642)
							(end -0.1778 0.2794)
						)
						(arc
							(start 0.1778 0.2794)
							(mid 0.249642 0.249642)
							(end 0.2794 0.1778)
						)
						(arc
							(start 0.2794 -0.1778)
							(mid 0.249642 -0.249642)
							(end 0.1778 -0.2794)
						)
					)
					(width 0)
					(fill yes)
				)
			)
		)
	)
	(footprint ""
		(layer "F.Cu")
		(at 289.932872 -223.592136 180)
		(property "Reference" "PC82"
			(at 0 0 180)
			(layer "F.SilkS")
			(hide yes)
			(effects
				(font
					(size 1.27 1.27)
				)
			)
		)
		(property "Value" "SC10U6D3V5KX-1GP"
			(at -0.0762 -6.1214 180)
			(unlocked yes)
			(layer "F.Fab")
			(hide yes)
			(effects
				(font
					(size 1.016 1.016)
					(thickness 0.1524)
				)
			)
		)
		(property "Device Type" "C805H54"
			(at -0.0762 -8.1534 180)
			(unlocked yes)
			(layer "F.Fab")
			(hide yes)
			(effects
				(font
					(size 1.016 1.016)
					(thickness 0.1524)
				)
			)
		)
		(duplicate_pad_numbers_are_jumpers no)
		(fp_line
			(start 0.635 0)
			(end -0.635 0)
			(stroke
				(width 0.508)
				(type default)
			)
			(layer "F.SilkS")
		)
		(fp_rect
			(start -0.9652 1.778)
			(end 0.9652 -1.778)
			(stroke
				(width 0)
				(type default)
			)
			(fill no)
			(layer "F.CrtYd")
		)
		(fp_poly
			(pts
				(xy -0.9652 -1.778) (xy 0.9652 -1.778) (xy 0.9652 1.778) (xy -0.9652 1.778)
			)
			(stroke
				(width 0)
				(type default)
			)
			(fill no)
			(layer "F.Fab")
		)
		(pad "1" smd rect
			(at 0 -0.9652 180)
			(size 1.397 1.143)
			(layers "F.Cu" "F.Mask" "F.Paste")
			(net "TPS74801_1V53_STBY_OUT")
		)
		(pad "2" smd rect
			(at 0 0.9652 180)
			(size 1.397 1.143)
			(layers "F.Cu" "F.Mask" "F.Paste")
			(net "GND")
		)
	)
	(footprint ""
		(layer "F.Cu")
		(at 152.247092 -106.582464 -90)
		(property "Reference" "SL17"
			(at 0 0 270)
			(layer "F.SilkS")
			(hide yes)
			(effects
				(font
					(size 1.27 1.27)
				)
			)
		)
		(property "Value" "MPZ2012S300AT-GP"
			(at 0 -4.2418 270)
			(unlocked yes)
			(layer "F.Fab")
			(hide yes)
			(effects
				(font
					(size 1.016 1.016)
					(thickness 0.1524)
				)
			)
		)
		(property "Device Type" "L805H42"
			(at 0 -5.7912 270)
			(unlocked yes)
			(layer "F.Fab")
			(hide yes)
			(effects
				(font
					(size 1.016 1.016)
					(thickness 0.1524)
				)
			)
		)
		(duplicate_pad_numbers_are_jumpers no)
		(fp_line
			(start -0.889 1.7018)
			(end -0.889 -1.7018)
			(stroke
				(width 0.1524)
				(type default)
			)
			(layer "F.SilkS")
		)
		(fp_line
			(start 0.889 1.7018)
			(end -0.889 1.7018)
			(stroke
				(width 0.1524)
				(type default)
			)
			(layer "F.SilkS")
		)
		(fp_line
			(start -0.889 -1.7018)
			(end 0.889 -1.7018)
			(stroke
				(width 0.1524)
				(type default)
			)
			(layer "F.SilkS")
		)
		(fp_line
			(start 0.889 -1.7018)
			(end 0.889 1.7018)
			(stroke
				(width 0.1524)
				(type default)
			)
			(layer "F.SilkS")
		)
		(fp_rect
			(start -0.9652 1.778)
			(end 0.9652 -1.778)
			(stroke
				(width 0)
				(type default)
			)
			(fill no)
			(layer "F.CrtYd")
		)
		(fp_rect
			(start -0.9652 1.778)
			(end 0.9652 -1.778)
			(stroke
				(width 0)
				(type default)
			)
			(fill no)
			(layer "F.Fab")
		)
		(pad "1" smd rect
			(at 0 -0.9652 270)
			(size 1.397 1.143)
			(layers "F.Cu" "F.Mask" "F.Paste")
			(net "P0V9_E")
		)
		(pad "2" smd rect
			(at 0 0.9652 270)
			(size 1.397 1.143)
			(layers "F.Cu" "F.Mask" "F.Paste")
			(net "GB_VDDA")
		)
	)
	(footprint ""
		(layer "F.Cu")
		(at 327.524872 -167.966136 180)
		(property "Reference" "R274"
			(at 0 0 180)
			(layer "F.SilkS")
			(hide yes)
			(effects
				(font
					(size 1.27 1.27)
				)
			)
		)
		(property "Value" "0R2J-2-GP"
			(at 0.064008 -3.993896 180)
			(unlocked yes)
			(layer "F.Fab")
			(hide yes)
			(effects
				(font
					(size 1.016 1.016)
					(thickness 0.1524)
				)
			)
		)
		(property "Device Type" "R402H16"
			(at 0.064008 -5.517896 180)
			(unlocked yes)
			(layer "F.Fab")
			(hide yes)
			(effects
				(font
					(size 1.016 1.016)
					(thickness 0.1524)
				)
			)
		)
		(duplicate_pad_numbers_are_jumpers no)
		(fp_line
			(start 0.508 -0.9398)
			(end -0.508 -0.9398)
			(stroke
				(width 0.1524)
				(type default)
			)
			(layer "F.SilkS")
		)
		(fp_line
			(start -0.508 -0.9398)
			(end -0.508 0.9398)
			(stroke
				(width 0.1524)
				(type default)
			)
			(layer "F.SilkS")
		)
		(fp_rect
			(start -0.508 0.9398)
			(end 0.508 -0.9398)
			(stroke
				(width 0)
				(type default)
			)
			(fill no)
			(layer "F.CrtYd")
		)
		(fp_rect
			(start -0.508 0.9398)
			(end 0.508 -0.9398)
			(stroke
				(width 0)
				(type default)
			)
			(fill no)
			(layer "F.Fab")
		)
		(pad "1" smd custom
			(at 0 -0.4445 180)
			(size 0.1397 0.1397)
			(layers "F.Cu" "F.Mask" "F.Paste")
			(net "BMC_UART_SWITCH_1R")
			(options
				(clearance outline)
				(anchor circle)
			)
			(primitives
				(gr_poly
					(pts
						(arc
							(start -0.1778 -0.2794)
							(mid -0.249642 -0.249642)
							(end -0.2794 -0.1778)
						)
						(arc
							(start -0.2794 0.1778)
							(mid -0.249642 0.249642)
							(end -0.1778 0.2794)
						)
						(arc
							(start 0.1778 0.2794)
							(mid 0.249642 0.249642)
							(end 0.2794 0.1778)
						)
						(arc
							(start 0.2794 -0.1778)
							(mid 0.249642 -0.249642)
							(end 0.1778 -0.2794)
						)
					)
					(width 0)
					(fill yes)
				)
			)
		)
		(pad "2" smd custom
			(at 0 0.4445 180)
			(size 0.1397 0.1397)
			(layers "F.Cu" "F.Mask" "F.Paste")
			(net "GND")
			(options
				(clearance outline)
				(anchor circle)
			)
			(primitives
				(gr_poly
					(pts
						(arc
							(start -0.1778 -0.2794)
							(mid -0.249642 -0.249642)
							(end -0.2794 -0.1778)
						)
						(arc
							(start -0.2794 0.1778)
							(mid -0.249642 0.249642)
							(end -0.1778 0.2794)
						)
						(arc
							(start 0.1778 0.2794)
							(mid 0.249642 0.249642)
							(end 0.2794 0.1778)
						)
						(arc
							(start 0.2794 -0.1778)
							(mid 0.249642 -0.249642)
							(end 0.1778 -0.2794)
						)
					)
					(width 0)
					(fill yes)
				)
			)
		)
	)
	(footprint ""
		(layer "F.Cu")
		(at 243.095272 -118.1735 180)
		(property "Reference" "SR936"
			(at 0 0 180)
			(layer "F.SilkS")
			(hide yes)
			(effects
				(font
					(size 1.27 1.27)
				)
			)
		)
		(property "Value" "0R2J-2-GP"
			(at 0.064008 -3.993896 180)
			(unlocked yes)
			(layer "F.Fab")
			(hide yes)
			(effects
				(font
					(size 1.016 1.016)
					(thickness 0.1524)
				)
			)
		)
		(property "Device Type" "R402H16"
			(at 0.064008 -5.517896 180)
			(unlocked yes)
			(layer "F.Fab")
			(hide yes)
			(effects
				(font
					(size 1.016 1.016)
					(thickness 0.1524)
				)
			)
		)
		(duplicate_pad_numbers_are_jumpers no)
		(fp_line
			(start 0.508 -0.9398)
			(end -0.508 -0.9398)
			(stroke
				(width 0.1524)
				(type default)
			)
			(layer "F.SilkS")
		)
		(fp_line
			(start -0.508 -0.9398)
			(end -0.508 0.9398)
			(stroke
				(width 0.1524)
				(type default)
			)
			(layer "F.SilkS")
		)
		(fp_rect
			(start -0.508 0.9398)
			(end 0.508 -0.9398)
			(stroke
				(width 0)
				(type default)
			)
			(fill no)
			(layer "F.CrtYd")
		)
		(fp_rect
			(start -0.508 0.9398)
			(end 0.508 -0.9398)
			(stroke
				(width 0)
				(type default)
			)
			(fill no)
			(layer "F.Fab")
		)
		(pad "1" smd custom
			(at 0 -0.4445 180)
			(size 0.1397 0.1397)
			(layers "F.Cu" "F.Mask" "F.Paste")
			(net "SAS_SMART_R_RX")
			(options
				(clearance outline)
				(anchor circle)
			)
			(primitives
				(gr_poly
					(pts
						(arc
							(start -0.1778 -0.2794)
							(mid -0.249642 -0.249642)
							(end -0.2794 -0.1778)
						)
						(arc
							(start -0.2794 0.1778)
							(mid -0.249642 0.249642)
							(end -0.1778 0.2794)
						)
						(arc
							(start 0.1778 0.2794)
							(mid 0.249642 0.249642)
							(end 0.2794 0.1778)
						)
						(arc
							(start 0.2794 -0.1778)
							(mid 0.249642 -0.249642)
							(end 0.1778 -0.2794)
						)
					)
					(width 0)
					(fill yes)
				)
			)
		)
		(pad "2" smd custom
			(at 0 0.4445 180)
			(size 0.1397 0.1397)
			(layers "F.Cu" "F.Mask" "F.Paste")
			(net "SAS_SMART_RX")
			(options
				(clearance outline)
				(anchor circle)
			)
			(primitives
				(gr_poly
					(pts
						(arc
							(start -0.1778 -0.2794)
							(mid -0.249642 -0.249642)
							(end -0.2794 -0.1778)
						)
						(arc
							(start -0.2794 0.1778)
							(mid -0.249642 0.249642)
							(end -0.1778 0.2794)
						)
						(arc
							(start 0.1778 0.2794)
							(mid 0.249642 0.249642)
							(end 0.2794 0.1778)
						)
						(arc
							(start 0.2794 -0.1778)
							(mid 0.249642 -0.249642)
							(end 0.1778 -0.2794)
						)
					)
					(width 0)
					(fill yes)
				)
			)
		)
	)
	(footprint ""
		(layer "F.Cu")
		(at 111.26597 -114.3 180)
		(property "Reference" "SC1079"
			(at 0 0 180)
			(layer "F.SilkS")
			(hide yes)
			(effects
				(font
					(size 1.27 1.27)
				)
			)
		)
		(property "Value" "SCD01U10V1KX-GP"
			(at -2.8321 -1.7399 180)
			(unlocked yes)
			(layer "F.Fab")
			(hide yes)
			(effects
				(font
					(size 1.016 1.016)
					(thickness 0.1524)
				)
			)
		)
		(property "Device Type" "C0201H13"
			(at -2.8321 -3.2639 180)
			(unlocked yes)
			(layer "F.Fab")
			(hide yes)
			(effects
				(font
					(size 1.016 1.016)
					(thickness 0.1524)
				)
			)
		)
		(duplicate_pad_numbers_are_jumpers no)
		(fp_rect
			(start -0.2794 0.6477)
			(end 0.2794 -0.6477)
			(stroke
				(width 0)
				(type default)
			)
			(fill no)
			(layer "F.CrtYd")
		)
		(fp_rect
			(start -0.2794 0.6477)
			(end 0.2794 -0.6477)
			(stroke
				(width 0)
				(type default)
			)
			(fill no)
			(layer "F.Fab")
		)
		(pad "1" smd custom
			(at 0 -0.2794 180)
			(size 0.0762 0.0762)
			(layers "F.Cu" "F.Mask" "F.Paste")
			(net "SAS_HDD_TX6_P")
			(options
				(clearance outline)
				(anchor circle)
			)
			(primitives
				(gr_poly
					(pts
						(arc
							(start 0.1524 -0.127)
							(mid 0.137521 -0.162921)
							(end 0.1016 -0.1778)
						)
						(arc
							(start -0.1016 -0.1778)
							(mid -0.137521 -0.162921)
							(end -0.1524 -0.127)
						)
						(arc
							(start -0.1524 0.127)
							(mid -0.137521 0.162921)
							(end -0.1016 0.1778)
						)
						(arc
							(start 0.1016 0.1778)
							(mid 0.137521 0.162921)
							(end 0.1524 0.127)
						)
					)
					(width 0)
					(fill yes)
				)
			)
		)
		(pad "2" smd custom
			(at 0 0.2794 180)
			(size 0.0762 0.0762)
			(layers "F.Cu" "F.Mask" "F.Paste")
			(net "SAS_EXP_GF_TX_DP10")
			(options
				(clearance outline)
				(anchor circle)
			)
			(primitives
				(gr_poly
					(pts
						(arc
							(start 0.1524 -0.127)
							(mid 0.137521 -0.162921)
							(end 0.1016 -0.1778)
						)
						(arc
							(start -0.1016 -0.1778)
							(mid -0.137521 -0.162921)
							(end -0.1524 -0.127)
						)
						(arc
							(start -0.1524 0.127)
							(mid -0.137521 0.162921)
							(end -0.1016 0.1778)
						)
						(arc
							(start 0.1016 0.1778)
							(mid 0.137521 0.162921)
							(end 0.1524 0.127)
						)
					)
					(width 0)
					(fill yes)
				)
			)
		)
	)
	(footprint ""
		(layer "F.Cu")
		(at 21.358352 -219.520008)
		(property "Reference" "SU14"
			(at 0 0 0)
			(layer "F.SilkS")
			(hide yes)
			(effects
				(font
					(size 1.27 1.27)
				)
			)
		)
		(property "Value" "PCA9575PW2-GP"
			(at 0.635 -8.0772 0)
			(unlocked yes)
			(layer "F.Fab")
			(hide yes)
			(effects
				(font
					(size 1.016 1.016)
					(thickness 0.1524)
				)
			)
		)
		(property "Device Type" "TSOIC28H44"
			(at 0.635 -9.9822 0)
			(unlocked yes)
			(layer "F.Fab")
			(hide yes)
			(effects
				(font
					(size 1.016 1.016)
					(thickness 0.1524)
				)
			)
		)
		(duplicate_pad_numbers_are_jumpers no)
		(fp_line
			(start -5.3467 -1.3716)
			(end 4.4704 -1.3716)
			(stroke
				(width 0.1524)
				(type default)
			)
			(layer "F.SilkS")
		)
		(fp_line
			(start -5.3467 -0.50292)
			(end -5.3467 -0.50038)
			(stroke
				(width 0.1524)
				(type default)
			)
			(layer "F.SilkS")
		)
		(fp_line
			(start -5.3467 -0.50038)
			(end -4.84632 0)
			(stroke
				(width 0.1524)
				(type default)
			)
			(layer "F.SilkS")
		)
		(fp_line
			(start -5.3467 1.7907)
			(end -5.3467 4.572)
			(stroke
				(width 0.508)
				(type default)
			)
			(layer "F.SilkS")
		)
		(fp_line
			(start -5.3467 4.572)
			(end -5.3467 -1.3716)
			(stroke
				(width 0.1524)
				(type default)
			)
			(layer "F.SilkS")
		)
		(fp_line
			(start -4.84632 0)
			(end -4.84632 0.00254)
			(stroke
				(width 0.1524)
				(type default)
			)
			(layer "F.SilkS")
		)
		(fp_line
			(start -4.84632 0.00254)
			(end -5.3467 0.50292)
			(stroke
				(width 0.1524)
				(type default)
			)
			(layer "F.SilkS")
		)
		(fp_line
			(start 4.4704 -1.3716)
			(end 4.4704 1.3716)
			(stroke
				(width 0.1524)
				(type default)
			)
			(layer "F.SilkS")
		)
		(fp_line
			(start 4.4704 1.3716)
			(end -5.3467 1.3716)
			(stroke
				(width 0.1524)
				(type default)
			)
			(layer "F.SilkS")
		)
		(fp_poly
			(pts
				(xy -4.55549 -1.8288) (xy -4.55549 1.8288) (xy 4.55549 1.8288) (xy 4.55549 -1.8288)
			)
			(stroke
				(width 0)
				(type default)
			)
			(fill yes)
			(layer "F.SilkS")
		)
		(fp_poly
			(pts
				(xy -5.3594 -4.0767) (xy 5.3594 -4.0767) (xy 5.3594 4.0767) (xy -5.3594 4.0767)
			)
			(stroke
				(width 0)
				(type default)
			)
			(fill no)
			(layer "F.CrtYd")
		)
		(fp_poly
			(pts
				(xy -5.3594 -4.0767) (xy 5.3594 -4.0767) (xy 5.3594 4.0767) (xy -5.3594 4.0767)
			)
			(stroke
				(width 0)
				(type default)
			)
			(fill no)
			(layer "F.Fab")
		)
		(pad "1" smd rect
			(at -4.22529 2.80543)
			(size 0.3556 1.524)
			(layers "F.Cu" "F.Mask" "F.Paste")
			(net "IO_EXP_HDD_PWR_A0")
		)
		(pad "2" smd rect
			(at -3.57505 2.80543)
			(size 0.3556 1.524)
			(layers "F.Cu" "F.Mask" "F.Paste")
			(net "P1V8_E")
		)
		(pad "3" smd rect
			(at -2.92481 2.80543)
			(size 0.3556 1.524)
			(layers "F.Cu" "F.Mask" "F.Paste")
			(net "I2C_IO_EXP_RESET#_PWR")
		)
		(pad "4" smd rect
			(at -2.27457 2.80543)
			(size 0.3556 1.524)
			(layers "F.Cu" "F.Mask" "F.Paste")
			(net "SAS_HDD_PWR0")
		)
		(pad "5" smd rect
			(at -1.6256 2.80543)
			(size 0.3556 1.524)
			(layers "F.Cu" "F.Mask" "F.Paste")
			(net "SAS_HDD_PWR1")
		)
		(pad "6" smd rect
			(at -0.97536 2.80543)
			(size 0.3556 1.524)
			(layers "F.Cu" "F.Mask" "F.Paste")
			(net "SAS_HDD_PWR2")
		)
		(pad "7" smd rect
			(at -0.32512 2.80543)
			(size 0.3556 1.524)
			(layers "F.Cu" "F.Mask" "F.Paste")
			(net "SAS_HDD_PWR3")
		)
		(pad "8" smd rect
			(at 0.32512 2.80543)
			(size 0.3556 1.524)
			(layers "F.Cu" "F.Mask" "F.Paste")
			(net "IO_EXP_HDD_PWR_A1")
		)
		(pad "9" smd rect
			(at 0.97536 2.80543)
			(size 0.3556 1.524)
			(layers "F.Cu" "F.Mask" "F.Paste")
			(net "P3V3_STBY")
		)
		(pad "10" smd rect
			(at 1.6256 2.80543)
			(size 0.3556 1.524)
			(layers "F.Cu" "F.Mask" "F.Paste")
			(net "SAS_HDD_PWR4")
		)
		(pad "11" smd rect
			(at 2.27457 2.80543)
			(size 0.3556 1.524)
			(layers "F.Cu" "F.Mask" "F.Paste")
			(net "SAS_HDD_PWR5")
		)
		(pad "12" smd rect
			(at 2.92481 2.80543)
			(size 0.3556 1.524)
			(layers "F.Cu" "F.Mask" "F.Paste")
			(net "SAS_HDD_PWR6")
		)
		(pad "13" smd rect
			(at 3.57505 2.80543)
			(size 0.3556 1.524)
			(layers "F.Cu" "F.Mask" "F.Paste")
			(net "SAS_HDD_PWR7")
		)
		(pad "14" smd rect
			(at 4.22529 2.80543)
			(size 0.3556 1.524)
			(layers "F.Cu" "F.Mask" "F.Paste")
			(net "HDD_PWR_IO_INT_N")
		)
		(pad "15" smd rect
			(at 4.22529 -2.80543)
			(size 0.3556 1.524)
			(layers "F.Cu" "F.Mask" "F.Paste")
			(net "IO_EXP_HDD_PWR_A2")
		)
		(pad "16" smd rect
			(at 3.57505 -2.80543)
			(size 0.3556 1.524)
			(layers "F.Cu" "F.Mask" "F.Paste")
			(net "GND")
		)
		(pad "17" smd rect
			(at 2.92481 -2.80543)
			(size 0.3556 1.524)
			(layers "F.Cu" "F.Mask" "F.Paste")
			(net "SAS_HDD_PWR15")
		)
		(pad "18" smd rect
			(at 2.27457 -2.80543)
			(size 0.3556 1.524)
			(layers "F.Cu" "F.Mask" "F.Paste")
			(net "SAS_HDD_PWR14")
		)
		(pad "19" smd rect
			(at 1.6256 -2.80543)
			(size 0.3556 1.524)
			(layers "F.Cu" "F.Mask" "F.Paste")
			(net "SAS_HDD_PWR13")
		)
		(pad "20" smd rect
			(at 0.97536 -2.80543)
			(size 0.3556 1.524)
			(layers "F.Cu" "F.Mask" "F.Paste")
			(net "SAS_HDD_PWR12")
		)
		(pad "21" smd rect
			(at 0.32512 -2.80543)
			(size 0.3556 1.524)
			(layers "F.Cu" "F.Mask" "F.Paste")
			(net "P3V3_STBY")
		)
		(pad "22" smd rect
			(at -0.32512 -2.80543)
			(size 0.3556 1.524)
			(layers "F.Cu" "F.Mask" "F.Paste")
			(net "IO_EXP_HDD_PWR_A3")
		)
		(pad "23" smd rect
			(at -0.97536 -2.80543)
			(size 0.3556 1.524)
			(layers "F.Cu" "F.Mask" "F.Paste")
			(net "SAS_HDD_PWR11")
		)
		(pad "24" smd rect
			(at -1.6256 -2.80543)
			(size 0.3556 1.524)
			(layers "F.Cu" "F.Mask" "F.Paste")
			(net "SAS_HDD_PWR10")
		)
		(pad "25" smd rect
			(at -2.27457 -2.80543)
			(size 0.3556 1.524)
			(layers "F.Cu" "F.Mask" "F.Paste")
			(net "SAS_HDD_PWR9")
		)
		(pad "26" smd rect
			(at -2.92481 -2.80543)
			(size 0.3556 1.524)
			(layers "F.Cu" "F.Mask" "F.Paste")
			(net "SAS_HDD_PWR8")
		)
		(pad "27" smd rect
			(at -3.57505 -2.80543)
			(size 0.3556 1.524)
			(layers "F.Cu" "F.Mask" "F.Paste")
			(net "PWR_SDA")
		)
		(pad "28" smd rect
			(at -4.22529 -2.80543)
			(size 0.3556 1.524)
			(layers "F.Cu" "F.Mask" "F.Paste")
			(net "PWR_SCL")
		)
	)
	(footprint ""
		(layer "F.Cu")
		(at 317.5 -110.617 90)
		(property "Reference" "PC31"
			(at 0 0 90)
			(layer "F.SilkS")
			(hide yes)
			(effects
				(font
					(size 1.27 1.27)
				)
			)
		)
		(property "Value" "SC1KP50V2KX-1GP"
			(at 1.1811 -2.7051 90)
			(unlocked yes)
			(layer "F.Fab")
			(hide yes)
			(effects
				(font
					(size 1.016 1.016)
					(thickness 0.1524)
				)
			)
		)
		(property "Device Type" "C402H22"
			(at 1.1811 -4.2291 90)
			(unlocked yes)
			(layer "F.Fab")
			(hide yes)
			(effects
				(font
					(size 1.016 1.016)
					(thickness 0.1524)
				)
			)
		)
		(duplicate_pad_numbers_are_jumpers no)
		(fp_rect
			(start -0.4318 0.9525)
			(end 0.4318 -0.9525)
			(stroke
				(width 0)
				(type default)
			)
			(fill no)
			(layer "F.CrtYd")
		)
		(fp_rect
			(start -0.4318 0.9525)
			(end 0.4318 -0.9525)
			(stroke
				(width 0)
				(type default)
			)
			(fill no)
			(layer "F.Fab")
		)
		(pad "1" smd custom
			(at 0 -0.4445 90)
			(size 0.1524 0.1524)
			(layers "F.Cu" "F.Mask" "F.Paste")
			(net "P3V3_STBY_LL_R")
			(options
				(clearance outline)
				(anchor circle)
			)
			(primitives
				(gr_poly
					(pts
						(arc
							(start 0.3048 -0.2032)
							(mid 0.275042 -0.275042)
							(end 0.2032 -0.3048)
						)
						(arc
							(start -0.2032 -0.3048)
							(mid -0.275042 -0.275042)
							(end -0.3048 -0.2032)
						)
						(arc
							(start -0.3048 0.2032)
							(mid -0.275042 0.275042)
							(end -0.2032 0.3048)
						)
						(arc
							(start 0.2032 0.3048)
							(mid 0.275042 0.275042)
							(end 0.3048 0.2032)
						)
					)
					(width 0)
					(fill yes)
				)
			)
		)
		(pad "2" smd custom
			(at 0 0.4445 90)
			(size 0.1524 0.1524)
			(layers "F.Cu" "F.Mask" "F.Paste")
			(net "P3V3_STBY_VFB")
			(options
				(clearance outline)
				(anchor circle)
			)
			(primitives
				(gr_poly
					(pts
						(arc
							(start 0.3048 -0.2032)
							(mid 0.275042 -0.275042)
							(end 0.2032 -0.3048)
						)
						(arc
							(start -0.2032 -0.3048)
							(mid -0.275042 -0.275042)
							(end -0.3048 -0.2032)
						)
						(arc
							(start -0.3048 0.2032)
							(mid -0.275042 0.275042)
							(end -0.2032 0.3048)
						)
						(arc
							(start 0.2032 0.3048)
							(mid 0.275042 0.275042)
							(end 0.3048 0.2032)
						)
					)
					(width 0)
					(fill yes)
				)
			)
		)
	)
	(footprint ""
		(layer "F.Cu")
		(at 84.455 -238.4044 180)
		(property "Reference" "SC432"
			(at 0 0 180)
			(layer "F.SilkS")
			(hide yes)
			(effects
				(font
					(size 1.27 1.27)
				)
			)
		)
		(property "Value" "SC1U10V3KX-4GP-U"
			(at 0 -2.8194 180)
			(unlocked yes)
			(layer "F.Fab")
			(hide yes)
			(effects
				(font
					(size 1.016 1.016)
					(thickness 0.1524)
				)
			)
		)
		(property "Device Type" "C603H36"
			(at 0 -4.3434 180)
			(unlocked yes)
			(layer "F.Fab")
			(hide yes)
			(effects
				(font
					(size 1.016 1.016)
					(thickness 0.1524)
				)
			)
		)
		(duplicate_pad_numbers_are_jumpers no)
		(fp_line
			(start 0.508 0)
			(end -0.508 0)
			(stroke
				(width 0.2032)
				(type default)
			)
			(layer "F.SilkS")
		)
		(fp_rect
			(start -0.5842 1.3335)
			(end 0.5842 -1.3335)
			(stroke
				(width 0)
				(type default)
			)
			(fill no)
			(layer "F.CrtYd")
		)
		(fp_rect
			(start -0.5842 1.3335)
			(end 0.5842 -1.3335)
			(stroke
				(width 0)
				(type default)
			)
			(fill no)
			(layer "F.Fab")
		)
		(pad "1" smd custom
			(at 0 -0.762 180)
			(size 0.2159 0.2159)
			(layers "F.Cu" "F.Mask" "F.Paste")
			(net "GND")
			(options
				(clearance outline)
				(anchor circle)
			)
			(primitives
				(gr_poly
					(pts
						(arc
							(start -0.3302 -0.4318)
							(mid -0.402042 -0.402042)
							(end -0.4318 -0.3302)
						)
						(arc
							(start -0.4318 0.3302)
							(mid -0.402042 0.402042)
							(end -0.3302 0.4318)
						)
						(arc
							(start 0.3302 0.4318)
							(mid 0.402042 0.402042)
							(end 0.4318 0.3302)
						)
						(arc
							(start 0.4318 -0.3302)
							(mid 0.402042 -0.402042)
							(end 0.3302 -0.4318)
						)
					)
					(width 0)
					(fill yes)
				)
			)
		)
		(pad "2" smd custom
			(at 0 0.762 180)
			(size 0.2159 0.2159)
			(layers "F.Cu" "F.Mask" "F.Paste")
			(net "P3V3_STBY")
			(options
				(clearance outline)
				(anchor circle)
			)
			(primitives
				(gr_poly
					(pts
						(arc
							(start -0.3302 -0.4318)
							(mid -0.402042 -0.402042)
							(end -0.4318 -0.3302)
						)
						(arc
							(start -0.4318 0.3302)
							(mid -0.402042 0.402042)
							(end -0.3302 0.4318)
						)
						(arc
							(start 0.3302 0.4318)
							(mid 0.402042 0.402042)
							(end 0.4318 0.3302)
						)
						(arc
							(start 0.4318 -0.3302)
							(mid 0.402042 -0.402042)
							(end 0.3302 -0.4318)
						)
					)
					(width 0)
					(fill yes)
				)
			)
		)
	)
	(footprint ""
		(layer "F.Cu")
		(at 180.529992 -25.4)
		(property "Reference" "TP132"
			(at 0 0 0)
			(layer "F.SilkS")
			(hide yes)
			(effects
				(font
					(size 1.27 1.27)
				)
			)
		)
		(property "Value" "TPAD28"
			(at 0.0127 -1.8034 0)
			(unlocked yes)
			(layer "F.Fab")
			(hide yes)
			(effects
				(font
					(size 1.016 1.016)
					(thickness 0.1524)
				)
			)
		)
		(property "Device Type" "TPAD28"
			(at 0.0127 -3.3274 0)
			(unlocked yes)
			(layer "F.Fab")
			(hide yes)
			(effects
				(font
					(size 1.016 1.016)
					(thickness 0.1524)
				)
			)
		)
		(duplicate_pad_numbers_are_jumpers no)
		(fp_poly
			(pts
				(arc
					(start 0.3556 0)
					(mid -0.3556 0)
					(end 0.3556 0)
				)
			)
			(stroke
				(width 0)
				(type default)
			)
			(fill no)
			(layer "F.CrtYd")
		)
		(fp_poly
			(pts
				(arc
					(start 0.6096 0)
					(mid -0.6096 0)
					(end 0.6096 0)
				)
			)
			(stroke
				(width 0)
				(type default)
			)
			(fill no)
			(layer "F.Fab")
		)
		(pad "1" smd circle
			(at 0 0)
			(size 0.7112 0.7112)
			(layers "F.Cu" "F.Mask" "F.Paste")
			(net "NC_PHYSPLOED_N")
		)
	)
	(footprint ""
		(layer "F.Cu")
		(at 316.484 -68.199 -90)
		(property "Reference" "R273"
			(at 0 0 270)
			(layer "F.SilkS")
			(hide yes)
			(effects
				(font
					(size 1.27 1.27)
				)
			)
		)
		(property "Value" "0R2J-2-GP"
			(at 0.064008 -3.993896 270)
			(unlocked yes)
			(layer "F.Fab")
			(hide yes)
			(effects
				(font
					(size 1.016 1.016)
					(thickness 0.1524)
				)
			)
		)
		(property "Device Type" "R402H16"
			(at 0.064008 -5.517896 270)
			(unlocked yes)
			(layer "F.Fab")
			(hide yes)
			(effects
				(font
					(size 1.016 1.016)
					(thickness 0.1524)
				)
			)
		)
		(duplicate_pad_numbers_are_jumpers no)
		(fp_line
			(start -0.508 -0.9398)
			(end -0.508 0.9398)
			(stroke
				(width 0.1524)
				(type default)
			)
			(layer "F.SilkS")
		)
		(fp_line
			(start 0.508 -0.9398)
			(end -0.508 -0.9398)
			(stroke
				(width 0.1524)
				(type default)
			)
			(layer "F.SilkS")
		)
		(fp_rect
			(start -0.508 0.9398)
			(end 0.508 -0.9398)
			(stroke
				(width 0)
				(type default)
			)
			(fill no)
			(layer "F.CrtYd")
		)
		(fp_rect
			(start -0.508 0.9398)
			(end 0.508 -0.9398)
			(stroke
				(width 0)
				(type default)
			)
			(fill no)
			(layer "F.Fab")
		)
		(pad "1" smd custom
			(at 0 -0.4445 270)
			(size 0.1397 0.1397)
			(layers "F.Cu" "F.Mask" "F.Paste")
			(net "CLK_100M_CLKBUFF_ENET2_DP")
			(options
				(clearance outline)
				(anchor circle)
			)
			(primitives
				(gr_poly
					(pts
						(arc
							(start -0.1778 -0.2794)
							(mid -0.249642 -0.249642)
							(end -0.2794 -0.1778)
						)
						(arc
							(start -0.2794 0.1778)
							(mid -0.249642 0.249642)
							(end -0.1778 0.2794)
						)
						(arc
							(start 0.1778 0.2794)
							(mid 0.249642 0.249642)
							(end 0.2794 0.1778)
						)
						(arc
							(start 0.2794 -0.1778)
							(mid 0.249642 -0.249642)
							(end 0.1778 -0.2794)
						)
					)
					(width 0)
					(fill yes)
				)
			)
		)
		(pad "2" smd custom
			(at 0 0.4445 270)
			(size 0.1397 0.1397)
			(layers "F.Cu" "F.Mask" "F.Paste")
			(net "PCIE_10G_REFCLK_2_P")
			(options
				(clearance outline)
				(anchor circle)
			)
			(primitives
				(gr_poly
					(pts
						(arc
							(start -0.1778 -0.2794)
							(mid -0.249642 -0.249642)
							(end -0.2794 -0.1778)
						)
						(arc
							(start -0.2794 0.1778)
							(mid -0.249642 0.249642)
							(end -0.1778 0.2794)
						)
						(arc
							(start 0.1778 0.2794)
							(mid 0.249642 0.249642)
							(end 0.2794 0.1778)
						)
						(arc
							(start 0.2794 -0.1778)
							(mid 0.249642 -0.249642)
							(end 0.1778 -0.2794)
						)
					)
					(width 0)
					(fill yes)
				)
			)
		)
	)
	(footprint ""
		(layer "F.Cu")
		(at 326.263 -82.55 180)
		(property "Reference" "R684"
			(at 0 0 180)
			(layer "F.SilkS")
			(hide yes)
			(effects
				(font
					(size 1.27 1.27)
				)
			)
		)
		(property "Value" "0R2J-2-GP"
			(at 0.064008 -3.993896 180)
			(unlocked yes)
			(layer "F.Fab")
			(hide yes)
			(effects
				(font
					(size 1.016 1.016)
					(thickness 0.1524)
				)
			)
		)
		(property "Device Type" "R402H16"
			(at 0.064008 -5.517896 180)
			(unlocked yes)
			(layer "F.Fab")
			(hide yes)
			(effects
				(font
					(size 1.016 1.016)
					(thickness 0.1524)
				)
			)
		)
		(duplicate_pad_numbers_are_jumpers no)
		(fp_line
			(start 0.508 -0.9398)
			(end -0.508 -0.9398)
			(stroke
				(width 0.1524)
				(type default)
			)
			(layer "F.SilkS")
		)
		(fp_line
			(start -0.508 -0.9398)
			(end -0.508 0.9398)
			(stroke
				(width 0.1524)
				(type default)
			)
			(layer "F.SilkS")
		)
		(fp_rect
			(start -0.508 0.9398)
			(end 0.508 -0.9398)
			(stroke
				(width 0)
				(type default)
			)
			(fill no)
			(layer "F.CrtYd")
		)
		(fp_rect
			(start -0.508 0.9398)
			(end 0.508 -0.9398)
			(stroke
				(width 0)
				(type default)
			)
			(fill no)
			(layer "F.Fab")
		)
		(pad "1" smd custom
			(at 0 -0.4445 180)
			(size 0.1397 0.1397)
			(layers "F.Cu" "F.Mask" "F.Paste")
			(net "FLA_CS_1")
			(options
				(clearance outline)
				(anchor circle)
			)
			(primitives
				(gr_poly
					(pts
						(arc
							(start -0.1778 -0.2794)
							(mid -0.249642 -0.249642)
							(end -0.2794 -0.1778)
						)
						(arc
							(start -0.2794 0.1778)
							(mid -0.249642 0.249642)
							(end -0.1778 0.2794)
						)
						(arc
							(start 0.1778 0.2794)
							(mid 0.249642 0.249642)
							(end 0.2794 0.1778)
						)
						(arc
							(start 0.2794 -0.1778)
							(mid 0.249642 -0.249642)
							(end 0.1778 -0.2794)
						)
					)
					(width 0)
					(fill yes)
				)
			)
		)
		(pad "2" smd custom
			(at 0 0.4445 180)
			(size 0.1397 0.1397)
			(layers "F.Cu" "F.Mask" "F.Paste")
			(net "FLA_CS_1_R")
			(options
				(clearance outline)
				(anchor circle)
			)
			(primitives
				(gr_poly
					(pts
						(arc
							(start -0.1778 -0.2794)
							(mid -0.249642 -0.249642)
							(end -0.2794 -0.1778)
						)
						(arc
							(start -0.2794 0.1778)
							(mid -0.249642 0.249642)
							(end -0.1778 0.2794)
						)
						(arc
							(start 0.1778 0.2794)
							(mid 0.249642 0.249642)
							(end 0.2794 0.1778)
						)
						(arc
							(start 0.2794 -0.1778)
							(mid 0.249642 -0.249642)
							(end 0.1778 -0.2794)
						)
					)
					(width 0)
					(fill yes)
				)
			)
		)
	)
	(footprint ""
		(layer "F.Cu")
		(at 144.653 -111.633 -90)
		(property "Reference" "SC1189"
			(at 0 0 270)
			(layer "F.SilkS")
			(hide yes)
			(effects
				(font
					(size 1.27 1.27)
				)
			)
		)
		(property "Value" "SC22U6D3V5MX-2GP"
			(at -0.0762 -6.1214 270)
			(unlocked yes)
			(layer "F.Fab")
			(hide yes)
			(effects
				(font
					(size 1.016 1.016)
					(thickness 0.1524)
				)
			)
		)
		(property "Device Type" "C805H58"
			(at -0.0762 -8.1534 270)
			(unlocked yes)
			(layer "F.Fab")
			(hide yes)
			(effects
				(font
					(size 1.016 1.016)
					(thickness 0.1524)
				)
			)
		)
		(duplicate_pad_numbers_are_jumpers no)
		(fp_line
			(start 0.635 0)
			(end -0.635 0)
			(stroke
				(width 0.508)
				(type default)
			)
			(layer "F.SilkS")
		)
		(fp_rect
			(start -0.9652 1.778)
			(end 0.9652 -1.778)
			(stroke
				(width 0)
				(type default)
			)
			(fill no)
			(layer "F.CrtYd")
		)
		(fp_poly
			(pts
				(xy -0.9652 -1.778) (xy 0.9652 -1.778) (xy 0.9652 1.778) (xy -0.9652 1.778)
			)
			(stroke
				(width 0)
				(type default)
			)
			(fill no)
			(layer "F.Fab")
		)
		(pad "1" smd rect
			(at 0 -0.9652 270)
			(size 1.397 1.143)
			(layers "F.Cu" "F.Mask" "F.Paste")
			(net "GB_VDDA")
		)
		(pad "2" smd rect
			(at 0 0.9652 270)
			(size 1.397 1.143)
			(layers "F.Cu" "F.Mask" "F.Paste")
			(net "GND")
		)
	)
	(footprint ""
		(layer "F.Cu")
		(at 34.798 -169.291 90)
		(property "Reference" "SR1279"
			(at 0 0 90)
			(layer "F.SilkS")
			(hide yes)
			(effects
				(font
					(size 1.27 1.27)
				)
			)
		)
		(property "Value" "4K7R2F-GP"
			(at 0.064008 -3.993896 90)
			(unlocked yes)
			(layer "F.Fab")
			(hide yes)
			(effects
				(font
					(size 1.016 1.016)
					(thickness 0.1524)
				)
			)
		)
		(property "Device Type" "R402H16"
			(at 0.064008 -5.517896 90)
			(unlocked yes)
			(layer "F.Fab")
			(hide yes)
			(effects
				(font
					(size 1.016 1.016)
					(thickness 0.1524)
				)
			)
		)
		(duplicate_pad_numbers_are_jumpers no)
		(fp_line
			(start 0.508 -0.9398)
			(end -0.508 -0.9398)
			(stroke
				(width 0.1524)
				(type default)
			)
			(layer "F.SilkS")
		)
		(fp_line
			(start -0.508 -0.9398)
			(end -0.508 0.9398)
			(stroke
				(width 0.1524)
				(type default)
			)
			(layer "F.SilkS")
		)
		(fp_rect
			(start -0.508 0.9398)
			(end 0.508 -0.9398)
			(stroke
				(width 0)
				(type default)
			)
			(fill no)
			(layer "F.CrtYd")
		)
		(fp_rect
			(start -0.508 0.9398)
			(end 0.508 -0.9398)
			(stroke
				(width 0)
				(type default)
			)
			(fill no)
			(layer "F.Fab")
		)
		(pad "1" smd custom
			(at 0 -0.4445 90)
			(size 0.1397 0.1397)
			(layers "F.Cu" "F.Mask" "F.Paste")
			(net "P3V3_STBY")
			(options
				(clearance outline)
				(anchor circle)
			)
			(primitives
				(gr_poly
					(pts
						(arc
							(start -0.1778 -0.2794)
							(mid -0.249642 -0.249642)
							(end -0.2794 -0.1778)
						)
						(arc
							(start -0.2794 0.1778)
							(mid -0.249642 0.249642)
							(end -0.1778 0.2794)
						)
						(arc
							(start 0.1778 0.2794)
							(mid 0.249642 0.249642)
							(end 0.2794 0.1778)
						)
						(arc
							(start 0.2794 -0.1778)
							(mid 0.249642 -0.249642)
							(end 0.1778 -0.2794)
						)
					)
					(width 0)
					(fill yes)
				)
			)
		)
		(pad "2" smd custom
			(at 0 0.4445 90)
			(size 0.1397 0.1397)
			(layers "F.Cu" "F.Mask" "F.Paste")
			(net "DP_BMC_EXP_RST_N")
			(options
				(clearance outline)
				(anchor circle)
			)
			(primitives
				(gr_poly
					(pts
						(arc
							(start -0.1778 -0.2794)
							(mid -0.249642 -0.249642)
							(end -0.2794 -0.1778)
						)
						(arc
							(start -0.2794 0.1778)
							(mid -0.249642 0.249642)
							(end -0.1778 0.2794)
						)
						(arc
							(start 0.1778 0.2794)
							(mid 0.249642 0.249642)
							(end 0.2794 0.1778)
						)
						(arc
							(start 0.2794 -0.1778)
							(mid 0.249642 -0.249642)
							(end 0.1778 -0.2794)
						)
					)
					(width 0)
					(fill yes)
				)
			)
		)
	)
	(footprint ""
		(layer "F.Cu")
		(at 319.913 -169.545 -90)
		(property "Reference" "R441"
			(at 0 0 270)
			(layer "F.SilkS")
			(hide yes)
			(effects
				(font
					(size 1.27 1.27)
				)
			)
		)
		(property "Value" "10KR2F-2-GP"
			(at 0.064008 -3.993896 270)
			(unlocked yes)
			(layer "F.Fab")
			(hide yes)
			(effects
				(font
					(size 1.016 1.016)
					(thickness 0.1524)
				)
			)
		)
		(property "Device Type" "R402H16"
			(at 0.064008 -5.517896 270)
			(unlocked yes)
			(layer "F.Fab")
			(hide yes)
			(effects
				(font
					(size 1.016 1.016)
					(thickness 0.1524)
				)
			)
		)
		(duplicate_pad_numbers_are_jumpers no)
		(fp_line
			(start -0.508 -0.9398)
			(end -0.508 0.9398)
			(stroke
				(width 0.1524)
				(type default)
			)
			(layer "F.SilkS")
		)
		(fp_line
			(start 0.508 -0.9398)
			(end -0.508 -0.9398)
			(stroke
				(width 0.1524)
				(type default)
			)
			(layer "F.SilkS")
		)
		(fp_rect
			(start -0.508 0.9398)
			(end 0.508 -0.9398)
			(stroke
				(width 0)
				(type default)
			)
			(fill no)
			(layer "F.CrtYd")
		)
		(fp_rect
			(start -0.508 0.9398)
			(end 0.508 -0.9398)
			(stroke
				(width 0)
				(type default)
			)
			(fill no)
			(layer "F.Fab")
		)
		(pad "1" smd custom
			(at 0 -0.4445 270)
			(size 0.1397 0.1397)
			(layers "F.Cu" "F.Mask" "F.Paste")
			(net "P3V3_STBY")
			(options
				(clearance outline)
				(anchor circle)
			)
			(primitives
				(gr_poly
					(pts
						(arc
							(start -0.1778 -0.2794)
							(mid -0.249642 -0.249642)
							(end -0.2794 -0.1778)
						)
						(arc
							(start -0.2794 0.1778)
							(mid -0.249642 0.249642)
							(end -0.1778 0.2794)
						)
						(arc
							(start 0.1778 0.2794)
							(mid 0.249642 0.249642)
							(end 0.2794 0.1778)
						)
						(arc
							(start 0.2794 -0.1778)
							(mid 0.249642 -0.249642)
							(end 0.1778 -0.2794)
						)
					)
					(width 0)
					(fill yes)
				)
			)
		)
		(pad "2" smd custom
			(at 0 0.4445 270)
			(size 0.1397 0.1397)
			(layers "F.Cu" "F.Mask" "F.Paste")
			(net "BMC_I2C_B_SCL")
			(options
				(clearance outline)
				(anchor circle)
			)
			(primitives
				(gr_poly
					(pts
						(arc
							(start -0.1778 -0.2794)
							(mid -0.249642 -0.249642)
							(end -0.2794 -0.1778)
						)
						(arc
							(start -0.2794 0.1778)
							(mid -0.249642 0.249642)
							(end -0.1778 0.2794)
						)
						(arc
							(start 0.1778 0.2794)
							(mid 0.249642 0.249642)
							(end 0.2794 0.1778)
						)
						(arc
							(start 0.2794 -0.1778)
							(mid 0.249642 -0.249642)
							(end 0.1778 -0.2794)
						)
					)
					(width 0)
					(fill yes)
				)
			)
		)
	)
	(footprint ""
		(layer "F.Cu")
		(at 152.019 -54.356 90)
		(property "Reference" "SR699"
			(at 0 0 90)
			(layer "F.SilkS")
			(hide yes)
			(effects
				(font
					(size 1.27 1.27)
				)
			)
		)
		(property "Value" "10KR2F-2-GP"
			(at 0.064008 -3.993896 90)
			(unlocked yes)
			(layer "F.Fab")
			(hide yes)
			(effects
				(font
					(size 1.016 1.016)
					(thickness 0.1524)
				)
			)
		)
		(property "Device Type" "R402H16"
			(at 0.064008 -5.517896 90)
			(unlocked yes)
			(layer "F.Fab")
			(hide yes)
			(effects
				(font
					(size 1.016 1.016)
					(thickness 0.1524)
				)
			)
		)
		(duplicate_pad_numbers_are_jumpers no)
		(fp_line
			(start 0.508 -0.9398)
			(end -0.508 -0.9398)
			(stroke
				(width 0.1524)
				(type default)
			)
			(layer "F.SilkS")
		)
		(fp_line
			(start -0.508 -0.9398)
			(end -0.508 0.9398)
			(stroke
				(width 0.1524)
				(type default)
			)
			(layer "F.SilkS")
		)
		(fp_rect
			(start -0.508 0.9398)
			(end 0.508 -0.9398)
			(stroke
				(width 0)
				(type default)
			)
			(fill no)
			(layer "F.CrtYd")
		)
		(fp_rect
			(start -0.508 0.9398)
			(end 0.508 -0.9398)
			(stroke
				(width 0)
				(type default)
			)
			(fill no)
			(layer "F.Fab")
		)
		(pad "1" smd custom
			(at 0 -0.4445 90)
			(size 0.1397 0.1397)
			(layers "F.Cu" "F.Mask" "F.Paste")
			(net "XM_ADDR_5")
			(options
				(clearance outline)
				(anchor circle)
			)
			(primitives
				(gr_poly
					(pts
						(arc
							(start -0.1778 -0.2794)
							(mid -0.249642 -0.249642)
							(end -0.2794 -0.1778)
						)
						(arc
							(start -0.2794 0.1778)
							(mid -0.249642 0.249642)
							(end -0.1778 0.2794)
						)
						(arc
							(start 0.1778 0.2794)
							(mid 0.249642 0.249642)
							(end 0.2794 0.1778)
						)
						(arc
							(start 0.2794 -0.1778)
							(mid 0.249642 -0.249642)
							(end 0.1778 -0.2794)
						)
					)
					(width 0)
					(fill yes)
				)
			)
		)
		(pad "2" smd custom
			(at 0 0.4445 90)
			(size 0.1397 0.1397)
			(layers "F.Cu" "F.Mask" "F.Paste")
			(net "GND")
			(options
				(clearance outline)
				(anchor circle)
			)
			(primitives
				(gr_poly
					(pts
						(arc
							(start -0.1778 -0.2794)
							(mid -0.249642 -0.249642)
							(end -0.2794 -0.1778)
						)
						(arc
							(start -0.2794 0.1778)
							(mid -0.249642 0.249642)
							(end -0.1778 0.2794)
						)
						(arc
							(start 0.1778 0.2794)
							(mid 0.249642 0.249642)
							(end 0.2794 0.1778)
						)
						(arc
							(start 0.2794 -0.1778)
							(mid 0.249642 -0.249642)
							(end 0.1778 -0.2794)
						)
					)
					(width 0)
					(fill yes)
				)
			)
		)
	)
	(footprint ""
		(layer "F.Cu")
		(at 268.4018 -44.704)
		(property "Reference" "PC49"
			(at 0 0 0)
			(layer "F.SilkS")
			(hide yes)
			(effects
				(font
					(size 1.27 1.27)
				)
			)
		)
		(property "Value" "SC1U10V3KX-4GP-U"
			(at 0 -2.8194 0)
			(unlocked yes)
			(layer "F.Fab")
			(hide yes)
			(effects
				(font
					(size 1.016 1.016)
					(thickness 0.1524)
				)
			)
		)
		(property "Device Type" "C603H36"
			(at 0 -4.3434 0)
			(unlocked yes)
			(layer "F.Fab")
			(hide yes)
			(effects
				(font
					(size 1.016 1.016)
					(thickness 0.1524)
				)
			)
		)
		(duplicate_pad_numbers_are_jumpers no)
		(fp_line
			(start 0.508 0)
			(end -0.508 0)
			(stroke
				(width 0.2032)
				(type default)
			)
			(layer "F.SilkS")
		)
		(fp_rect
			(start -0.5842 1.3335)
			(end 0.5842 -1.3335)
			(stroke
				(width 0)
				(type default)
			)
			(fill no)
			(layer "F.CrtYd")
		)
		(fp_rect
			(start -0.5842 1.3335)
			(end 0.5842 -1.3335)
			(stroke
				(width 0)
				(type default)
			)
			(fill no)
			(layer "F.Fab")
		)
		(pad "1" smd custom
			(at 0 -0.762)
			(size 0.2159 0.2159)
			(layers "F.Cu" "F.Mask" "F.Paste")
			(net "GND")
			(options
				(clearance outline)
				(anchor circle)
			)
			(primitives
				(gr_poly
					(pts
						(arc
							(start -0.3302 -0.4318)
							(mid -0.402042 -0.402042)
							(end -0.4318 -0.3302)
						)
						(arc
							(start -0.4318 0.3302)
							(mid -0.402042 0.402042)
							(end -0.3302 0.4318)
						)
						(arc
							(start 0.3302 0.4318)
							(mid 0.402042 0.402042)
							(end 0.4318 0.3302)
						)
						(arc
							(start 0.4318 -0.3302)
							(mid 0.402042 -0.402042)
							(end 0.3302 -0.4318)
						)
					)
					(width 0)
					(fill yes)
				)
			)
		)
		(pad "2" smd custom
			(at 0 0.762)
			(size 0.2159 0.2159)
			(layers "F.Cu" "F.Mask" "F.Paste")
			(net "P1V8_STBY_VREG")
			(options
				(clearance outline)
				(anchor circle)
			)
			(primitives
				(gr_poly
					(pts
						(arc
							(start -0.3302 -0.4318)
							(mid -0.402042 -0.402042)
							(end -0.4318 -0.3302)
						)
						(arc
							(start -0.4318 0.3302)
							(mid -0.402042 0.402042)
							(end -0.3302 0.4318)
						)
						(arc
							(start 0.3302 0.4318)
							(mid 0.402042 0.402042)
							(end 0.4318 0.3302)
						)
						(arc
							(start 0.4318 -0.3302)
							(mid 0.402042 -0.402042)
							(end 0.3302 -0.4318)
						)
					)
					(width 0)
					(fill yes)
				)
			)
		)
	)
	(footprint ""
		(layer "F.Cu")
		(at 303.53 -102.108)
		(property "Reference" "R164"
			(at 0 0 0)
			(layer "F.SilkS")
			(hide yes)
			(effects
				(font
					(size 1.27 1.27)
				)
			)
		)
		(property "Value" "4K7R2F-GP"
			(at 0.064008 -3.993896 0)
			(unlocked yes)
			(layer "F.Fab")
			(hide yes)
			(effects
				(font
					(size 1.016 1.016)
					(thickness 0.1524)
				)
			)
		)
		(property "Device Type" "R402H16"
			(at 0.064008 -5.517896 0)
			(unlocked yes)
			(layer "F.Fab")
			(hide yes)
			(effects
				(font
					(size 1.016 1.016)
					(thickness 0.1524)
				)
			)
		)
		(duplicate_pad_numbers_are_jumpers no)
		(fp_line
			(start -0.508 -0.9398)
			(end -0.508 0.9398)
			(stroke
				(width 0.1524)
				(type default)
			)
			(layer "F.SilkS")
		)
		(fp_line
			(start 0.508 -0.9398)
			(end -0.508 -0.9398)
			(stroke
				(width 0.1524)
				(type default)
			)
			(layer "F.SilkS")
		)
		(fp_rect
			(start -0.508 0.9398)
			(end 0.508 -0.9398)
			(stroke
				(width 0)
				(type default)
			)
			(fill no)
			(layer "F.CrtYd")
		)
		(fp_rect
			(start -0.508 0.9398)
			(end 0.508 -0.9398)
			(stroke
				(width 0)
				(type default)
			)
			(fill no)
			(layer "F.Fab")
		)
		(pad "1" smd custom
			(at 0 -0.4445)
			(size 0.1397 0.1397)
			(layers "F.Cu" "F.Mask" "F.Paste")
			(net "P3V3_STBY")
			(options
				(clearance outline)
				(anchor circle)
			)
			(primitives
				(gr_poly
					(pts
						(arc
							(start -0.1778 -0.2794)
							(mid -0.249642 -0.249642)
							(end -0.2794 -0.1778)
						)
						(arc
							(start -0.2794 0.1778)
							(mid -0.249642 0.249642)
							(end -0.1778 0.2794)
						)
						(arc
							(start 0.1778 0.2794)
							(mid 0.249642 0.249642)
							(end 0.2794 0.1778)
						)
						(arc
							(start 0.2794 -0.1778)
							(mid 0.249642 -0.249642)
							(end 0.1778 -0.2794)
						)
					)
					(width 0)
					(fill yes)
				)
			)
		)
		(pad "2" smd custom
			(at 0 0.4445)
			(size 0.1397 0.1397)
			(layers "F.Cu" "F.Mask" "F.Paste")
			(net "TEMP_2_A2")
			(options
				(clearance outline)
				(anchor circle)
			)
			(primitives
				(gr_poly
					(pts
						(arc
							(start -0.1778 -0.2794)
							(mid -0.249642 -0.249642)
							(end -0.2794 -0.1778)
						)
						(arc
							(start -0.2794 0.1778)
							(mid -0.249642 0.249642)
							(end -0.1778 0.2794)
						)
						(arc
							(start 0.1778 0.2794)
							(mid 0.249642 0.249642)
							(end 0.2794 0.1778)
						)
						(arc
							(start 0.2794 -0.1778)
							(mid 0.249642 -0.249642)
							(end 0.1778 -0.2794)
						)
					)
					(width 0)
					(fill yes)
				)
			)
		)
	)
	(footprint ""
		(layer "F.Cu")
		(at 350.484948 -12.999974 180)
		(property "Reference" "SW1"
			(at 0 0 180)
			(layer "F.SilkS")
			(hide yes)
			(effects
				(font
					(size 1.27 1.27)
				)
			)
		)
		(property "Value" "SW-TACT-4P-185-GP"
			(at -5.746242 -1.509776 180)
			(unlocked yes)
			(layer "F.Fab")
			(hide yes)
			(effects
				(font
					(size 1.016 1.016)
					(thickness 0.1524)
				)
			)
		)
		(property "Device Type" "DTS-65K-S-V"
			(at -5.746242 -3.033776 180)
			(unlocked yes)
			(layer "F.Fab")
			(hide yes)
			(effects
				(font
					(size 1.016 1.016)
					(thickness 0.1524)
				)
			)
		)
		(duplicate_pad_numbers_are_jumpers no)
		(fp_line
			(start 4.2164 3.3528)
			(end 4.2164 -3.3528)
			(stroke
				(width 0.1524)
				(type default)
			)
			(layer "F.SilkS")
		)
		(fp_line
			(start 4.2164 -3.3528)
			(end -4.2164 -3.3528)
			(stroke
				(width 0.1524)
				(type default)
			)
			(layer "F.SilkS")
		)
		(fp_line
			(start 0 0.762)
			(end 0 2.54)
			(stroke
				(width 0.1524)
				(type default)
			)
			(layer "F.SilkS")
		)
		(fp_line
			(start 0 -0.762)
			(end 0.508 0.508)
			(stroke
				(width 0.1524)
				(type default)
			)
			(layer "F.SilkS")
		)
		(fp_line
			(start 0 -2.54)
			(end 0 -0.762)
			(stroke
				(width 0.1524)
				(type default)
			)
			(layer "F.SilkS")
		)
		(fp_line
			(start -3.2258 -3.6322)
			(end -4.4958 -3.6322)
			(stroke
				(width 0.4064)
				(type default)
			)
			(layer "F.SilkS")
		)
		(fp_line
			(start -4.2164 3.3528)
			(end 4.2164 3.3528)
			(stroke
				(width 0.1524)
				(type default)
			)
			(layer "F.SilkS")
		)
		(fp_line
			(start -4.2164 -3.3528)
			(end -4.2164 3.3528)
			(stroke
				(width 0.1524)
				(type default)
			)
			(layer "F.SilkS")
		)
		(fp_line
			(start -4.4958 -3.6322)
			(end -4.4958 -2.3622)
			(stroke
				(width 0.4064)
				(type default)
			)
			(layer "F.SilkS")
		)
		(fp_circle
			(center 3.24993 2.249932)
			(end 2.18313 2.249932)
			(stroke
				(width 0.3048)
				(type default)
			)
			(fill no)
			(layer "F.SilkS")
		)
		(fp_circle
			(center 3.24993 -2.249932)
			(end 2.18313 -2.249932)
			(stroke
				(width 0.3048)
				(type default)
			)
			(fill no)
			(layer "F.SilkS")
		)
		(fp_circle
			(center 0 0.762)
			(end -0.0762 0.762)
			(stroke
				(width 0.1524)
				(type default)
			)
			(fill no)
			(layer "F.SilkS")
		)
		(fp_circle
			(center 0 -0.762)
			(end -0.0762 -0.762)
			(stroke
				(width 0.1524)
				(type default)
			)
			(fill no)
			(layer "F.SilkS")
		)
		(fp_circle
			(center -3.24993 2.249932)
			(end -4.31673 2.249932)
			(stroke
				(width 0.3048)
				(type default)
			)
			(fill no)
			(layer "F.SilkS")
		)
		(fp_circle
			(center -3.24993 -2.249932)
			(end -4.31673 -2.249932)
			(stroke
				(width 0.3048)
				(type default)
			)
			(fill no)
			(layer "F.SilkS")
		)
		(fp_poly
			(pts
				(xy -3.0988 3.0988) (xy -3.0988 2.605532) (xy -3.9497 2.605532) (xy -3.9497 1.894332) (xy -3.0988 1.894332)
				(xy -3.0988 -1.894332) (xy -3.9497 -1.894332) (xy -3.9497 -2.605532) (xy -3.0988 -2.605532) (xy -3.0988 -3.0988)
				(xy 3.0988 -3.0988) (xy 3.0988 -2.605532) (xy 3.9497 -2.605532) (xy 3.9497 -1.894332) (xy 3.0988 -1.894332)
				(xy 3.0988 1.894332) (xy 3.9497 1.894332) (xy 3.9497 2.605532) (xy 3.0988 2.605532) (xy 3.0988 3.0988)
			)
			(stroke
				(width 0)
				(type default)
			)
			(fill no)
			(layer "F.CrtYd")
		)
		(fp_poly
			(pts
				(xy -4.4704 3.6068) (xy -4.4704 -3.6068) (xy 4.4704 -3.6068) (xy 4.4704 3.6068) (xy 0.00254 3.6068)
				(xy 0.00254 3.0988) (xy 3.0988 3.0988) (xy 3.0988 2.605532) (xy 3.9497 2.605532) (xy 3.9497 1.894332)
				(xy 3.0988 1.894332) (xy 3.0988 -1.894332) (xy 3.9497 -1.894332) (xy 3.9497 -2.605532) (xy 3.0988 -2.605532)
				(xy 3.0988 -3.0988) (xy -3.0988 -3.0988) (xy -3.0988 -2.605532) (xy -3.9497 -2.605532) (xy -3.9497 -1.894332)
				(xy -3.0988 -1.894332) (xy -3.0988 1.894332) (xy -3.9497 1.894332) (xy -3.9497 2.605532) (xy -3.0988 2.605532)
				(xy -3.0988 3.0988) (xy -0.00254 3.0988) (xy -0.00254 3.6068)
			)
			(stroke
				(width 0)
				(type default)
			)
			(fill no)
			(layer "F.CrtYd")
		)
		(fp_rect
			(start -4.4704 3.6068)
			(end 4.4704 -3.6068)
			(stroke
				(width 0)
				(type default)
			)
			(fill no)
			(layer "F.Fab")
		)
		(pad "1" thru_hole circle
			(at -3.24993 -2.249932 180)
			(size 1.4224 1.4224)
			(drill 1.016)
			(layers "*.Cu" "*.Mask")
			(remove_unused_layers no)
			(net "FP_PWR_BTN_N")
			(clearance 0.1524)
			(thermal_gap 0.1524)
		)
		(pad "2" thru_hole circle
			(at 3.24993 -2.249932 180)
			(size 1.4224 1.4224)
			(drill 1.016)
			(layers "*.Cu" "*.Mask")
			(remove_unused_layers no)
			(net "FP_PWR_BTN_N")
			(clearance 0.1524)
			(thermal_gap 0.1524)
		)
		(pad "3" thru_hole circle
			(at -3.24993 2.249932 180)
			(size 1.4224 1.4224)
			(drill 1.016)
			(layers "*.Cu" "*.Mask")
			(remove_unused_layers no)
			(net "GND")
			(clearance 0.1524)
			(thermal_gap 0.1524)
		)
		(pad "4" thru_hole circle
			(at 3.24993 2.249932 180)
			(size 1.4224 1.4224)
			(drill 1.016)
			(layers "*.Cu" "*.Mask")
			(remove_unused_layers no)
			(net "GND")
			(clearance 0.1524)
			(thermal_gap 0.1524)
		)
	)
	(footprint ""
		(layer "F.Cu")
		(at 341.249 -100.203)
		(property "Reference" "PL1"
			(at 0 0 0)
			(layer "F.SilkS")
			(hide yes)
			(effects
				(font
					(size 1.27 1.27)
				)
			)
		)
		(property "Value" "COIL-6D8UH-10-GP"
			(at -4.699 -4.0132 0)
			(unlocked yes)
			(layer "F.Fab")
			(hide yes)
			(effects
				(font
					(size 1.016 1.016)
					(thickness 0.1524)
				)
			)
		)
		(property "Device Type" "L7066-1830-UH119"
			(at -4.699 -5.5372 0)
			(unlocked yes)
			(layer "F.Fab")
			(hide yes)
			(effects
				(font
					(size 1.016 1.016)
					(thickness 0.1524)
				)
			)
		)
		(duplicate_pad_numbers_are_jumpers no)
		(fp_line
			(start -3.556 -4.4958)
			(end 3.556 -4.4958)
			(stroke
				(width 0.1524)
				(type default)
			)
			(layer "F.SilkS")
		)
		(fp_line
			(start -3.556 4.4958)
			(end -3.556 -4.4958)
			(stroke
				(width 0.1524)
				(type default)
			)
			(layer "F.SilkS")
		)
		(fp_line
			(start 3.556 -4.4958)
			(end 3.556 4.4958)
			(stroke
				(width 0.1524)
				(type default)
			)
			(layer "F.SilkS")
		)
		(fp_line
			(start 3.556 4.4958)
			(end -3.556 4.4958)
			(stroke
				(width 0.1524)
				(type default)
			)
			(layer "F.SilkS")
		)
		(fp_rect
			(start -3.302 3.4798)
			(end 3.302 -3.4798)
			(stroke
				(width 0)
				(type default)
			)
			(fill no)
			(layer "F.CrtYd")
		)
		(fp_poly
			(pts
				(xy -3.81 4.572) (xy -3.81 -4.572) (xy 3.81 -4.572) (xy 3.81 -0.5588) (xy 3.302 -0.5588) (xy 3.302 -3.4798)
				(xy -3.302 -3.4798) (xy -3.302 3.4798) (xy 3.302 3.4798) (xy 3.302 -0.5461) (xy 3.81 -0.5461) (xy 3.81 4.572)
			)
			(stroke
				(width 0)
				(type default)
			)
			(fill no)
			(layer "F.CrtYd")
		)
		(fp_rect
			(start -3.81 4.572)
			(end 3.81 -4.572)
			(stroke
				(width 0)
				(type default)
			)
			(fill no)
			(layer "F.Fab")
		)
		(pad "1" smd rect
			(at 0 -2.779522)
			(size 3.5052 2.921)
			(layers "F.Cu" "F.Mask" "F.Paste")
			(net "P5V_STBY_SW")
		)
		(pad "2" smd rect
			(at 0 2.779522)
			(size 3.5052 2.921)
			(layers "F.Cu" "F.Mask" "F.Paste")
			(net "P5V_STBY")
		)
	)
	(footprint ""
		(layer "F.Cu")
		(at 59.594242 -144.191482)
		(property "Reference" "SR785"
			(at 0 0 0)
			(layer "F.SilkS")
			(hide yes)
			(effects
				(font
					(size 1.27 1.27)
				)
			)
		)
		(property "Value" "10KR2F-2-GP"
			(at 0.064008 -3.993896 0)
			(unlocked yes)
			(layer "F.Fab")
			(hide yes)
			(effects
				(font
					(size 1.016 1.016)
					(thickness 0.1524)
				)
			)
		)
		(property "Device Type" "R402H16"
			(at 0.064008 -5.517896 0)
			(unlocked yes)
			(layer "F.Fab")
			(hide yes)
			(effects
				(font
					(size 1.016 1.016)
					(thickness 0.1524)
				)
			)
		)
		(duplicate_pad_numbers_are_jumpers no)
		(fp_line
			(start -0.508 -0.9398)
			(end -0.508 0.9398)
			(stroke
				(width 0.1524)
				(type default)
			)
			(layer "F.SilkS")
		)
		(fp_line
			(start 0.508 -0.9398)
			(end -0.508 -0.9398)
			(stroke
				(width 0.1524)
				(type default)
			)
			(layer "F.SilkS")
		)
		(fp_rect
			(start -0.508 0.9398)
			(end 0.508 -0.9398)
			(stroke
				(width 0)
				(type default)
			)
			(fill no)
			(layer "F.CrtYd")
		)
		(fp_rect
			(start -0.508 0.9398)
			(end 0.508 -0.9398)
			(stroke
				(width 0)
				(type default)
			)
			(fill no)
			(layer "F.Fab")
		)
		(pad "1" smd custom
			(at 0 -0.4445)
			(size 0.1397 0.1397)
			(layers "F.Cu" "F.Mask" "F.Paste")
			(net "P1V8_E")
			(options
				(clearance outline)
				(anchor circle)
			)
			(primitives
				(gr_poly
					(pts
						(arc
							(start -0.1778 -0.2794)
							(mid -0.249642 -0.249642)
							(end -0.2794 -0.1778)
						)
						(arc
							(start -0.2794 0.1778)
							(mid -0.249642 0.249642)
							(end -0.1778 0.2794)
						)
						(arc
							(start 0.1778 0.2794)
							(mid 0.249642 0.249642)
							(end 0.2794 0.1778)
						)
						(arc
							(start 0.2794 -0.1778)
							(mid 0.249642 -0.249642)
							(end 0.1778 -0.2794)
						)
					)
					(width 0)
					(fill yes)
				)
			)
		)
		(pad "2" smd custom
			(at 0 0.4445)
			(size 0.1397 0.1397)
			(layers "F.Cu" "F.Mask" "F.Paste")
			(net "EXP_XM_CS_N_0")
			(options
				(clearance outline)
				(anchor circle)
			)
			(primitives
				(gr_poly
					(pts
						(arc
							(start -0.1778 -0.2794)
							(mid -0.249642 -0.249642)
							(end -0.2794 -0.1778)
						)
						(arc
							(start -0.2794 0.1778)
							(mid -0.249642 0.249642)
							(end -0.1778 0.2794)
						)
						(arc
							(start 0.1778 0.2794)
							(mid 0.249642 0.249642)
							(end 0.2794 0.1778)
						)
						(arc
							(start 0.2794 -0.1778)
							(mid 0.249642 -0.249642)
							(end 0.1778 -0.2794)
						)
					)
					(width 0)
					(fill yes)
				)
			)
		)
	)
	(footprint ""
		(layer "F.Cu")
		(at 172.268388 -31.646368)
		(property "Reference" "R401"
			(at 0 0 0)
			(layer "F.SilkS")
			(hide yes)
			(effects
				(font
					(size 1.27 1.27)
				)
			)
		)
		(property "Value" "49D9R2F-GP"
			(at 0.064008 -3.993896 0)
			(unlocked yes)
			(layer "F.Fab")
			(hide yes)
			(effects
				(font
					(size 1.016 1.016)
					(thickness 0.1524)
				)
			)
		)
		(property "Device Type" "R402H16"
			(at 0.064008 -5.517896 0)
			(unlocked yes)
			(layer "F.Fab")
			(hide yes)
			(effects
				(font
					(size 1.016 1.016)
					(thickness 0.1524)
				)
			)
		)
		(duplicate_pad_numbers_are_jumpers no)
		(fp_line
			(start -0.508 -0.9398)
			(end -0.508 0.9398)
			(stroke
				(width 0.1524)
				(type default)
			)
			(layer "F.SilkS")
		)
		(fp_line
			(start 0.508 -0.9398)
			(end -0.508 -0.9398)
			(stroke
				(width 0.1524)
				(type default)
			)
			(layer "F.SilkS")
		)
		(fp_rect
			(start -0.508 0.9398)
			(end 0.508 -0.9398)
			(stroke
				(width 0)
				(type default)
			)
			(fill no)
			(layer "F.CrtYd")
		)
		(fp_rect
			(start -0.508 0.9398)
			(end 0.508 -0.9398)
			(stroke
				(width 0)
				(type default)
			)
			(fill no)
			(layer "F.Fab")
		)
		(pad "1" smd custom
			(at 0 -0.4445)
			(size 0.1397 0.1397)
			(layers "F.Cu" "F.Mask" "F.Paste")
			(net "MOD_IMC_FAB_D_COP")
			(options
				(clearance outline)
				(anchor circle)
			)
			(primitives
				(gr_poly
					(pts
						(arc
							(start -0.1778 -0.2794)
							(mid -0.249642 -0.249642)
							(end -0.2794 -0.1778)
						)
						(arc
							(start -0.2794 0.1778)
							(mid -0.249642 0.249642)
							(end -0.1778 0.2794)
						)
						(arc
							(start 0.1778 0.2794)
							(mid 0.249642 0.249642)
							(end 0.2794 0.1778)
						)
						(arc
							(start 0.2794 -0.1778)
							(mid 0.249642 -0.249642)
							(end 0.1778 -0.2794)
						)
					)
					(width 0)
					(fill yes)
				)
			)
		)
		(pad "2" smd custom
			(at 0 0.4445)
			(size 0.1397 0.1397)
			(layers "F.Cu" "F.Mask" "F.Paste")
			(net "BCM5221_RX_C_DP")
			(options
				(clearance outline)
				(anchor circle)
			)
			(primitives
				(gr_poly
					(pts
						(arc
							(start -0.1778 -0.2794)
							(mid -0.249642 -0.249642)
							(end -0.2794 -0.1778)
						)
						(arc
							(start -0.2794 0.1778)
							(mid -0.249642 0.249642)
							(end -0.1778 0.2794)
						)
						(arc
							(start 0.1778 0.2794)
							(mid 0.249642 0.249642)
							(end 0.2794 0.1778)
						)
						(arc
							(start 0.2794 -0.1778)
							(mid 0.249642 -0.249642)
							(end 0.1778 -0.2794)
						)
					)
					(width 0)
					(fill yes)
				)
			)
		)
	)
	(footprint ""
		(layer "F.Cu")
		(at 146.939 -16.764 -90)
		(property "Reference" "C324"
			(at 0 0 270)
			(layer "F.SilkS")
			(hide yes)
			(effects
				(font
					(size 1.27 1.27)
				)
			)
		)
		(property "Value" "SCD1U16V2KX-3GP"
			(at 1.1811 -2.7051 270)
			(unlocked yes)
			(layer "F.Fab")
			(hide yes)
			(effects
				(font
					(size 1.016 1.016)
					(thickness 0.1524)
				)
			)
		)
		(property "Device Type" "C402H22"
			(at 1.1811 -4.2291 270)
			(unlocked yes)
			(layer "F.Fab")
			(hide yes)
			(effects
				(font
					(size 1.016 1.016)
					(thickness 0.1524)
				)
			)
		)
		(duplicate_pad_numbers_are_jumpers no)
		(fp_rect
			(start -0.4318 0.9525)
			(end 0.4318 -0.9525)
			(stroke
				(width 0)
				(type default)
			)
			(fill no)
			(layer "F.CrtYd")
		)
		(fp_rect
			(start -0.4318 0.9525)
			(end 0.4318 -0.9525)
			(stroke
				(width 0)
				(type default)
			)
			(fill no)
			(layer "F.Fab")
		)
		(pad "1" smd custom
			(at 0 -0.4445 270)
			(size 0.1524 0.1524)
			(layers "F.Cu" "F.Mask" "F.Paste")
			(net "PHY_AVDD")
			(options
				(clearance outline)
				(anchor circle)
			)
			(primitives
				(gr_poly
					(pts
						(arc
							(start 0.3048 -0.2032)
							(mid 0.275042 -0.275042)
							(end 0.2032 -0.3048)
						)
						(arc
							(start -0.2032 -0.3048)
							(mid -0.275042 -0.275042)
							(end -0.3048 -0.2032)
						)
						(arc
							(start -0.3048 0.2032)
							(mid -0.275042 0.275042)
							(end -0.2032 0.3048)
						)
						(arc
							(start 0.2032 0.3048)
							(mid 0.275042 0.275042)
							(end 0.3048 0.2032)
						)
					)
					(width 0)
					(fill yes)
				)
			)
		)
		(pad "2" smd custom
			(at 0 0.4445 270)
			(size 0.1524 0.1524)
			(layers "F.Cu" "F.Mask" "F.Paste")
			(net "GND")
			(options
				(clearance outline)
				(anchor circle)
			)
			(primitives
				(gr_poly
					(pts
						(arc
							(start 0.3048 -0.2032)
							(mid 0.275042 -0.275042)
							(end 0.2032 -0.3048)
						)
						(arc
							(start -0.2032 -0.3048)
							(mid -0.275042 -0.275042)
							(end -0.3048 -0.2032)
						)
						(arc
							(start -0.3048 0.2032)
							(mid -0.275042 0.275042)
							(end -0.2032 0.3048)
						)
						(arc
							(start 0.2032 0.3048)
							(mid 0.275042 0.275042)
							(end 0.3048 0.2032)
						)
					)
					(width 0)
					(fill yes)
				)
			)
		)
	)
	(footprint ""
		(layer "F.Cu")
		(at 290.068 -158.496 180)
		(property "Reference" "R422"
			(at 0 0 180)
			(layer "F.SilkS")
			(hide yes)
			(effects
				(font
					(size 1.27 1.27)
				)
			)
		)
		(property "Value" "2K2R2J-2-GP"
			(at 0.064008 -3.993896 180)
			(unlocked yes)
			(layer "F.Fab")
			(hide yes)
			(effects
				(font
					(size 1.016 1.016)
					(thickness 0.1524)
				)
			)
		)
		(property "Device Type" "R402H16"
			(at 0.064008 -5.517896 180)
			(unlocked yes)
			(layer "F.Fab")
			(hide yes)
			(effects
				(font
					(size 1.016 1.016)
					(thickness 0.1524)
				)
			)
		)
		(duplicate_pad_numbers_are_jumpers no)
		(fp_line
			(start 0.508 -0.9398)
			(end -0.508 -0.9398)
			(stroke
				(width 0.1524)
				(type default)
			)
			(layer "F.SilkS")
		)
		(fp_line
			(start -0.508 -0.9398)
			(end -0.508 0.9398)
			(stroke
				(width 0.1524)
				(type default)
			)
			(layer "F.SilkS")
		)
		(fp_rect
			(start -0.508 0.9398)
			(end 0.508 -0.9398)
			(stroke
				(width 0)
				(type default)
			)
			(fill no)
			(layer "F.CrtYd")
		)
		(fp_rect
			(start -0.508 0.9398)
			(end 0.508 -0.9398)
			(stroke
				(width 0)
				(type default)
			)
			(fill no)
			(layer "F.Fab")
		)
		(pad "1" smd custom
			(at 0 -0.4445 180)
			(size 0.1397 0.1397)
			(layers "F.Cu" "F.Mask" "F.Paste")
			(net "P3V3_STBY")
			(options
				(clearance outline)
				(anchor circle)
			)
			(primitives
				(gr_poly
					(pts
						(arc
							(start -0.1778 -0.2794)
							(mid -0.249642 -0.249642)
							(end -0.2794 -0.1778)
						)
						(arc
							(start -0.2794 0.1778)
							(mid -0.249642 0.249642)
							(end -0.1778 0.2794)
						)
						(arc
							(start 0.1778 0.2794)
							(mid 0.249642 0.249642)
							(end 0.2794 0.1778)
						)
						(arc
							(start 0.2794 -0.1778)
							(mid 0.249642 -0.249642)
							(end 0.1778 -0.2794)
						)
					)
					(width 0)
					(fill yes)
				)
			)
		)
		(pad "2" smd custom
			(at 0 0.4445 180)
			(size 0.1397 0.1397)
			(layers "F.Cu" "F.Mask" "F.Paste")
			(net "CPU_BMC_UART_RX")
			(options
				(clearance outline)
				(anchor circle)
			)
			(primitives
				(gr_poly
					(pts
						(arc
							(start -0.1778 -0.2794)
							(mid -0.249642 -0.249642)
							(end -0.2794 -0.1778)
						)
						(arc
							(start -0.2794 0.1778)
							(mid -0.249642 0.249642)
							(end -0.1778 0.2794)
						)
						(arc
							(start 0.1778 0.2794)
							(mid 0.249642 0.249642)
							(end 0.2794 0.1778)
						)
						(arc
							(start 0.2794 -0.1778)
							(mid 0.249642 -0.249642)
							(end 0.1778 -0.2794)
						)
					)
					(width 0)
					(fill yes)
				)
			)
		)
	)
	(footprint ""
		(layer "F.Cu")
		(at 108.458 -28.194)
		(property "Reference" "STP43"
			(at 0 0 0)
			(layer "F.SilkS")
			(hide yes)
			(effects
				(font
					(size 1.27 1.27)
				)
			)
		)
		(property "Value" "TPAD28"
			(at 0.0127 -1.8034 0)
			(unlocked yes)
			(layer "F.Fab")
			(hide yes)
			(effects
				(font
					(size 1.016 1.016)
					(thickness 0.1524)
				)
			)
		)
		(property "Device Type" "TPAD28"
			(at 0.0127 -3.3274 0)
			(unlocked yes)
			(layer "F.Fab")
			(hide yes)
			(effects
				(font
					(size 1.016 1.016)
					(thickness 0.1524)
				)
			)
		)
		(duplicate_pad_numbers_are_jumpers no)
		(fp_poly
			(pts
				(arc
					(start 0.3556 0)
					(mid -0.3556 0)
					(end 0.3556 0)
				)
			)
			(stroke
				(width 0)
				(type default)
			)
			(fill no)
			(layer "F.CrtYd")
		)
		(fp_poly
			(pts
				(arc
					(start 0.6096 0)
					(mid -0.6096 0)
					(end 0.6096 0)
				)
			)
			(stroke
				(width 0)
				(type default)
			)
			(fill no)
			(layer "F.Fab")
		)
		(pad "1" smd circle
			(at 0 0)
			(size 0.7112 0.7112)
			(layers "F.Cu" "F.Mask" "F.Paste")
			(net "SYS_DBMODE1")
		)
	)
	(footprint ""
		(layer "F.Cu")
		(at 307.086 -223.139 90)
		(property "Reference" "C331"
			(at 0 0 90)
			(layer "F.SilkS")
			(hide yes)
			(effects
				(font
					(size 1.27 1.27)
				)
			)
		)
		(property "Value" "SCD1U25V2KX-2-GP"
			(at 1.1811 -2.7051 90)
			(unlocked yes)
			(layer "F.Fab")
			(hide yes)
			(effects
				(font
					(size 1.016 1.016)
					(thickness 0.1524)
				)
			)
		)
		(property "Device Type" "C402H22"
			(at 1.1811 -4.2291 90)
			(unlocked yes)
			(layer "F.Fab")
			(hide yes)
			(effects
				(font
					(size 1.016 1.016)
					(thickness 0.1524)
				)
			)
		)
		(duplicate_pad_numbers_are_jumpers no)
		(fp_rect
			(start -0.4318 0.9525)
			(end 0.4318 -0.9525)
			(stroke
				(width 0)
				(type default)
			)
			(fill no)
			(layer "F.CrtYd")
		)
		(fp_rect
			(start -0.4318 0.9525)
			(end 0.4318 -0.9525)
			(stroke
				(width 0)
				(type default)
			)
			(fill no)
			(layer "F.Fab")
		)
		(pad "1" smd custom
			(at 0 -0.4445 90)
			(size 0.1524 0.1524)
			(layers "F.Cu" "F.Mask" "F.Paste")
			(net "P3V3_STBY")
			(options
				(clearance outline)
				(anchor circle)
			)
			(primitives
				(gr_poly
					(pts
						(arc
							(start 0.3048 -0.2032)
							(mid 0.275042 -0.275042)
							(end 0.2032 -0.3048)
						)
						(arc
							(start -0.2032 -0.3048)
							(mid -0.275042 -0.275042)
							(end -0.3048 -0.2032)
						)
						(arc
							(start -0.3048 0.2032)
							(mid -0.275042 0.275042)
							(end -0.2032 0.3048)
						)
						(arc
							(start 0.2032 0.3048)
							(mid 0.275042 0.275042)
							(end 0.3048 0.2032)
						)
					)
					(width 0)
					(fill yes)
				)
			)
		)
		(pad "2" smd custom
			(at 0 0.4445 90)
			(size 0.1524 0.1524)
			(layers "F.Cu" "F.Mask" "F.Paste")
			(net "GND")
			(options
				(clearance outline)
				(anchor circle)
			)
			(primitives
				(gr_poly
					(pts
						(arc
							(start 0.3048 -0.2032)
							(mid 0.275042 -0.275042)
							(end 0.2032 -0.3048)
						)
						(arc
							(start -0.2032 -0.3048)
							(mid -0.275042 -0.275042)
							(end -0.3048 -0.2032)
						)
						(arc
							(start -0.3048 0.2032)
							(mid -0.275042 0.275042)
							(end -0.2032 0.3048)
						)
						(arc
							(start 0.2032 0.3048)
							(mid 0.275042 0.275042)
							(end 0.3048 0.2032)
						)
					)
					(width 0)
					(fill yes)
				)
			)
		)
	)
	(footprint ""
		(layer "F.Cu")
		(at 291.973 -210.058 90)
		(property "Reference" "C180"
			(at 0 0 90)
			(layer "F.SilkS")
			(hide yes)
			(effects
				(font
					(size 1.27 1.27)
				)
			)
		)
		(property "Value" "SC1U16V3KX-5GP"
			(at 0 -2.8194 90)
			(unlocked yes)
			(layer "F.Fab")
			(hide yes)
			(effects
				(font
					(size 1.016 1.016)
					(thickness 0.1524)
				)
			)
		)
		(property "Device Type" "C603H36"
			(at 0 -4.3434 90)
			(unlocked yes)
			(layer "F.Fab")
			(hide yes)
			(effects
				(font
					(size 1.016 1.016)
					(thickness 0.1524)
				)
			)
		)
		(duplicate_pad_numbers_are_jumpers no)
		(fp_line
			(start 0.508 0)
			(end -0.508 0)
			(stroke
				(width 0.2032)
				(type default)
			)
			(layer "F.SilkS")
		)
		(fp_rect
			(start -0.5842 1.3335)
			(end 0.5842 -1.3335)
			(stroke
				(width 0)
				(type default)
			)
			(fill no)
			(layer "F.CrtYd")
		)
		(fp_rect
			(start -0.5842 1.3335)
			(end 0.5842 -1.3335)
			(stroke
				(width 0)
				(type default)
			)
			(fill no)
			(layer "F.Fab")
		)
		(pad "1" smd custom
			(at 0 -0.762 90)
			(size 0.2159 0.2159)
			(layers "F.Cu" "F.Mask" "F.Paste")
			(net "DDR_VREF")
			(options
				(clearance outline)
				(anchor circle)
			)
			(primitives
				(gr_poly
					(pts
						(arc
							(start -0.3302 -0.4318)
							(mid -0.402042 -0.402042)
							(end -0.4318 -0.3302)
						)
						(arc
							(start -0.4318 0.3302)
							(mid -0.402042 0.402042)
							(end -0.3302 0.4318)
						)
						(arc
							(start 0.3302 0.4318)
							(mid 0.402042 0.402042)
							(end 0.4318 0.3302)
						)
						(arc
							(start 0.4318 -0.3302)
							(mid 0.402042 -0.402042)
							(end 0.3302 -0.4318)
						)
					)
					(width 0)
					(fill yes)
				)
			)
		)
		(pad "2" smd custom
			(at 0 0.762 90)
			(size 0.2159 0.2159)
			(layers "F.Cu" "F.Mask" "F.Paste")
			(net "GND")
			(options
				(clearance outline)
				(anchor circle)
			)
			(primitives
				(gr_poly
					(pts
						(arc
							(start -0.3302 -0.4318)
							(mid -0.402042 -0.402042)
							(end -0.4318 -0.3302)
						)
						(arc
							(start -0.4318 0.3302)
							(mid -0.402042 0.402042)
							(end -0.3302 0.4318)
						)
						(arc
							(start 0.3302 0.4318)
							(mid 0.402042 0.402042)
							(end 0.4318 0.3302)
						)
						(arc
							(start 0.4318 -0.3302)
							(mid 0.402042 -0.402042)
							(end 0.3302 -0.4318)
						)
					)
					(width 0)
					(fill yes)
				)
			)
		)
	)
	(footprint ""
		(layer "F.Cu")
		(at 310.896 -186.817 -90)
		(property "Reference" "SR853"
			(at 0 0 270)
			(layer "F.SilkS")
			(hide yes)
			(effects
				(font
					(size 1.27 1.27)
				)
			)
		)
		(property "Value" "4K75R2F-1-GP"
			(at 0.064008 -3.993896 270)
			(unlocked yes)
			(layer "F.Fab")
			(hide yes)
			(effects
				(font
					(size 1.016 1.016)
					(thickness 0.1524)
				)
			)
		)
		(property "Device Type" "R402H16"
			(at 0.064008 -5.517896 270)
			(unlocked yes)
			(layer "F.Fab")
			(hide yes)
			(effects
				(font
					(size 1.016 1.016)
					(thickness 0.1524)
				)
			)
		)
		(duplicate_pad_numbers_are_jumpers no)
		(fp_line
			(start -0.508 -0.9398)
			(end -0.508 0.9398)
			(stroke
				(width 0.1524)
				(type default)
			)
			(layer "F.SilkS")
		)
		(fp_line
			(start 0.508 -0.9398)
			(end -0.508 -0.9398)
			(stroke
				(width 0.1524)
				(type default)
			)
			(layer "F.SilkS")
		)
		(fp_rect
			(start -0.508 0.9398)
			(end 0.508 -0.9398)
			(stroke
				(width 0)
				(type default)
			)
			(fill no)
			(layer "F.CrtYd")
		)
		(fp_rect
			(start -0.508 0.9398)
			(end 0.508 -0.9398)
			(stroke
				(width 0)
				(type default)
			)
			(fill no)
			(layer "F.Fab")
		)
		(pad "1" smd custom
			(at 0 -0.4445 270)
			(size 0.1397 0.1397)
			(layers "F.Cu" "F.Mask" "F.Paste")
			(net "P3V3_STBY")
			(options
				(clearance outline)
				(anchor circle)
			)
			(primitives
				(gr_poly
					(pts
						(arc
							(start -0.1778 -0.2794)
							(mid -0.249642 -0.249642)
							(end -0.2794 -0.1778)
						)
						(arc
							(start -0.2794 0.1778)
							(mid -0.249642 0.249642)
							(end -0.1778 0.2794)
						)
						(arc
							(start 0.1778 0.2794)
							(mid 0.249642 0.249642)
							(end 0.2794 0.1778)
						)
						(arc
							(start 0.2794 -0.1778)
							(mid 0.249642 -0.249642)
							(end 0.1778 -0.2794)
						)
					)
					(width 0)
					(fill yes)
				)
			)
		)
		(pad "2" smd custom
			(at 0 0.4445 270)
			(size 0.1397 0.1397)
			(layers "F.Cu" "F.Mask" "F.Paste")
			(net "BMC_FW_DET_BOARD_VER_2")
			(options
				(clearance outline)
				(anchor circle)
			)
			(primitives
				(gr_poly
					(pts
						(arc
							(start -0.1778 -0.2794)
							(mid -0.249642 -0.249642)
							(end -0.2794 -0.1778)
						)
						(arc
							(start -0.2794 0.1778)
							(mid -0.249642 0.249642)
							(end -0.1778 0.2794)
						)
						(arc
							(start 0.1778 0.2794)
							(mid 0.249642 0.249642)
							(end 0.2794 0.1778)
						)
						(arc
							(start 0.2794 -0.1778)
							(mid 0.249642 -0.249642)
							(end 0.1778 -0.2794)
						)
					)
					(width 0)
					(fill yes)
				)
			)
		)
	)
	(footprint ""
		(layer "F.Cu")
		(at 78.99019 -57.879488 -90)
		(property "Reference" "SC927"
			(at 0 0 270)
			(layer "F.SilkS")
			(hide yes)
			(effects
				(font
					(size 1.27 1.27)
				)
			)
		)
		(property "Value" "SC22U6D3V5MX-2GP"
			(at -0.0762 -6.1214 270)
			(unlocked yes)
			(layer "F.Fab")
			(hide yes)
			(effects
				(font
					(size 1.016 1.016)
					(thickness 0.1524)
				)
			)
		)
		(property "Device Type" "C805H58"
			(at -0.0762 -8.1534 270)
			(unlocked yes)
			(layer "F.Fab")
			(hide yes)
			(effects
				(font
					(size 1.016 1.016)
					(thickness 0.1524)
				)
			)
		)
		(duplicate_pad_numbers_are_jumpers no)
		(fp_line
			(start 0.635 0)
			(end -0.635 0)
			(stroke
				(width 0.508)
				(type default)
			)
			(layer "F.SilkS")
		)
		(fp_rect
			(start -0.9652 1.778)
			(end 0.9652 -1.778)
			(stroke
				(width 0)
				(type default)
			)
			(fill no)
			(layer "F.CrtYd")
		)
		(fp_poly
			(pts
				(xy -0.9652 -1.778) (xy 0.9652 -1.778) (xy 0.9652 1.778) (xy -0.9652 1.778)
			)
			(stroke
				(width 0)
				(type default)
			)
			(fill no)
			(layer "F.Fab")
		)
		(pad "1" smd rect
			(at 0 -0.9652 270)
			(size 1.397 1.143)
			(layers "F.Cu" "F.Mask" "F.Paste")
			(net "SHELL_PLL_VDD")
		)
		(pad "2" smd rect
			(at 0 0.9652 270)
			(size 1.397 1.143)
			(layers "F.Cu" "F.Mask" "F.Paste")
			(net "GND")
		)
	)
	(footprint ""
		(layer "F.Cu")
		(at 243.080032 -96.52 180)
		(property "Reference" "CN7"
			(at 0 0 180)
			(layer "F.SilkS")
			(hide yes)
			(effects
				(font
					(size 1.27 1.27)
				)
			)
		)
		(property "Value" "AMP-CONN10D-3-GP"
			(at 5.1562 -6.9469 180)
			(unlocked yes)
			(layer "F.Fab")
			(hide yes)
			(effects
				(font
					(size 1.016 1.016)
					(thickness 0.1524)
				)
			)
		)
		(property "Device Type" "G823MB10221KEU"
			(at 5.1562 -8.4709 180)
			(unlocked yes)
			(layer "F.Fab")
			(hide yes)
			(effects
				(font
					(size 1.016 1.016)
					(thickness 0.1524)
				)
			)
		)
		(duplicate_pad_numbers_are_jumpers no)
		(fp_line
			(start 6.5786 3.6576)
			(end 6.5786 -3.6576)
			(stroke
				(width 0.1524)
				(type default)
			)
			(layer "F.SilkS")
		)
		(fp_line
			(start 6.5786 -3.6576)
			(end -6.5786 -3.6576)
			(stroke
				(width 0.1524)
				(type default)
			)
			(layer "F.SilkS")
		)
		(fp_line
			(start 0.635 3.6576)
			(end 6.5786 3.6576)
			(stroke
				(width 0.1524)
				(type default)
			)
			(layer "F.SilkS")
		)
		(fp_line
			(start -0.7239 3.6576)
			(end -6.5786 3.6576)
			(stroke
				(width 0.1524)
				(type default)
			)
			(layer "F.SilkS")
		)
		(fp_line
			(start -3.6322 -3.7592)
			(end -3.6195 -3.7465)
			(stroke
				(width 0.3302)
				(type default)
			)
			(layer "F.SilkS")
		)
		(fp_line
			(start -4.3815 -3.7592)
			(end -3.6322 -3.7592)
			(stroke
				(width 0.3302)
				(type default)
			)
			(layer "F.SilkS")
		)
		(fp_line
			(start -6.5786 -3.6576)
			(end -6.5786 3.6576)
			(stroke
				(width 0.1524)
				(type default)
			)
			(layer "F.SilkS")
		)
		(fp_poly
			(pts
				(xy -3.999992 -3.7338) (xy -3.364992 -4.3688) (xy -4.634992 -4.3688)
			)
			(stroke
				(width 0)
				(type default)
			)
			(fill yes)
			(layer "F.SilkS")
		)
		(fp_poly
			(pts
				(xy -2.1844 0.70231) (xy 2.1971 0.70231) (xy 2.1971 -0.70231) (xy -2.1844 -0.70231)
			)
			(stroke
				(width 0)
				(type default)
			)
			(fill yes)
			(layer "F.SilkS")
		)
		(fp_rect
			(start -6.3246 3.1496)
			(end 6.3246 -3.1496)
			(stroke
				(width 0)
				(type default)
			)
			(fill no)
			(layer "F.CrtYd")
		)
		(fp_poly
			(pts
				(xy 6.8326 -3.1496) (xy -6.3246 -3.1496) (xy -6.3246 3.1496) (xy 6.3246 3.1496) (xy 6.3246 -3.1369)
				(xy 6.8326 -3.1369) (xy 6.8326 3.9116) (xy -6.8326 3.9116) (xy -6.8326 -3.9116) (xy 6.8326 -3.9116)
			)
			(stroke
				(width 0)
				(type default)
			)
			(fill no)
			(layer "F.CrtYd")
		)
		(fp_rect
			(start -6.8326 3.9116)
			(end 6.8326 -3.9116)
			(stroke
				(width 0)
				(type default)
			)
			(fill no)
			(layer "F.Fab")
		)
		(pad "" np_thru_hole circle
			(at -2.999994 0 180)
			(size 0.254 0.254)
			(drill 1.016)
			(layers "*.Cu" "*.Mask")
			(clearance 0.7366)
			(thermal_gap 0.7366)
		)
		(pad "" np_thru_hole circle
			(at 2.999994 0 180)
			(size 0.254 0.254)
			(drill 1.016)
			(layers "*.Cu" "*.Mask")
			(clearance 0.7366)
			(thermal_gap 0.7366)
		)
		(pad "1" smd rect
			(at -3.999992 -2.15011 180)
			(size 0.889 2.4892)
			(layers "F.Cu" "F.Mask" "F.Paste")
			(net "BMC_JTAG_L_EN")
		)
		(pad "2" smd rect
			(at -3.999992 2.15011 180)
			(size 0.889 2.4892)
			(layers "F.Cu" "F.Mask" "F.Paste")
			(net "JTAG_BMC_TCK")
		)
		(pad "3" smd rect
			(at -1.999996 -2.15011 180)
			(size 0.889 2.4892)
			(layers "F.Cu" "F.Mask" "F.Paste")
			(net "P3V3_STBY")
		)
		(pad "4" smd rect
			(at -1.999996 2.15011 180)
			(size 0.889 2.4892)
			(layers "F.Cu" "F.Mask" "F.Paste")
			(net "JTAG_IOC_TDO_L")
		)
		(pad "5" smd rect
			(at 0 -2.15011 180)
			(size 0.889 2.4892)
			(layers "F.Cu" "F.Mask" "F.Paste")
			(net "Net_257")
		)
		(pad "6" smd rect
			(at 0 2.15011 180)
			(size 0.889 2.4892)
			(layers "F.Cu" "F.Mask" "F.Paste")
			(net "JTAG_BMC_TMS")
		)
		(pad "7" smd rect
			(at 1.999996 -2.15011 180)
			(size 0.889 2.4892)
			(layers "F.Cu" "F.Mask" "F.Paste")
			(net "JTAG_BMC_TRST_N")
		)
		(pad "8" smd rect
			(at 1.999996 2.15011 180)
			(size 0.889 2.4892)
			(layers "F.Cu" "F.Mask" "F.Paste")
			(net "Net_256")
		)
		(pad "9" smd rect
			(at 3.999992 -2.15011 180)
			(size 0.889 2.4892)
			(layers "F.Cu" "F.Mask" "F.Paste")
			(net "GND")
		)
		(pad "10" smd rect
			(at 3.999992 2.15011 180)
			(size 0.889 2.4892)
			(layers "F.Cu" "F.Mask" "F.Paste")
			(net "JTAG_BMC_TDI")
		)
		(zone
			(layer "F.Cu")
			(hatch none 0.5)
			(connect_pads
				(clearance 0)
			)
			(min_thickness 0.25)
			(keepout
				(tracks allowed)
				(vias not_allowed)
				(pads allowed)
				(copperpour not_allowed)
				(footprints allowed)
			)
			(placement
				(enabled no)
				(sheetname "")
			)
			(fill
				(thermal_gap 0.5)
				(thermal_bridge_width 0.5)
				(island_removal_mode 0)
			)
			(polygon
				(pts
					(xy 239.270032 -97.42551) (xy 238.63554 -97.42551) (xy 238.63554 -96.91751) (xy 239.270032 -96.91751)
				)
			)
		)
		(zone
			(layer "F.Cu")
			(hatch none 0.5)
			(connect_pads
				(clearance 0)
			)
			(min_thickness 0.25)
			(keepout
				(tracks not_allowed)
				(vias allowed)
				(pads allowed)
				(copperpour not_allowed)
				(footprints allowed)
			)
			(placement
				(enabled no)
				(sheetname "")
			)
			(fill
				(thermal_gap 0.5)
				(thermal_bridge_width 0.5)
				(island_removal_mode 0)
			)
			(polygon
				(pts
					(xy 239.270032 -97.42551) (xy 238.63554 -97.42551) (xy 238.63554 -95.61449) (xy 239.270032 -95.61449)
				)
			)
		)
		(zone
			(layer "F.Cu")
			(hatch none 0.5)
			(connect_pads
				(clearance 0)
			)
			(min_thickness 0.25)
			(keepout
				(tracks allowed)
				(vias not_allowed)
				(pads allowed)
				(copperpour not_allowed)
				(footprints allowed)
			)
			(placement
				(enabled no)
				(sheetname "")
			)
			(fill
				(thermal_gap 0.5)
				(thermal_bridge_width 0.5)
				(island_removal_mode 0)
			)
			(polygon
				(pts
					(xy 239.270032 -97.42551) (xy 238.63554 -97.42551) (xy 238.63554 -95.61449) (xy 239.270032 -95.61449)
				)
			)
		)
		(zone
			(layer "F.Cu")
			(hatch none 0.5)
			(connect_pads
				(clearance 0)
			)
			(min_thickness 0.25)
			(keepout
				(tracks allowed)
				(vias not_allowed)
				(pads allowed)
				(copperpour not_allowed)
				(footprints allowed)
			)
			(placement
				(enabled no)
				(sheetname "")
			)
			(fill
				(thermal_gap 0.5)
				(thermal_bridge_width 0.5)
				(island_removal_mode 0)
			)
			(polygon
				(pts
					(xy 239.270032 -96.12249) (xy 238.63554 -96.12249) (xy 238.63554 -95.61449) (xy 239.270032 -95.61449)
				)
			)
		)
		(zone
			(layer "F.Cu")
			(hatch none 0.5)
			(connect_pads
				(clearance 0)
			)
			(min_thickness 0.25)
			(keepout
				(tracks allowed)
				(vias not_allowed)
				(pads allowed)
				(copperpour not_allowed)
				(footprints allowed)
			)
			(placement
				(enabled no)
				(sheetname "")
			)
			(fill
				(thermal_gap 0.5)
				(thermal_bridge_width 0.5)
				(island_removal_mode 0)
			)
			(polygon
				(pts
					(xy 245.264432 -97.42551) (xy 240.882932 -97.42551) (xy 240.882932 -96.91751) (xy 245.264432 -96.91751)
				)
			)
		)
		(zone
			(layer "F.Cu")
			(hatch none 0.5)
			(connect_pads
				(clearance 0)
			)
			(min_thickness 0.25)
			(keepout
				(tracks not_allowed)
				(vias allowed)
				(pads allowed)
				(copperpour not_allowed)
				(footprints allowed)
			)
			(placement
				(enabled no)
				(sheetname "")
			)
			(fill
				(thermal_gap 0.5)
				(thermal_bridge_width 0.5)
				(island_removal_mode 0)
			)
			(polygon
				(pts
					(xy 245.264432 -97.42551) (xy 240.882932 -97.42551) (xy 240.882932 -95.61449) (xy 245.264432 -95.61449)
				)
			)
		)
		(zone
			(layer "F.Cu")
			(hatch none 0.5)
			(connect_pads
				(clearance 0)
			)
			(min_thickness 0.25)
			(keepout
				(tracks allowed)
				(vias not_allowed)
				(pads allowed)
				(copperpour not_allowed)
				(footprints allowed)
			)
			(placement
				(enabled no)
				(sheetname "")
			)
			(fill
				(thermal_gap 0.5)
				(thermal_bridge_width 0.5)
				(island_removal_mode 0)
			)
			(polygon
				(pts
					(xy 245.264432 -97.42551) (xy 240.882932 -97.42551) (xy 240.882932 -95.61449) (xy 245.264432 -95.61449)
				)
			)
		)
		(zone
			(layer "F.Cu")
			(hatch none 0.5)
			(connect_pads
				(clearance 0)
			)
			(min_thickness 0.25)
			(keepout
				(tracks allowed)
				(vias not_allowed)
				(pads allowed)
				(copperpour not_allowed)
				(footprints allowed)
			)
			(placement
				(enabled no)
				(sheetname "")
			)
			(fill
				(thermal_gap 0.5)
				(thermal_bridge_width 0.5)
				(island_removal_mode 0)
			)
			(polygon
				(pts
					(xy 245.264432 -96.12249) (xy 240.882932 -96.12249) (xy 240.882932 -95.61449) (xy 245.264432 -95.61449)
				)
			)
		)
		(zone
			(layer "F.Cu")
			(hatch none 0.5)
			(connect_pads
				(clearance 0)
			)
			(min_thickness 0.25)
			(keepout
				(tracks allowed)
				(vias not_allowed)
				(pads allowed)
				(copperpour not_allowed)
				(footprints allowed)
			)
			(placement
				(enabled no)
				(sheetname "")
			)
			(fill
				(thermal_gap 0.5)
				(thermal_bridge_width 0.5)
				(island_removal_mode 0)
			)
			(polygon
				(pts
					(xy 247.524524 -97.42551) (xy 246.890032 -97.42551) (xy 246.890032 -96.91751) (xy 247.524524 -96.91751)
				)
			)
		)
		(zone
			(layer "F.Cu")
			(hatch none 0.5)
			(connect_pads
				(clearance 0)
			)
			(min_thickness 0.25)
			(keepout
				(tracks not_allowed)
				(vias allowed)
				(pads allowed)
				(copperpour not_allowed)
				(footprints allowed)
			)
			(placement
				(enabled no)
				(sheetname "")
			)
			(fill
				(thermal_gap 0.5)
				(thermal_bridge_width 0.5)
				(island_removal_mode 0)
			)
			(polygon
				(pts
					(xy 247.524524 -97.42551) (xy 246.890032 -97.42551) (xy 246.890032 -95.61449) (xy 247.524524 -95.61449)
				)
			)
		)
		(zone
			(layer "F.Cu")
			(hatch none 0.5)
			(connect_pads
				(clearance 0)
			)
			(min_thickness 0.25)
			(keepout
				(tracks allowed)
				(vias not_allowed)
				(pads allowed)
				(copperpour not_allowed)
				(footprints allowed)
			)
			(placement
				(enabled no)
				(sheetname "")
			)
			(fill
				(thermal_gap 0.5)
				(thermal_bridge_width 0.5)
				(island_removal_mode 0)
			)
			(polygon
				(pts
					(xy 247.524524 -97.42551) (xy 246.890032 -97.42551) (xy 246.890032 -95.61449) (xy 247.524524 -95.61449)
				)
			)
		)
		(zone
			(layer "F.Cu")
			(hatch none 0.5)
			(connect_pads
				(clearance 0)
			)
			(min_thickness 0.25)
			(keepout
				(tracks allowed)
				(vias not_allowed)
				(pads allowed)
				(copperpour not_allowed)
				(footprints allowed)
			)
			(placement
				(enabled no)
				(sheetname "")
			)
			(fill
				(thermal_gap 0.5)
				(thermal_bridge_width 0.5)
				(island_removal_mode 0)
			)
			(polygon
				(pts
					(xy 247.524524 -96.12249) (xy 246.890032 -96.12249) (xy 246.890032 -95.61449) (xy 247.524524 -95.61449)
				)
			)
		)
		(zone
			(layers "F.Cu" "B.Cu" "In1.Cu" "In2.Cu" "In3.Cu" "In4.Cu" "In5.Cu" "In6.Cu")
			(hatch none 0.5)
			(connect_pads
				(clearance 0)
			)
			(min_thickness 0.25)
			(keepout
				(tracks not_allowed)
				(vias allowed)
				(pads allowed)
				(copperpour not_allowed)
				(footprints allowed)
			)
			(placement
				(enabled no)
				(sheetname "")
			)
			(fill
				(thermal_gap 0.5)
				(thermal_bridge_width 0.5)
				(island_removal_mode 0)
			)
			(polygon
				(pts
					(arc
						(start 240.892838 -96.52)
						(mid 239.267238 -96.52)
						(end 240.892838 -96.52)
					)
				)
			)
		)
		(zone
			(layers "F.Cu" "B.Cu" "In1.Cu" "In2.Cu" "In3.Cu" "In4.Cu" "In5.Cu" "In6.Cu")
			(hatch none 0.5)
			(connect_pads
				(clearance 0)
			)
			(min_thickness 0.25)
			(keepout
				(tracks not_allowed)
				(vias allowed)
				(pads allowed)
				(copperpour not_allowed)
				(footprints allowed)
			)
			(placement
				(enabled no)
				(sheetname "")
			)
			(fill
				(thermal_gap 0.5)
				(thermal_bridge_width 0.5)
				(island_removal_mode 0)
			)
			(polygon
				(pts
					(arc
						(start 246.892826 -96.52)
						(mid 245.267226 -96.52)
						(end 246.892826 -96.52)
					)
				)
			)
		)
	)
	(footprint ""
		(layer "F.Cu")
		(at 79.888842 -126.284482 90)
		(property "Reference" "SC1100"
			(at 0 0 90)
			(layer "F.SilkS")
			(hide yes)
			(effects
				(font
					(size 1.27 1.27)
				)
			)
		)
		(property "Value" "SCD1U16V2KX-3GP"
			(at 1.1811 -2.7051 90)
			(unlocked yes)
			(layer "F.Fab")
			(hide yes)
			(effects
				(font
					(size 1.016 1.016)
					(thickness 0.1524)
				)
			)
		)
		(property "Device Type" "C402H22"
			(at 1.1811 -4.2291 90)
			(unlocked yes)
			(layer "F.Fab")
			(hide yes)
			(effects
				(font
					(size 1.016 1.016)
					(thickness 0.1524)
				)
			)
		)
		(duplicate_pad_numbers_are_jumpers no)
		(fp_rect
			(start -0.4318 0.9525)
			(end 0.4318 -0.9525)
			(stroke
				(width 0)
				(type default)
			)
			(fill no)
			(layer "F.CrtYd")
		)
		(fp_rect
			(start -0.4318 0.9525)
			(end 0.4318 -0.9525)
			(stroke
				(width 0)
				(type default)
			)
			(fill no)
			(layer "F.Fab")
		)
		(pad "1" smd custom
			(at 0 -0.4445 90)
			(size 0.1524 0.1524)
			(layers "F.Cu" "F.Mask" "F.Paste")
			(net "P1V8_E")
			(options
				(clearance outline)
				(anchor circle)
			)
			(primitives
				(gr_poly
					(pts
						(arc
							(start 0.3048 -0.2032)
							(mid 0.275042 -0.275042)
							(end 0.2032 -0.3048)
						)
						(arc
							(start -0.2032 -0.3048)
							(mid -0.275042 -0.275042)
							(end -0.3048 -0.2032)
						)
						(arc
							(start -0.3048 0.2032)
							(mid -0.275042 0.275042)
							(end -0.2032 0.3048)
						)
						(arc
							(start 0.2032 0.3048)
							(mid 0.275042 0.275042)
							(end 0.3048 0.2032)
						)
					)
					(width 0)
					(fill yes)
				)
			)
		)
		(pad "2" smd custom
			(at 0 0.4445 90)
			(size 0.1524 0.1524)
			(layers "F.Cu" "F.Mask" "F.Paste")
			(net "GND")
			(options
				(clearance outline)
				(anchor circle)
			)
			(primitives
				(gr_poly
					(pts
						(arc
							(start 0.3048 -0.2032)
							(mid 0.275042 -0.275042)
							(end 0.2032 -0.3048)
						)
						(arc
							(start -0.2032 -0.3048)
							(mid -0.275042 -0.275042)
							(end -0.3048 -0.2032)
						)
						(arc
							(start -0.3048 0.2032)
							(mid -0.275042 0.275042)
							(end -0.2032 0.3048)
						)
						(arc
							(start 0.2032 0.3048)
							(mid 0.275042 0.275042)
							(end 0.3048 0.2032)
						)
					)
					(width 0)
					(fill yes)
				)
			)
		)
	)
	(footprint ""
		(layer "F.Cu")
		(at 62.357 -215.265 90)
		(property "Reference" "R2102"
			(at 0 0 90)
			(layer "F.SilkS")
			(hide yes)
			(effects
				(font
					(size 1.27 1.27)
				)
			)
		)
		(property "Value" "26K1R2F-2-GP"
			(at 0.064008 -3.993896 90)
			(unlocked yes)
			(layer "F.Fab")
			(hide yes)
			(effects
				(font
					(size 1.016 1.016)
					(thickness 0.1524)
				)
			)
		)
		(property "Device Type" "R402H16"
			(at 0.064008 -5.517896 90)
			(unlocked yes)
			(layer "F.Fab")
			(hide yes)
			(effects
				(font
					(size 1.016 1.016)
					(thickness 0.1524)
				)
			)
		)
		(duplicate_pad_numbers_are_jumpers no)
		(fp_line
			(start 0.508 -0.9398)
			(end -0.508 -0.9398)
			(stroke
				(width 0.1524)
				(type default)
			)
			(layer "F.SilkS")
		)
		(fp_line
			(start -0.508 -0.9398)
			(end -0.508 0.9398)
			(stroke
				(width 0.1524)
				(type default)
			)
			(layer "F.SilkS")
		)
		(fp_rect
			(start -0.508 0.9398)
			(end 0.508 -0.9398)
			(stroke
				(width 0)
				(type default)
			)
			(fill no)
			(layer "F.CrtYd")
		)
		(fp_rect
			(start -0.508 0.9398)
			(end 0.508 -0.9398)
			(stroke
				(width 0)
				(type default)
			)
			(fill no)
			(layer "F.Fab")
		)
		(pad "1" smd custom
			(at 0 -0.4445 90)
			(size 0.1397 0.1397)
			(layers "F.Cu" "F.Mask" "F.Paste")
			(net "MB0_P12V_PWRGOOD")
			(options
				(clearance outline)
				(anchor circle)
			)
			(primitives
				(gr_poly
					(pts
						(arc
							(start -0.1778 -0.2794)
							(mid -0.249642 -0.249642)
							(end -0.2794 -0.1778)
						)
						(arc
							(start -0.2794 0.1778)
							(mid -0.249642 0.249642)
							(end -0.1778 0.2794)
						)
						(arc
							(start 0.1778 0.2794)
							(mid 0.249642 0.249642)
							(end 0.2794 0.1778)
						)
						(arc
							(start 0.2794 -0.1778)
							(mid 0.249642 -0.249642)
							(end 0.1778 -0.2794)
						)
					)
					(width 0)
					(fill yes)
				)
			)
		)
		(pad "2" smd custom
			(at 0 0.4445 90)
			(size 0.1397 0.1397)
			(layers "F.Cu" "F.Mask" "F.Paste")
			(net "AGND_CURRENT_MON")
			(options
				(clearance outline)
				(anchor circle)
			)
			(primitives
				(gr_poly
					(pts
						(arc
							(start -0.1778 -0.2794)
							(mid -0.249642 -0.249642)
							(end -0.2794 -0.1778)
						)
						(arc
							(start -0.2794 0.1778)
							(mid -0.249642 0.249642)
							(end -0.1778 0.2794)
						)
						(arc
							(start 0.1778 0.2794)
							(mid 0.249642 0.249642)
							(end 0.2794 0.1778)
						)
						(arc
							(start 0.2794 -0.1778)
							(mid 0.249642 -0.249642)
							(end 0.1778 -0.2794)
						)
					)
					(width 0)
					(fill yes)
				)
			)
		)
	)
	(footprint ""
		(layer "F.Cu")
		(at 192.278 -177.419 90)
		(property "Reference" "R479"
			(at 0 0 90)
			(layer "F.SilkS")
			(hide yes)
			(effects
				(font
					(size 1.27 1.27)
				)
			)
		)
		(property "Value" "51R2010F-GP"
			(at 0.254 -8.0772 90)
			(unlocked yes)
			(layer "F.Fab")
			(hide yes)
			(effects
				(font
					(size 1.016 1.016)
					(thickness 0.1524)
				)
			)
		)
		(property "Device Type" "R2010H28"
			(at 0.254 -9.6774 90)
			(unlocked yes)
			(layer "F.Fab")
			(hide yes)
			(effects
				(font
					(size 1.016 1.016)
					(thickness 0.1524)
				)
			)
		)
		(duplicate_pad_numbers_are_jumpers no)
		(fp_line
			(start 1.651 -3.302)
			(end -1.651 -3.302)
			(stroke
				(width 0.1524)
				(type default)
			)
			(layer "F.SilkS")
		)
		(fp_line
			(start -1.651 -3.302)
			(end -1.651 3.302)
			(stroke
				(width 0.1524)
				(type default)
			)
			(layer "F.SilkS")
		)
		(fp_line
			(start 1.651 3.302)
			(end 1.651 -3.302)
			(stroke
				(width 0.1524)
				(type default)
			)
			(layer "F.SilkS")
		)
		(fp_line
			(start -1.651 3.302)
			(end 1.651 3.302)
			(stroke
				(width 0.1524)
				(type default)
			)
			(layer "F.SilkS")
		)
		(fp_rect
			(start -1.7272 -3.3782)
			(end 1.7272 3.3782)
			(stroke
				(width 0)
				(type default)
			)
			(fill no)
			(layer "F.CrtYd")
		)
		(fp_poly
			(pts
				(xy 1.7272 3.3782) (xy 1.7272 -3.3782) (xy -1.7272 -3.3782) (xy -1.7272 3.3782)
			)
			(stroke
				(width 0)
				(type default)
			)
			(fill no)
			(layer "F.Fab")
		)
		(pad "1" smd rect
			(at 0 -2.3495 90)
			(size 2.794 1.143)
			(layers "F.Cu" "F.Mask" "F.Paste")
			(net "P3V3_STBY")
		)
		(pad "2" smd rect
			(at 0 2.3495 90)
			(size 2.794 1.143)
			(layers "F.Cu" "F.Mask" "F.Paste")
			(net "HB_OUT")
		)
	)
	(footprint ""
		(layer "F.Cu")
		(at 283.21 -207.518 90)
		(property "Reference" "C272"
			(at 0 0 90)
			(layer "F.SilkS")
			(hide yes)
			(effects
				(font
					(size 1.27 1.27)
				)
			)
		)
		(property "Value" "SCD1U16V2KX-3GP"
			(at 1.1811 -2.7051 90)
			(unlocked yes)
			(layer "F.Fab")
			(hide yes)
			(effects
				(font
					(size 1.016 1.016)
					(thickness 0.1524)
				)
			)
		)
		(property "Device Type" "C402H22"
			(at 1.1811 -4.2291 90)
			(unlocked yes)
			(layer "F.Fab")
			(hide yes)
			(effects
				(font
					(size 1.016 1.016)
					(thickness 0.1524)
				)
			)
		)
		(duplicate_pad_numbers_are_jumpers no)
		(fp_rect
			(start -0.4318 0.9525)
			(end 0.4318 -0.9525)
			(stroke
				(width 0)
				(type default)
			)
			(fill no)
			(layer "F.CrtYd")
		)
		(fp_rect
			(start -0.4318 0.9525)
			(end 0.4318 -0.9525)
			(stroke
				(width 0)
				(type default)
			)
			(fill no)
			(layer "F.Fab")
		)
		(pad "1" smd custom
			(at 0 -0.4445 90)
			(size 0.1524 0.1524)
			(layers "F.Cu" "F.Mask" "F.Paste")
			(net "P3V3_STBY")
			(options
				(clearance outline)
				(anchor circle)
			)
			(primitives
				(gr_poly
					(pts
						(arc
							(start 0.3048 -0.2032)
							(mid 0.275042 -0.275042)
							(end 0.2032 -0.3048)
						)
						(arc
							(start -0.2032 -0.3048)
							(mid -0.275042 -0.275042)
							(end -0.3048 -0.2032)
						)
						(arc
							(start -0.3048 0.2032)
							(mid -0.275042 0.275042)
							(end -0.2032 0.3048)
						)
						(arc
							(start 0.2032 0.3048)
							(mid 0.275042 0.275042)
							(end 0.3048 0.2032)
						)
					)
					(width 0)
					(fill yes)
				)
			)
		)
		(pad "2" smd custom
			(at 0 0.4445 90)
			(size 0.1524 0.1524)
			(layers "F.Cu" "F.Mask" "F.Paste")
			(net "GND")
			(options
				(clearance outline)
				(anchor circle)
			)
			(primitives
				(gr_poly
					(pts
						(arc
							(start 0.3048 -0.2032)
							(mid 0.275042 -0.275042)
							(end 0.2032 -0.3048)
						)
						(arc
							(start -0.2032 -0.3048)
							(mid -0.275042 -0.275042)
							(end -0.3048 -0.2032)
						)
						(arc
							(start -0.3048 0.2032)
							(mid -0.275042 0.275042)
							(end -0.2032 0.3048)
						)
						(arc
							(start 0.2032 0.3048)
							(mid 0.275042 0.275042)
							(end 0.3048 0.2032)
						)
					)
					(width 0)
					(fill yes)
				)
			)
		)
	)
	(footprint ""
		(layer "F.Cu")
		(at 120.15597 -114.3 180)
		(property "Reference" "SC1069"
			(at 0 0 180)
			(layer "F.SilkS")
			(hide yes)
			(effects
				(font
					(size 1.27 1.27)
				)
			)
		)
		(property "Value" "SCD01U10V1KX-GP"
			(at -2.8321 -1.7399 180)
			(unlocked yes)
			(layer "F.Fab")
			(hide yes)
			(effects
				(font
					(size 1.016 1.016)
					(thickness 0.1524)
				)
			)
		)
		(property "Device Type" "C0201H13"
			(at -2.8321 -3.2639 180)
			(unlocked yes)
			(layer "F.Fab")
			(hide yes)
			(effects
				(font
					(size 1.016 1.016)
					(thickness 0.1524)
				)
			)
		)
		(duplicate_pad_numbers_are_jumpers no)
		(fp_rect
			(start -0.2794 0.6477)
			(end 0.2794 -0.6477)
			(stroke
				(width 0)
				(type default)
			)
			(fill no)
			(layer "F.CrtYd")
		)
		(fp_rect
			(start -0.2794 0.6477)
			(end 0.2794 -0.6477)
			(stroke
				(width 0)
				(type default)
			)
			(fill no)
			(layer "F.Fab")
		)
		(pad "1" smd custom
			(at 0 -0.2794 180)
			(size 0.0762 0.0762)
			(layers "F.Cu" "F.Mask" "F.Paste")
			(net "SAS_HDD_TX1_P")
			(options
				(clearance outline)
				(anchor circle)
			)
			(primitives
				(gr_poly
					(pts
						(arc
							(start 0.1524 -0.127)
							(mid 0.137521 -0.162921)
							(end 0.1016 -0.1778)
						)
						(arc
							(start -0.1016 -0.1778)
							(mid -0.137521 -0.162921)
							(end -0.1524 -0.127)
						)
						(arc
							(start -0.1524 0.127)
							(mid -0.137521 0.162921)
							(end -0.1016 0.1778)
						)
						(arc
							(start 0.1016 0.1778)
							(mid 0.137521 0.162921)
							(end 0.1524 0.127)
						)
					)
					(width 0)
					(fill yes)
				)
			)
		)
		(pad "2" smd custom
			(at 0 0.2794 180)
			(size 0.0762 0.0762)
			(layers "F.Cu" "F.Mask" "F.Paste")
			(net "SAS_EXP_GF_TX_DP5")
			(options
				(clearance outline)
				(anchor circle)
			)
			(primitives
				(gr_poly
					(pts
						(arc
							(start 0.1524 -0.127)
							(mid 0.137521 -0.162921)
							(end 0.1016 -0.1778)
						)
						(arc
							(start -0.1016 -0.1778)
							(mid -0.137521 -0.162921)
							(end -0.1524 -0.127)
						)
						(arc
							(start -0.1524 0.127)
							(mid -0.137521 0.162921)
							(end -0.1016 0.1778)
						)
						(arc
							(start 0.1016 0.1778)
							(mid 0.137521 0.162921)
							(end 0.1524 0.127)
						)
					)
					(width 0)
					(fill yes)
				)
			)
		)
	)
	(footprint ""
		(layer "F.Cu")
		(at 165.703504 -24.184356 180)
		(property "Reference" "R416"
			(at 0 0 180)
			(layer "F.SilkS")
			(hide yes)
			(effects
				(font
					(size 1.27 1.27)
				)
			)
		)
		(property "Value" "0R2J-2-GP"
			(at 0.064008 -3.993896 180)
			(unlocked yes)
			(layer "F.Fab")
			(hide yes)
			(effects
				(font
					(size 1.016 1.016)
					(thickness 0.1524)
				)
			)
		)
		(property "Device Type" "R402H16"
			(at 0.064008 -5.517896 180)
			(unlocked yes)
			(layer "F.Fab")
			(hide yes)
			(effects
				(font
					(size 1.016 1.016)
					(thickness 0.1524)
				)
			)
		)
		(duplicate_pad_numbers_are_jumpers no)
		(fp_line
			(start 0.508 -0.9398)
			(end -0.508 -0.9398)
			(stroke
				(width 0.1524)
				(type default)
			)
			(layer "F.SilkS")
		)
		(fp_line
			(start -0.508 -0.9398)
			(end -0.508 0.9398)
			(stroke
				(width 0.1524)
				(type default)
			)
			(layer "F.SilkS")
		)
		(fp_rect
			(start -0.508 0.9398)
			(end 0.508 -0.9398)
			(stroke
				(width 0)
				(type default)
			)
			(fill no)
			(layer "F.CrtYd")
		)
		(fp_rect
			(start -0.508 0.9398)
			(end 0.508 -0.9398)
			(stroke
				(width 0)
				(type default)
			)
			(fill no)
			(layer "F.Fab")
		)
		(pad "1" smd custom
			(at 0 -0.4445 180)
			(size 0.1397 0.1397)
			(layers "F.Cu" "F.Mask" "F.Paste")
			(net "TP_LAN_4")
			(options
				(clearance outline)
				(anchor circle)
			)
			(primitives
				(gr_poly
					(pts
						(arc
							(start -0.1778 -0.2794)
							(mid -0.249642 -0.249642)
							(end -0.2794 -0.1778)
						)
						(arc
							(start -0.2794 0.1778)
							(mid -0.249642 0.249642)
							(end -0.1778 0.2794)
						)
						(arc
							(start 0.1778 0.2794)
							(mid 0.249642 0.249642)
							(end 0.2794 0.1778)
						)
						(arc
							(start 0.2794 -0.1778)
							(mid 0.249642 -0.249642)
							(end 0.1778 -0.2794)
						)
					)
					(width 0)
					(fill yes)
				)
			)
		)
		(pad "2" smd custom
			(at 0 0.4445 180)
			(size 0.1397 0.1397)
			(layers "F.Cu" "F.Mask" "F.Paste")
			(net "GND")
			(options
				(clearance outline)
				(anchor circle)
			)
			(primitives
				(gr_poly
					(pts
						(arc
							(start -0.1778 -0.2794)
							(mid -0.249642 -0.249642)
							(end -0.2794 -0.1778)
						)
						(arc
							(start -0.2794 0.1778)
							(mid -0.249642 0.249642)
							(end -0.1778 0.2794)
						)
						(arc
							(start 0.1778 0.2794)
							(mid 0.249642 0.249642)
							(end 0.2794 0.1778)
						)
						(arc
							(start 0.2794 -0.1778)
							(mid 0.249642 -0.249642)
							(end 0.1778 -0.2794)
						)
					)
					(width 0)
					(fill yes)
				)
			)
		)
	)
	(footprint ""
		(layer "F.Cu")
		(at 60.706 -109.474 -90)
		(property "Reference" "SR823"
			(at 0 0 270)
			(layer "F.SilkS")
			(hide yes)
			(effects
				(font
					(size 1.27 1.27)
				)
			)
		)
		(property "Value" "4K75R2F-1-GP"
			(at 0.064008 -3.993896 270)
			(unlocked yes)
			(layer "F.Fab")
			(hide yes)
			(effects
				(font
					(size 1.016 1.016)
					(thickness 0.1524)
				)
			)
		)
		(property "Device Type" "R402H16"
			(at 0.064008 -5.517896 270)
			(unlocked yes)
			(layer "F.Fab")
			(hide yes)
			(effects
				(font
					(size 1.016 1.016)
					(thickness 0.1524)
				)
			)
		)
		(duplicate_pad_numbers_are_jumpers no)
		(fp_line
			(start -0.508 -0.9398)
			(end -0.508 0.9398)
			(stroke
				(width 0.1524)
				(type default)
			)
			(layer "F.SilkS")
		)
		(fp_line
			(start 0.508 -0.9398)
			(end -0.508 -0.9398)
			(stroke
				(width 0.1524)
				(type default)
			)
			(layer "F.SilkS")
		)
		(fp_rect
			(start -0.508 0.9398)
			(end 0.508 -0.9398)
			(stroke
				(width 0)
				(type default)
			)
			(fill no)
			(layer "F.CrtYd")
		)
		(fp_rect
			(start -0.508 0.9398)
			(end 0.508 -0.9398)
			(stroke
				(width 0)
				(type default)
			)
			(fill no)
			(layer "F.Fab")
		)
		(pad "1" smd custom
			(at 0 -0.4445 270)
			(size 0.1397 0.1397)
			(layers "F.Cu" "F.Mask" "F.Paste")
			(net "EXP_FW_DET_BOARD_VER_0")
			(options
				(clearance outline)
				(anchor circle)
			)
			(primitives
				(gr_poly
					(pts
						(arc
							(start -0.1778 -0.2794)
							(mid -0.249642 -0.249642)
							(end -0.2794 -0.1778)
						)
						(arc
							(start -0.2794 0.1778)
							(mid -0.249642 0.249642)
							(end -0.1778 0.2794)
						)
						(arc
							(start 0.1778 0.2794)
							(mid 0.249642 0.249642)
							(end 0.2794 0.1778)
						)
						(arc
							(start 0.2794 -0.1778)
							(mid 0.249642 -0.249642)
							(end 0.1778 -0.2794)
						)
					)
					(width 0)
					(fill yes)
				)
			)
		)
		(pad "2" smd custom
			(at 0 0.4445 270)
			(size 0.1397 0.1397)
			(layers "F.Cu" "F.Mask" "F.Paste")
			(net "GND")
			(options
				(clearance outline)
				(anchor circle)
			)
			(primitives
				(gr_poly
					(pts
						(arc
							(start -0.1778 -0.2794)
							(mid -0.249642 -0.249642)
							(end -0.2794 -0.1778)
						)
						(arc
							(start -0.2794 0.1778)
							(mid -0.249642 0.249642)
							(end -0.1778 0.2794)
						)
						(arc
							(start 0.1778 0.2794)
							(mid 0.249642 0.249642)
							(end 0.2794 0.1778)
						)
						(arc
							(start 0.2794 -0.1778)
							(mid 0.249642 -0.249642)
							(end 0.1778 -0.2794)
						)
					)
					(width 0)
					(fill yes)
				)
			)
		)
	)
	(footprint ""
		(layer "F.Cu")
		(at 138.176 -38.862 180)
		(property "Reference" "SR693"
			(at 0 0 180)
			(layer "F.SilkS")
			(hide yes)
			(effects
				(font
					(size 1.27 1.27)
				)
			)
		)
		(property "Value" "10KR2F-2-GP"
			(at 0.064008 -3.993896 180)
			(unlocked yes)
			(layer "F.Fab")
			(hide yes)
			(effects
				(font
					(size 1.016 1.016)
					(thickness 0.1524)
				)
			)
		)
		(property "Device Type" "R402H16"
			(at 0.064008 -5.517896 180)
			(unlocked yes)
			(layer "F.Fab")
			(hide yes)
			(effects
				(font
					(size 1.016 1.016)
					(thickness 0.1524)
				)
			)
		)
		(duplicate_pad_numbers_are_jumpers no)
		(fp_line
			(start 0.508 -0.9398)
			(end -0.508 -0.9398)
			(stroke
				(width 0.1524)
				(type default)
			)
			(layer "F.SilkS")
		)
		(fp_line
			(start -0.508 -0.9398)
			(end -0.508 0.9398)
			(stroke
				(width 0.1524)
				(type default)
			)
			(layer "F.SilkS")
		)
		(fp_rect
			(start -0.508 0.9398)
			(end 0.508 -0.9398)
			(stroke
				(width 0)
				(type default)
			)
			(fill no)
			(layer "F.CrtYd")
		)
		(fp_rect
			(start -0.508 0.9398)
			(end 0.508 -0.9398)
			(stroke
				(width 0)
				(type default)
			)
			(fill no)
			(layer "F.Fab")
		)
		(pad "1" smd custom
			(at 0 -0.4445 180)
			(size 0.1397 0.1397)
			(layers "F.Cu" "F.Mask" "F.Paste")
			(net "P1V8_C")
			(options
				(clearance outline)
				(anchor circle)
			)
			(primitives
				(gr_poly
					(pts
						(arc
							(start -0.1778 -0.2794)
							(mid -0.249642 -0.249642)
							(end -0.2794 -0.1778)
						)
						(arc
							(start -0.2794 0.1778)
							(mid -0.249642 0.249642)
							(end -0.1778 0.2794)
						)
						(arc
							(start 0.1778 0.2794)
							(mid 0.249642 0.249642)
							(end 0.2794 0.1778)
						)
						(arc
							(start 0.2794 -0.1778)
							(mid 0.249642 -0.249642)
							(end 0.1778 -0.2794)
						)
					)
					(width 0)
					(fill yes)
				)
			)
		)
		(pad "2" smd custom
			(at 0 0.4445 180)
			(size 0.1397 0.1397)
			(layers "F.Cu" "F.Mask" "F.Paste")
			(net "XM_ADDR_23")
			(options
				(clearance outline)
				(anchor circle)
			)
			(primitives
				(gr_poly
					(pts
						(arc
							(start -0.1778 -0.2794)
							(mid -0.249642 -0.249642)
							(end -0.2794 -0.1778)
						)
						(arc
							(start -0.2794 0.1778)
							(mid -0.249642 0.249642)
							(end -0.1778 0.2794)
						)
						(arc
							(start 0.1778 0.2794)
							(mid 0.249642 0.249642)
							(end 0.2794 0.1778)
						)
						(arc
							(start 0.2794 -0.1778)
							(mid 0.249642 -0.249642)
							(end 0.1778 -0.2794)
						)
					)
					(width 0)
					(fill yes)
				)
			)
		)
	)
	(footprint ""
		(layer "F.Cu")
		(at 235.966 -13.081 90)
		(property "Reference" "C269"
			(at 0 0 90)
			(layer "F.SilkS")
			(hide yes)
			(effects
				(font
					(size 1.27 1.27)
				)
			)
		)
		(property "Value" "SCD1U16V2KX-3GP"
			(at 1.1811 -2.7051 90)
			(unlocked yes)
			(layer "F.Fab")
			(hide yes)
			(effects
				(font
					(size 1.016 1.016)
					(thickness 0.1524)
				)
			)
		)
		(property "Device Type" "C402H22"
			(at 1.1811 -4.2291 90)
			(unlocked yes)
			(layer "F.Fab")
			(hide yes)
			(effects
				(font
					(size 1.016 1.016)
					(thickness 0.1524)
				)
			)
		)
		(duplicate_pad_numbers_are_jumpers no)
		(fp_rect
			(start -0.4318 0.9525)
			(end 0.4318 -0.9525)
			(stroke
				(width 0)
				(type default)
			)
			(fill no)
			(layer "F.CrtYd")
		)
		(fp_rect
			(start -0.4318 0.9525)
			(end 0.4318 -0.9525)
			(stroke
				(width 0)
				(type default)
			)
			(fill no)
			(layer "F.Fab")
		)
		(pad "1" smd custom
			(at 0 -0.4445 90)
			(size 0.1524 0.1524)
			(layers "F.Cu" "F.Mask" "F.Paste")
			(net "P3V3_STBY")
			(options
				(clearance outline)
				(anchor circle)
			)
			(primitives
				(gr_poly
					(pts
						(arc
							(start 0.3048 -0.2032)
							(mid 0.275042 -0.275042)
							(end 0.2032 -0.3048)
						)
						(arc
							(start -0.2032 -0.3048)
							(mid -0.275042 -0.275042)
							(end -0.3048 -0.2032)
						)
						(arc
							(start -0.3048 0.2032)
							(mid -0.275042 0.275042)
							(end -0.2032 0.3048)
						)
						(arc
							(start 0.2032 0.3048)
							(mid 0.275042 0.275042)
							(end 0.3048 0.2032)
						)
					)
					(width 0)
					(fill yes)
				)
			)
		)
		(pad "2" smd custom
			(at 0 0.4445 90)
			(size 0.1524 0.1524)
			(layers "F.Cu" "F.Mask" "F.Paste")
			(net "GND")
			(options
				(clearance outline)
				(anchor circle)
			)
			(primitives
				(gr_poly
					(pts
						(arc
							(start 0.3048 -0.2032)
							(mid 0.275042 -0.275042)
							(end 0.2032 -0.3048)
						)
						(arc
							(start -0.2032 -0.3048)
							(mid -0.275042 -0.275042)
							(end -0.3048 -0.2032)
						)
						(arc
							(start -0.3048 0.2032)
							(mid -0.275042 0.275042)
							(end -0.2032 0.3048)
						)
						(arc
							(start 0.2032 0.3048)
							(mid 0.275042 0.275042)
							(end 0.3048 0.2032)
						)
					)
					(width 0)
					(fill yes)
				)
			)
		)
	)
	(footprint ""
		(layer "F.Cu")
		(at 310.896 -183.515 90)
		(property "Reference" "R800"
			(at 0 0 90)
			(layer "F.SilkS")
			(hide yes)
			(effects
				(font
					(size 1.27 1.27)
				)
			)
		)
		(property "Value" "0R2J-2-GP"
			(at 0.064008 -3.993896 90)
			(unlocked yes)
			(layer "F.Fab")
			(hide yes)
			(effects
				(font
					(size 1.016 1.016)
					(thickness 0.1524)
				)
			)
		)
		(property "Device Type" "R402H16"
			(at 0.064008 -5.517896 90)
			(unlocked yes)
			(layer "F.Fab")
			(hide yes)
			(effects
				(font
					(size 1.016 1.016)
					(thickness 0.1524)
				)
			)
		)
		(duplicate_pad_numbers_are_jumpers no)
		(fp_line
			(start 0.508 -0.9398)
			(end -0.508 -0.9398)
			(stroke
				(width 0.1524)
				(type default)
			)
			(layer "F.SilkS")
		)
		(fp_line
			(start -0.508 -0.9398)
			(end -0.508 0.9398)
			(stroke
				(width 0.1524)
				(type default)
			)
			(layer "F.SilkS")
		)
		(fp_rect
			(start -0.508 0.9398)
			(end 0.508 -0.9398)
			(stroke
				(width 0)
				(type default)
			)
			(fill no)
			(layer "F.CrtYd")
		)
		(fp_rect
			(start -0.508 0.9398)
			(end 0.508 -0.9398)
			(stroke
				(width 0)
				(type default)
			)
			(fill no)
			(layer "F.Fab")
		)
		(pad "1" smd custom
			(at 0 -0.4445 90)
			(size 0.1397 0.1397)
			(layers "F.Cu" "F.Mask" "F.Paste")
			(net "BMC0_LED_DR_R_LED1")
			(options
				(clearance outline)
				(anchor circle)
			)
			(primitives
				(gr_poly
					(pts
						(arc
							(start -0.1778 -0.2794)
							(mid -0.249642 -0.249642)
							(end -0.2794 -0.1778)
						)
						(arc
							(start -0.2794 0.1778)
							(mid -0.249642 0.249642)
							(end -0.1778 0.2794)
						)
						(arc
							(start 0.1778 0.2794)
							(mid 0.249642 0.249642)
							(end 0.2794 0.1778)
						)
						(arc
							(start 0.2794 -0.1778)
							(mid 0.249642 -0.249642)
							(end 0.1778 -0.2794)
						)
					)
					(width 0)
					(fill yes)
				)
			)
		)
		(pad "2" smd custom
			(at 0 0.4445 90)
			(size 0.1397 0.1397)
			(layers "F.Cu" "F.Mask" "F.Paste")
			(net "LED_DR_LED1")
			(options
				(clearance outline)
				(anchor circle)
			)
			(primitives
				(gr_poly
					(pts
						(arc
							(start -0.1778 -0.2794)
							(mid -0.249642 -0.249642)
							(end -0.2794 -0.1778)
						)
						(arc
							(start -0.2794 0.1778)
							(mid -0.249642 0.249642)
							(end -0.1778 0.2794)
						)
						(arc
							(start 0.1778 0.2794)
							(mid 0.249642 0.249642)
							(end 0.2794 0.1778)
						)
						(arc
							(start 0.2794 -0.1778)
							(mid 0.249642 -0.249642)
							(end 0.1778 -0.2794)
						)
					)
					(width 0)
					(fill yes)
				)
			)
		)
	)
	(footprint ""
		(layer "F.Cu")
		(at 264.033 -30.353 -90)
		(property "Reference" "PR54"
			(at 0 0 270)
			(layer "F.SilkS")
			(hide yes)
			(effects
				(font
					(size 1.27 1.27)
				)
			)
		)
		(property "Value" "0R2J-2-GP"
			(at 0.064008 -3.993896 270)
			(unlocked yes)
			(layer "F.Fab")
			(hide yes)
			(effects
				(font
					(size 1.016 1.016)
					(thickness 0.1524)
				)
			)
		)
		(property "Device Type" "R402H16"
			(at 0.064008 -5.517896 270)
			(unlocked yes)
			(layer "F.Fab")
			(hide yes)
			(effects
				(font
					(size 1.016 1.016)
					(thickness 0.1524)
				)
			)
		)
		(duplicate_pad_numbers_are_jumpers no)
		(fp_line
			(start -0.508 -0.9398)
			(end -0.508 0.9398)
			(stroke
				(width 0.1524)
				(type default)
			)
			(layer "F.SilkS")
		)
		(fp_line
			(start 0.508 -0.9398)
			(end -0.508 -0.9398)
			(stroke
				(width 0.1524)
				(type default)
			)
			(layer "F.SilkS")
		)
		(fp_rect
			(start -0.508 0.9398)
			(end 0.508 -0.9398)
			(stroke
				(width 0)
				(type default)
			)
			(fill no)
			(layer "F.CrtYd")
		)
		(fp_rect
			(start -0.508 0.9398)
			(end 0.508 -0.9398)
			(stroke
				(width 0)
				(type default)
			)
			(fill no)
			(layer "F.Fab")
		)
		(pad "1" smd custom
			(at 0 -0.4445 270)
			(size 0.1397 0.1397)
			(layers "F.Cu" "F.Mask" "F.Paste")
			(net "P1V8_STBY_ROVP")
			(options
				(clearance outline)
				(anchor circle)
			)
			(primitives
				(gr_poly
					(pts
						(arc
							(start -0.1778 -0.2794)
							(mid -0.249642 -0.249642)
							(end -0.2794 -0.1778)
						)
						(arc
							(start -0.2794 0.1778)
							(mid -0.249642 0.249642)
							(end -0.1778 0.2794)
						)
						(arc
							(start 0.1778 0.2794)
							(mid 0.249642 0.249642)
							(end 0.2794 0.1778)
						)
						(arc
							(start 0.2794 -0.1778)
							(mid 0.249642 -0.249642)
							(end 0.1778 -0.2794)
						)
					)
					(width 0)
					(fill yes)
				)
			)
		)
		(pad "2" smd custom
			(at 0 0.4445 270)
			(size 0.1397 0.1397)
			(layers "F.Cu" "F.Mask" "F.Paste")
			(net "P1V8_STBY")
			(options
				(clearance outline)
				(anchor circle)
			)
			(primitives
				(gr_poly
					(pts
						(arc
							(start -0.1778 -0.2794)
							(mid -0.249642 -0.249642)
							(end -0.2794 -0.1778)
						)
						(arc
							(start -0.2794 0.1778)
							(mid -0.249642 0.249642)
							(end -0.1778 0.2794)
						)
						(arc
							(start 0.1778 0.2794)
							(mid 0.249642 0.249642)
							(end 0.2794 0.1778)
						)
						(arc
							(start 0.2794 -0.1778)
							(mid 0.249642 -0.249642)
							(end 0.1778 -0.2794)
						)
					)
					(width 0)
					(fill yes)
				)
			)
		)
	)
	(footprint ""
		(layer "F.Cu")
		(at 89.281 -242.443 180)
		(property "Reference" "SR954"
			(at 0 0 180)
			(layer "F.SilkS")
			(hide yes)
			(effects
				(font
					(size 1.27 1.27)
				)
			)
		)
		(property "Value" "4K7R2F-GP"
			(at 0.064008 -3.993896 180)
			(unlocked yes)
			(layer "F.Fab")
			(hide yes)
			(effects
				(font
					(size 1.016 1.016)
					(thickness 0.1524)
				)
			)
		)
		(property "Device Type" "R402H16"
			(at 0.064008 -5.517896 180)
			(unlocked yes)
			(layer "F.Fab")
			(hide yes)
			(effects
				(font
					(size 1.016 1.016)
					(thickness 0.1524)
				)
			)
		)
		(duplicate_pad_numbers_are_jumpers no)
		(fp_line
			(start 0.508 -0.9398)
			(end -0.508 -0.9398)
			(stroke
				(width 0.1524)
				(type default)
			)
			(layer "F.SilkS")
		)
		(fp_line
			(start -0.508 -0.9398)
			(end -0.508 0.9398)
			(stroke
				(width 0.1524)
				(type default)
			)
			(layer "F.SilkS")
		)
		(fp_rect
			(start -0.508 0.9398)
			(end 0.508 -0.9398)
			(stroke
				(width 0)
				(type default)
			)
			(fill no)
			(layer "F.CrtYd")
		)
		(fp_rect
			(start -0.508 0.9398)
			(end 0.508 -0.9398)
			(stroke
				(width 0)
				(type default)
			)
			(fill no)
			(layer "F.Fab")
		)
		(pad "1" smd custom
			(at 0 -0.4445 180)
			(size 0.1397 0.1397)
			(layers "F.Cu" "F.Mask" "F.Paste")
			(net "SAS_FAULT_LED13")
			(options
				(clearance outline)
				(anchor circle)
			)
			(primitives
				(gr_poly
					(pts
						(arc
							(start -0.1778 -0.2794)
							(mid -0.249642 -0.249642)
							(end -0.2794 -0.1778)
						)
						(arc
							(start -0.2794 0.1778)
							(mid -0.249642 0.249642)
							(end -0.1778 0.2794)
						)
						(arc
							(start 0.1778 0.2794)
							(mid 0.249642 0.249642)
							(end 0.2794 0.1778)
						)
						(arc
							(start 0.2794 -0.1778)
							(mid 0.249642 -0.249642)
							(end 0.1778 -0.2794)
						)
					)
					(width 0)
					(fill yes)
				)
			)
		)
		(pad "2" smd custom
			(at 0 0.4445 180)
			(size 0.1397 0.1397)
			(layers "F.Cu" "F.Mask" "F.Paste")
			(net "P3V3_STBY")
			(options
				(clearance outline)
				(anchor circle)
			)
			(primitives
				(gr_poly
					(pts
						(arc
							(start -0.1778 -0.2794)
							(mid -0.249642 -0.249642)
							(end -0.2794 -0.1778)
						)
						(arc
							(start -0.2794 0.1778)
							(mid -0.249642 0.249642)
							(end -0.1778 0.2794)
						)
						(arc
							(start 0.1778 0.2794)
							(mid 0.249642 0.249642)
							(end 0.2794 0.1778)
						)
						(arc
							(start 0.2794 -0.1778)
							(mid 0.249642 -0.249642)
							(end 0.1778 -0.2794)
						)
					)
					(width 0)
					(fill yes)
				)
			)
		)
	)
	(footprint ""
		(layer "F.Cu")
		(at 280.289 -196.215 -90)
		(property "Reference" "C196"
			(at 0 0 270)
			(layer "F.SilkS")
			(hide yes)
			(effects
				(font
					(size 1.27 1.27)
				)
			)
		)
		(property "Value" "SC100P50V2JN-3GP"
			(at 1.1811 -2.7051 270)
			(unlocked yes)
			(layer "F.Fab")
			(hide yes)
			(effects
				(font
					(size 1.016 1.016)
					(thickness 0.1524)
				)
			)
		)
		(property "Device Type" "C402H22"
			(at 1.1811 -4.2291 270)
			(unlocked yes)
			(layer "F.Fab")
			(hide yes)
			(effects
				(font
					(size 1.016 1.016)
					(thickness 0.1524)
				)
			)
		)
		(duplicate_pad_numbers_are_jumpers no)
		(fp_rect
			(start -0.4318 0.9525)
			(end 0.4318 -0.9525)
			(stroke
				(width 0)
				(type default)
			)
			(fill no)
			(layer "F.CrtYd")
		)
		(fp_rect
			(start -0.4318 0.9525)
			(end 0.4318 -0.9525)
			(stroke
				(width 0)
				(type default)
			)
			(fill no)
			(layer "F.Fab")
		)
		(pad "1" smd custom
			(at 0 -0.4445 270)
			(size 0.1524 0.1524)
			(layers "F.Cu" "F.Mask" "F.Paste")
			(net "MPLLAV33")
			(options
				(clearance outline)
				(anchor circle)
			)
			(primitives
				(gr_poly
					(pts
						(arc
							(start 0.3048 -0.2032)
							(mid 0.275042 -0.275042)
							(end 0.2032 -0.3048)
						)
						(arc
							(start -0.2032 -0.3048)
							(mid -0.275042 -0.275042)
							(end -0.3048 -0.2032)
						)
						(arc
							(start -0.3048 0.2032)
							(mid -0.275042 0.275042)
							(end -0.2032 0.3048)
						)
						(arc
							(start 0.2032 0.3048)
							(mid 0.275042 0.275042)
							(end 0.3048 0.2032)
						)
					)
					(width 0)
					(fill yes)
				)
			)
		)
		(pad "2" smd custom
			(at 0 0.4445 270)
			(size 0.1524 0.1524)
			(layers "F.Cu" "F.Mask" "F.Paste")
			(net "GND")
			(options
				(clearance outline)
				(anchor circle)
			)
			(primitives
				(gr_poly
					(pts
						(arc
							(start 0.3048 -0.2032)
							(mid 0.275042 -0.275042)
							(end 0.2032 -0.3048)
						)
						(arc
							(start -0.2032 -0.3048)
							(mid -0.275042 -0.275042)
							(end -0.3048 -0.2032)
						)
						(arc
							(start -0.3048 0.2032)
							(mid -0.275042 0.275042)
							(end -0.2032 0.3048)
						)
						(arc
							(start 0.2032 0.3048)
							(mid 0.275042 0.275042)
							(end 0.3048 0.2032)
						)
					)
					(width 0)
					(fill yes)
				)
			)
		)
	)
	(footprint ""
		(layer "F.Cu")
		(at 314.071 -192.405)
		(property "Reference" "TP177"
			(at 0 0 0)
			(layer "F.SilkS")
			(hide yes)
			(effects
				(font
					(size 1.27 1.27)
				)
			)
		)
		(property "Value" "TPAD28"
			(at -0.0127 -1.6637 0)
			(unlocked yes)
			(layer "F.Fab")
			(hide yes)
			(effects
				(font
					(size 1.016 1.016)
					(thickness 0.1524)
				)
			)
		)
		(property "Device Type" "TPAD28"
			(at -0.0127 -3.1877 0)
			(unlocked yes)
			(layer "F.Fab")
			(hide yes)
			(effects
				(font
					(size 1.016 1.016)
					(thickness 0.1524)
				)
			)
		)
		(duplicate_pad_numbers_are_jumpers no)
		(fp_poly
			(pts
				(arc
					(start 0.3556 0)
					(mid -0.3556 0)
					(end 0.3556 0)
				)
			)
			(stroke
				(width 0)
				(type default)
			)
			(fill no)
			(layer "F.CrtYd")
		)
		(fp_poly
			(pts
				(arc
					(start 0.6096 0)
					(mid -0.6096 0)
					(end 0.6096 0)
				)
			)
			(stroke
				(width 0)
				(type default)
			)
			(fill no)
			(layer "F.Fab")
		)
		(pad "1" smd circle
			(at 0 0)
			(size 0.7112 0.7112)
			(layers "F.Cu" "F.Mask" "F.Paste")
			(net "JTAG_BMC_TMS")
		)
	)
	(footprint ""
		(layer "F.Cu")
		(at 293.497 -161.544 180)
		(property "Reference" "R281"
			(at 0 0 180)
			(layer "F.SilkS")
			(hide yes)
			(effects
				(font
					(size 1.27 1.27)
				)
			)
		)
		(property "Value" "0R2J-2-GP"
			(at 0.064008 -3.993896 180)
			(unlocked yes)
			(layer "F.Fab")
			(hide yes)
			(effects
				(font
					(size 1.016 1.016)
					(thickness 0.1524)
				)
			)
		)
		(property "Device Type" "R402H16"
			(at 0.064008 -5.517896 180)
			(unlocked yes)
			(layer "F.Fab")
			(hide yes)
			(effects
				(font
					(size 1.016 1.016)
					(thickness 0.1524)
				)
			)
		)
		(duplicate_pad_numbers_are_jumpers no)
		(fp_line
			(start 0.508 -0.9398)
			(end -0.508 -0.9398)
			(stroke
				(width 0.1524)
				(type default)
			)
			(layer "F.SilkS")
		)
		(fp_line
			(start -0.508 -0.9398)
			(end -0.508 0.9398)
			(stroke
				(width 0.1524)
				(type default)
			)
			(layer "F.SilkS")
		)
		(fp_rect
			(start -0.508 0.9398)
			(end 0.508 -0.9398)
			(stroke
				(width 0)
				(type default)
			)
			(fill no)
			(layer "F.CrtYd")
		)
		(fp_rect
			(start -0.508 0.9398)
			(end 0.508 -0.9398)
			(stroke
				(width 0)
				(type default)
			)
			(fill no)
			(layer "F.Fab")
		)
		(pad "1" smd custom
			(at 0 -0.4445 180)
			(size 0.1397 0.1397)
			(layers "F.Cu" "F.Mask" "F.Paste")
			(net "RMII_BMC_TX_EN")
			(options
				(clearance outline)
				(anchor circle)
			)
			(primitives
				(gr_poly
					(pts
						(arc
							(start -0.1778 -0.2794)
							(mid -0.249642 -0.249642)
							(end -0.2794 -0.1778)
						)
						(arc
							(start -0.2794 0.1778)
							(mid -0.249642 0.249642)
							(end -0.1778 0.2794)
						)
						(arc
							(start 0.1778 0.2794)
							(mid 0.249642 0.249642)
							(end 0.2794 0.1778)
						)
						(arc
							(start 0.2794 -0.1778)
							(mid 0.249642 -0.249642)
							(end 0.1778 -0.2794)
						)
					)
					(width 0)
					(fill yes)
				)
			)
		)
		(pad "2" smd custom
			(at 0 0.4445 180)
			(size 0.1397 0.1397)
			(layers "F.Cu" "F.Mask" "F.Paste")
			(net "RMII0_BMC_C_TX_EN")
			(options
				(clearance outline)
				(anchor circle)
			)
			(primitives
				(gr_poly
					(pts
						(arc
							(start -0.1778 -0.2794)
							(mid -0.249642 -0.249642)
							(end -0.2794 -0.1778)
						)
						(arc
							(start -0.2794 0.1778)
							(mid -0.249642 0.249642)
							(end -0.1778 0.2794)
						)
						(arc
							(start 0.1778 0.2794)
							(mid 0.249642 0.249642)
							(end 0.2794 0.1778)
						)
						(arc
							(start 0.2794 -0.1778)
							(mid 0.249642 -0.249642)
							(end 0.1778 -0.2794)
						)
					)
					(width 0)
					(fill yes)
				)
			)
		)
	)
	(footprint ""
		(layer "F.Cu")
		(at 83.57997 -140.843 180)
		(property "Reference" "SR920"
			(at 0 0 180)
			(layer "F.SilkS")
			(hide yes)
			(effects
				(font
					(size 1.27 1.27)
				)
			)
		)
		(property "Value" "0R2J-2-GP"
			(at 0.064008 -3.993896 180)
			(unlocked yes)
			(layer "F.Fab")
			(hide yes)
			(effects
				(font
					(size 1.016 1.016)
					(thickness 0.1524)
				)
			)
		)
		(property "Device Type" "R402H16"
			(at 0.064008 -5.517896 180)
			(unlocked yes)
			(layer "F.Fab")
			(hide yes)
			(effects
				(font
					(size 1.016 1.016)
					(thickness 0.1524)
				)
			)
		)
		(duplicate_pad_numbers_are_jumpers no)
		(fp_line
			(start 0.508 -0.9398)
			(end -0.508 -0.9398)
			(stroke
				(width 0.1524)
				(type default)
			)
			(layer "F.SilkS")
		)
		(fp_line
			(start -0.508 -0.9398)
			(end -0.508 0.9398)
			(stroke
				(width 0.1524)
				(type default)
			)
			(layer "F.SilkS")
		)
		(fp_rect
			(start -0.508 0.9398)
			(end 0.508 -0.9398)
			(stroke
				(width 0)
				(type default)
			)
			(fill no)
			(layer "F.CrtYd")
		)
		(fp_rect
			(start -0.508 0.9398)
			(end 0.508 -0.9398)
			(stroke
				(width 0)
				(type default)
			)
			(fill no)
			(layer "F.Fab")
		)
		(pad "1" smd custom
			(at 0 -0.4445 180)
			(size 0.1397 0.1397)
			(layers "F.Cu" "F.Mask" "F.Paste")
			(net "FAN_PWM_PCIE_R")
			(options
				(clearance outline)
				(anchor circle)
			)
			(primitives
				(gr_poly
					(pts
						(arc
							(start -0.1778 -0.2794)
							(mid -0.249642 -0.249642)
							(end -0.2794 -0.1778)
						)
						(arc
							(start -0.2794 0.1778)
							(mid -0.249642 0.249642)
							(end -0.1778 0.2794)
						)
						(arc
							(start 0.1778 0.2794)
							(mid 0.249642 0.249642)
							(end 0.2794 0.1778)
						)
						(arc
							(start 0.2794 -0.1778)
							(mid 0.249642 -0.249642)
							(end 0.1778 -0.2794)
						)
					)
					(width 0)
					(fill yes)
				)
			)
		)
		(pad "2" smd custom
			(at 0 0.4445 180)
			(size 0.1397 0.1397)
			(layers "F.Cu" "F.Mask" "F.Paste")
			(net "FAN_PWM_PCIE")
			(options
				(clearance outline)
				(anchor circle)
			)
			(primitives
				(gr_poly
					(pts
						(arc
							(start -0.1778 -0.2794)
							(mid -0.249642 -0.249642)
							(end -0.2794 -0.1778)
						)
						(arc
							(start -0.2794 0.1778)
							(mid -0.249642 0.249642)
							(end -0.1778 0.2794)
						)
						(arc
							(start 0.1778 0.2794)
							(mid 0.249642 0.249642)
							(end 0.2794 0.1778)
						)
						(arc
							(start 0.2794 -0.1778)
							(mid 0.249642 -0.249642)
							(end 0.1778 -0.2794)
						)
					)
					(width 0)
					(fill yes)
				)
			)
		)
	)
	(footprint ""
		(layer "F.Cu")
		(at 267.643864 -70.603872 90)
		(property "Reference" "C253"
			(at 0 0 90)
			(layer "F.SilkS")
			(hide yes)
			(effects
				(font
					(size 1.27 1.27)
				)
			)
		)
		(property "Value" "SC1U25V3KX-GP"
			(at 0 -2.8194 90)
			(unlocked yes)
			(layer "F.Fab")
			(hide yes)
			(effects
				(font
					(size 1.016 1.016)
					(thickness 0.1524)
				)
			)
		)
		(property "Device Type" "C603H36"
			(at 0 -4.3434 90)
			(unlocked yes)
			(layer "F.Fab")
			(hide yes)
			(effects
				(font
					(size 1.016 1.016)
					(thickness 0.1524)
				)
			)
		)
		(duplicate_pad_numbers_are_jumpers no)
		(fp_line
			(start 0.508 0)
			(end -0.508 0)
			(stroke
				(width 0.2032)
				(type default)
			)
			(layer "F.SilkS")
		)
		(fp_rect
			(start -0.5842 1.3335)
			(end 0.5842 -1.3335)
			(stroke
				(width 0)
				(type default)
			)
			(fill no)
			(layer "F.CrtYd")
		)
		(fp_rect
			(start -0.5842 1.3335)
			(end 0.5842 -1.3335)
			(stroke
				(width 0)
				(type default)
			)
			(fill no)
			(layer "F.Fab")
		)
		(pad "1" smd custom
			(at 0 -0.762 90)
			(size 0.2159 0.2159)
			(layers "F.Cu" "F.Mask" "F.Paste")
			(net "P12V_MSB")
			(options
				(clearance outline)
				(anchor circle)
			)
			(primitives
				(gr_poly
					(pts
						(arc
							(start -0.3302 -0.4318)
							(mid -0.402042 -0.402042)
							(end -0.4318 -0.3302)
						)
						(arc
							(start -0.4318 0.3302)
							(mid -0.402042 0.402042)
							(end -0.3302 0.4318)
						)
						(arc
							(start 0.3302 0.4318)
							(mid 0.402042 0.402042)
							(end 0.4318 0.3302)
						)
						(arc
							(start 0.4318 -0.3302)
							(mid 0.402042 -0.402042)
							(end 0.3302 -0.4318)
						)
					)
					(width 0)
					(fill yes)
				)
			)
		)
		(pad "2" smd custom
			(at 0 0.762 90)
			(size 0.2159 0.2159)
			(layers "F.Cu" "F.Mask" "F.Paste")
			(net "GND")
			(options
				(clearance outline)
				(anchor circle)
			)
			(primitives
				(gr_poly
					(pts
						(arc
							(start -0.3302 -0.4318)
							(mid -0.402042 -0.402042)
							(end -0.4318 -0.3302)
						)
						(arc
							(start -0.4318 0.3302)
							(mid -0.402042 0.402042)
							(end -0.3302 0.4318)
						)
						(arc
							(start 0.3302 0.4318)
							(mid 0.402042 0.402042)
							(end 0.4318 0.3302)
						)
						(arc
							(start 0.4318 -0.3302)
							(mid 0.402042 -0.402042)
							(end 0.3302 -0.4318)
						)
					)
					(width 0)
					(fill yes)
				)
			)
		)
	)
	(footprint ""
		(layer "F.Cu")
		(at 266.500864 -230.369872 90)
		(property "Reference" "PC91"
			(at 0 0 90)
			(layer "F.SilkS")
			(hide yes)
			(effects
				(font
					(size 1.27 1.27)
				)
			)
		)
		(property "Value" "SC10U6D3V5KX-1GP"
			(at -0.0762 -6.1214 90)
			(unlocked yes)
			(layer "F.Fab")
			(hide yes)
			(effects
				(font
					(size 1.016 1.016)
					(thickness 0.1524)
				)
			)
		)
		(property "Device Type" "C805H54"
			(at -0.0762 -8.1534 90)
			(unlocked yes)
			(layer "F.Fab")
			(hide yes)
			(effects
				(font
					(size 1.016 1.016)
					(thickness 0.1524)
				)
			)
		)
		(duplicate_pad_numbers_are_jumpers no)
		(fp_line
			(start 0.635 0)
			(end -0.635 0)
			(stroke
				(width 0.508)
				(type default)
			)
			(layer "F.SilkS")
		)
		(fp_rect
			(start -0.9652 1.778)
			(end 0.9652 -1.778)
			(stroke
				(width 0)
				(type default)
			)
			(fill no)
			(layer "F.CrtYd")
		)
		(fp_poly
			(pts
				(xy -0.9652 -1.778) (xy 0.9652 -1.778) (xy 0.9652 1.778) (xy -0.9652 1.778)
			)
			(stroke
				(width 0)
				(type default)
			)
			(fill no)
			(layer "F.Fab")
		)
		(pad "1" smd rect
			(at 0 -0.9652 90)
			(size 1.397 1.143)
			(layers "F.Cu" "F.Mask" "F.Paste")
			(net "TPS74801_P1V26_STBY_IN")
		)
		(pad "2" smd rect
			(at 0 0.9652 90)
			(size 1.397 1.143)
			(layers "F.Cu" "F.Mask" "F.Paste")
			(net "GND")
		)
	)
	(footprint ""
		(layer "F.Cu")
		(at 320.294 -144.907 90)
		(property "Reference" "C1698"
			(at 0 0 90)
			(layer "F.SilkS")
			(hide yes)
			(effects
				(font
					(size 1.27 1.27)
				)
			)
		)
		(property "Value" "SC22U6D3V5MX-2GP"
			(at -0.0762 -6.1214 90)
			(unlocked yes)
			(layer "F.Fab")
			(hide yes)
			(effects
				(font
					(size 1.016 1.016)
					(thickness 0.1524)
				)
			)
		)
		(property "Device Type" "C805H58"
			(at -0.0762 -8.1534 90)
			(unlocked yes)
			(layer "F.Fab")
			(hide yes)
			(effects
				(font
					(size 1.016 1.016)
					(thickness 0.1524)
				)
			)
		)
		(duplicate_pad_numbers_are_jumpers no)
		(fp_line
			(start 0.635 0)
			(end -0.635 0)
			(stroke
				(width 0.508)
				(type default)
			)
			(layer "F.SilkS")
		)
		(fp_rect
			(start -0.9652 1.778)
			(end 0.9652 -1.778)
			(stroke
				(width 0)
				(type default)
			)
			(fill no)
			(layer "F.CrtYd")
		)
		(fp_poly
			(pts
				(xy -0.9652 -1.778) (xy 0.9652 -1.778) (xy 0.9652 1.778) (xy -0.9652 1.778)
			)
			(stroke
				(width 0)
				(type default)
			)
			(fill no)
			(layer "F.Fab")
		)
		(pad "1" smd rect
			(at 0 -0.9652 90)
			(size 1.397 1.143)
			(layers "F.Cu" "F.Mask" "F.Paste")
			(net "P3V3_RTC")
		)
		(pad "2" smd rect
			(at 0 0.9652 90)
			(size 1.397 1.143)
			(layers "F.Cu" "F.Mask" "F.Paste")
			(net "GND")
		)
	)
	(footprint ""
		(layer "F.Cu")
		(at 171.131992 -16.129 -90)
		(property "Reference" "R420"
			(at 0 0 270)
			(layer "F.SilkS")
			(hide yes)
			(effects
				(font
					(size 1.27 1.27)
				)
			)
		)
		(property "Value" "150R3J-L-GP"
			(at -0.0254 -2.5146 270)
			(unlocked yes)
			(layer "F.Fab")
			(hide yes)
			(effects
				(font
					(size 1.016 1.016)
					(thickness 0.1524)
				)
			)
		)
		(property "Device Type" "R603H22"
			(at -0.0254 -4.0386 270)
			(unlocked yes)
			(layer "F.Fab")
			(hide yes)
			(effects
				(font
					(size 1.016 1.016)
					(thickness 0.1524)
				)
			)
		)
		(duplicate_pad_numbers_are_jumpers no)
		(fp_line
			(start -0.4826 0)
			(end -0.2032 0)
			(stroke
				(width 0.2032)
				(type default)
			)
			(layer "F.SilkS")
		)
		(fp_line
			(start 0.2032 0)
			(end 0.4826 0)
			(stroke
				(width 0.2032)
				(type default)
			)
			(layer "F.SilkS")
		)
		(fp_rect
			(start -0.5842 1.3335)
			(end 0.5842 -1.3335)
			(stroke
				(width 0)
				(type default)
			)
			(fill no)
			(layer "F.CrtYd")
		)
		(fp_rect
			(start -0.5842 1.3335)
			(end 0.5842 -1.3335)
			(stroke
				(width 0)
				(type default)
			)
			(fill no)
			(layer "F.Fab")
		)
		(pad "1" smd custom
			(at 0 -0.762 270)
			(size 0.2159 0.2159)
			(layers "F.Cu" "F.Mask" "F.Paste")
			(net "P3V3_STBY")
			(options
				(clearance outline)
				(anchor circle)
			)
			(primitives
				(gr_poly
					(pts
						(arc
							(start -0.3302 -0.4318)
							(mid -0.402042 -0.402042)
							(end -0.4318 -0.3302)
						)
						(arc
							(start -0.4318 0.3302)
							(mid -0.402042 0.402042)
							(end -0.3302 0.4318)
						)
						(arc
							(start 0.3302 0.4318)
							(mid 0.402042 0.402042)
							(end 0.4318 0.3302)
						)
						(arc
							(start 0.4318 -0.3302)
							(mid 0.402042 -0.402042)
							(end 0.3302 -0.4318)
						)
					)
					(width 0)
					(fill yes)
				)
			)
		)
		(pad "2" smd custom
			(at 0 0.762 270)
			(size 0.2159 0.2159)
			(layers "F.Cu" "F.Mask" "F.Paste")
			(net "LED_MDI0_ACT")
			(options
				(clearance outline)
				(anchor circle)
			)
			(primitives
				(gr_poly
					(pts
						(arc
							(start -0.3302 -0.4318)
							(mid -0.402042 -0.402042)
							(end -0.4318 -0.3302)
						)
						(arc
							(start -0.4318 0.3302)
							(mid -0.402042 0.402042)
							(end -0.3302 0.4318)
						)
						(arc
							(start 0.3302 0.4318)
							(mid 0.402042 0.402042)
							(end 0.4318 0.3302)
						)
						(arc
							(start 0.4318 -0.3302)
							(mid 0.402042 -0.402042)
							(end 0.3302 -0.4318)
						)
					)
					(width 0)
					(fill yes)
				)
			)
		)
	)
	(footprint ""
		(layer "F.Cu")
		(at 104.950006 -5.999988 180)
		(property "Reference" "Q4"
			(at 0 0 180)
			(layer "F.SilkS")
			(hide yes)
			(effects
				(font
					(size 1.27 1.27)
				)
			)
		)
		(property "Value" "MPS2907ARLRAG-GP"
			(at 5.0419 -5.5372 180)
			(unlocked yes)
			(layer "F.Fab")
			(hide yes)
			(effects
				(font
					(size 1.016 1.016)
					(thickness 0.1524)
				)
			)
		)
		(property "Device Type" "TO-92-CBE-5737H368"
			(at 5.0419 -7.0612 180)
			(unlocked yes)
			(layer "F.Fab")
			(hide yes)
			(effects
				(font
					(size 1.016 1.016)
					(thickness 0.1524)
				)
			)
		)
		(duplicate_pad_numbers_are_jumpers no)
		(fp_line
			(start 3.429 0.8255)
			(end 2.518664 0.8255)
			(stroke
				(width 0.1524)
				(type default)
			)
			(layer "F.SilkS")
		)
		(fp_line
			(start 3.429 -0.8255)
			(end 3.429 0.8255)
			(stroke
				(width 0.1524)
				(type default)
			)
			(layer "F.SilkS")
		)
		(fp_line
			(start 2.551938 -0.8255)
			(end 3.429 -0.8255)
			(stroke
				(width 0.1524)
				(type default)
			)
			(layer "F.SilkS")
		)
		(fp_line
			(start -2.170684 -1.6002)
			(end 2.170684 -1.6002)
			(stroke
				(width 0.1524)
				(type default)
			)
			(layer "F.SilkS")
		)
		(fp_line
			(start -2.518664 0.8255)
			(end -3.429 0.8255)
			(stroke
				(width 0.1524)
				(type default)
			)
			(layer "F.SilkS")
		)
		(fp_line
			(start -3.429 0.8255)
			(end -3.429 -0.8255)
			(stroke
				(width 0.1524)
				(type default)
			)
			(layer "F.SilkS")
		)
		(fp_line
			(start -3.429 -0.8255)
			(end -2.551938 -0.8255)
			(stroke
				(width 0.1524)
				(type default)
			)
			(layer "F.SilkS")
		)
		(fp_arc
			(start 2.533396 -0.883666)
			(mid 2.542832 -0.854636)
			(end 2.551938 -0.8255)
			(stroke
				(width 0.1524)
				(type default)
			)
			(layer "F.SilkS")
		)
		(fp_arc
			(start 2.521204 -0.92075)
			(mid 2.527368 -0.90223)
			(end 2.533396 -0.883666)
			(stroke
				(width 0.1524)
				(type default)
			)
			(layer "F.SilkS")
		)
		(fp_arc
			(start 2.518664 0.8255)
			(mid 0 2.615953)
			(end -2.518664 0.8255)
			(stroke
				(width 0.1524)
				(type default)
			)
			(layer "F.SilkS")
		)
		(fp_arc
			(start 2.170684 -1.6002)
			(mid 2.370425 -1.273104)
			(end 2.521204 -0.92075)
			(stroke
				(width 0.1524)
				(type default)
			)
			(layer "F.SilkS")
		)
		(fp_arc
			(start -2.521204 -0.92075)
			(mid -2.370409 -1.273096)
			(end -2.170684 -1.6002)
			(stroke
				(width 0.1524)
				(type default)
			)
			(layer "F.SilkS")
		)
		(fp_arc
			(start -2.533396 -0.883666)
			(mid -2.527368 -0.90223)
			(end -2.521204 -0.92075)
			(stroke
				(width 0.1524)
				(type default)
			)
			(layer "F.SilkS")
		)
		(fp_arc
			(start -2.551938 -0.8255)
			(mid -2.542834 -0.854636)
			(end -2.533396 -0.883666)
			(stroke
				(width 0.1524)
				(type default)
			)
			(layer "F.SilkS")
		)
		(fp_poly
			(pts
				(arc
					(start 2.396744 0.2286)
					(mid 0 2.362175)
					(end -2.396744 0.2286)
				)
				(xy -2.8321 0.2286) (xy -2.8321 -0.2286)
				(arc
					(start -2.406396 -0.2286)
					(mid -2.366841 -0.520127)
					(end -2.292096 -0.804672)
				)
				(arc
					(start -2.28092 -0.8382)
					(mid -2.17326 -1.099387)
					(end -2.03581 -1.3462)
				)
				(arc
					(start 2.03581 -1.3462)
					(mid 2.173258 -1.099386)
					(end 2.28092 -0.8382)
				)
				(arc
					(start 2.292096 -0.804672)
					(mid 2.366834 -0.520126)
					(end 2.406396 -0.2286)
				)
				(xy 2.8321 -0.2286) (xy 2.8321 0.2286)
			)
			(stroke
				(width 0)
				(type default)
			)
			(fill no)
			(layer "F.CrtYd")
		)
		(fp_poly
			(pts
				(arc
					(start 2.693162 1.0795)
					(mid 0 2.869936)
					(end -2.693162 1.0795)
				)
				(xy -3.683 1.0795) (xy -3.683 -1.0795)
				(arc
					(start -2.733802 -1.0795)
					(mid -2.545381 -1.483534)
					(end -2.297684 -1.8542)
				)
				(xy 0.6223 -1.8542) (xy 0.6223 -1.346454)
				(arc
					(start -2.036064 -1.346454)
					(mid -2.173513 -1.099511)
					(end -2.281174 -0.8382)
				)
				(arc
					(start -2.29235 -0.804672)
					(mid -2.367086 -0.520253)
					(end -2.40665 -0.228854)
				)
				(xy -2.832354 -0.228854) (xy -2.832354 0.228854)
				(arc
					(start -2.396998 0.228854)
					(mid 0 2.362456)
					(end 2.396998 0.228854)
				)
				(xy 2.832354 0.228854) (xy 2.832354 -0.228854)
				(arc
					(start 2.40665 -0.228854)
					(mid 2.367063 -0.520249)
					(end 2.29235 -0.804672)
				)
				(arc
					(start 2.281174 -0.8382)
					(mid 2.173536 -1.099521)
					(end 2.036064 -1.346454)
				)
				(xy 0.635 -1.346454) (xy 0.635 -1.8542)
				(arc
					(start 2.297684 -1.8542)
					(mid 2.545396 -1.483542)
					(end 2.733802 -1.0795)
				)
				(xy 3.683 -1.0795) (xy 3.683 1.0795)
			)
			(stroke
				(width 0)
				(type default)
			)
			(fill no)
			(layer "F.CrtYd")
		)
		(fp_poly
			(pts
				(arc
					(start 2.693162 1.0795)
					(mid 0 2.869936)
					(end -2.693162 1.0795)
				)
				(xy -3.683 1.0795) (xy -3.683 -1.0795)
				(arc
					(start -2.733802 -1.0795)
					(mid -2.545381 -1.483534)
					(end -2.297684 -1.8542)
				)
				(arc
					(start 2.297684 -1.8542)
					(mid 2.545396 -1.483542)
					(end 2.733802 -1.0795)
				)
				(xy 3.683 -1.0795) (xy 3.683 1.0795)
			)
			(stroke
				(width 0)
				(type default)
			)
			(fill no)
			(layer "F.Fab")
		)
		(pad "B" thru_hole circle
			(at 0 0 180)
			(size 1.143 1.143)
			(drill 0.7874)
			(layers "*.Cu" "*.Mask")
			(remove_unused_layers no)
			(net "TEMP_SENSOR_DXN_BJT")
			(clearance 0.1778)
			(thermal_gap 0.1778)
		)
		(pad "C" thru_hole circle
			(at -2.599944 0 180)
			(size 1.143 1.143)
			(drill 0.7874)
			(layers "*.Cu" "*.Mask")
			(remove_unused_layers no)
			(net "TEMP_SENSOR_C")
			(clearance 0.1778)
			(thermal_gap 0.1778)
		)
		(pad "E" thru_hole circle
			(at 2.599944 0 180)
			(size 1.143 1.143)
			(drill 0.7874)
			(layers "*.Cu" "*.Mask")
			(remove_unused_layers no)
			(net "TEMP_SENSOR_DXP_R")
			(clearance 0.1778)
			(thermal_gap 0.1778)
		)
	)
	(footprint ""
		(layer "F.Cu")
		(at 278.257 -111.887 180)
		(property "Reference" "PQ5"
			(at 0 0 180)
			(layer "F.SilkS")
			(hide yes)
			(effects
				(font
					(size 1.27 1.27)
				)
			)
		)
		(property "Value" "2N7002A-7-GP"
			(at 0.127 -8.9662 180)
			(unlocked yes)
			(layer "F.Fab")
			(hide yes)
			(effects
				(font
					(size 1.016 1.016)
					(thickness 0.1524)
				)
			)
		)
		(property "Device Type" "SOT23DGS2D4H48"
			(at 0.127 -10.4902 180)
			(unlocked yes)
			(layer "F.Fab")
			(hide yes)
			(effects
				(font
					(size 1.016 1.016)
					(thickness 0.1524)
				)
			)
		)
		(duplicate_pad_numbers_are_jumpers no)
		(fp_line
			(start 1.651 1.778)
			(end 1.651 -1.778)
			(stroke
				(width 0.1524)
				(type default)
			)
			(layer "F.SilkS")
		)
		(fp_line
			(start 1.651 -1.778)
			(end -1.651 -1.778)
			(stroke
				(width 0.1524)
				(type default)
			)
			(layer "F.SilkS")
		)
		(fp_line
			(start -1.651 1.778)
			(end 1.651 1.778)
			(stroke
				(width 0.1524)
				(type default)
			)
			(layer "F.SilkS")
		)
		(fp_line
			(start -1.651 -1.778)
			(end -1.651 1.778)
			(stroke
				(width 0.1524)
				(type default)
			)
			(layer "F.SilkS")
		)
		(fp_poly
			(pts
				(xy -1.778 1.8796) (xy -1.778 -1.8796) (xy 1.778 -1.8796) (xy 1.778 1.8796)
			)
			(stroke
				(width 0)
				(type default)
			)
			(fill no)
			(layer "F.CrtYd")
		)
		(fp_poly
			(pts
				(xy -1.778 1.8796) (xy -1.778 -1.8796) (xy 1.778 -1.8796) (xy 1.778 1.8796)
			)
			(stroke
				(width 0)
				(type default)
			)
			(fill no)
			(layer "F.Fab")
		)
		(pad "D" smd custom
			(at 0 -0.9525 180)
			(size 0.1905 0.1905)
			(layers "F.Cu" "F.Mask" "F.Paste")
			(net "P1V8_C_EN_LV")
			(options
				(clearance outline)
				(anchor circle)
			)
			(primitives
				(gr_poly
					(pts
						(arc
							(start -0.1778 0.5715)
							(mid -0.321484 0.511984)
							(end -0.381 0.3683)
						)
						(arc
							(start -0.381 -0.3683)
							(mid -0.321484 -0.511984)
							(end -0.1778 -0.5715)
						)
						(arc
							(start 0.1778 -0.5715)
							(mid 0.321484 -0.511984)
							(end 0.381 -0.3683)
						)
						(arc
							(start 0.381 0.3683)
							(mid 0.321484 0.511984)
							(end 0.1778 0.5715)
						)
					)
					(width 0)
					(fill yes)
				)
			)
		)
		(pad "G" smd custom
			(at -0.98425 0.9525 180)
			(size 0.1905 0.1905)
			(layers "F.Cu" "F.Mask" "F.Paste")
			(net "P1V8_C_EN_G")
			(options
				(clearance outline)
				(anchor circle)
			)
			(primitives
				(gr_poly
					(pts
						(arc
							(start -0.1778 0.5715)
							(mid -0.321484 0.511984)
							(end -0.381 0.3683)
						)
						(arc
							(start -0.381 -0.3683)
							(mid -0.321484 -0.511984)
							(end -0.1778 -0.5715)
						)
						(arc
							(start 0.1778 -0.5715)
							(mid 0.321484 -0.511984)
							(end 0.381 -0.3683)
						)
						(arc
							(start 0.381 0.3683)
							(mid 0.321484 0.511984)
							(end 0.1778 0.5715)
						)
					)
					(width 0)
					(fill yes)
				)
			)
		)
		(pad "S" smd custom
			(at 0.98425 0.9525 180)
			(size 0.1905 0.1905)
			(layers "F.Cu" "F.Mask" "F.Paste")
			(net "P1V8_C_EN_B")
			(options
				(clearance outline)
				(anchor circle)
			)
			(primitives
				(gr_poly
					(pts
						(arc
							(start -0.1778 0.5715)
							(mid -0.321484 0.511984)
							(end -0.381 0.3683)
						)
						(arc
							(start -0.381 -0.3683)
							(mid -0.321484 -0.511984)
							(end -0.1778 -0.5715)
						)
						(arc
							(start 0.1778 -0.5715)
							(mid 0.321484 -0.511984)
							(end 0.381 -0.3683)
						)
						(arc
							(start 0.381 0.3683)
							(mid 0.321484 0.511984)
							(end 0.1778 0.5715)
						)
					)
					(width 0)
					(fill yes)
				)
			)
		)
	)
	(footprint ""
		(layer "F.Cu")
		(at 307.086 -199.136)
		(property "Reference" "U12"
			(at 0 0 0)
			(layer "F.SilkS")
			(hide yes)
			(effects
				(font
					(size 1.27 1.27)
				)
			)
		)
		(property "Value" "PCA9550DP-1-GP"
			(at 0 -13.1572 0)
			(unlocked yes)
			(layer "F.Fab")
			(hide yes)
			(effects
				(font
					(size 1.016 1.016)
					(thickness 0.1524)
				)
			)
		)
		(property "Device Type" "SSOIC8-2H44"
			(at 0 -15.1892 0)
			(unlocked yes)
			(layer "F.Fab")
			(hide yes)
			(effects
				(font
					(size 1.016 1.016)
					(thickness 0.1524)
				)
			)
		)
		(duplicate_pad_numbers_are_jumpers no)
		(fp_line
			(start -1.9304 -1.016)
			(end 1.0922 -1.016)
			(stroke
				(width 0.1524)
				(type default)
			)
			(layer "F.SilkS")
		)
		(fp_line
			(start -1.9304 1.016)
			(end -1.9304 -1.016)
			(stroke
				(width 0.1524)
				(type default)
			)
			(layer "F.SilkS")
		)
		(fp_line
			(start -1.7018 1.0414)
			(end -1.7018 2.9718)
			(stroke
				(width 0.635)
				(type default)
			)
			(layer "F.SilkS")
		)
		(fp_line
			(start -1.524 0)
			(end -1.9304 -0.4064)
			(stroke
				(width 0.1524)
				(type default)
			)
			(layer "F.SilkS")
		)
		(fp_line
			(start -1.524 0)
			(end -1.9304 0.4064)
			(stroke
				(width 0.1524)
				(type default)
			)
			(layer "F.SilkS")
		)
		(fp_line
			(start 1.0922 -1.016)
			(end 1.0922 1.016)
			(stroke
				(width 0.1524)
				(type default)
			)
			(layer "F.SilkS")
		)
		(fp_line
			(start 1.0922 1.016)
			(end -1.9304 1.016)
			(stroke
				(width 0.1524)
				(type default)
			)
			(layer "F.SilkS")
		)
		(fp_poly
			(pts
				(xy -1.1938 -1.016) (xy 1.0922 -1.016) (xy 1.0922 1.016) (xy -1.1938 1.016)
			)
			(stroke
				(width 0)
				(type default)
			)
			(fill yes)
			(layer "F.SilkS")
		)
		(fp_rect
			(start -2.0066 3.3401)
			(end 2.0066 -3.3401)
			(stroke
				(width 0)
				(type default)
			)
			(fill no)
			(layer "F.CrtYd")
		)
		(fp_poly
			(pts
				(xy -2.0066 -3.3401) (xy 2.0066 -3.3401) (xy 2.0066 3.3401) (xy -2.0066 3.3401)
			)
			(stroke
				(width 0)
				(type default)
			)
			(fill no)
			(layer "F.Fab")
		)
		(pad "1" smd rect
			(at -0.97536 2.0701)
			(size 0.4064 1.524)
			(layers "F.Cu" "F.Mask" "F.Paste")
			(net "LED_DR_A0")
		)
		(pad "2" smd rect
			(at -0.32512 2.0701)
			(size 0.4064 1.524)
			(layers "F.Cu" "F.Mask" "F.Paste")
			(net "LED_DR_LED0")
		)
		(pad "3" smd rect
			(at 0.32512 2.0701)
			(size 0.4064 1.524)
			(layers "F.Cu" "F.Mask" "F.Paste")
			(net "LED_DR_LED1")
		)
		(pad "4" smd rect
			(at 0.97536 2.0701)
			(size 0.4064 1.524)
			(layers "F.Cu" "F.Mask" "F.Paste")
			(net "GND")
		)
		(pad "5" smd rect
			(at 0.97536 -2.0701)
			(size 0.4064 1.524)
			(layers "F.Cu" "F.Mask" "F.Paste")
			(net "LED_DR_RESET#")
		)
		(pad "6" smd rect
			(at 0.32512 -2.0701)
			(size 0.4064 1.524)
			(layers "F.Cu" "F.Mask" "F.Paste")
			(net "LED_DR_I2C_SCL")
		)
		(pad "7" smd rect
			(at -0.32512 -2.0701)
			(size 0.4064 1.524)
			(layers "F.Cu" "F.Mask" "F.Paste")
			(net "LED_DR_I2C_SDA")
		)
		(pad "8" smd rect
			(at -0.97536 -2.0701)
			(size 0.4064 1.524)
			(layers "F.Cu" "F.Mask" "F.Paste")
			(net "P3V3_STBY")
		)
	)
	(footprint ""
		(layer "F.Cu")
		(at 131.318 -87.249 90)
		(property "Reference" "SC1262"
			(at 0 0 90)
			(layer "F.SilkS")
			(hide yes)
			(effects
				(font
					(size 1.27 1.27)
				)
			)
		)
		(property "Value" "SCD01U10V1KX-GP"
			(at -2.8321 -1.7399 90)
			(unlocked yes)
			(layer "F.Fab")
			(hide yes)
			(effects
				(font
					(size 1.016 1.016)
					(thickness 0.1524)
				)
			)
		)
		(property "Device Type" "C0201H13"
			(at -2.8321 -3.2639 90)
			(unlocked yes)
			(layer "F.Fab")
			(hide yes)
			(effects
				(font
					(size 1.016 1.016)
					(thickness 0.1524)
				)
			)
		)
		(duplicate_pad_numbers_are_jumpers no)
		(fp_rect
			(start -0.2794 0.6477)
			(end 0.2794 -0.6477)
			(stroke
				(width 0)
				(type default)
			)
			(fill no)
			(layer "F.CrtYd")
		)
		(fp_rect
			(start -0.2794 0.6477)
			(end 0.2794 -0.6477)
			(stroke
				(width 0)
				(type default)
			)
			(fill no)
			(layer "F.Fab")
		)
		(pad "1" smd custom
			(at 0 -0.2794 90)
			(size 0.0762 0.0762)
			(layers "F.Cu" "F.Mask" "F.Paste")
			(net "3X24_SAS_TX16_P")
			(options
				(clearance outline)
				(anchor circle)
			)
			(primitives
				(gr_poly
					(pts
						(arc
							(start 0.1524 -0.127)
							(mid 0.137521 -0.162921)
							(end 0.1016 -0.1778)
						)
						(arc
							(start -0.1016 -0.1778)
							(mid -0.137521 -0.162921)
							(end -0.1524 -0.127)
						)
						(arc
							(start -0.1524 0.127)
							(mid -0.137521 0.162921)
							(end -0.1016 0.1778)
						)
						(arc
							(start 0.1016 0.1778)
							(mid 0.137521 0.162921)
							(end 0.1524 0.127)
						)
					)
					(width 0)
					(fill yes)
				)
			)
		)
		(pad "2" smd custom
			(at 0 0.2794 90)
			(size 0.0762 0.0762)
			(layers "F.Cu" "F.Mask" "F.Paste")
			(net "SAS_EXP2CONN_TX_P_20")
			(options
				(clearance outline)
				(anchor circle)
			)
			(primitives
				(gr_poly
					(pts
						(arc
							(start 0.1524 -0.127)
							(mid 0.137521 -0.162921)
							(end 0.1016 -0.1778)
						)
						(arc
							(start -0.1016 -0.1778)
							(mid -0.137521 -0.162921)
							(end -0.1524 -0.127)
						)
						(arc
							(start -0.1524 0.127)
							(mid -0.137521 0.162921)
							(end -0.1016 0.1778)
						)
						(arc
							(start 0.1016 0.1778)
							(mid 0.137521 0.162921)
							(end 0.1524 0.127)
						)
					)
					(width 0)
					(fill yes)
				)
			)
		)
	)
	(footprint ""
		(layer "F.Cu")
		(at 95.70085 -102.56012 -90)
		(property "Reference" "SR788"
			(at 0 0 270)
			(layer "F.SilkS")
			(hide yes)
			(effects
				(font
					(size 1.27 1.27)
				)
			)
		)
		(property "Value" "0R2J-2-GP"
			(at 0.064008 -3.993896 270)
			(unlocked yes)
			(layer "F.Fab")
			(hide yes)
			(effects
				(font
					(size 1.016 1.016)
					(thickness 0.1524)
				)
			)
		)
		(property "Device Type" "R402H16"
			(at 0.064008 -5.517896 270)
			(unlocked yes)
			(layer "F.Fab")
			(hide yes)
			(effects
				(font
					(size 1.016 1.016)
					(thickness 0.1524)
				)
			)
		)
		(duplicate_pad_numbers_are_jumpers no)
		(fp_line
			(start -0.508 -0.9398)
			(end -0.508 0.9398)
			(stroke
				(width 0.1524)
				(type default)
			)
			(layer "F.SilkS")
		)
		(fp_line
			(start 0.508 -0.9398)
			(end -0.508 -0.9398)
			(stroke
				(width 0.1524)
				(type default)
			)
			(layer "F.SilkS")
		)
		(fp_rect
			(start -0.508 0.9398)
			(end 0.508 -0.9398)
			(stroke
				(width 0)
				(type default)
			)
			(fill no)
			(layer "F.CrtYd")
		)
		(fp_rect
			(start -0.508 0.9398)
			(end 0.508 -0.9398)
			(stroke
				(width 0)
				(type default)
			)
			(fill no)
			(layer "F.Fab")
		)
		(pad "1" smd custom
			(at 0 -0.4445 270)
			(size 0.1397 0.1397)
			(layers "F.Cu" "F.Mask" "F.Paste")
			(net "SDB_R_RX")
			(options
				(clearance outline)
				(anchor circle)
			)
			(primitives
				(gr_poly
					(pts
						(arc
							(start -0.1778 -0.2794)
							(mid -0.249642 -0.249642)
							(end -0.2794 -0.1778)
						)
						(arc
							(start -0.2794 0.1778)
							(mid -0.249642 0.249642)
							(end -0.1778 0.2794)
						)
						(arc
							(start 0.1778 0.2794)
							(mid 0.249642 0.249642)
							(end 0.2794 0.1778)
						)
						(arc
							(start 0.2794 -0.1778)
							(mid 0.249642 -0.249642)
							(end 0.1778 -0.2794)
						)
					)
					(width 0)
					(fill yes)
				)
			)
		)
		(pad "2" smd custom
			(at 0 0.4445 270)
			(size 0.1397 0.1397)
			(layers "F.Cu" "F.Mask" "F.Paste")
			(net "SDB_RX")
			(options
				(clearance outline)
				(anchor circle)
			)
			(primitives
				(gr_poly
					(pts
						(arc
							(start -0.1778 -0.2794)
							(mid -0.249642 -0.249642)
							(end -0.2794 -0.1778)
						)
						(arc
							(start -0.2794 0.1778)
							(mid -0.249642 0.249642)
							(end -0.1778 0.2794)
						)
						(arc
							(start 0.1778 0.2794)
							(mid 0.249642 0.249642)
							(end 0.2794 0.1778)
						)
						(arc
							(start 0.2794 -0.1778)
							(mid 0.249642 -0.249642)
							(end 0.1778 -0.2794)
						)
					)
					(width 0)
					(fill yes)
				)
			)
		)
	)
	(footprint ""
		(layer "F.Cu")
		(at 89.662 -21.082 180)
		(property "Reference" "PR183"
			(at 0 0 180)
			(layer "F.SilkS")
			(hide yes)
			(effects
				(font
					(size 1.27 1.27)
				)
			)
		)
		(property "Value" "1K21R2F-2-GP"
			(at 0.064008 -3.993896 180)
			(unlocked yes)
			(layer "F.Fab")
			(hide yes)
			(effects
				(font
					(size 1.016 1.016)
					(thickness 0.1524)
				)
			)
		)
		(property "Device Type" "R402H16"
			(at 0.064008 -5.517896 180)
			(unlocked yes)
			(layer "F.Fab")
			(hide yes)
			(effects
				(font
					(size 1.016 1.016)
					(thickness 0.1524)
				)
			)
		)
		(duplicate_pad_numbers_are_jumpers no)
		(fp_line
			(start 0.508 -0.9398)
			(end -0.508 -0.9398)
			(stroke
				(width 0.1524)
				(type default)
			)
			(layer "F.SilkS")
		)
		(fp_line
			(start -0.508 -0.9398)
			(end -0.508 0.9398)
			(stroke
				(width 0.1524)
				(type default)
			)
			(layer "F.SilkS")
		)
		(fp_rect
			(start -0.508 0.9398)
			(end 0.508 -0.9398)
			(stroke
				(width 0)
				(type default)
			)
			(fill no)
			(layer "F.CrtYd")
		)
		(fp_rect
			(start -0.508 0.9398)
			(end 0.508 -0.9398)
			(stroke
				(width 0)
				(type default)
			)
			(fill no)
			(layer "F.Fab")
		)
		(pad "1" smd custom
			(at 0 -0.4445 180)
			(size 0.1397 0.1397)
			(layers "F.Cu" "F.Mask" "F.Paste")
			(net "VT235_VFB")
			(options
				(clearance outline)
				(anchor circle)
			)
			(primitives
				(gr_poly
					(pts
						(arc
							(start -0.1778 -0.2794)
							(mid -0.249642 -0.249642)
							(end -0.2794 -0.1778)
						)
						(arc
							(start -0.2794 0.1778)
							(mid -0.249642 0.249642)
							(end -0.1778 0.2794)
						)
						(arc
							(start 0.1778 0.2794)
							(mid 0.249642 0.249642)
							(end 0.2794 0.1778)
						)
						(arc
							(start 0.2794 -0.1778)
							(mid 0.249642 -0.249642)
							(end 0.1778 -0.2794)
						)
					)
					(width 0)
					(fill yes)
				)
			)
		)
		(pad "2" smd custom
			(at 0 0.4445 180)
			(size 0.1397 0.1397)
			(layers "F.Cu" "F.Mask" "F.Paste")
			(net "VT235_VDES_RC")
			(options
				(clearance outline)
				(anchor circle)
			)
			(primitives
				(gr_poly
					(pts
						(arc
							(start -0.1778 -0.2794)
							(mid -0.249642 -0.249642)
							(end -0.2794 -0.1778)
						)
						(arc
							(start -0.2794 0.1778)
							(mid -0.249642 0.249642)
							(end -0.1778 0.2794)
						)
						(arc
							(start 0.1778 0.2794)
							(mid 0.249642 0.249642)
							(end 0.2794 0.1778)
						)
						(arc
							(start 0.2794 -0.1778)
							(mid 0.249642 -0.249642)
							(end 0.1778 -0.2794)
						)
					)
					(width 0)
					(fill yes)
				)
			)
		)
	)
	(footprint ""
		(layer "F.Cu")
		(at 291.964872 -223.592136 180)
		(property "Reference" "PC83"
			(at 0 0 180)
			(layer "F.SilkS")
			(hide yes)
			(effects
				(font
					(size 1.27 1.27)
				)
			)
		)
		(property "Value" "SC10U6D3V5KX-1GP"
			(at -0.0762 -6.1214 180)
			(unlocked yes)
			(layer "F.Fab")
			(hide yes)
			(effects
				(font
					(size 1.016 1.016)
					(thickness 0.1524)
				)
			)
		)
		(property "Device Type" "C805H54"
			(at -0.0762 -8.1534 180)
			(unlocked yes)
			(layer "F.Fab")
			(hide yes)
			(effects
				(font
					(size 1.016 1.016)
					(thickness 0.1524)
				)
			)
		)
		(duplicate_pad_numbers_are_jumpers no)
		(fp_line
			(start 0.635 0)
			(end -0.635 0)
			(stroke
				(width 0.508)
				(type default)
			)
			(layer "F.SilkS")
		)
		(fp_rect
			(start -0.9652 1.778)
			(end 0.9652 -1.778)
			(stroke
				(width 0)
				(type default)
			)
			(fill no)
			(layer "F.CrtYd")
		)
		(fp_poly
			(pts
				(xy -0.9652 -1.778) (xy 0.9652 -1.778) (xy 0.9652 1.778) (xy -0.9652 1.778)
			)
			(stroke
				(width 0)
				(type default)
			)
			(fill no)
			(layer "F.Fab")
		)
		(pad "1" smd rect
			(at 0 -0.9652 180)
			(size 1.397 1.143)
			(layers "F.Cu" "F.Mask" "F.Paste")
			(net "TPS74801_1V53_STBY_OUT")
		)
		(pad "2" smd rect
			(at 0 0.9652 180)
			(size 1.397 1.143)
			(layers "F.Cu" "F.Mask" "F.Paste")
			(net "GND")
		)
	)
	(footprint ""
		(layer "F.Cu")
		(at 10.110216 -237.29188)
		(property "Reference" "SC430"
			(at 0 0 0)
			(layer "F.SilkS")
			(hide yes)
			(effects
				(font
					(size 1.27 1.27)
				)
			)
		)
		(property "Value" "SC1U10V3KX-4GP-U"
			(at 0 -2.8194 0)
			(unlocked yes)
			(layer "F.Fab")
			(hide yes)
			(effects
				(font
					(size 1.016 1.016)
					(thickness 0.1524)
				)
			)
		)
		(property "Device Type" "C603H36"
			(at 0 -4.3434 0)
			(unlocked yes)
			(layer "F.Fab")
			(hide yes)
			(effects
				(font
					(size 1.016 1.016)
					(thickness 0.1524)
				)
			)
		)
		(duplicate_pad_numbers_are_jumpers no)
		(fp_line
			(start 0.508 0)
			(end -0.508 0)
			(stroke
				(width 0.2032)
				(type default)
			)
			(layer "F.SilkS")
		)
		(fp_rect
			(start -0.5842 1.3335)
			(end 0.5842 -1.3335)
			(stroke
				(width 0)
				(type default)
			)
			(fill no)
			(layer "F.CrtYd")
		)
		(fp_rect
			(start -0.5842 1.3335)
			(end 0.5842 -1.3335)
			(stroke
				(width 0)
				(type default)
			)
			(fill no)
			(layer "F.Fab")
		)
		(pad "1" smd custom
			(at 0 -0.762)
			(size 0.2159 0.2159)
			(layers "F.Cu" "F.Mask" "F.Paste")
			(net "GND")
			(options
				(clearance outline)
				(anchor circle)
			)
			(primitives
				(gr_poly
					(pts
						(arc
							(start -0.3302 -0.4318)
							(mid -0.402042 -0.402042)
							(end -0.4318 -0.3302)
						)
						(arc
							(start -0.4318 0.3302)
							(mid -0.402042 0.402042)
							(end -0.3302 0.4318)
						)
						(arc
							(start 0.3302 0.4318)
							(mid 0.402042 0.402042)
							(end 0.4318 0.3302)
						)
						(arc
							(start 0.4318 -0.3302)
							(mid 0.402042 -0.402042)
							(end 0.3302 -0.4318)
						)
					)
					(width 0)
					(fill yes)
				)
			)
		)
		(pad "2" smd custom
			(at 0 0.762)
			(size 0.2159 0.2159)
			(layers "F.Cu" "F.Mask" "F.Paste")
			(net "P3V3_STBY")
			(options
				(clearance outline)
				(anchor circle)
			)
			(primitives
				(gr_poly
					(pts
						(arc
							(start -0.3302 -0.4318)
							(mid -0.402042 -0.402042)
							(end -0.4318 -0.3302)
						)
						(arc
							(start -0.4318 0.3302)
							(mid -0.402042 0.402042)
							(end -0.3302 0.4318)
						)
						(arc
							(start 0.3302 0.4318)
							(mid 0.402042 0.402042)
							(end 0.4318 0.3302)
						)
						(arc
							(start 0.4318 -0.3302)
							(mid 0.402042 -0.402042)
							(end 0.3302 -0.4318)
						)
					)
					(width 0)
					(fill yes)
				)
			)
		)
	)
	(footprint ""
		(layer "F.Cu")
		(at 306.959 -109.855 -90)
		(property "Reference" "C5"
			(at 0 0 270)
			(layer "F.SilkS")
			(hide yes)
			(effects
				(font
					(size 1.27 1.27)
				)
			)
		)
		(property "Value" "SCD1U16V2KX-3GP"
			(at 1.1811 -2.7051 270)
			(unlocked yes)
			(layer "F.Fab")
			(hide yes)
			(effects
				(font
					(size 1.016 1.016)
					(thickness 0.1524)
				)
			)
		)
		(property "Device Type" "C402H22"
			(at 1.1811 -4.2291 270)
			(unlocked yes)
			(layer "F.Fab")
			(hide yes)
			(effects
				(font
					(size 1.016 1.016)
					(thickness 0.1524)
				)
			)
		)
		(duplicate_pad_numbers_are_jumpers no)
		(fp_rect
			(start -0.4318 0.9525)
			(end 0.4318 -0.9525)
			(stroke
				(width 0)
				(type default)
			)
			(fill no)
			(layer "F.CrtYd")
		)
		(fp_rect
			(start -0.4318 0.9525)
			(end 0.4318 -0.9525)
			(stroke
				(width 0)
				(type default)
			)
			(fill no)
			(layer "F.Fab")
		)
		(pad "1" smd custom
			(at 0 -0.4445 270)
			(size 0.1524 0.1524)
			(layers "F.Cu" "F.Mask" "F.Paste")
			(net "P3V3_STBY")
			(options
				(clearance outline)
				(anchor circle)
			)
			(primitives
				(gr_poly
					(pts
						(arc
							(start 0.3048 -0.2032)
							(mid 0.275042 -0.275042)
							(end 0.2032 -0.3048)
						)
						(arc
							(start -0.2032 -0.3048)
							(mid -0.275042 -0.275042)
							(end -0.3048 -0.2032)
						)
						(arc
							(start -0.3048 0.2032)
							(mid -0.275042 0.275042)
							(end -0.2032 0.3048)
						)
						(arc
							(start 0.2032 0.3048)
							(mid 0.275042 0.275042)
							(end 0.3048 0.2032)
						)
					)
					(width 0)
					(fill yes)
				)
			)
		)
		(pad "2" smd custom
			(at 0 0.4445 270)
			(size 0.1524 0.1524)
			(layers "F.Cu" "F.Mask" "F.Paste")
			(net "GND")
			(options
				(clearance outline)
				(anchor circle)
			)
			(primitives
				(gr_poly
					(pts
						(arc
							(start 0.3048 -0.2032)
							(mid 0.275042 -0.275042)
							(end 0.2032 -0.3048)
						)
						(arc
							(start -0.2032 -0.3048)
							(mid -0.275042 -0.275042)
							(end -0.3048 -0.2032)
						)
						(arc
							(start -0.3048 0.2032)
							(mid -0.275042 0.275042)
							(end -0.2032 0.3048)
						)
						(arc
							(start 0.2032 0.3048)
							(mid 0.275042 0.275042)
							(end 0.3048 0.2032)
						)
					)
					(width 0)
					(fill yes)
				)
			)
		)
	)
	(footprint ""
		(layer "F.Cu")
		(at 55.89397 -143.383 90)
		(property "Reference" "SR1277"
			(at 0 0 90)
			(layer "F.SilkS")
			(hide yes)
			(effects
				(font
					(size 1.27 1.27)
				)
			)
		)
		(property "Value" "0R2J-2-GP"
			(at 0.064008 -3.993896 90)
			(unlocked yes)
			(layer "F.Fab")
			(hide yes)
			(effects
				(font
					(size 1.016 1.016)
					(thickness 0.1524)
				)
			)
		)
		(property "Device Type" "R402H16"
			(at 0.064008 -5.517896 90)
			(unlocked yes)
			(layer "F.Fab")
			(hide yes)
			(effects
				(font
					(size 1.016 1.016)
					(thickness 0.1524)
				)
			)
		)
		(duplicate_pad_numbers_are_jumpers no)
		(fp_line
			(start 0.508 -0.9398)
			(end -0.508 -0.9398)
			(stroke
				(width 0.1524)
				(type default)
			)
			(layer "F.SilkS")
		)
		(fp_line
			(start -0.508 -0.9398)
			(end -0.508 0.9398)
			(stroke
				(width 0.1524)
				(type default)
			)
			(layer "F.SilkS")
		)
		(fp_rect
			(start -0.508 0.9398)
			(end 0.508 -0.9398)
			(stroke
				(width 0)
				(type default)
			)
			(fill no)
			(layer "F.CrtYd")
		)
		(fp_rect
			(start -0.508 0.9398)
			(end 0.508 -0.9398)
			(stroke
				(width 0)
				(type default)
			)
			(fill no)
			(layer "F.Fab")
		)
		(pad "1" smd custom
			(at 0 -0.4445 90)
			(size 0.1397 0.1397)
			(layers "F.Cu" "F.Mask" "F.Paste")
			(net "DP_EXP_RST")
			(options
				(clearance outline)
				(anchor circle)
			)
			(primitives
				(gr_poly
					(pts
						(arc
							(start -0.1778 -0.2794)
							(mid -0.249642 -0.249642)
							(end -0.2794 -0.1778)
						)
						(arc
							(start -0.2794 0.1778)
							(mid -0.249642 0.249642)
							(end -0.1778 0.2794)
						)
						(arc
							(start 0.1778 0.2794)
							(mid 0.249642 0.249642)
							(end 0.2794 0.1778)
						)
						(arc
							(start 0.2794 -0.1778)
							(mid 0.249642 -0.249642)
							(end 0.1778 -0.2794)
						)
					)
					(width 0)
					(fill yes)
				)
			)
		)
		(pad "2" smd custom
			(at 0 0.4445 90)
			(size 0.1397 0.1397)
			(layers "F.Cu" "F.Mask" "F.Paste")
			(net "DP_EXP_RST_R")
			(options
				(clearance outline)
				(anchor circle)
			)
			(primitives
				(gr_poly
					(pts
						(arc
							(start -0.1778 -0.2794)
							(mid -0.249642 -0.249642)
							(end -0.2794 -0.1778)
						)
						(arc
							(start -0.2794 0.1778)
							(mid -0.249642 0.249642)
							(end -0.1778 0.2794)
						)
						(arc
							(start 0.1778 0.2794)
							(mid 0.249642 0.249642)
							(end 0.2794 0.1778)
						)
						(arc
							(start 0.2794 -0.1778)
							(mid 0.249642 -0.249642)
							(end 0.1778 -0.2794)
						)
					)
					(width 0)
					(fill yes)
				)
			)
		)
	)
	(footprint ""
		(layer "F.Cu")
		(at 197.039992 -46.355 180)
		(property "Reference" "R521"
			(at 0 0 180)
			(layer "F.SilkS")
			(hide yes)
			(effects
				(font
					(size 1.27 1.27)
				)
			)
		)
		(property "Value" "10KR2F-2-GP"
			(at 0.064008 -3.993896 180)
			(unlocked yes)
			(layer "F.Fab")
			(hide yes)
			(effects
				(font
					(size 1.016 1.016)
					(thickness 0.1524)
				)
			)
		)
		(property "Device Type" "R402H16"
			(at 0.064008 -5.517896 180)
			(unlocked yes)
			(layer "F.Fab")
			(hide yes)
			(effects
				(font
					(size 1.016 1.016)
					(thickness 0.1524)
				)
			)
		)
		(duplicate_pad_numbers_are_jumpers no)
		(fp_line
			(start 0.508 -0.9398)
			(end -0.508 -0.9398)
			(stroke
				(width 0.1524)
				(type default)
			)
			(layer "F.SilkS")
		)
		(fp_line
			(start -0.508 -0.9398)
			(end -0.508 0.9398)
			(stroke
				(width 0.1524)
				(type default)
			)
			(layer "F.SilkS")
		)
		(fp_rect
			(start -0.508 0.9398)
			(end 0.508 -0.9398)
			(stroke
				(width 0)
				(type default)
			)
			(fill no)
			(layer "F.CrtYd")
		)
		(fp_rect
			(start -0.508 0.9398)
			(end 0.508 -0.9398)
			(stroke
				(width 0)
				(type default)
			)
			(fill no)
			(layer "F.Fab")
		)
		(pad "1" smd custom
			(at 0 -0.4445 180)
			(size 0.1397 0.1397)
			(layers "F.Cu" "F.Mask" "F.Paste")
			(net "PRSNT_MSB_B81")
			(options
				(clearance outline)
				(anchor circle)
			)
			(primitives
				(gr_poly
					(pts
						(arc
							(start -0.1778 -0.2794)
							(mid -0.249642 -0.249642)
							(end -0.2794 -0.1778)
						)
						(arc
							(start -0.2794 0.1778)
							(mid -0.249642 0.249642)
							(end -0.1778 0.2794)
						)
						(arc
							(start 0.1778 0.2794)
							(mid 0.249642 0.249642)
							(end 0.2794 0.1778)
						)
						(arc
							(start 0.2794 -0.1778)
							(mid 0.249642 -0.249642)
							(end 0.1778 -0.2794)
						)
					)
					(width 0)
					(fill yes)
				)
			)
		)
		(pad "2" smd custom
			(at 0 0.4445 180)
			(size 0.1397 0.1397)
			(layers "F.Cu" "F.Mask" "F.Paste")
			(net "P3V3_STBY")
			(options
				(clearance outline)
				(anchor circle)
			)
			(primitives
				(gr_poly
					(pts
						(arc
							(start -0.1778 -0.2794)
							(mid -0.249642 -0.249642)
							(end -0.2794 -0.1778)
						)
						(arc
							(start -0.2794 0.1778)
							(mid -0.249642 0.249642)
							(end -0.1778 0.2794)
						)
						(arc
							(start 0.1778 0.2794)
							(mid 0.249642 0.249642)
							(end 0.2794 0.1778)
						)
						(arc
							(start 0.2794 -0.1778)
							(mid 0.249642 -0.249642)
							(end 0.1778 -0.2794)
						)
					)
					(width 0)
					(fill yes)
				)
			)
		)
	)
	(footprint ""
		(layer "F.Cu")
		(at 329.057 -8.255)
		(property "Reference" "R458"
			(at 0 0 0)
			(layer "F.SilkS")
			(hide yes)
			(effects
				(font
					(size 1.27 1.27)
				)
			)
		)
		(property "Value" "33R2J-2-GP"
			(at 0.064008 -3.993896 0)
			(unlocked yes)
			(layer "F.Fab")
			(hide yes)
			(effects
				(font
					(size 1.016 1.016)
					(thickness 0.1524)
				)
			)
		)
		(property "Device Type" "R402H16"
			(at 0.064008 -5.517896 0)
			(unlocked yes)
			(layer "F.Fab")
			(hide yes)
			(effects
				(font
					(size 1.016 1.016)
					(thickness 0.1524)
				)
			)
		)
		(duplicate_pad_numbers_are_jumpers no)
		(fp_line
			(start -0.508 -0.9398)
			(end -0.508 0.9398)
			(stroke
				(width 0.1524)
				(type default)
			)
			(layer "F.SilkS")
		)
		(fp_line
			(start 0.508 -0.9398)
			(end -0.508 -0.9398)
			(stroke
				(width 0.1524)
				(type default)
			)
			(layer "F.SilkS")
		)
		(fp_rect
			(start -0.508 0.9398)
			(end 0.508 -0.9398)
			(stroke
				(width 0)
				(type default)
			)
			(fill no)
			(layer "F.CrtYd")
		)
		(fp_rect
			(start -0.508 0.9398)
			(end 0.508 -0.9398)
			(stroke
				(width 0)
				(type default)
			)
			(fill no)
			(layer "F.Fab")
		)
		(pad "1" smd custom
			(at 0 -0.4445)
			(size 0.1397 0.1397)
			(layers "F.Cu" "F.Mask" "F.Paste")
			(net "GND")
			(options
				(clearance outline)
				(anchor circle)
			)
			(primitives
				(gr_poly
					(pts
						(arc
							(start -0.1778 -0.2794)
							(mid -0.249642 -0.249642)
							(end -0.2794 -0.1778)
						)
						(arc
							(start -0.2794 0.1778)
							(mid -0.249642 0.249642)
							(end -0.1778 0.2794)
						)
						(arc
							(start 0.1778 0.2794)
							(mid 0.249642 0.249642)
							(end 0.2794 0.1778)
						)
						(arc
							(start 0.2794 -0.1778)
							(mid 0.249642 -0.249642)
							(end 0.1778 -0.2794)
						)
					)
					(width 0)
					(fill yes)
				)
			)
		)
		(pad "2" smd custom
			(at 0 0.4445)
			(size 0.1397 0.1397)
			(layers "F.Cu" "F.Mask" "F.Paste")
			(net "DEBUG_PORT_GND")
			(options
				(clearance outline)
				(anchor circle)
			)
			(primitives
				(gr_poly
					(pts
						(arc
							(start -0.1778 -0.2794)
							(mid -0.249642 -0.249642)
							(end -0.2794 -0.1778)
						)
						(arc
							(start -0.2794 0.1778)
							(mid -0.249642 0.249642)
							(end -0.1778 0.2794)
						)
						(arc
							(start 0.1778 0.2794)
							(mid 0.249642 0.249642)
							(end 0.2794 0.1778)
						)
						(arc
							(start 0.2794 -0.1778)
							(mid 0.249642 -0.249642)
							(end 0.1778 -0.2794)
						)
					)
					(width 0)
					(fill yes)
				)
			)
		)
	)
	(footprint ""
		(layer "F.Cu")
		(at 302.641 -160.274)
		(property "Reference" "TP91"
			(at 0 0 0)
			(layer "F.SilkS")
			(hide yes)
			(effects
				(font
					(size 1.27 1.27)
				)
			)
		)
		(property "Value" "TPAD28"
			(at 0.0127 -1.8034 0)
			(unlocked yes)
			(layer "F.Fab")
			(hide yes)
			(effects
				(font
					(size 1.016 1.016)
					(thickness 0.1524)
				)
			)
		)
		(property "Device Type" "TPAD28"
			(at 0.0127 -3.3274 0)
			(unlocked yes)
			(layer "F.Fab")
			(hide yes)
			(effects
				(font
					(size 1.016 1.016)
					(thickness 0.1524)
				)
			)
		)
		(duplicate_pad_numbers_are_jumpers no)
		(fp_poly
			(pts
				(arc
					(start 0.3556 0)
					(mid -0.3556 0)
					(end 0.3556 0)
				)
			)
			(stroke
				(width 0)
				(type default)
			)
			(fill no)
			(layer "F.CrtYd")
		)
		(fp_poly
			(pts
				(arc
					(start 0.6096 0)
					(mid -0.6096 0)
					(end 0.6096 0)
				)
			)
			(stroke
				(width 0)
				(type default)
			)
			(fill no)
			(layer "F.Fab")
		)
		(pad "1" smd circle
			(at 0 0)
			(size 0.7112 0.7112)
			(layers "F.Cu" "F.Mask" "F.Paste")
			(net "TP_GPIOH2")
		)
	)
	(footprint ""
		(layer "F.Cu")
		(at 81.024222 -115.410742 -90)
		(property "Reference" "SR754"
			(at 0 0 270)
			(layer "F.SilkS")
			(hide yes)
			(effects
				(font
					(size 1.27 1.27)
				)
			)
		)
		(property "Value" "200KR2F-L-GP"
			(at 0.064008 -3.993896 270)
			(unlocked yes)
			(layer "F.Fab")
			(hide yes)
			(effects
				(font
					(size 1.016 1.016)
					(thickness 0.1524)
				)
			)
		)
		(property "Device Type" "R402H16"
			(at 0.064008 -5.517896 270)
			(unlocked yes)
			(layer "F.Fab")
			(hide yes)
			(effects
				(font
					(size 1.016 1.016)
					(thickness 0.1524)
				)
			)
		)
		(duplicate_pad_numbers_are_jumpers no)
		(fp_line
			(start -0.508 -0.9398)
			(end -0.508 0.9398)
			(stroke
				(width 0.1524)
				(type default)
			)
			(layer "F.SilkS")
		)
		(fp_line
			(start 0.508 -0.9398)
			(end -0.508 -0.9398)
			(stroke
				(width 0.1524)
				(type default)
			)
			(layer "F.SilkS")
		)
		(fp_rect
			(start -0.508 0.9398)
			(end 0.508 -0.9398)
			(stroke
				(width 0)
				(type default)
			)
			(fill no)
			(layer "F.CrtYd")
		)
		(fp_rect
			(start -0.508 0.9398)
			(end 0.508 -0.9398)
			(stroke
				(width 0)
				(type default)
			)
			(fill no)
			(layer "F.Fab")
		)
		(pad "1" smd custom
			(at 0 -0.4445 270)
			(size 0.1397 0.1397)
			(layers "F.Cu" "F.Mask" "F.Paste")
			(net "EXP_I2C_VREF_1")
			(options
				(clearance outline)
				(anchor circle)
			)
			(primitives
				(gr_poly
					(pts
						(arc
							(start -0.1778 -0.2794)
							(mid -0.249642 -0.249642)
							(end -0.2794 -0.1778)
						)
						(arc
							(start -0.2794 0.1778)
							(mid -0.249642 0.249642)
							(end -0.1778 0.2794)
						)
						(arc
							(start 0.1778 0.2794)
							(mid 0.249642 0.249642)
							(end 0.2794 0.1778)
						)
						(arc
							(start 0.2794 -0.1778)
							(mid 0.249642 -0.249642)
							(end 0.1778 -0.2794)
						)
					)
					(width 0)
					(fill yes)
				)
			)
		)
		(pad "2" smd custom
			(at 0 0.4445 270)
			(size 0.1397 0.1397)
			(layers "F.Cu" "F.Mask" "F.Paste")
			(net "P3V3_STBY")
			(options
				(clearance outline)
				(anchor circle)
			)
			(primitives
				(gr_poly
					(pts
						(arc
							(start -0.1778 -0.2794)
							(mid -0.249642 -0.249642)
							(end -0.2794 -0.1778)
						)
						(arc
							(start -0.2794 0.1778)
							(mid -0.249642 0.249642)
							(end -0.1778 0.2794)
						)
						(arc
							(start 0.1778 0.2794)
							(mid 0.249642 0.249642)
							(end 0.2794 0.1778)
						)
						(arc
							(start 0.2794 -0.1778)
							(mid 0.249642 -0.249642)
							(end 0.1778 -0.2794)
						)
					)
					(width 0)
					(fill yes)
				)
			)
		)
	)
	(footprint ""
		(layer "F.Cu")
		(at 107.45597 -75.057)
		(property "Reference" "R178"
			(at 0 0 0)
			(layer "F.SilkS")
			(hide yes)
			(effects
				(font
					(size 1.27 1.27)
				)
			)
		)
		(property "Value" "4K7R2F-GP"
			(at 0.064008 -3.993896 0)
			(unlocked yes)
			(layer "F.Fab")
			(hide yes)
			(effects
				(font
					(size 1.016 1.016)
					(thickness 0.1524)
				)
			)
		)
		(property "Device Type" "R402H16"
			(at 0.064008 -5.517896 0)
			(unlocked yes)
			(layer "F.Fab")
			(hide yes)
			(effects
				(font
					(size 1.016 1.016)
					(thickness 0.1524)
				)
			)
		)
		(duplicate_pad_numbers_are_jumpers no)
		(fp_line
			(start -0.508 -0.9398)
			(end -0.508 0.9398)
			(stroke
				(width 0.1524)
				(type default)
			)
			(layer "F.SilkS")
		)
		(fp_line
			(start 0.508 -0.9398)
			(end -0.508 -0.9398)
			(stroke
				(width 0.1524)
				(type default)
			)
			(layer "F.SilkS")
		)
		(fp_rect
			(start -0.508 0.9398)
			(end 0.508 -0.9398)
			(stroke
				(width 0)
				(type default)
			)
			(fill no)
			(layer "F.CrtYd")
		)
		(fp_rect
			(start -0.508 0.9398)
			(end 0.508 -0.9398)
			(stroke
				(width 0)
				(type default)
			)
			(fill no)
			(layer "F.Fab")
		)
		(pad "1" smd custom
			(at 0 -0.4445)
			(size 0.1397 0.1397)
			(layers "F.Cu" "F.Mask" "F.Paste")
			(net "P3V3_STBY")
			(options
				(clearance outline)
				(anchor circle)
			)
			(primitives
				(gr_poly
					(pts
						(arc
							(start -0.1778 -0.2794)
							(mid -0.249642 -0.249642)
							(end -0.2794 -0.1778)
						)
						(arc
							(start -0.2794 0.1778)
							(mid -0.249642 0.249642)
							(end -0.1778 0.2794)
						)
						(arc
							(start 0.1778 0.2794)
							(mid 0.249642 0.249642)
							(end 0.2794 0.1778)
						)
						(arc
							(start 0.2794 -0.1778)
							(mid 0.249642 -0.249642)
							(end 0.1778 -0.2794)
						)
					)
					(width 0)
					(fill yes)
				)
			)
		)
		(pad "2" smd custom
			(at 0 0.4445)
			(size 0.1397 0.1397)
			(layers "F.Cu" "F.Mask" "F.Paste")
			(net "TEMP_4_A2")
			(options
				(clearance outline)
				(anchor circle)
			)
			(primitives
				(gr_poly
					(pts
						(arc
							(start -0.1778 -0.2794)
							(mid -0.249642 -0.249642)
							(end -0.2794 -0.1778)
						)
						(arc
							(start -0.2794 0.1778)
							(mid -0.249642 0.249642)
							(end -0.1778 0.2794)
						)
						(arc
							(start 0.1778 0.2794)
							(mid 0.249642 0.249642)
							(end 0.2794 0.1778)
						)
						(arc
							(start 0.2794 -0.1778)
							(mid 0.249642 -0.249642)
							(end 0.1778 -0.2794)
						)
					)
					(width 0)
					(fill yes)
				)
			)
		)
	)
	(footprint ""
		(layer "F.Cu")
		(at 316.484 -69.215 -90)
		(property "Reference" "R272"
			(at 0 0 270)
			(layer "F.SilkS")
			(hide yes)
			(effects
				(font
					(size 1.27 1.27)
				)
			)
		)
		(property "Value" "0R2J-2-GP"
			(at 0.064008 -3.993896 270)
			(unlocked yes)
			(layer "F.Fab")
			(hide yes)
			(effects
				(font
					(size 1.016 1.016)
					(thickness 0.1524)
				)
			)
		)
		(property "Device Type" "R402H16"
			(at 0.064008 -5.517896 270)
			(unlocked yes)
			(layer "F.Fab")
			(hide yes)
			(effects
				(font
					(size 1.016 1.016)
					(thickness 0.1524)
				)
			)
		)
		(duplicate_pad_numbers_are_jumpers no)
		(fp_line
			(start -0.508 -0.9398)
			(end -0.508 0.9398)
			(stroke
				(width 0.1524)
				(type default)
			)
			(layer "F.SilkS")
		)
		(fp_line
			(start 0.508 -0.9398)
			(end -0.508 -0.9398)
			(stroke
				(width 0.1524)
				(type default)
			)
			(layer "F.SilkS")
		)
		(fp_rect
			(start -0.508 0.9398)
			(end 0.508 -0.9398)
			(stroke
				(width 0)
				(type default)
			)
			(fill no)
			(layer "F.CrtYd")
		)
		(fp_rect
			(start -0.508 0.9398)
			(end 0.508 -0.9398)
			(stroke
				(width 0)
				(type default)
			)
			(fill no)
			(layer "F.Fab")
		)
		(pad "1" smd custom
			(at 0 -0.4445 270)
			(size 0.1397 0.1397)
			(layers "F.Cu" "F.Mask" "F.Paste")
			(net "CLK_100M_CLKBUFF_ENET2_DN")
			(options
				(clearance outline)
				(anchor circle)
			)
			(primitives
				(gr_poly
					(pts
						(arc
							(start -0.1778 -0.2794)
							(mid -0.249642 -0.249642)
							(end -0.2794 -0.1778)
						)
						(arc
							(start -0.2794 0.1778)
							(mid -0.249642 0.249642)
							(end -0.1778 0.2794)
						)
						(arc
							(start 0.1778 0.2794)
							(mid 0.249642 0.249642)
							(end 0.2794 0.1778)
						)
						(arc
							(start 0.2794 -0.1778)
							(mid 0.249642 -0.249642)
							(end 0.1778 -0.2794)
						)
					)
					(width 0)
					(fill yes)
				)
			)
		)
		(pad "2" smd custom
			(at 0 0.4445 270)
			(size 0.1397 0.1397)
			(layers "F.Cu" "F.Mask" "F.Paste")
			(net "PCIE_10G_REFCLK_2_N")
			(options
				(clearance outline)
				(anchor circle)
			)
			(primitives
				(gr_poly
					(pts
						(arc
							(start -0.1778 -0.2794)
							(mid -0.249642 -0.249642)
							(end -0.2794 -0.1778)
						)
						(arc
							(start -0.2794 0.1778)
							(mid -0.249642 0.249642)
							(end -0.1778 0.2794)
						)
						(arc
							(start 0.1778 0.2794)
							(mid 0.249642 0.249642)
							(end 0.2794 0.1778)
						)
						(arc
							(start 0.2794 -0.1778)
							(mid 0.249642 -0.249642)
							(end 0.1778 -0.2794)
						)
					)
					(width 0)
					(fill yes)
				)
			)
		)
	)
	(footprint ""
		(layer "F.Cu")
		(at 210.57997 -69.088 180)
		(property "Reference" "R19"
			(at 0 0 180)
			(layer "F.SilkS")
			(hide yes)
			(effects
				(font
					(size 1.27 1.27)
				)
			)
		)
		(property "Value" "0R2J-2-GP"
			(at 0.064008 -3.993896 180)
			(unlocked yes)
			(layer "F.Fab")
			(hide yes)
			(effects
				(font
					(size 1.016 1.016)
					(thickness 0.1524)
				)
			)
		)
		(property "Device Type" "R402H16"
			(at 0.064008 -5.517896 180)
			(unlocked yes)
			(layer "F.Fab")
			(hide yes)
			(effects
				(font
					(size 1.016 1.016)
					(thickness 0.1524)
				)
			)
		)
		(duplicate_pad_numbers_are_jumpers no)
		(fp_line
			(start 0.508 -0.9398)
			(end -0.508 -0.9398)
			(stroke
				(width 0.1524)
				(type default)
			)
			(layer "F.SilkS")
		)
		(fp_line
			(start -0.508 -0.9398)
			(end -0.508 0.9398)
			(stroke
				(width 0.1524)
				(type default)
			)
			(layer "F.SilkS")
		)
		(fp_rect
			(start -0.508 0.9398)
			(end 0.508 -0.9398)
			(stroke
				(width 0)
				(type default)
			)
			(fill no)
			(layer "F.CrtYd")
		)
		(fp_rect
			(start -0.508 0.9398)
			(end 0.508 -0.9398)
			(stroke
				(width 0)
				(type default)
			)
			(fill no)
			(layer "F.Fab")
		)
		(pad "1" smd custom
			(at 0 -0.4445 180)
			(size 0.1397 0.1397)
			(layers "F.Cu" "F.Mask" "F.Paste")
			(net "CPU_RESET_N")
			(options
				(clearance outline)
				(anchor circle)
			)
			(primitives
				(gr_poly
					(pts
						(arc
							(start -0.1778 -0.2794)
							(mid -0.249642 -0.249642)
							(end -0.2794 -0.1778)
						)
						(arc
							(start -0.2794 0.1778)
							(mid -0.249642 0.249642)
							(end -0.1778 0.2794)
						)
						(arc
							(start 0.1778 0.2794)
							(mid 0.249642 0.249642)
							(end 0.2794 0.1778)
						)
						(arc
							(start 0.2794 -0.1778)
							(mid 0.249642 -0.249642)
							(end 0.1778 -0.2794)
						)
					)
					(width 0)
					(fill yes)
				)
			)
		)
		(pad "2" smd custom
			(at 0 0.4445 180)
			(size 0.1397 0.1397)
			(layers "F.Cu" "F.Mask" "F.Paste")
			(net "CPU_RESET_N_R")
			(options
				(clearance outline)
				(anchor circle)
			)
			(primitives
				(gr_poly
					(pts
						(arc
							(start -0.1778 -0.2794)
							(mid -0.249642 -0.249642)
							(end -0.2794 -0.1778)
						)
						(arc
							(start -0.2794 0.1778)
							(mid -0.249642 0.249642)
							(end -0.1778 0.2794)
						)
						(arc
							(start 0.1778 0.2794)
							(mid 0.249642 0.249642)
							(end 0.2794 0.1778)
						)
						(arc
							(start 0.2794 -0.1778)
							(mid 0.249642 -0.249642)
							(end 0.1778 -0.2794)
						)
					)
					(width 0)
					(fill yes)
				)
			)
		)
	)
	(footprint ""
		(layer "F.Cu")
		(at 270.637 -41.021)
		(property "Reference" "PC45"
			(at 0 0 0)
			(layer "F.SilkS")
			(hide yes)
			(effects
				(font
					(size 1.27 1.27)
				)
			)
		)
		(property "Value" "SCD1U25V3KX-GP"
			(at 0 -2.8194 0)
			(unlocked yes)
			(layer "F.Fab")
			(hide yes)
			(effects
				(font
					(size 1.016 1.016)
					(thickness 0.1524)
				)
			)
		)
		(property "Device Type" "C603H36"
			(at 0 -4.3434 0)
			(unlocked yes)
			(layer "F.Fab")
			(hide yes)
			(effects
				(font
					(size 1.016 1.016)
					(thickness 0.1524)
				)
			)
		)
		(duplicate_pad_numbers_are_jumpers no)
		(fp_line
			(start 0.508 0)
			(end -0.508 0)
			(stroke
				(width 0.2032)
				(type default)
			)
			(layer "F.SilkS")
		)
		(fp_rect
			(start -0.5842 1.3335)
			(end 0.5842 -1.3335)
			(stroke
				(width 0)
				(type default)
			)
			(fill no)
			(layer "F.CrtYd")
		)
		(fp_rect
			(start -0.5842 1.3335)
			(end 0.5842 -1.3335)
			(stroke
				(width 0)
				(type default)
			)
			(fill no)
			(layer "F.Fab")
		)
		(pad "1" smd custom
			(at 0 -0.762)
			(size 0.2159 0.2159)
			(layers "F.Cu" "F.Mask" "F.Paste")
			(net "P1V8_STBY_VIN")
			(options
				(clearance outline)
				(anchor circle)
			)
			(primitives
				(gr_poly
					(pts
						(arc
							(start -0.3302 -0.4318)
							(mid -0.402042 -0.402042)
							(end -0.4318 -0.3302)
						)
						(arc
							(start -0.4318 0.3302)
							(mid -0.402042 0.402042)
							(end -0.3302 0.4318)
						)
						(arc
							(start 0.3302 0.4318)
							(mid 0.402042 0.402042)
							(end 0.4318 0.3302)
						)
						(arc
							(start 0.4318 -0.3302)
							(mid 0.402042 -0.402042)
							(end 0.3302 -0.4318)
						)
					)
					(width 0)
					(fill yes)
				)
			)
		)
		(pad "2" smd custom
			(at 0 0.762)
			(size 0.2159 0.2159)
			(layers "F.Cu" "F.Mask" "F.Paste")
			(net "GND")
			(options
				(clearance outline)
				(anchor circle)
			)
			(primitives
				(gr_poly
					(pts
						(arc
							(start -0.3302 -0.4318)
							(mid -0.402042 -0.402042)
							(end -0.4318 -0.3302)
						)
						(arc
							(start -0.4318 0.3302)
							(mid -0.402042 0.402042)
							(end -0.3302 0.4318)
						)
						(arc
							(start 0.3302 0.4318)
							(mid 0.402042 0.402042)
							(end 0.4318 0.3302)
						)
						(arc
							(start 0.4318 -0.3302)
							(mid 0.402042 -0.402042)
							(end 0.3302 -0.4318)
						)
					)
					(width 0)
					(fill yes)
				)
			)
		)
	)
	(footprint ""
		(layer "F.Cu")
		(at 180.648864 -22.551136 180)
		(property "Reference" "R387"
			(at 0 0 180)
			(layer "F.SilkS")
			(hide yes)
			(effects
				(font
					(size 1.27 1.27)
				)
			)
		)
		(property "Value" "4K7R2J-2-GP"
			(at 0.064008 -3.993896 180)
			(unlocked yes)
			(layer "F.Fab")
			(hide yes)
			(effects
				(font
					(size 1.016 1.016)
					(thickness 0.1524)
				)
			)
		)
		(property "Device Type" "R402H16"
			(at 0.064008 -5.517896 180)
			(unlocked yes)
			(layer "F.Fab")
			(hide yes)
			(effects
				(font
					(size 1.016 1.016)
					(thickness 0.1524)
				)
			)
		)
		(duplicate_pad_numbers_are_jumpers no)
		(fp_line
			(start 0.508 -0.9398)
			(end -0.508 -0.9398)
			(stroke
				(width 0.1524)
				(type default)
			)
			(layer "F.SilkS")
		)
		(fp_line
			(start -0.508 -0.9398)
			(end -0.508 0.9398)
			(stroke
				(width 0.1524)
				(type default)
			)
			(layer "F.SilkS")
		)
		(fp_rect
			(start -0.508 0.9398)
			(end 0.508 -0.9398)
			(stroke
				(width 0)
				(type default)
			)
			(fill no)
			(layer "F.CrtYd")
		)
		(fp_rect
			(start -0.508 0.9398)
			(end 0.508 -0.9398)
			(stroke
				(width 0)
				(type default)
			)
			(fill no)
			(layer "F.Fab")
		)
		(pad "1" smd custom
			(at 0 -0.4445 180)
			(size 0.1397 0.1397)
			(layers "F.Cu" "F.Mask" "F.Paste")
			(net "P3V3_STBY")
			(options
				(clearance outline)
				(anchor circle)
			)
			(primitives
				(gr_poly
					(pts
						(arc
							(start -0.1778 -0.2794)
							(mid -0.249642 -0.249642)
							(end -0.2794 -0.1778)
						)
						(arc
							(start -0.2794 0.1778)
							(mid -0.249642 0.249642)
							(end -0.1778 0.2794)
						)
						(arc
							(start 0.1778 0.2794)
							(mid 0.249642 0.249642)
							(end 0.2794 0.1778)
						)
						(arc
							(start 0.2794 -0.1778)
							(mid 0.249642 -0.249642)
							(end 0.1778 -0.2794)
						)
					)
					(width 0)
					(fill yes)
				)
			)
		)
		(pad "2" smd custom
			(at 0 0.4445 180)
			(size 0.1397 0.1397)
			(layers "F.Cu" "F.Mask" "F.Paste")
			(net "PHY_ANEN")
			(options
				(clearance outline)
				(anchor circle)
			)
			(primitives
				(gr_poly
					(pts
						(arc
							(start -0.1778 -0.2794)
							(mid -0.249642 -0.249642)
							(end -0.2794 -0.1778)
						)
						(arc
							(start -0.2794 0.1778)
							(mid -0.249642 0.249642)
							(end -0.1778 0.2794)
						)
						(arc
							(start 0.1778 0.2794)
							(mid 0.249642 0.249642)
							(end 0.2794 0.1778)
						)
						(arc
							(start 0.2794 -0.1778)
							(mid 0.249642 -0.249642)
							(end 0.1778 -0.2794)
						)
					)
					(width 0)
					(fill yes)
				)
			)
		)
	)
	(footprint ""
		(layer "F.Cu")
		(at 26.112216 -214.43188 -90)
		(property "Reference" "SR270"
			(at 0 0 270)
			(layer "F.SilkS")
			(hide yes)
			(effects
				(font
					(size 1.27 1.27)
				)
			)
		)
		(property "Value" "4K7R2F-GP"
			(at 0.064008 -3.993896 270)
			(unlocked yes)
			(layer "F.Fab")
			(hide yes)
			(effects
				(font
					(size 1.016 1.016)
					(thickness 0.1524)
				)
			)
		)
		(property "Device Type" "R402H16"
			(at 0.064008 -5.517896 270)
			(unlocked yes)
			(layer "F.Fab")
			(hide yes)
			(effects
				(font
					(size 1.016 1.016)
					(thickness 0.1524)
				)
			)
		)
		(duplicate_pad_numbers_are_jumpers no)
		(fp_line
			(start -0.508 -0.9398)
			(end -0.508 0.9398)
			(stroke
				(width 0.1524)
				(type default)
			)
			(layer "F.SilkS")
		)
		(fp_line
			(start 0.508 -0.9398)
			(end -0.508 -0.9398)
			(stroke
				(width 0.1524)
				(type default)
			)
			(layer "F.SilkS")
		)
		(fp_rect
			(start -0.508 0.9398)
			(end 0.508 -0.9398)
			(stroke
				(width 0)
				(type default)
			)
			(fill no)
			(layer "F.CrtYd")
		)
		(fp_rect
			(start -0.508 0.9398)
			(end 0.508 -0.9398)
			(stroke
				(width 0)
				(type default)
			)
			(fill no)
			(layer "F.Fab")
		)
		(pad "1" smd custom
			(at 0 -0.4445 270)
			(size 0.1397 0.1397)
			(layers "F.Cu" "F.Mask" "F.Paste")
			(net "P1V8_E")
			(options
				(clearance outline)
				(anchor circle)
			)
			(primitives
				(gr_poly
					(pts
						(arc
							(start -0.1778 -0.2794)
							(mid -0.249642 -0.249642)
							(end -0.2794 -0.1778)
						)
						(arc
							(start -0.2794 0.1778)
							(mid -0.249642 0.249642)
							(end -0.1778 0.2794)
						)
						(arc
							(start 0.1778 0.2794)
							(mid 0.249642 0.249642)
							(end 0.2794 0.1778)
						)
						(arc
							(start 0.2794 -0.1778)
							(mid 0.249642 -0.249642)
							(end 0.1778 -0.2794)
						)
					)
					(width 0)
					(fill yes)
				)
			)
		)
		(pad "2" smd custom
			(at 0 0.4445 270)
			(size 0.1397 0.1397)
			(layers "F.Cu" "F.Mask" "F.Paste")
			(net "HDD_PWR_IO_INT_N")
			(options
				(clearance outline)
				(anchor circle)
			)
			(primitives
				(gr_poly
					(pts
						(arc
							(start -0.1778 -0.2794)
							(mid -0.249642 -0.249642)
							(end -0.2794 -0.1778)
						)
						(arc
							(start -0.2794 0.1778)
							(mid -0.249642 0.249642)
							(end -0.1778 0.2794)
						)
						(arc
							(start 0.1778 0.2794)
							(mid 0.249642 0.249642)
							(end 0.2794 0.1778)
						)
						(arc
							(start 0.2794 -0.1778)
							(mid 0.249642 -0.249642)
							(end 0.1778 -0.2794)
						)
					)
					(width 0)
					(fill yes)
				)
			)
		)
	)
	(footprint ""
		(layer "F.Cu")
		(at 255.778 -118.618 90)
		(property "Reference" "U46"
			(at 0 0 90)
			(layer "F.SilkS")
			(hide yes)
			(effects
				(font
					(size 1.27 1.27)
				)
			)
		)
		(property "Value" "SN74LVC1G08DCKR-GP"
			(at -2.3368 -8.6868 90)
			(unlocked yes)
			(layer "F.Fab")
			(hide yes)
			(effects
				(font
					(size 1.016 1.016)
					(thickness 0.1524)
				)
			)
		)
		(property "Device Type" "SC70-5H44"
			(at -2.3114 -10.414 90)
			(unlocked yes)
			(layer "F.Fab")
			(hide yes)
			(effects
				(font
					(size 1.016 1.016)
					(thickness 0.1524)
				)
			)
		)
		(duplicate_pad_numbers_are_jumpers no)
		(fp_line
			(start 1.3843 -1.8034)
			(end 1.3843 -1.1176)
			(stroke
				(width 0.3302)
				(type default)
			)
			(layer "F.SilkS")
		)
		(fp_line
			(start 0.6604 -1.8034)
			(end 1.3843 -1.8034)
			(stroke
				(width 0.3302)
				(type default)
			)
			(layer "F.SilkS")
		)
		(fp_line
			(start 1.27 -1.7018)
			(end 1.27 1.7018)
			(stroke
				(width 0.1524)
				(type default)
			)
			(layer "F.SilkS")
		)
		(fp_line
			(start -1.27 -1.7018)
			(end 1.27 -1.7018)
			(stroke
				(width 0.1524)
				(type default)
			)
			(layer "F.SilkS")
		)
		(fp_line
			(start 1.27 1.7018)
			(end -1.27 1.7018)
			(stroke
				(width 0.1524)
				(type default)
			)
			(layer "F.SilkS")
		)
		(fp_line
			(start -1.27 1.7018)
			(end -1.27 -1.7018)
			(stroke
				(width 0.1524)
				(type default)
			)
			(layer "F.SilkS")
		)
		(fp_rect
			(start -1.524 1.9558)
			(end 1.524 -1.9558)
			(stroke
				(width 0)
				(type default)
			)
			(fill no)
			(layer "F.CrtYd")
		)
		(fp_poly
			(pts
				(xy -1.524 -1.9558) (xy 1.524 -1.9558) (xy 1.524 1.9558) (xy -1.524 1.9558)
			)
			(stroke
				(width 0)
				(type default)
			)
			(fill no)
			(layer "F.Fab")
		)
		(pad "1" smd rect
			(at 0.65024 -0.8255 90)
			(size 0.4064 1.2192)
			(layers "F.Cu" "F.Mask" "F.Paste")
			(net "CPU_U192_PIN3_RX_R")
		)
		(pad "2" smd rect
			(at 0 -0.8255 90)
			(size 0.4064 1.2192)
			(layers "F.Cu" "F.Mask" "F.Paste")
			(net "CPU_U193_PIN3_RX_R")
		)
		(pad "3" smd rect
			(at -0.65024 -0.8255 90)
			(size 0.4064 1.2192)
			(layers "F.Cu" "F.Mask" "F.Paste")
			(net "GND")
		)
		(pad "4" smd rect
			(at -0.65024 0.8255 90)
			(size 0.4064 1.2192)
			(layers "F.Cu" "F.Mask" "F.Paste")
			(net "CPU_RXD_R")
		)
		(pad "5" smd rect
			(at 0.65024 0.8255 90)
			(size 0.4064 1.2192)
			(layers "F.Cu" "F.Mask" "F.Paste")
			(net "P3V3_STBY")
		)
	)
	(footprint ""
		(layer "F.Cu")
		(at 333.375 -217.3605)
		(property "Reference" "R184"
			(at 0 0 0)
			(layer "F.SilkS")
			(hide yes)
			(effects
				(font
					(size 1.27 1.27)
				)
			)
		)
		(property "Value" "0R2J-2-GP"
			(at 0.064008 -3.993896 0)
			(unlocked yes)
			(layer "F.Fab")
			(hide yes)
			(effects
				(font
					(size 1.016 1.016)
					(thickness 0.1524)
				)
			)
		)
		(property "Device Type" "R402H16"
			(at 0.064008 -5.517896 0)
			(unlocked yes)
			(layer "F.Fab")
			(hide yes)
			(effects
				(font
					(size 1.016 1.016)
					(thickness 0.1524)
				)
			)
		)
		(duplicate_pad_numbers_are_jumpers no)
		(fp_line
			(start -0.508 -0.9398)
			(end -0.508 0.9398)
			(stroke
				(width 0.1524)
				(type default)
			)
			(layer "F.SilkS")
		)
		(fp_line
			(start 0.508 -0.9398)
			(end -0.508 -0.9398)
			(stroke
				(width 0.1524)
				(type default)
			)
			(layer "F.SilkS")
		)
		(fp_rect
			(start -0.508 0.9398)
			(end 0.508 -0.9398)
			(stroke
				(width 0)
				(type default)
			)
			(fill no)
			(layer "F.CrtYd")
		)
		(fp_rect
			(start -0.508 0.9398)
			(end 0.508 -0.9398)
			(stroke
				(width 0)
				(type default)
			)
			(fill no)
			(layer "F.Fab")
		)
		(pad "1" smd custom
			(at 0 -0.4445)
			(size 0.1397 0.1397)
			(layers "F.Cu" "F.Mask" "F.Paste")
			(net "VOL_SEN_SDA")
			(options
				(clearance outline)
				(anchor circle)
			)
			(primitives
				(gr_poly
					(pts
						(arc
							(start -0.1778 -0.2794)
							(mid -0.249642 -0.249642)
							(end -0.2794 -0.1778)
						)
						(arc
							(start -0.2794 0.1778)
							(mid -0.249642 0.249642)
							(end -0.1778 0.2794)
						)
						(arc
							(start 0.1778 0.2794)
							(mid 0.249642 0.249642)
							(end 0.2794 0.1778)
						)
						(arc
							(start 0.2794 -0.1778)
							(mid 0.249642 -0.249642)
							(end 0.1778 -0.2794)
						)
					)
					(width 0)
					(fill yes)
				)
			)
		)
		(pad "2" smd custom
			(at 0 0.4445)
			(size 0.1397 0.1397)
			(layers "F.Cu" "F.Mask" "F.Paste")
			(net "BMC_I2C_A_SDA")
			(options
				(clearance outline)
				(anchor circle)
			)
			(primitives
				(gr_poly
					(pts
						(arc
							(start -0.1778 -0.2794)
							(mid -0.249642 -0.249642)
							(end -0.2794 -0.1778)
						)
						(arc
							(start -0.2794 0.1778)
							(mid -0.249642 0.249642)
							(end -0.1778 0.2794)
						)
						(arc
							(start 0.1778 0.2794)
							(mid 0.249642 0.249642)
							(end 0.2794 0.1778)
						)
						(arc
							(start 0.2794 -0.1778)
							(mid 0.249642 -0.249642)
							(end 0.1778 -0.2794)
						)
					)
					(width 0)
					(fill yes)
				)
			)
		)
	)
	(footprint ""
		(layer "F.Cu")
		(at 315.4934 -209.1944)
		(property "Reference" "C90"
			(at 0 0 0)
			(layer "F.SilkS")
			(hide yes)
			(effects
				(font
					(size 1.27 1.27)
				)
			)
		)
		(property "Value" "SCD1U16V2KX-3GP"
			(at 1.1811 -2.7051 0)
			(unlocked yes)
			(layer "F.Fab")
			(hide yes)
			(effects
				(font
					(size 1.016 1.016)
					(thickness 0.1524)
				)
			)
		)
		(property "Device Type" "C402H22"
			(at 1.1811 -4.2291 0)
			(unlocked yes)
			(layer "F.Fab")
			(hide yes)
			(effects
				(font
					(size 1.016 1.016)
					(thickness 0.1524)
				)
			)
		)
		(duplicate_pad_numbers_are_jumpers no)
		(fp_rect
			(start -0.4318 0.9525)
			(end 0.4318 -0.9525)
			(stroke
				(width 0)
				(type default)
			)
			(fill no)
			(layer "F.CrtYd")
		)
		(fp_rect
			(start -0.4318 0.9525)
			(end 0.4318 -0.9525)
			(stroke
				(width 0)
				(type default)
			)
			(fill no)
			(layer "F.Fab")
		)
		(pad "1" smd custom
			(at 0 -0.4445)
			(size 0.1524 0.1524)
			(layers "F.Cu" "F.Mask" "F.Paste")
			(net "P1V8_STBY")
			(options
				(clearance outline)
				(anchor circle)
			)
			(primitives
				(gr_poly
					(pts
						(arc
							(start 0.3048 -0.2032)
							(mid 0.275042 -0.275042)
							(end 0.2032 -0.3048)
						)
						(arc
							(start -0.2032 -0.3048)
							(mid -0.275042 -0.275042)
							(end -0.3048 -0.2032)
						)
						(arc
							(start -0.3048 0.2032)
							(mid -0.275042 0.275042)
							(end -0.2032 0.3048)
						)
						(arc
							(start 0.2032 0.3048)
							(mid 0.275042 0.275042)
							(end 0.3048 0.2032)
						)
					)
					(width 0)
					(fill yes)
				)
			)
		)
		(pad "2" smd custom
			(at 0 0.4445)
			(size 0.1524 0.1524)
			(layers "F.Cu" "F.Mask" "F.Paste")
			(net "GND")
			(options
				(clearance outline)
				(anchor circle)
			)
			(primitives
				(gr_poly
					(pts
						(arc
							(start 0.3048 -0.2032)
							(mid 0.275042 -0.275042)
							(end 0.2032 -0.3048)
						)
						(arc
							(start -0.2032 -0.3048)
							(mid -0.275042 -0.275042)
							(end -0.3048 -0.2032)
						)
						(arc
							(start -0.3048 0.2032)
							(mid -0.275042 0.275042)
							(end -0.2032 0.3048)
						)
						(arc
							(start 0.2032 0.3048)
							(mid 0.275042 0.275042)
							(end 0.3048 0.2032)
						)
					)
					(width 0)
					(fill yes)
				)
			)
		)
	)
	(footprint ""
		(layer "F.Cu")
		(at 291.837872 -59.889136 180)
		(property "Reference" "PQ1"
			(at 0 0 180)
			(layer "F.SilkS")
			(hide yes)
			(effects
				(font
					(size 1.27 1.27)
				)
			)
		)
		(property "Value" "AO4406AL-GP"
			(at -3.707384 -1.5367 180)
			(unlocked yes)
			(layer "F.Fab")
			(hide yes)
			(effects
				(font
					(size 1.016 1.016)
					(thickness 0.1524)
				)
			)
		)
		(property "Device Type" "SOIC8H69"
			(at -3.707384 -3.0607 180)
			(unlocked yes)
			(layer "F.Fab")
			(hide yes)
			(effects
				(font
					(size 1.016 1.016)
					(thickness 0.1524)
				)
			)
		)
		(duplicate_pad_numbers_are_jumpers no)
		(fp_line
			(start 2.1336 1.4224)
			(end 2.1336 -1.4224)
			(stroke
				(width 0.1524)
				(type default)
			)
			(layer "F.SilkS")
		)
		(fp_line
			(start 2.1336 -1.4224)
			(end -2.7432 -1.4224)
			(stroke
				(width 0.1524)
				(type default)
			)
			(layer "F.SilkS")
		)
		(fp_line
			(start -2.1844 -0.0508)
			(end -2.7178 0.508)
			(stroke
				(width 0.1524)
				(type default)
			)
			(layer "F.SilkS")
		)
		(fp_line
			(start -2.6289 3.4417)
			(end -2.6289 1.4732)
			(stroke
				(width 0.381)
				(type default)
			)
			(layer "F.SilkS")
		)
		(fp_line
			(start -2.7178 -0.508)
			(end -2.1844 -0.0508)
			(stroke
				(width 0.1524)
				(type default)
			)
			(layer "F.SilkS")
		)
		(fp_line
			(start -2.7432 1.4224)
			(end 2.1336 1.4224)
			(stroke
				(width 0.1524)
				(type default)
			)
			(layer "F.SilkS")
		)
		(fp_line
			(start -2.7432 1.4224)
			(end -2.6416 1.4224)
			(stroke
				(width 0.1524)
				(type default)
			)
			(layer "F.SilkS")
		)
		(fp_line
			(start -2.7432 -1.4224)
			(end -2.7432 1.4224)
			(stroke
				(width 0.1524)
				(type default)
			)
			(layer "F.SilkS")
		)
		(fp_poly
			(pts
				(xy -2.2098 -1.4224) (xy -2.2098 1.4224) (xy 2.2098 1.4224) (xy 2.2098 -1.4224)
			)
			(stroke
				(width 0)
				(type default)
			)
			(fill yes)
			(layer "F.SilkS")
		)
		(fp_rect
			(start -2.450084 2.999994)
			(end 2.450084 -2.999994)
			(stroke
				(width 0)
				(type default)
			)
			(fill no)
			(layer "F.CrtYd")
		)
		(fp_poly
			(pts
				(xy -2.8194 3.6322) (xy -2.8194 -3.6322) (xy 2.8194 -3.6322) (xy 2.8194 1.18364) (xy 2.450084 1.18364)
				(xy 2.450084 -2.999994) (xy -2.450084 -2.999994) (xy -2.450084 2.999994) (xy 2.450084 2.999994)
				(xy 2.450084 1.18618) (xy 2.8194 1.18618) (xy 2.8194 3.6322)
			)
			(stroke
				(width 0)
				(type default)
			)
			(fill no)
			(layer "F.CrtYd")
		)
		(fp_rect
			(start -2.8194 3.6322)
			(end 2.8194 -3.6322)
			(stroke
				(width 0)
				(type default)
			)
			(fill no)
			(layer "F.Fab")
		)
		(pad "1" smd rect
			(at -1.905 2.54 180)
			(size 0.635 1.651)
			(layers "F.Cu" "F.Mask" "F.Paste")
			(net "P3V3")
		)
		(pad "2" smd rect
			(at -0.635 2.54 180)
			(size 0.635 1.651)
			(layers "F.Cu" "F.Mask" "F.Paste")
			(net "P3V3")
		)
		(pad "3" smd rect
			(at 0.635 2.54 180)
			(size 0.635 1.651)
			(layers "F.Cu" "F.Mask" "F.Paste")
			(net "P3V3")
		)
		(pad "4" smd rect
			(at 1.905 2.54 180)
			(size 0.635 1.651)
			(layers "F.Cu" "F.Mask" "F.Paste")
			(net "P3V3_EN_LV")
		)
		(pad "5" smd rect
			(at 1.905 -2.54 180)
			(size 0.635 1.651)
			(layers "F.Cu" "F.Mask" "F.Paste")
			(net "P3V3_STBY")
		)
		(pad "6" smd rect
			(at 0.635 -2.54 180)
			(size 0.635 1.651)
			(layers "F.Cu" "F.Mask" "F.Paste")
			(net "P3V3_STBY")
		)
		(pad "7" smd rect
			(at -0.635 -2.54 180)
			(size 0.635 1.651)
			(layers "F.Cu" "F.Mask" "F.Paste")
			(net "P3V3_STBY")
		)
		(pad "8" smd rect
			(at -1.905 -2.54 180)
			(size 0.635 1.651)
			(layers "F.Cu" "F.Mask" "F.Paste")
			(net "P3V3_STBY")
		)
	)
	(footprint ""
		(layer "F.Cu")
		(at 95.89897 -95.377 -90)
		(property "Reference" "SR782"
			(at 0 0 270)
			(layer "F.SilkS")
			(hide yes)
			(effects
				(font
					(size 1.27 1.27)
				)
			)
		)
		(property "Value" "4K7R2F-GP"
			(at 0.064008 -3.993896 270)
			(unlocked yes)
			(layer "F.Fab")
			(hide yes)
			(effects
				(font
					(size 1.016 1.016)
					(thickness 0.1524)
				)
			)
		)
		(property "Device Type" "R402H16"
			(at 0.064008 -5.517896 270)
			(unlocked yes)
			(layer "F.Fab")
			(hide yes)
			(effects
				(font
					(size 1.016 1.016)
					(thickness 0.1524)
				)
			)
		)
		(duplicate_pad_numbers_are_jumpers no)
		(fp_line
			(start -0.508 -0.9398)
			(end -0.508 0.9398)
			(stroke
				(width 0.1524)
				(type default)
			)
			(layer "F.SilkS")
		)
		(fp_line
			(start 0.508 -0.9398)
			(end -0.508 -0.9398)
			(stroke
				(width 0.1524)
				(type default)
			)
			(layer "F.SilkS")
		)
		(fp_rect
			(start -0.508 0.9398)
			(end 0.508 -0.9398)
			(stroke
				(width 0)
				(type default)
			)
			(fill no)
			(layer "F.CrtYd")
		)
		(fp_rect
			(start -0.508 0.9398)
			(end 0.508 -0.9398)
			(stroke
				(width 0)
				(type default)
			)
			(fill no)
			(layer "F.Fab")
		)
		(pad "1" smd custom
			(at 0 -0.4445 270)
			(size 0.1397 0.1397)
			(layers "F.Cu" "F.Mask" "F.Paste")
			(net "EXP_XM_ADDR_25")
			(options
				(clearance outline)
				(anchor circle)
			)
			(primitives
				(gr_poly
					(pts
						(arc
							(start -0.1778 -0.2794)
							(mid -0.249642 -0.249642)
							(end -0.2794 -0.1778)
						)
						(arc
							(start -0.2794 0.1778)
							(mid -0.249642 0.249642)
							(end -0.1778 0.2794)
						)
						(arc
							(start 0.1778 0.2794)
							(mid 0.249642 0.249642)
							(end 0.2794 0.1778)
						)
						(arc
							(start 0.2794 -0.1778)
							(mid 0.249642 -0.249642)
							(end 0.1778 -0.2794)
						)
					)
					(width 0)
					(fill yes)
				)
			)
		)
		(pad "2" smd custom
			(at 0 0.4445 270)
			(size 0.1397 0.1397)
			(layers "F.Cu" "F.Mask" "F.Paste")
			(net "GND")
			(options
				(clearance outline)
				(anchor circle)
			)
			(primitives
				(gr_poly
					(pts
						(arc
							(start -0.1778 -0.2794)
							(mid -0.249642 -0.249642)
							(end -0.2794 -0.1778)
						)
						(arc
							(start -0.2794 0.1778)
							(mid -0.249642 0.249642)
							(end -0.1778 0.2794)
						)
						(arc
							(start 0.1778 0.2794)
							(mid 0.249642 0.249642)
							(end 0.2794 0.1778)
						)
						(arc
							(start 0.2794 -0.1778)
							(mid 0.249642 -0.249642)
							(end 0.1778 -0.2794)
						)
					)
					(width 0)
					(fill yes)
				)
			)
		)
	)
	(footprint ""
		(layer "F.Cu")
		(at 324.739 -141.478 90)
		(property "Reference" "X2"
			(at 0 0 90)
			(layer "F.SilkS")
			(hide yes)
			(effects
				(font
					(size 1.27 1.27)
				)
			)
		)
		(property "Value" "X-32D768KHZ-56GP"
			(at 0 -5.0292 90)
			(unlocked yes)
			(layer "F.Fab")
			(hide yes)
			(effects
				(font
					(size 1.016 1.016)
					(thickness 0.1524)
				)
			)
		)
		(property "Device Type" "DST310SH34"
			(at 0 -6.5532 90)
			(unlocked yes)
			(layer "F.Fab")
			(hide yes)
			(effects
				(font
					(size 1.016 1.016)
					(thickness 0.1524)
				)
			)
		)
		(duplicate_pad_numbers_are_jumpers no)
		(fp_line
			(start 1.1303 -2.2479)
			(end 1.1303 2.2479)
			(stroke
				(width 0.1524)
				(type default)
			)
			(layer "F.SilkS")
		)
		(fp_line
			(start -1.1303 -2.2479)
			(end 1.1303 -2.2479)
			(stroke
				(width 0.1524)
				(type default)
			)
			(layer "F.SilkS")
		)
		(fp_line
			(start 1.1303 2.2479)
			(end -1.1303 2.2479)
			(stroke
				(width 0.1524)
				(type default)
			)
			(layer "F.SilkS")
		)
		(fp_line
			(start -1.1303 2.2479)
			(end -1.1303 -2.2479)
			(stroke
				(width 0.1524)
				(type default)
			)
			(layer "F.SilkS")
		)
		(fp_rect
			(start -1.3843 2.5019)
			(end 1.3843 -2.5019)
			(stroke
				(width 0)
				(type default)
			)
			(fill no)
			(layer "F.CrtYd")
		)
		(fp_rect
			(start -1.3843 2.5019)
			(end 1.3843 -2.5019)
			(stroke
				(width 0)
				(type default)
			)
			(fill no)
			(layer "F.Fab")
		)
		(pad "1" smd rect
			(at 0 -1.294384 90)
			(size 1.7526 1.397)
			(layers "F.Cu" "F.Mask" "F.Paste")
			(net "RTC_OSCI")
		)
		(pad "2" smd rect
			(at 0 1.294384 90)
			(size 1.7526 1.397)
			(layers "F.Cu" "F.Mask" "F.Paste")
			(net "RTC_OSCO")
		)
	)
	(footprint ""
		(layer "F.Cu")
		(at 265.675872 -44.903136 180)
		(property "Reference" "PC46"
			(at 0 0 180)
			(layer "F.SilkS")
			(hide yes)
			(effects
				(font
					(size 1.27 1.27)
				)
			)
		)
		(property "Value" "SC4D7U25V5KX-1-GP"
			(at -0.0762 -6.1214 180)
			(unlocked yes)
			(layer "F.Fab")
			(hide yes)
			(effects
				(font
					(size 1.016 1.016)
					(thickness 0.1524)
				)
			)
		)
		(property "Device Type" "C805H58"
			(at -0.0762 -8.1534 180)
			(unlocked yes)
			(layer "F.Fab")
			(hide yes)
			(effects
				(font
					(size 1.016 1.016)
					(thickness 0.1524)
				)
			)
		)
		(duplicate_pad_numbers_are_jumpers no)
		(fp_line
			(start 0.635 0)
			(end -0.635 0)
			(stroke
				(width 0.508)
				(type default)
			)
			(layer "F.SilkS")
		)
		(fp_rect
			(start -0.9652 1.778)
			(end 0.9652 -1.778)
			(stroke
				(width 0)
				(type default)
			)
			(fill no)
			(layer "F.CrtYd")
		)
		(fp_poly
			(pts
				(xy -0.9652 -1.778) (xy 0.9652 -1.778) (xy 0.9652 1.778) (xy -0.9652 1.778)
			)
			(stroke
				(width 0)
				(type default)
			)
			(fill no)
			(layer "F.Fab")
		)
		(pad "1" smd rect
			(at 0 -0.9652 180)
			(size 1.397 1.143)
			(layers "F.Cu" "F.Mask" "F.Paste")
			(net "P1V8_STBY_VDD")
		)
		(pad "2" smd rect
			(at 0 0.9652 180)
			(size 1.397 1.143)
			(layers "F.Cu" "F.Mask" "F.Paste")
			(net "GND")
		)
	)
	(footprint ""
		(layer "F.Cu")
		(at 132.72897 -98.806 180)
		(property "Reference" "SC1271"
			(at 0 0 180)
			(layer "F.SilkS")
			(hide yes)
			(effects
				(font
					(size 1.27 1.27)
				)
			)
		)
		(property "Value" "SCD01U10V1KX-GP"
			(at -2.8321 -1.7399 180)
			(unlocked yes)
			(layer "F.Fab")
			(hide yes)
			(effects
				(font
					(size 1.016 1.016)
					(thickness 0.1524)
				)
			)
		)
		(property "Device Type" "C0201H13"
			(at -2.8321 -3.2639 180)
			(unlocked yes)
			(layer "F.Fab")
			(hide yes)
			(effects
				(font
					(size 1.016 1.016)
					(thickness 0.1524)
				)
			)
		)
		(duplicate_pad_numbers_are_jumpers no)
		(fp_rect
			(start -0.2794 0.6477)
			(end 0.2794 -0.6477)
			(stroke
				(width 0)
				(type default)
			)
			(fill no)
			(layer "F.CrtYd")
		)
		(fp_rect
			(start -0.2794 0.6477)
			(end 0.2794 -0.6477)
			(stroke
				(width 0)
				(type default)
			)
			(fill no)
			(layer "F.Fab")
		)
		(pad "1" smd custom
			(at 0 -0.2794 180)
			(size 0.0762 0.0762)
			(layers "F.Cu" "F.Mask" "F.Paste")
			(net "3X24_SAS_TX22_N")
			(options
				(clearance outline)
				(anchor circle)
			)
			(primitives
				(gr_poly
					(pts
						(arc
							(start 0.1524 -0.127)
							(mid 0.137521 -0.162921)
							(end 0.1016 -0.1778)
						)
						(arc
							(start -0.1016 -0.1778)
							(mid -0.137521 -0.162921)
							(end -0.1524 -0.127)
						)
						(arc
							(start -0.1524 0.127)
							(mid -0.137521 0.162921)
							(end -0.1016 0.1778)
						)
						(arc
							(start 0.1016 0.1778)
							(mid 0.137521 0.162921)
							(end 0.1524 0.127)
						)
					)
					(width 0)
					(fill yes)
				)
			)
		)
		(pad "2" smd custom
			(at 0 0.2794 180)
			(size 0.0762 0.0762)
			(layers "F.Cu" "F.Mask" "F.Paste")
			(net "SAS_EXP_GF_TX_DN2")
			(options
				(clearance outline)
				(anchor circle)
			)
			(primitives
				(gr_poly
					(pts
						(arc
							(start 0.1524 -0.127)
							(mid 0.137521 -0.162921)
							(end 0.1016 -0.1778)
						)
						(arc
							(start -0.1016 -0.1778)
							(mid -0.137521 -0.162921)
							(end -0.1524 -0.127)
						)
						(arc
							(start -0.1524 0.127)
							(mid -0.137521 0.162921)
							(end -0.1016 0.1778)
						)
						(arc
							(start 0.1016 0.1778)
							(mid 0.137521 0.162921)
							(end 0.1524 0.127)
						)
					)
					(width 0)
					(fill yes)
				)
			)
		)
	)
	(footprint ""
		(layer "F.Cu")
		(at 16.079216 -181.91988)
		(property "Reference" "R648"
			(at 0 0 0)
			(layer "F.SilkS")
			(hide yes)
			(effects
				(font
					(size 1.27 1.27)
				)
			)
		)
		(property "Value" "4K7R2F-GP"
			(at 0.064008 -3.993896 0)
			(unlocked yes)
			(layer "F.Fab")
			(hide yes)
			(effects
				(font
					(size 1.016 1.016)
					(thickness 0.1524)
				)
			)
		)
		(property "Device Type" "R402H16"
			(at 0.064008 -5.517896 0)
			(unlocked yes)
			(layer "F.Fab")
			(hide yes)
			(effects
				(font
					(size 1.016 1.016)
					(thickness 0.1524)
				)
			)
		)
		(duplicate_pad_numbers_are_jumpers no)
		(fp_line
			(start -0.508 -0.9398)
			(end -0.508 0.9398)
			(stroke
				(width 0.1524)
				(type default)
			)
			(layer "F.SilkS")
		)
		(fp_line
			(start 0.508 -0.9398)
			(end -0.508 -0.9398)
			(stroke
				(width 0.1524)
				(type default)
			)
			(layer "F.SilkS")
		)
		(fp_rect
			(start -0.508 0.9398)
			(end 0.508 -0.9398)
			(stroke
				(width 0)
				(type default)
			)
			(fill no)
			(layer "F.CrtYd")
		)
		(fp_rect
			(start -0.508 0.9398)
			(end 0.508 -0.9398)
			(stroke
				(width 0)
				(type default)
			)
			(fill no)
			(layer "F.Fab")
		)
		(pad "1" smd custom
			(at 0 -0.4445)
			(size 0.1397 0.1397)
			(layers "F.Cu" "F.Mask" "F.Paste")
			(net "IO_EXP_HDD_PRE_A2")
			(options
				(clearance outline)
				(anchor circle)
			)
			(primitives
				(gr_poly
					(pts
						(arc
							(start -0.1778 -0.2794)
							(mid -0.249642 -0.249642)
							(end -0.2794 -0.1778)
						)
						(arc
							(start -0.2794 0.1778)
							(mid -0.249642 0.249642)
							(end -0.1778 0.2794)
						)
						(arc
							(start 0.1778 0.2794)
							(mid 0.249642 0.249642)
							(end 0.2794 0.1778)
						)
						(arc
							(start 0.2794 -0.1778)
							(mid 0.249642 -0.249642)
							(end 0.1778 -0.2794)
						)
					)
					(width 0)
					(fill yes)
				)
			)
		)
		(pad "2" smd custom
			(at 0 0.4445)
			(size 0.1397 0.1397)
			(layers "F.Cu" "F.Mask" "F.Paste")
			(net "GND")
			(options
				(clearance outline)
				(anchor circle)
			)
			(primitives
				(gr_poly
					(pts
						(arc
							(start -0.1778 -0.2794)
							(mid -0.249642 -0.249642)
							(end -0.2794 -0.1778)
						)
						(arc
							(start -0.2794 0.1778)
							(mid -0.249642 0.249642)
							(end -0.1778 0.2794)
						)
						(arc
							(start 0.1778 0.2794)
							(mid 0.249642 0.249642)
							(end 0.2794 0.1778)
						)
						(arc
							(start 0.2794 -0.1778)
							(mid 0.249642 -0.249642)
							(end 0.1778 -0.2794)
						)
					)
					(width 0)
					(fill yes)
				)
			)
		)
	)
	(footprint ""
		(layer "F.Cu")
		(at 208.391252 -111.64316)
		(property "Reference" "PC227"
			(at 0 0 0)
			(layer "F.SilkS")
			(hide yes)
			(effects
				(font
					(size 1.27 1.27)
				)
			)
		)
		(property "Value" "SC22U25V5MX-GP"
			(at -0.0762 -6.1214 0)
			(unlocked yes)
			(layer "F.Fab")
			(hide yes)
			(effects
				(font
					(size 1.016 1.016)
					(thickness 0.1524)
				)
			)
		)
		(property "Device Type" "C805H58"
			(at -0.0762 -8.1534 0)
			(unlocked yes)
			(layer "F.Fab")
			(hide yes)
			(effects
				(font
					(size 1.016 1.016)
					(thickness 0.1524)
				)
			)
		)
		(duplicate_pad_numbers_are_jumpers no)
		(fp_line
			(start 0.635 0)
			(end -0.635 0)
			(stroke
				(width 0.508)
				(type default)
			)
			(layer "F.SilkS")
		)
		(fp_rect
			(start -0.9652 1.778)
			(end 0.9652 -1.778)
			(stroke
				(width 0)
				(type default)
			)
			(fill no)
			(layer "F.CrtYd")
		)
		(fp_poly
			(pts
				(xy -0.9652 -1.778) (xy 0.9652 -1.778) (xy 0.9652 1.778) (xy -0.9652 1.778)
			)
			(stroke
				(width 0)
				(type default)
			)
			(fill no)
			(layer "F.Fab")
		)
		(pad "1" smd rect
			(at 0 -0.9652)
			(size 1.397 1.143)
			(layers "F.Cu" "F.Mask" "F.Paste")
			(net "P1V5_E_VIN")
		)
		(pad "2" smd rect
			(at 0 0.9652)
			(size 1.397 1.143)
			(layers "F.Cu" "F.Mask" "F.Paste")
			(net "GND")
		)
	)
	(footprint ""
		(layer "F.Cu")
		(at 319.913 -167.894 -90)
		(property "Reference" "R440"
			(at 0 0 270)
			(layer "F.SilkS")
			(hide yes)
			(effects
				(font
					(size 1.27 1.27)
				)
			)
		)
		(property "Value" "10KR2F-2-GP"
			(at 0.064008 -3.993896 270)
			(unlocked yes)
			(layer "F.Fab")
			(hide yes)
			(effects
				(font
					(size 1.016 1.016)
					(thickness 0.1524)
				)
			)
		)
		(property "Device Type" "R402H16"
			(at 0.064008 -5.517896 270)
			(unlocked yes)
			(layer "F.Fab")
			(hide yes)
			(effects
				(font
					(size 1.016 1.016)
					(thickness 0.1524)
				)
			)
		)
		(duplicate_pad_numbers_are_jumpers no)
		(fp_line
			(start -0.508 -0.9398)
			(end -0.508 0.9398)
			(stroke
				(width 0.1524)
				(type default)
			)
			(layer "F.SilkS")
		)
		(fp_line
			(start 0.508 -0.9398)
			(end -0.508 -0.9398)
			(stroke
				(width 0.1524)
				(type default)
			)
			(layer "F.SilkS")
		)
		(fp_rect
			(start -0.508 0.9398)
			(end 0.508 -0.9398)
			(stroke
				(width 0)
				(type default)
			)
			(fill no)
			(layer "F.CrtYd")
		)
		(fp_rect
			(start -0.508 0.9398)
			(end 0.508 -0.9398)
			(stroke
				(width 0)
				(type default)
			)
			(fill no)
			(layer "F.Fab")
		)
		(pad "1" smd custom
			(at 0 -0.4445 270)
			(size 0.1397 0.1397)
			(layers "F.Cu" "F.Mask" "F.Paste")
			(net "P3V3_STBY")
			(options
				(clearance outline)
				(anchor circle)
			)
			(primitives
				(gr_poly
					(pts
						(arc
							(start -0.1778 -0.2794)
							(mid -0.249642 -0.249642)
							(end -0.2794 -0.1778)
						)
						(arc
							(start -0.2794 0.1778)
							(mid -0.249642 0.249642)
							(end -0.1778 0.2794)
						)
						(arc
							(start 0.1778 0.2794)
							(mid 0.249642 0.249642)
							(end 0.2794 0.1778)
						)
						(arc
							(start 0.2794 -0.1778)
							(mid 0.249642 -0.249642)
							(end 0.1778 -0.2794)
						)
					)
					(width 0)
					(fill yes)
				)
			)
		)
		(pad "2" smd custom
			(at 0 0.4445 270)
			(size 0.1397 0.1397)
			(layers "F.Cu" "F.Mask" "F.Paste")
			(net "BMC_I2C_B_SDA")
			(options
				(clearance outline)
				(anchor circle)
			)
			(primitives
				(gr_poly
					(pts
						(arc
							(start -0.1778 -0.2794)
							(mid -0.249642 -0.249642)
							(end -0.2794 -0.1778)
						)
						(arc
							(start -0.2794 0.1778)
							(mid -0.249642 0.249642)
							(end -0.1778 0.2794)
						)
						(arc
							(start 0.1778 0.2794)
							(mid 0.249642 0.249642)
							(end 0.2794 0.1778)
						)
						(arc
							(start 0.2794 -0.1778)
							(mid 0.249642 -0.249642)
							(end 0.1778 -0.2794)
						)
					)
					(width 0)
					(fill yes)
				)
			)
		)
	)
	(footprint ""
		(layer "F.Cu")
		(at 116.332 -72.771 90)
		(property "Reference" "TP171"
			(at 0 0 90)
			(layer "F.SilkS")
			(hide yes)
			(effects
				(font
					(size 1.27 1.27)
				)
			)
		)
		(property "Value" "TPAD32-GP"
			(at 0 -3.166364 90)
			(unlocked yes)
			(layer "F.Fab")
			(hide yes)
			(effects
				(font
					(size 1.016 1.016)
					(thickness 0.1524)
				)
			)
		)
		(property "Device Type" "TPAD32"
			(at 0 -4.690618 90)
			(unlocked yes)
			(layer "F.Fab")
			(hide yes)
			(effects
				(font
					(size 1.016 1.016)
					(thickness 0.1524)
				)
			)
		)
		(duplicate_pad_numbers_are_jumpers no)
		(fp_poly
			(pts
				(arc
					(start 0 0.4064)
					(mid 0 -0.4064)
					(end 0 0.4064)
				)
			)
			(stroke
				(width 0)
				(type default)
			)
			(fill no)
			(layer "F.CrtYd")
		)
		(fp_poly
			(pts
				(arc
					(start 0 0.7112)
					(mid 0 -0.7112)
					(end 0 0.7112)
				)
			)
			(stroke
				(width 0)
				(type default)
			)
			(fill no)
			(layer "F.Fab")
		)
		(pad "1" smd circle
			(at 0 0 90)
			(size 0.8128 0.8128)
			(layers "F.Cu" "F.Mask" "F.Paste")
			(net "TEMP_4_ALERT")
		)
	)
	(footprint ""
		(layer "F.Cu")
		(at 330.399136 -211.463128 180)
		(property "Reference" "C152"
			(at 0 0 180)
			(layer "F.SilkS")
			(hide yes)
			(effects
				(font
					(size 1.27 1.27)
				)
			)
		)
		(property "Value" "SCD1U16V2JX-1-GP"
			(at 1.1811 -2.7051 180)
			(unlocked yes)
			(layer "F.Fab")
			(hide yes)
			(effects
				(font
					(size 1.016 1.016)
					(thickness 0.1524)
				)
			)
		)
		(property "Device Type" "C402H22"
			(at 1.1811 -4.2291 180)
			(unlocked yes)
			(layer "F.Fab")
			(hide yes)
			(effects
				(font
					(size 1.016 1.016)
					(thickness 0.1524)
				)
			)
		)
		(duplicate_pad_numbers_are_jumpers no)
		(fp_rect
			(start -0.4318 0.9525)
			(end 0.4318 -0.9525)
			(stroke
				(width 0)
				(type default)
			)
			(fill no)
			(layer "F.CrtYd")
		)
		(fp_rect
			(start -0.4318 0.9525)
			(end 0.4318 -0.9525)
			(stroke
				(width 0)
				(type default)
			)
			(fill no)
			(layer "F.Fab")
		)
		(pad "1" smd custom
			(at 0 -0.4445 180)
			(size 0.1524 0.1524)
			(layers "F.Cu" "F.Mask" "F.Paste")
			(net "P3V3_STBY")
			(options
				(clearance outline)
				(anchor circle)
			)
			(primitives
				(gr_poly
					(pts
						(arc
							(start 0.3048 -0.2032)
							(mid 0.275042 -0.275042)
							(end 0.2032 -0.3048)
						)
						(arc
							(start -0.2032 -0.3048)
							(mid -0.275042 -0.275042)
							(end -0.3048 -0.2032)
						)
						(arc
							(start -0.3048 0.2032)
							(mid -0.275042 0.275042)
							(end -0.2032 0.3048)
						)
						(arc
							(start 0.2032 0.3048)
							(mid 0.275042 0.275042)
							(end 0.3048 0.2032)
						)
					)
					(width 0)
					(fill yes)
				)
			)
		)
		(pad "2" smd custom
			(at 0 0.4445 180)
			(size 0.1524 0.1524)
			(layers "F.Cu" "F.Mask" "F.Paste")
			(net "GND")
			(options
				(clearance outline)
				(anchor circle)
			)
			(primitives
				(gr_poly
					(pts
						(arc
							(start 0.3048 -0.2032)
							(mid 0.275042 -0.275042)
							(end 0.2032 -0.3048)
						)
						(arc
							(start -0.2032 -0.3048)
							(mid -0.275042 -0.275042)
							(end -0.3048 -0.2032)
						)
						(arc
							(start -0.3048 0.2032)
							(mid -0.275042 0.275042)
							(end -0.2032 0.3048)
						)
						(arc
							(start 0.2032 0.3048)
							(mid 0.275042 0.275042)
							(end 0.3048 0.2032)
						)
					)
					(width 0)
					(fill yes)
				)
			)
		)
	)
	(footprint ""
		(layer "F.Cu")
		(at 172.675804 -25.152096 90)
		(property "Reference" "R388"
			(at 0 0 90)
			(layer "F.SilkS")
			(hide yes)
			(effects
				(font
					(size 1.27 1.27)
				)
			)
		)
		(property "Value" "0R2J-2-GP"
			(at 0.064008 -3.993896 90)
			(unlocked yes)
			(layer "F.Fab")
			(hide yes)
			(effects
				(font
					(size 1.016 1.016)
					(thickness 0.1524)
				)
			)
		)
		(property "Device Type" "R402H16"
			(at 0.064008 -5.517896 90)
			(unlocked yes)
			(layer "F.Fab")
			(hide yes)
			(effects
				(font
					(size 1.016 1.016)
					(thickness 0.1524)
				)
			)
		)
		(duplicate_pad_numbers_are_jumpers no)
		(fp_line
			(start 0.508 -0.9398)
			(end -0.508 -0.9398)
			(stroke
				(width 0.1524)
				(type default)
			)
			(layer "F.SilkS")
		)
		(fp_line
			(start -0.508 -0.9398)
			(end -0.508 0.9398)
			(stroke
				(width 0.1524)
				(type default)
			)
			(layer "F.SilkS")
		)
		(fp_rect
			(start -0.508 0.9398)
			(end 0.508 -0.9398)
			(stroke
				(width 0)
				(type default)
			)
			(fill no)
			(layer "F.CrtYd")
		)
		(fp_rect
			(start -0.508 0.9398)
			(end 0.508 -0.9398)
			(stroke
				(width 0)
				(type default)
			)
			(fill no)
			(layer "F.Fab")
		)
		(pad "1" smd custom
			(at 0 -0.4445 90)
			(size 0.1397 0.1397)
			(layers "F.Cu" "F.Mask" "F.Paste")
			(net "BCM5221_MB_TX_DP")
			(options
				(clearance outline)
				(anchor circle)
			)
			(primitives
				(gr_poly
					(pts
						(arc
							(start -0.1778 -0.2794)
							(mid -0.249642 -0.249642)
							(end -0.2794 -0.1778)
						)
						(arc
							(start -0.2794 0.1778)
							(mid -0.249642 0.249642)
							(end -0.1778 0.2794)
						)
						(arc
							(start 0.1778 0.2794)
							(mid 0.249642 0.249642)
							(end 0.2794 0.1778)
						)
						(arc
							(start 0.2794 -0.1778)
							(mid 0.249642 -0.249642)
							(end 0.1778 -0.2794)
						)
					)
					(width 0)
					(fill yes)
				)
			)
		)
		(pad "2" smd custom
			(at 0 0.4445 90)
			(size 0.1397 0.1397)
			(layers "F.Cu" "F.Mask" "F.Paste")
			(net "BCM5221_TX_C_DP")
			(options
				(clearance outline)
				(anchor circle)
			)
			(primitives
				(gr_poly
					(pts
						(arc
							(start -0.1778 -0.2794)
							(mid -0.249642 -0.249642)
							(end -0.2794 -0.1778)
						)
						(arc
							(start -0.2794 0.1778)
							(mid -0.249642 0.249642)
							(end -0.1778 0.2794)
						)
						(arc
							(start 0.1778 0.2794)
							(mid 0.249642 0.249642)
							(end 0.2794 0.1778)
						)
						(arc
							(start 0.2794 -0.1778)
							(mid 0.249642 -0.249642)
							(end 0.1778 -0.2794)
						)
					)
					(width 0)
					(fill yes)
				)
			)
		)
	)
	(footprint ""
		(layer "F.Cu")
		(at 152.247092 -112.043464 -90)
		(property "Reference" "SR832"
			(at 0 0 270)
			(layer "F.SilkS")
			(hide yes)
			(effects
				(font
					(size 1.27 1.27)
				)
			)
		)
		(property "Value" "D51R3F-2-GP"
			(at -0.0254 -2.5146 270)
			(unlocked yes)
			(layer "F.Fab")
			(hide yes)
			(effects
				(font
					(size 1.016 1.016)
					(thickness 0.1524)
				)
			)
		)
		(property "Device Type" "R603H22"
			(at -0.0254 -4.0386 270)
			(unlocked yes)
			(layer "F.Fab")
			(hide yes)
			(effects
				(font
					(size 1.016 1.016)
					(thickness 0.1524)
				)
			)
		)
		(duplicate_pad_numbers_are_jumpers no)
		(fp_line
			(start -0.4826 0)
			(end -0.2032 0)
			(stroke
				(width 0.2032)
				(type default)
			)
			(layer "F.SilkS")
		)
		(fp_line
			(start 0.2032 0)
			(end 0.4826 0)
			(stroke
				(width 0.2032)
				(type default)
			)
			(layer "F.SilkS")
		)
		(fp_rect
			(start -0.5842 1.3335)
			(end 0.5842 -1.3335)
			(stroke
				(width 0)
				(type default)
			)
			(fill no)
			(layer "F.CrtYd")
		)
		(fp_rect
			(start -0.5842 1.3335)
			(end 0.5842 -1.3335)
			(stroke
				(width 0)
				(type default)
			)
			(fill no)
			(layer "F.Fab")
		)
		(pad "1" smd custom
			(at 0 -0.762 270)
			(size 0.2159 0.2159)
			(layers "F.Cu" "F.Mask" "F.Paste")
			(net "P0V9_E")
			(options
				(clearance outline)
				(anchor circle)
			)
			(primitives
				(gr_poly
					(pts
						(arc
							(start -0.3302 -0.4318)
							(mid -0.402042 -0.402042)
							(end -0.4318 -0.3302)
						)
						(arc
							(start -0.4318 0.3302)
							(mid -0.402042 0.402042)
							(end -0.3302 0.4318)
						)
						(arc
							(start 0.3302 0.4318)
							(mid 0.402042 0.402042)
							(end 0.4318 0.3302)
						)
						(arc
							(start 0.4318 -0.3302)
							(mid 0.402042 -0.402042)
							(end 0.3302 -0.4318)
						)
					)
					(width 0)
					(fill yes)
				)
			)
		)
		(pad "2" smd custom
			(at 0 0.762 270)
			(size 0.2159 0.2159)
			(layers "F.Cu" "F.Mask" "F.Paste")
			(net "GB_VDDA")
			(options
				(clearance outline)
				(anchor circle)
			)
			(primitives
				(gr_poly
					(pts
						(arc
							(start -0.3302 -0.4318)
							(mid -0.402042 -0.402042)
							(end -0.4318 -0.3302)
						)
						(arc
							(start -0.4318 0.3302)
							(mid -0.402042 0.402042)
							(end -0.3302 0.4318)
						)
						(arc
							(start 0.3302 0.4318)
							(mid 0.402042 0.402042)
							(end 0.4318 0.3302)
						)
						(arc
							(start 0.4318 -0.3302)
							(mid 0.402042 -0.402042)
							(end 0.3302 -0.4318)
						)
					)
					(width 0)
					(fill yes)
				)
			)
		)
	)
	(footprint ""
		(layer "F.Cu")
		(at 290.898072 -199.335136 -90)
		(property "Reference" "U18"
			(at 0 0 270)
			(layer "F.SilkS")
			(hide yes)
			(effects
				(font
					(size 1.27 1.27)
				)
			)
		)
		(property "Value" "NT5CB64M16FP-DH-GP"
			(at -8.221218 -0.6731 270)
			(unlocked yes)
			(layer "F.Fab")
			(hide yes)
			(effects
				(font
					(size 1.016 1.016)
					(thickness 0.1524)
				)
			)
		)
		(property "Device Type" "BGA96D0913H48"
			(at -8.221218 -2.1971 270)
			(unlocked yes)
			(layer "F.Fab")
			(hide yes)
			(effects
				(font
					(size 1.016 1.016)
					(thickness 0.1524)
				)
			)
		)
		(duplicate_pad_numbers_are_jumpers no)
		(fp_line
			(start -4.500118 6.500114)
			(end 4.500118 6.500114)
			(stroke
				(width 0.1524)
				(type default)
			)
			(layer "F.SilkS")
		)
		(fp_line
			(start 4.500118 6.500114)
			(end 4.500118 -6.500114)
			(stroke
				(width 0.1524)
				(type default)
			)
			(layer "F.SilkS")
		)
		(fp_line
			(start -4.830318 -5.230114)
			(end -4.830318 -6.830314)
			(stroke
				(width 0.508)
				(type default)
			)
			(layer "F.SilkS")
		)
		(fp_line
			(start -4.500118 -6.500114)
			(end -4.500118 6.500114)
			(stroke
				(width 0.1524)
				(type default)
			)
			(layer "F.SilkS")
		)
		(fp_line
			(start 4.500118 -6.500114)
			(end -4.500118 -6.500114)
			(stroke
				(width 0.1524)
				(type default)
			)
			(layer "F.SilkS")
		)
		(fp_line
			(start -4.830318 -6.830314)
			(end -3.230118 -6.830314)
			(stroke
				(width 0.508)
				(type default)
			)
			(layer "F.SilkS")
		)
		(fp_rect
			(start -4.500118 6.500114)
			(end 4.500118 -6.500114)
			(stroke
				(width 0)
				(type default)
			)
			(fill no)
			(layer "F.CrtYd")
		)
		(fp_poly
			(pts
				(xy -5.500116 7.500112) (xy -5.500116 -7.500112) (xy 5.500116 -7.500112) (xy 5.500116 -0.0254) (xy 4.500118 -0.0254)
				(xy 4.500118 -6.500114) (xy -4.500118 -6.500114) (xy -4.500118 6.500114) (xy 4.500118 6.500114)
				(xy 4.500118 -0.0127) (xy 5.500116 -0.0127) (xy 5.500116 7.500112)
			)
			(stroke
				(width 0)
				(type default)
			)
			(fill no)
			(layer "F.CrtYd")
		)
		(fp_rect
			(start -6.500114 8.50011)
			(end 6.500114 -8.50011)
			(stroke
				(width 0)
				(type default)
			)
			(fill no)
			(layer "F.Fab")
		)
		(pad "A1" smd circle
			(at -3.199892 -5.999988 270)
			(size 0.3556 0.3556)
			(layers "F.Cu" "F.Mask" "F.Paste")
			(net "P1V53_STBY")
		)
		(pad "A2" smd circle
			(at -2.400046 -5.999988 270)
			(size 0.3556 0.3556)
			(layers "F.Cu" "F.Mask" "F.Paste")
			(net "MEMDQ_15")
		)
		(pad "A3" smd circle
			(at -1.599946 -5.999988 270)
			(size 0.3556 0.3556)
			(layers "F.Cu" "F.Mask" "F.Paste")
			(net "MEMDQ_14")
		)
		(pad "A7" smd circle
			(at 1.599946 -5.999988 270)
			(size 0.3556 0.3556)
			(layers "F.Cu" "F.Mask" "F.Paste")
			(net "MEMDQ_10")
		)
		(pad "A8" smd circle
			(at 2.400046 -5.999988 270)
			(size 0.3556 0.3556)
			(layers "F.Cu" "F.Mask" "F.Paste")
			(net "P1V53_STBY")
		)
		(pad "A9" smd circle
			(at 3.199892 -5.999988 270)
			(size 0.3556 0.3556)
			(layers "F.Cu" "F.Mask" "F.Paste")
			(net "GND")
		)
		(pad "B1" smd circle
			(at -3.199892 -5.199888 270)
			(size 0.3556 0.3556)
			(layers "F.Cu" "F.Mask" "F.Paste")
			(net "GND")
		)
		(pad "B2" smd circle
			(at -2.400046 -5.199888 270)
			(size 0.3556 0.3556)
			(layers "F.Cu" "F.Mask" "F.Paste")
			(net "P1V53_STBY")
		)
		(pad "B3" smd circle
			(at -1.599946 -5.199888 270)
			(size 0.3556 0.3556)
			(layers "F.Cu" "F.Mask" "F.Paste")
			(net "GND")
		)
		(pad "B7" smd circle
			(at 1.599946 -5.199888 270)
			(size 0.3556 0.3556)
			(layers "F.Cu" "F.Mask" "F.Paste")
			(net "MEMDQS_N1")
		)
		(pad "B8" smd circle
			(at 2.400046 -5.199888 270)
			(size 0.3556 0.3556)
			(layers "F.Cu" "F.Mask" "F.Paste")
			(net "MEMDQ_9")
		)
		(pad "B9" smd circle
			(at 3.199892 -5.199888 270)
			(size 0.3556 0.3556)
			(layers "F.Cu" "F.Mask" "F.Paste")
			(net "GND")
		)
		(pad "C1" smd circle
			(at -3.199892 -4.400042 270)
			(size 0.3556 0.3556)
			(layers "F.Cu" "F.Mask" "F.Paste")
			(net "P1V53_STBY")
		)
		(pad "C2" smd circle
			(at -2.400046 -4.400042 270)
			(size 0.3556 0.3556)
			(layers "F.Cu" "F.Mask" "F.Paste")
			(net "MEMDQ_12")
		)
		(pad "C3" smd circle
			(at -1.599946 -4.400042 270)
			(size 0.3556 0.3556)
			(layers "F.Cu" "F.Mask" "F.Paste")
			(net "MEMDQ_11")
		)
		(pad "C7" smd circle
			(at 1.599946 -4.400042 270)
			(size 0.3556 0.3556)
			(layers "F.Cu" "F.Mask" "F.Paste")
			(net "MEMDQS_P1")
		)
		(pad "C8" smd circle
			(at 2.400046 -4.400042 270)
			(size 0.3556 0.3556)
			(layers "F.Cu" "F.Mask" "F.Paste")
			(net "MEMDQ_13")
		)
		(pad "C9" smd circle
			(at 3.199892 -4.400042 270)
			(size 0.3556 0.3556)
			(layers "F.Cu" "F.Mask" "F.Paste")
			(net "P1V53_STBY")
		)
		(pad "D1" smd circle
			(at -3.199892 -3.599942 270)
			(size 0.3556 0.3556)
			(layers "F.Cu" "F.Mask" "F.Paste")
			(net "GND")
		)
		(pad "D2" smd circle
			(at -2.400046 -3.599942 270)
			(size 0.3556 0.3556)
			(layers "F.Cu" "F.Mask" "F.Paste")
			(net "P1V53_STBY")
		)
		(pad "D3" smd circle
			(at -1.599946 -3.599942 270)
			(size 0.3556 0.3556)
			(layers "F.Cu" "F.Mask" "F.Paste")
			(net "MEMDM_1")
		)
		(pad "D7" smd circle
			(at 1.599946 -3.599942 270)
			(size 0.3556 0.3556)
			(layers "F.Cu" "F.Mask" "F.Paste")
			(net "MEMDQ_8")
		)
		(pad "D8" smd circle
			(at 2.400046 -3.599942 270)
			(size 0.3556 0.3556)
			(layers "F.Cu" "F.Mask" "F.Paste")
			(net "GND")
		)
		(pad "D9" smd circle
			(at 3.199892 -3.599942 270)
			(size 0.3556 0.3556)
			(layers "F.Cu" "F.Mask" "F.Paste")
			(net "P1V53_STBY")
		)
		(pad "E1" smd circle
			(at -3.199892 -2.800096 270)
			(size 0.3556 0.3556)
			(layers "F.Cu" "F.Mask" "F.Paste")
			(net "GND")
		)
		(pad "E2" smd circle
			(at -2.400046 -2.800096 270)
			(size 0.3556 0.3556)
			(layers "F.Cu" "F.Mask" "F.Paste")
			(net "GND")
		)
		(pad "E3" smd circle
			(at -1.599946 -2.800096 270)
			(size 0.3556 0.3556)
			(layers "F.Cu" "F.Mask" "F.Paste")
			(net "MEMDQ_7")
		)
		(pad "E7" smd circle
			(at 1.599946 -2.800096 270)
			(size 0.3556 0.3556)
			(layers "F.Cu" "F.Mask" "F.Paste")
			(net "MEMDM_0")
		)
		(pad "E8" smd circle
			(at 2.400046 -2.800096 270)
			(size 0.3556 0.3556)
			(layers "F.Cu" "F.Mask" "F.Paste")
			(net "GND")
		)
		(pad "E9" smd circle
			(at 3.199892 -2.800096 270)
			(size 0.3556 0.3556)
			(layers "F.Cu" "F.Mask" "F.Paste")
			(net "P1V53_STBY")
		)
		(pad "F1" smd circle
			(at -3.199892 -1.999996 270)
			(size 0.3556 0.3556)
			(layers "F.Cu" "F.Mask" "F.Paste")
			(net "P1V53_STBY")
		)
		(pad "F2" smd circle
			(at -2.400046 -1.999996 270)
			(size 0.3556 0.3556)
			(layers "F.Cu" "F.Mask" "F.Paste")
			(net "MEMDQ_4")
		)
		(pad "F3" smd circle
			(at -1.599946 -1.999996 270)
			(size 0.3556 0.3556)
			(layers "F.Cu" "F.Mask" "F.Paste")
			(net "MEMDQS_P0")
		)
		(pad "F7" smd circle
			(at 1.599946 -1.999996 270)
			(size 0.3556 0.3556)
			(layers "F.Cu" "F.Mask" "F.Paste")
			(net "MEMDQ_3")
		)
		(pad "F8" smd circle
			(at 2.400046 -1.999996 270)
			(size 0.3556 0.3556)
			(layers "F.Cu" "F.Mask" "F.Paste")
			(net "MEMDQ_2")
		)
		(pad "F9" smd circle
			(at 3.199892 -1.999996 270)
			(size 0.3556 0.3556)
			(layers "F.Cu" "F.Mask" "F.Paste")
			(net "GND")
		)
		(pad "G1" smd circle
			(at -3.199892 -1.199896 270)
			(size 0.3556 0.3556)
			(layers "F.Cu" "F.Mask" "F.Paste")
			(net "GND")
		)
		(pad "G2" smd circle
			(at -2.400046 -1.199896 270)
			(size 0.3556 0.3556)
			(layers "F.Cu" "F.Mask" "F.Paste")
			(net "MEMDQ_5")
		)
		(pad "G3" smd circle
			(at -1.599946 -1.199896 270)
			(size 0.3556 0.3556)
			(layers "F.Cu" "F.Mask" "F.Paste")
			(net "MEMDQS_N0")
		)
		(pad "G7" smd circle
			(at 1.599946 -1.199896 270)
			(size 0.3556 0.3556)
			(layers "F.Cu" "F.Mask" "F.Paste")
			(net "P1V53_STBY")
		)
		(pad "G8" smd circle
			(at 2.400046 -1.199896 270)
			(size 0.3556 0.3556)
			(layers "F.Cu" "F.Mask" "F.Paste")
			(net "GND")
		)
		(pad "G9" smd circle
			(at 3.199892 -1.199896 270)
			(size 0.3556 0.3556)
			(layers "F.Cu" "F.Mask" "F.Paste")
			(net "GND")
		)
		(pad "H1" smd circle
			(at -3.199892 -0.40005 270)
			(size 0.3556 0.3556)
			(layers "F.Cu" "F.Mask" "F.Paste")
			(net "DDR_VREF")
		)
		(pad "H2" smd circle
			(at -2.400046 -0.40005 270)
			(size 0.3556 0.3556)
			(layers "F.Cu" "F.Mask" "F.Paste")
			(net "P1V53_STBY")
		)
		(pad "H3" smd circle
			(at -1.599946 -0.40005 270)
			(size 0.3556 0.3556)
			(layers "F.Cu" "F.Mask" "F.Paste")
			(net "MEMDQ_1")
		)
		(pad "H7" smd circle
			(at 1.599946 -0.40005 270)
			(size 0.3556 0.3556)
			(layers "F.Cu" "F.Mask" "F.Paste")
			(net "MEMDQ_0")
		)
		(pad "H8" smd circle
			(at 2.400046 -0.40005 270)
			(size 0.3556 0.3556)
			(layers "F.Cu" "F.Mask" "F.Paste")
			(net "MEMDQ_6")
		)
		(pad "H9" smd circle
			(at 3.199892 -0.40005 270)
			(size 0.3556 0.3556)
			(layers "F.Cu" "F.Mask" "F.Paste")
			(net "P1V53_STBY")
		)
		(pad "J1" smd circle
			(at -3.199892 0.40005 270)
			(size 0.3556 0.3556)
			(layers "F.Cu" "F.Mask" "F.Paste")
			(net "Net_6")
		)
		(pad "J2" smd circle
			(at -2.400046 0.40005 270)
			(size 0.3556 0.3556)
			(layers "F.Cu" "F.Mask" "F.Paste")
			(net "GND")
		)
		(pad "J3" smd circle
			(at -1.599946 0.40005 270)
			(size 0.3556 0.3556)
			(layers "F.Cu" "F.Mask" "F.Paste")
			(net "MEMRASN")
		)
		(pad "J7" smd circle
			(at 1.599946 0.40005 270)
			(size 0.3556 0.3556)
			(layers "F.Cu" "F.Mask" "F.Paste")
			(net "MEMCK_P")
		)
		(pad "J8" smd circle
			(at 2.400046 0.40005 270)
			(size 0.3556 0.3556)
			(layers "F.Cu" "F.Mask" "F.Paste")
			(net "GND")
		)
		(pad "J9" smd circle
			(at 3.199892 0.40005 270)
			(size 0.3556 0.3556)
			(layers "F.Cu" "F.Mask" "F.Paste")
			(net "Net_5")
		)
		(pad "K1" smd circle
			(at -3.199892 1.199896 270)
			(size 0.3556 0.3556)
			(layers "F.Cu" "F.Mask" "F.Paste")
			(net "MEMODT")
		)
		(pad "K2" smd circle
			(at -2.400046 1.199896 270)
			(size 0.3556 0.3556)
			(layers "F.Cu" "F.Mask" "F.Paste")
			(net "P1V53_STBY")
		)
		(pad "K3" smd circle
			(at -1.599946 1.199896 270)
			(size 0.3556 0.3556)
			(layers "F.Cu" "F.Mask" "F.Paste")
			(net "MEMCASN")
		)
		(pad "K7" smd circle
			(at 1.599946 1.199896 270)
			(size 0.3556 0.3556)
			(layers "F.Cu" "F.Mask" "F.Paste")
			(net "MEMCK_N")
		)
		(pad "K8" smd circle
			(at 2.400046 1.199896 270)
			(size 0.3556 0.3556)
			(layers "F.Cu" "F.Mask" "F.Paste")
			(net "P1V53_STBY")
		)
		(pad "K9" smd circle
			(at 3.199892 1.199896 270)
			(size 0.3556 0.3556)
			(layers "F.Cu" "F.Mask" "F.Paste")
			(net "MEMCKE")
		)
		(pad "L1" smd circle
			(at -3.199892 1.999996 270)
			(size 0.3556 0.3556)
			(layers "F.Cu" "F.Mask" "F.Paste")
			(net "Net_4")
		)
		(pad "L2" smd circle
			(at -2.400046 1.999996 270)
			(size 0.3556 0.3556)
			(layers "F.Cu" "F.Mask" "F.Paste")
			(net "MEMCSN")
		)
		(pad "L3" smd circle
			(at -1.599946 1.999996 270)
			(size 0.3556 0.3556)
			(layers "F.Cu" "F.Mask" "F.Paste")
			(net "MEMWEN")
		)
		(pad "L7" smd circle
			(at 1.599946 1.999996 270)
			(size 0.3556 0.3556)
			(layers "F.Cu" "F.Mask" "F.Paste")
			(net "MEMA_10")
		)
		(pad "L8" smd circle
			(at 2.400046 1.999996 270)
			(size 0.3556 0.3556)
			(layers "F.Cu" "F.Mask" "F.Paste")
			(net "PD_ZQ")
		)
		(pad "L9" smd circle
			(at 3.199892 1.999996 270)
			(size 0.3556 0.3556)
			(layers "F.Cu" "F.Mask" "F.Paste")
			(net "Net_3")
		)
		(pad "M1" smd circle
			(at -3.199892 2.800096 270)
			(size 0.3556 0.3556)
			(layers "F.Cu" "F.Mask" "F.Paste")
			(net "GND")
		)
		(pad "M2" smd circle
			(at -2.400046 2.800096 270)
			(size 0.3556 0.3556)
			(layers "F.Cu" "F.Mask" "F.Paste")
			(net "MEMBA_0")
		)
		(pad "M3" smd circle
			(at -1.599946 2.800096 270)
			(size 0.3556 0.3556)
			(layers "F.Cu" "F.Mask" "F.Paste")
			(net "MEMBA_2")
		)
		(pad "M7" smd circle
			(at 1.599946 2.800096 270)
			(size 0.3556 0.3556)
			(layers "F.Cu" "F.Mask" "F.Paste")
			(net "Net_2")
		)
		(pad "M8" smd circle
			(at 2.400046 2.800096 270)
			(size 0.3556 0.3556)
			(layers "F.Cu" "F.Mask" "F.Paste")
			(net "DDR_VREF")
		)
		(pad "M9" smd circle
			(at 3.199892 2.800096 270)
			(size 0.3556 0.3556)
			(layers "F.Cu" "F.Mask" "F.Paste")
			(net "GND")
		)
		(pad "N1" smd circle
			(at -3.199892 3.599942 270)
			(size 0.3556 0.3556)
			(layers "F.Cu" "F.Mask" "F.Paste")
			(net "P1V53_STBY")
		)
		(pad "N2" smd circle
			(at -2.400046 3.599942 270)
			(size 0.3556 0.3556)
			(layers "F.Cu" "F.Mask" "F.Paste")
			(net "MEMA_3")
		)
		(pad "N3" smd circle
			(at -1.599946 3.599942 270)
			(size 0.3556 0.3556)
			(layers "F.Cu" "F.Mask" "F.Paste")
			(net "MEMA_0")
		)
		(pad "N7" smd circle
			(at 1.599946 3.599942 270)
			(size 0.3556 0.3556)
			(layers "F.Cu" "F.Mask" "F.Paste")
			(net "MEMA_12")
		)
		(pad "N8" smd circle
			(at 2.400046 3.599942 270)
			(size 0.3556 0.3556)
			(layers "F.Cu" "F.Mask" "F.Paste")
			(net "MEMBA_1")
		)
		(pad "N9" smd circle
			(at 3.199892 3.599942 270)
			(size 0.3556 0.3556)
			(layers "F.Cu" "F.Mask" "F.Paste")
			(net "P1V53_STBY")
		)
		(pad "P1" smd circle
			(at -3.199892 4.400042 270)
			(size 0.3556 0.3556)
			(layers "F.Cu" "F.Mask" "F.Paste")
			(net "GND")
		)
		(pad "P2" smd circle
			(at -2.400046 4.400042 270)
			(size 0.3556 0.3556)
			(layers "F.Cu" "F.Mask" "F.Paste")
			(net "MEMA_5")
		)
		(pad "P3" smd circle
			(at -1.599946 4.400042 270)
			(size 0.3556 0.3556)
			(layers "F.Cu" "F.Mask" "F.Paste")
			(net "MEMA_2")
		)
		(pad "P7" smd circle
			(at 1.599946 4.400042 270)
			(size 0.3556 0.3556)
			(layers "F.Cu" "F.Mask" "F.Paste")
			(net "MEMA_1")
		)
		(pad "P8" smd circle
			(at 2.400046 4.400042 270)
			(size 0.3556 0.3556)
			(layers "F.Cu" "F.Mask" "F.Paste")
			(net "MEMA_4")
		)
		(pad "P9" smd circle
			(at 3.199892 4.400042 270)
			(size 0.3556 0.3556)
			(layers "F.Cu" "F.Mask" "F.Paste")
			(net "GND")
		)
		(pad "R1" smd circle
			(at -3.199892 5.199888 270)
			(size 0.3556 0.3556)
			(layers "F.Cu" "F.Mask" "F.Paste")
			(net "P1V53_STBY")
		)
		(pad "R2" smd circle
			(at -2.400046 5.199888 270)
			(size 0.3556 0.3556)
			(layers "F.Cu" "F.Mask" "F.Paste")
			(net "MEMA_7")
		)
		(pad "R3" smd circle
			(at -1.599946 5.199888 270)
			(size 0.3556 0.3556)
			(layers "F.Cu" "F.Mask" "F.Paste")
			(net "MEMA_9")
		)
		(pad "R7" smd circle
			(at 1.599946 5.199888 270)
			(size 0.3556 0.3556)
			(layers "F.Cu" "F.Mask" "F.Paste")
			(net "MEMA_11")
		)
		(pad "R8" smd circle
			(at 2.400046 5.199888 270)
			(size 0.3556 0.3556)
			(layers "F.Cu" "F.Mask" "F.Paste")
			(net "MEMA_6")
		)
		(pad "R9" smd circle
			(at 3.199892 5.199888 270)
			(size 0.3556 0.3556)
			(layers "F.Cu" "F.Mask" "F.Paste")
			(net "P1V53_STBY")
		)
		(pad "T1" smd circle
			(at -3.199892 5.999988 270)
			(size 0.3556 0.3556)
			(layers "F.Cu" "F.Mask" "F.Paste")
			(net "GND")
		)
		(pad "T2" smd circle
			(at -2.400046 5.999988 270)
			(size 0.3556 0.3556)
			(layers "F.Cu" "F.Mask" "F.Paste")
			(net "BMC_DDR3_RST_N")
		)
		(pad "T3" smd circle
			(at -1.599946 5.999988 270)
			(size 0.3556 0.3556)
			(layers "F.Cu" "F.Mask" "F.Paste")
			(net "MEMA_13")
		)
		(pad "T7" smd circle
			(at 1.599946 5.999988 270)
			(size 0.3556 0.3556)
			(layers "F.Cu" "F.Mask" "F.Paste")
			(net "MEMA_14")
		)
		(pad "T8" smd circle
			(at 2.400046 5.999988 270)
			(size 0.3556 0.3556)
			(layers "F.Cu" "F.Mask" "F.Paste")
			(net "MEMA_8")
		)
		(pad "T9" smd circle
			(at 3.199892 5.999988 270)
			(size 0.3556 0.3556)
			(layers "F.Cu" "F.Mask" "F.Paste")
			(net "GND")
		)
	)
	(footprint ""
		(layer "F.Cu")
		(at 274.193 -161.417 90)
		(property "Reference" "R292"
			(at 0 0 90)
			(layer "F.SilkS")
			(hide yes)
			(effects
				(font
					(size 1.27 1.27)
				)
			)
		)
		(property "Value" "0R2J-2-GP"
			(at 0.064008 -3.993896 90)
			(unlocked yes)
			(layer "F.Fab")
			(hide yes)
			(effects
				(font
					(size 1.016 1.016)
					(thickness 0.1524)
				)
			)
		)
		(property "Device Type" "R402H16"
			(at 0.064008 -5.517896 90)
			(unlocked yes)
			(layer "F.Fab")
			(hide yes)
			(effects
				(font
					(size 1.016 1.016)
					(thickness 0.1524)
				)
			)
		)
		(duplicate_pad_numbers_are_jumpers no)
		(fp_line
			(start 0.508 -0.9398)
			(end -0.508 -0.9398)
			(stroke
				(width 0.1524)
				(type default)
			)
			(layer "F.SilkS")
		)
		(fp_line
			(start -0.508 -0.9398)
			(end -0.508 0.9398)
			(stroke
				(width 0.1524)
				(type default)
			)
			(layer "F.SilkS")
		)
		(fp_rect
			(start -0.508 0.9398)
			(end 0.508 -0.9398)
			(stroke
				(width 0)
				(type default)
			)
			(fill no)
			(layer "F.CrtYd")
		)
		(fp_rect
			(start -0.508 0.9398)
			(end 0.508 -0.9398)
			(stroke
				(width 0)
				(type default)
			)
			(fill no)
			(layer "F.Fab")
		)
		(pad "1" smd custom
			(at 0 -0.4445 90)
			(size 0.1397 0.1397)
			(layers "F.Cu" "F.Mask" "F.Paste")
			(net "BMC_EN_P3V3")
			(options
				(clearance outline)
				(anchor circle)
			)
			(primitives
				(gr_poly
					(pts
						(arc
							(start -0.1778 -0.2794)
							(mid -0.249642 -0.249642)
							(end -0.2794 -0.1778)
						)
						(arc
							(start -0.2794 0.1778)
							(mid -0.249642 0.249642)
							(end -0.1778 0.2794)
						)
						(arc
							(start 0.1778 0.2794)
							(mid 0.249642 0.249642)
							(end 0.2794 0.1778)
						)
						(arc
							(start 0.2794 -0.1778)
							(mid 0.249642 -0.249642)
							(end 0.1778 -0.2794)
						)
					)
					(width 0)
					(fill yes)
				)
			)
		)
		(pad "2" smd custom
			(at 0 0.4445 90)
			(size 0.1397 0.1397)
			(layers "F.Cu" "F.Mask" "F.Paste")
			(net "BMC_EN_P3V3_R")
			(options
				(clearance outline)
				(anchor circle)
			)
			(primitives
				(gr_poly
					(pts
						(arc
							(start -0.1778 -0.2794)
							(mid -0.249642 -0.249642)
							(end -0.2794 -0.1778)
						)
						(arc
							(start -0.2794 0.1778)
							(mid -0.249642 0.249642)
							(end -0.1778 0.2794)
						)
						(arc
							(start 0.1778 0.2794)
							(mid 0.249642 0.249642)
							(end 0.2794 0.1778)
						)
						(arc
							(start 0.2794 -0.1778)
							(mid 0.249642 -0.249642)
							(end 0.1778 -0.2794)
						)
					)
					(width 0)
					(fill yes)
				)
			)
		)
	)
	(footprint ""
		(layer "F.Cu")
		(at 268.224 -214.503 90)
		(property "Reference" "PC99"
			(at 0 0 90)
			(layer "F.SilkS")
			(hide yes)
			(effects
				(font
					(size 1.27 1.27)
				)
			)
		)
		(property "Value" "SCD1U10V2KX-5GP"
			(at 1.1811 -2.7051 90)
			(unlocked yes)
			(layer "F.Fab")
			(hide yes)
			(effects
				(font
					(size 1.016 1.016)
					(thickness 0.1524)
				)
			)
		)
		(property "Device Type" "C402H22"
			(at 1.1811 -4.2291 90)
			(unlocked yes)
			(layer "F.Fab")
			(hide yes)
			(effects
				(font
					(size 1.016 1.016)
					(thickness 0.1524)
				)
			)
		)
		(duplicate_pad_numbers_are_jumpers no)
		(fp_rect
			(start -0.4318 0.9525)
			(end 0.4318 -0.9525)
			(stroke
				(width 0)
				(type default)
			)
			(fill no)
			(layer "F.CrtYd")
		)
		(fp_rect
			(start -0.4318 0.9525)
			(end 0.4318 -0.9525)
			(stroke
				(width 0)
				(type default)
			)
			(fill no)
			(layer "F.Fab")
		)
		(pad "1" smd custom
			(at 0 -0.4445 90)
			(size 0.1524 0.1524)
			(layers "F.Cu" "F.Mask" "F.Paste")
			(net "TPS74801_1V26_STBY_OUT")
			(options
				(clearance outline)
				(anchor circle)
			)
			(primitives
				(gr_poly
					(pts
						(arc
							(start 0.3048 -0.2032)
							(mid 0.275042 -0.275042)
							(end 0.2032 -0.3048)
						)
						(arc
							(start -0.2032 -0.3048)
							(mid -0.275042 -0.275042)
							(end -0.3048 -0.2032)
						)
						(arc
							(start -0.3048 0.2032)
							(mid -0.275042 0.275042)
							(end -0.2032 0.3048)
						)
						(arc
							(start 0.2032 0.3048)
							(mid 0.275042 0.275042)
							(end 0.3048 0.2032)
						)
					)
					(width 0)
					(fill yes)
				)
			)
		)
		(pad "2" smd custom
			(at 0 0.4445 90)
			(size 0.1524 0.1524)
			(layers "F.Cu" "F.Mask" "F.Paste")
			(net "GND")
			(options
				(clearance outline)
				(anchor circle)
			)
			(primitives
				(gr_poly
					(pts
						(arc
							(start 0.3048 -0.2032)
							(mid 0.275042 -0.275042)
							(end 0.2032 -0.3048)
						)
						(arc
							(start -0.2032 -0.3048)
							(mid -0.275042 -0.275042)
							(end -0.3048 -0.2032)
						)
						(arc
							(start -0.3048 0.2032)
							(mid -0.275042 0.275042)
							(end -0.2032 0.3048)
						)
						(arc
							(start 0.2032 0.3048)
							(mid 0.275042 0.275042)
							(end 0.3048 0.2032)
						)
					)
					(width 0)
					(fill yes)
				)
			)
		)
	)
	(footprint ""
		(layer "F.Cu")
		(at 179.324 -17.272 90)
		(property "Reference" "R202"
			(at 0 0 90)
			(layer "F.SilkS")
			(hide yes)
			(effects
				(font
					(size 1.27 1.27)
				)
			)
		)
		(property "Value" "49D9R2D-GP"
			(at 0.064008 -3.993896 90)
			(unlocked yes)
			(layer "F.Fab")
			(hide yes)
			(effects
				(font
					(size 1.016 1.016)
					(thickness 0.1524)
				)
			)
		)
		(property "Device Type" "R402H16"
			(at 0.064008 -5.517896 90)
			(unlocked yes)
			(layer "F.Fab")
			(hide yes)
			(effects
				(font
					(size 1.016 1.016)
					(thickness 0.1524)
				)
			)
		)
		(duplicate_pad_numbers_are_jumpers no)
		(fp_line
			(start 0.508 -0.9398)
			(end -0.508 -0.9398)
			(stroke
				(width 0.1524)
				(type default)
			)
			(layer "F.SilkS")
		)
		(fp_line
			(start -0.508 -0.9398)
			(end -0.508 0.9398)
			(stroke
				(width 0.1524)
				(type default)
			)
			(layer "F.SilkS")
		)
		(fp_rect
			(start -0.508 0.9398)
			(end 0.508 -0.9398)
			(stroke
				(width 0)
				(type default)
			)
			(fill no)
			(layer "F.CrtYd")
		)
		(fp_rect
			(start -0.508 0.9398)
			(end 0.508 -0.9398)
			(stroke
				(width 0)
				(type default)
			)
			(fill no)
			(layer "F.Fab")
		)
		(pad "1" smd custom
			(at 0 -0.4445 90)
			(size 0.1397 0.1397)
			(layers "F.Cu" "F.Mask" "F.Paste")
			(net "TEMP_SENSOR_DXN_BJT")
			(options
				(clearance outline)
				(anchor circle)
			)
			(primitives
				(gr_poly
					(pts
						(arc
							(start -0.1778 -0.2794)
							(mid -0.249642 -0.249642)
							(end -0.2794 -0.1778)
						)
						(arc
							(start -0.2794 0.1778)
							(mid -0.249642 0.249642)
							(end -0.1778 0.2794)
						)
						(arc
							(start 0.1778 0.2794)
							(mid 0.249642 0.249642)
							(end 0.2794 0.1778)
						)
						(arc
							(start 0.2794 -0.1778)
							(mid 0.249642 -0.249642)
							(end 0.1778 -0.2794)
						)
					)
					(width 0)
					(fill yes)
				)
			)
		)
		(pad "2" smd custom
			(at 0 0.4445 90)
			(size 0.1397 0.1397)
			(layers "F.Cu" "F.Mask" "F.Paste")
			(net "TEMP_SENSOR_DXN")
			(options
				(clearance outline)
				(anchor circle)
			)
			(primitives
				(gr_poly
					(pts
						(arc
							(start -0.1778 -0.2794)
							(mid -0.249642 -0.249642)
							(end -0.2794 -0.1778)
						)
						(arc
							(start -0.2794 0.1778)
							(mid -0.249642 0.249642)
							(end -0.1778 0.2794)
						)
						(arc
							(start 0.1778 0.2794)
							(mid 0.249642 0.249642)
							(end 0.2794 0.1778)
						)
						(arc
							(start 0.2794 -0.1778)
							(mid 0.249642 -0.249642)
							(end 0.1778 -0.2794)
						)
					)
					(width 0)
					(fill yes)
				)
			)
		)
	)
	(footprint ""
		(layer "F.Cu")
		(at 344.424 -113.792 90)
		(property "Reference" "PR11"
			(at 0 0 90)
			(layer "F.SilkS")
			(hide yes)
			(effects
				(font
					(size 1.27 1.27)
				)
			)
		)
		(property "Value" "0R2J-2-GP"
			(at 0.064008 -3.993896 90)
			(unlocked yes)
			(layer "F.Fab")
			(hide yes)
			(effects
				(font
					(size 1.016 1.016)
					(thickness 0.1524)
				)
			)
		)
		(property "Device Type" "R402H16"
			(at 0.064008 -5.517896 90)
			(unlocked yes)
			(layer "F.Fab")
			(hide yes)
			(effects
				(font
					(size 1.016 1.016)
					(thickness 0.1524)
				)
			)
		)
		(duplicate_pad_numbers_are_jumpers no)
		(fp_line
			(start 0.508 -0.9398)
			(end -0.508 -0.9398)
			(stroke
				(width 0.1524)
				(type default)
			)
			(layer "F.SilkS")
		)
		(fp_line
			(start -0.508 -0.9398)
			(end -0.508 0.9398)
			(stroke
				(width 0.1524)
				(type default)
			)
			(layer "F.SilkS")
		)
		(fp_rect
			(start -0.508 0.9398)
			(end 0.508 -0.9398)
			(stroke
				(width 0)
				(type default)
			)
			(fill no)
			(layer "F.CrtYd")
		)
		(fp_rect
			(start -0.508 0.9398)
			(end 0.508 -0.9398)
			(stroke
				(width 0)
				(type default)
			)
			(fill no)
			(layer "F.Fab")
		)
		(pad "1" smd custom
			(at 0 -0.4445 90)
			(size 0.1397 0.1397)
			(layers "F.Cu" "F.Mask" "F.Paste")
			(net "P5V_STBY_VO")
			(options
				(clearance outline)
				(anchor circle)
			)
			(primitives
				(gr_poly
					(pts
						(arc
							(start -0.1778 -0.2794)
							(mid -0.249642 -0.249642)
							(end -0.2794 -0.1778)
						)
						(arc
							(start -0.2794 0.1778)
							(mid -0.249642 0.249642)
							(end -0.1778 0.2794)
						)
						(arc
							(start 0.1778 0.2794)
							(mid 0.249642 0.249642)
							(end 0.2794 0.1778)
						)
						(arc
							(start 0.2794 -0.1778)
							(mid 0.249642 -0.249642)
							(end 0.1778 -0.2794)
						)
					)
					(width 0)
					(fill yes)
				)
			)
		)
		(pad "2" smd custom
			(at 0 0.4445 90)
			(size 0.1397 0.1397)
			(layers "F.Cu" "F.Mask" "F.Paste")
			(net "P5V_STBY_CC_R")
			(options
				(clearance outline)
				(anchor circle)
			)
			(primitives
				(gr_poly
					(pts
						(arc
							(start -0.1778 -0.2794)
							(mid -0.249642 -0.249642)
							(end -0.2794 -0.1778)
						)
						(arc
							(start -0.2794 0.1778)
							(mid -0.249642 0.249642)
							(end -0.1778 0.2794)
						)
						(arc
							(start 0.1778 0.2794)
							(mid 0.249642 0.249642)
							(end 0.2794 0.1778)
						)
						(arc
							(start 0.2794 -0.1778)
							(mid 0.249642 -0.249642)
							(end 0.1778 -0.2794)
						)
					)
					(width 0)
					(fill yes)
				)
			)
		)
	)
	(footprint ""
		(layer "F.Cu")
		(at 97.795842 -98.496882)
		(property "Reference" "STP96"
			(at 0 0 0)
			(layer "F.SilkS")
			(hide yes)
			(effects
				(font
					(size 1.27 1.27)
				)
			)
		)
		(property "Value" "TPAD28"
			(at 0.0127 -1.8034 0)
			(unlocked yes)
			(layer "F.Fab")
			(hide yes)
			(effects
				(font
					(size 1.016 1.016)
					(thickness 0.1524)
				)
			)
		)
		(property "Device Type" "TPAD28"
			(at 0.0127 -3.3274 0)
			(unlocked yes)
			(layer "F.Fab")
			(hide yes)
			(effects
				(font
					(size 1.016 1.016)
					(thickness 0.1524)
				)
			)
		)
		(duplicate_pad_numbers_are_jumpers no)
		(fp_poly
			(pts
				(arc
					(start 0.3556 0)
					(mid -0.3556 0)
					(end 0.3556 0)
				)
			)
			(stroke
				(width 0)
				(type default)
			)
			(fill no)
			(layer "F.CrtYd")
		)
		(fp_poly
			(pts
				(arc
					(start 0.6096 0)
					(mid -0.6096 0)
					(end 0.6096 0)
				)
			)
			(stroke
				(width 0)
				(type default)
			)
			(fill no)
			(layer "F.Fab")
		)
		(pad "1" smd circle
			(at 0 0)
			(size 0.7112 0.7112)
			(layers "F.Cu" "F.Mask" "F.Paste")
			(net "LSI_EFUSE")
		)
	)
	(footprint ""
		(layer "F.Cu")
		(at 283.845 -156.464)
		(property "Reference" "R20"
			(at 0 0 0)
			(layer "F.SilkS")
			(hide yes)
			(effects
				(font
					(size 1.27 1.27)
				)
			)
		)
		(property "Value" "100R2F-L1-GP-U"
			(at 0.064008 -3.993896 0)
			(unlocked yes)
			(layer "F.Fab")
			(hide yes)
			(effects
				(font
					(size 1.016 1.016)
					(thickness 0.1524)
				)
			)
		)
		(property "Device Type" "R402H14"
			(at 0.064008 -5.517896 0)
			(unlocked yes)
			(layer "F.Fab")
			(hide yes)
			(effects
				(font
					(size 1.016 1.016)
					(thickness 0.1524)
				)
			)
		)
		(duplicate_pad_numbers_are_jumpers no)
		(fp_line
			(start -0.508 -0.9398)
			(end -0.508 0.9398)
			(stroke
				(width 0.1524)
				(type default)
			)
			(layer "F.SilkS")
		)
		(fp_line
			(start 0.508 -0.9398)
			(end -0.508 -0.9398)
			(stroke
				(width 0.1524)
				(type default)
			)
			(layer "F.SilkS")
		)
		(fp_rect
			(start -0.508 0.9398)
			(end 0.508 -0.9398)
			(stroke
				(width 0)
				(type default)
			)
			(fill no)
			(layer "F.CrtYd")
		)
		(fp_rect
			(start -0.508 0.9398)
			(end 0.508 -0.9398)
			(stroke
				(width 0)
				(type default)
			)
			(fill no)
			(layer "F.Fab")
		)
		(pad "1" smd custom
			(at 0 -0.4445)
			(size 0.1397 0.1397)
			(layers "F.Cu" "F.Mask" "F.Paste")
			(net "BMC_LSI_BOARD")
			(options
				(clearance outline)
				(anchor circle)
			)
			(primitives
				(gr_poly
					(pts
						(arc
							(start -0.1778 -0.2794)
							(mid -0.249642 -0.249642)
							(end -0.2794 -0.1778)
						)
						(arc
							(start -0.2794 0.1778)
							(mid -0.249642 0.249642)
							(end -0.1778 0.2794)
						)
						(arc
							(start 0.1778 0.2794)
							(mid 0.249642 0.249642)
							(end 0.2794 0.1778)
						)
						(arc
							(start 0.2794 -0.1778)
							(mid 0.249642 -0.249642)
							(end 0.1778 -0.2794)
						)
					)
					(width 0)
					(fill yes)
				)
			)
		)
		(pad "2" smd custom
			(at 0 0.4445)
			(size 0.1397 0.1397)
			(layers "F.Cu" "F.Mask" "F.Paste")
			(net "GND")
			(options
				(clearance outline)
				(anchor circle)
			)
			(primitives
				(gr_poly
					(pts
						(arc
							(start -0.1778 -0.2794)
							(mid -0.249642 -0.249642)
							(end -0.2794 -0.1778)
						)
						(arc
							(start -0.2794 0.1778)
							(mid -0.249642 0.249642)
							(end -0.1778 0.2794)
						)
						(arc
							(start 0.1778 0.2794)
							(mid 0.249642 0.249642)
							(end 0.2794 0.1778)
						)
						(arc
							(start 0.2794 -0.1778)
							(mid 0.249642 -0.249642)
							(end 0.1778 -0.2794)
						)
					)
					(width 0)
					(fill yes)
				)
			)
		)
	)
	(footprint ""
		(layer "F.Cu")
		(at 97.54997 -94.234)
		(property "Reference" "STP99"
			(at 0 0 0)
			(layer "F.SilkS")
			(hide yes)
			(effects
				(font
					(size 1.27 1.27)
				)
			)
		)
		(property "Value" "TPAD28"
			(at 0.0127 -1.8034 0)
			(unlocked yes)
			(layer "F.Fab")
			(hide yes)
			(effects
				(font
					(size 1.016 1.016)
					(thickness 0.1524)
				)
			)
		)
		(property "Device Type" "TPAD28"
			(at 0.0127 -3.3274 0)
			(unlocked yes)
			(layer "F.Fab")
			(hide yes)
			(effects
				(font
					(size 1.016 1.016)
					(thickness 0.1524)
				)
			)
		)
		(duplicate_pad_numbers_are_jumpers no)
		(fp_poly
			(pts
				(arc
					(start 0.3556 0)
					(mid -0.3556 0)
					(end 0.3556 0)
				)
			)
			(stroke
				(width 0)
				(type default)
			)
			(fill no)
			(layer "F.CrtYd")
		)
		(fp_poly
			(pts
				(arc
					(start 0.6096 0)
					(mid -0.6096 0)
					(end 0.6096 0)
				)
			)
			(stroke
				(width 0)
				(type default)
			)
			(fill no)
			(layer "F.Fab")
		)
		(pad "1" smd circle
			(at 0 0)
			(size 0.7112 0.7112)
			(layers "F.Cu" "F.Mask" "F.Paste")
			(net "LSI_SCAN_ENABLE")
		)
	)
	(footprint ""
		(layer "F.Cu")
		(at 69.469 -50.673)
		(property "Reference" "SR714"
			(at 0 0 0)
			(layer "F.SilkS")
			(hide yes)
			(effects
				(font
					(size 1.27 1.27)
				)
			)
		)
		(property "Value" "10R2F-L-GP"
			(at 0.064008 -3.993896 0)
			(unlocked yes)
			(layer "F.Fab")
			(hide yes)
			(effects
				(font
					(size 1.016 1.016)
					(thickness 0.1524)
				)
			)
		)
		(property "Device Type" "R402H14"
			(at 0.064008 -5.517896 0)
			(unlocked yes)
			(layer "F.Fab")
			(hide yes)
			(effects
				(font
					(size 1.016 1.016)
					(thickness 0.1524)
				)
			)
		)
		(duplicate_pad_numbers_are_jumpers no)
		(fp_line
			(start -0.508 -0.9398)
			(end -0.508 0.9398)
			(stroke
				(width 0.1524)
				(type default)
			)
			(layer "F.SilkS")
		)
		(fp_line
			(start 0.508 -0.9398)
			(end -0.508 -0.9398)
			(stroke
				(width 0.1524)
				(type default)
			)
			(layer "F.SilkS")
		)
		(fp_rect
			(start -0.508 0.9398)
			(end 0.508 -0.9398)
			(stroke
				(width 0)
				(type default)
			)
			(fill no)
			(layer "F.CrtYd")
		)
		(fp_rect
			(start -0.508 0.9398)
			(end 0.508 -0.9398)
			(stroke
				(width 0)
				(type default)
			)
			(fill no)
			(layer "F.Fab")
		)
		(pad "1" smd custom
			(at 0 -0.4445)
			(size 0.1397 0.1397)
			(layers "F.Cu" "F.Mask" "F.Paste")
			(net "P1V8_C")
			(options
				(clearance outline)
				(anchor circle)
			)
			(primitives
				(gr_poly
					(pts
						(arc
							(start -0.1778 -0.2794)
							(mid -0.249642 -0.249642)
							(end -0.2794 -0.1778)
						)
						(arc
							(start -0.2794 0.1778)
							(mid -0.249642 0.249642)
							(end -0.1778 0.2794)
						)
						(arc
							(start 0.1778 0.2794)
							(mid 0.249642 0.249642)
							(end 0.2794 0.1778)
						)
						(arc
							(start 0.2794 -0.1778)
							(mid 0.249642 -0.249642)
							(end 0.1778 -0.2794)
						)
					)
					(width 0)
					(fill yes)
				)
			)
		)
		(pad "2" smd custom
			(at 0 0.4445)
			(size 0.1397 0.1397)
			(layers "F.Cu" "F.Mask" "F.Paste")
			(net "SAS0_VDDH")
			(options
				(clearance outline)
				(anchor circle)
			)
			(primitives
				(gr_poly
					(pts
						(arc
							(start -0.1778 -0.2794)
							(mid -0.249642 -0.249642)
							(end -0.2794 -0.1778)
						)
						(arc
							(start -0.2794 0.1778)
							(mid -0.249642 0.249642)
							(end -0.1778 0.2794)
						)
						(arc
							(start 0.1778 0.2794)
							(mid 0.249642 0.249642)
							(end 0.2794 0.1778)
						)
						(arc
							(start 0.2794 -0.1778)
							(mid 0.249642 -0.249642)
							(end 0.1778 -0.2794)
						)
					)
					(width 0)
					(fill yes)
				)
			)
		)
	)
	(footprint ""
		(layer "F.Cu")
		(at 194.818 -120.269)
		(property "Reference" "R599"
			(at 0 0 0)
			(layer "F.SilkS")
			(hide yes)
			(effects
				(font
					(size 1.27 1.27)
				)
			)
		)
		(property "Value" "4K7R2F-GP"
			(at 0.064008 -3.993896 0)
			(unlocked yes)
			(layer "F.Fab")
			(hide yes)
			(effects
				(font
					(size 1.016 1.016)
					(thickness 0.1524)
				)
			)
		)
		(property "Device Type" "R402H16"
			(at 0.064008 -5.517896 0)
			(unlocked yes)
			(layer "F.Fab")
			(hide yes)
			(effects
				(font
					(size 1.016 1.016)
					(thickness 0.1524)
				)
			)
		)
		(duplicate_pad_numbers_are_jumpers no)
		(fp_line
			(start -0.508 -0.9398)
			(end -0.508 0.9398)
			(stroke
				(width 0.1524)
				(type default)
			)
			(layer "F.SilkS")
		)
		(fp_line
			(start 0.508 -0.9398)
			(end -0.508 -0.9398)
			(stroke
				(width 0.1524)
				(type default)
			)
			(layer "F.SilkS")
		)
		(fp_rect
			(start -0.508 0.9398)
			(end 0.508 -0.9398)
			(stroke
				(width 0)
				(type default)
			)
			(fill no)
			(layer "F.CrtYd")
		)
		(fp_rect
			(start -0.508 0.9398)
			(end 0.508 -0.9398)
			(stroke
				(width 0)
				(type default)
			)
			(fill no)
			(layer "F.Fab")
		)
		(pad "1" smd custom
			(at 0 -0.4445)
			(size 0.1397 0.1397)
			(layers "F.Cu" "F.Mask" "F.Paste")
			(net "P3V3_STBY")
			(options
				(clearance outline)
				(anchor circle)
			)
			(primitives
				(gr_poly
					(pts
						(arc
							(start -0.1778 -0.2794)
							(mid -0.249642 -0.249642)
							(end -0.2794 -0.1778)
						)
						(arc
							(start -0.2794 0.1778)
							(mid -0.249642 0.249642)
							(end -0.1778 0.2794)
						)
						(arc
							(start 0.1778 0.2794)
							(mid 0.249642 0.249642)
							(end 0.2794 0.1778)
						)
						(arc
							(start 0.2794 -0.1778)
							(mid 0.249642 -0.249642)
							(end 0.1778 -0.2794)
						)
					)
					(width 0)
					(fill yes)
				)
			)
		)
		(pad "2" smd custom
			(at 0 0.4445)
			(size 0.1397 0.1397)
			(layers "F.Cu" "F.Mask" "F.Paste")
			(net "P1V8_PG_R_1")
			(options
				(clearance outline)
				(anchor circle)
			)
			(primitives
				(gr_poly
					(pts
						(arc
							(start -0.1778 -0.2794)
							(mid -0.249642 -0.249642)
							(end -0.2794 -0.1778)
						)
						(arc
							(start -0.2794 0.1778)
							(mid -0.249642 0.249642)
							(end -0.1778 0.2794)
						)
						(arc
							(start 0.1778 0.2794)
							(mid 0.249642 0.249642)
							(end 0.2794 0.1778)
						)
						(arc
							(start 0.2794 -0.1778)
							(mid 0.249642 -0.249642)
							(end 0.1778 -0.2794)
						)
					)
					(width 0)
					(fill yes)
				)
			)
		)
	)
	(footprint ""
		(layer "F.Cu")
		(at 36.449 -175.82134)
		(property "Reference" "SQ16"
			(at 0 0 0)
			(layer "F.SilkS")
			(hide yes)
			(effects
				(font
					(size 1.27 1.27)
				)
			)
		)
		(property "Value" "2N7002A-7-GP"
			(at 0.127 -8.9662 0)
			(unlocked yes)
			(layer "F.Fab")
			(hide yes)
			(effects
				(font
					(size 1.016 1.016)
					(thickness 0.1524)
				)
			)
		)
		(property "Device Type" "SOT23DGS2D4H48"
			(at 0.127 -10.4902 0)
			(unlocked yes)
			(layer "F.Fab")
			(hide yes)
			(effects
				(font
					(size 1.016 1.016)
					(thickness 0.1524)
				)
			)
		)
		(duplicate_pad_numbers_are_jumpers no)
		(fp_line
			(start -1.651 -1.778)
			(end -1.651 1.778)
			(stroke
				(width 0.1524)
				(type default)
			)
			(layer "F.SilkS")
		)
		(fp_line
			(start -1.651 1.778)
			(end 1.651 1.778)
			(stroke
				(width 0.1524)
				(type default)
			)
			(layer "F.SilkS")
		)
		(fp_line
			(start 1.651 -1.778)
			(end -1.651 -1.778)
			(stroke
				(width 0.1524)
				(type default)
			)
			(layer "F.SilkS")
		)
		(fp_line
			(start 1.651 1.778)
			(end 1.651 -1.778)
			(stroke
				(width 0.1524)
				(type default)
			)
			(layer "F.SilkS")
		)
		(fp_poly
			(pts
				(xy -1.778 1.8796) (xy -1.778 -1.8796) (xy 1.778 -1.8796) (xy 1.778 1.8796)
			)
			(stroke
				(width 0)
				(type default)
			)
			(fill no)
			(layer "F.CrtYd")
		)
		(fp_poly
			(pts
				(xy -1.778 1.8796) (xy -1.778 -1.8796) (xy 1.778 -1.8796) (xy 1.778 1.8796)
			)
			(stroke
				(width 0)
				(type default)
			)
			(fill no)
			(layer "F.Fab")
		)
		(pad "D" smd custom
			(at 0 -0.9525)
			(size 0.1905 0.1905)
			(layers "F.Cu" "F.Mask" "F.Paste")
			(net "DP_EXP_RST_R")
			(options
				(clearance outline)
				(anchor circle)
			)
			(primitives
				(gr_poly
					(pts
						(arc
							(start -0.1778 0.5715)
							(mid -0.321484 0.511984)
							(end -0.381 0.3683)
						)
						(arc
							(start -0.381 -0.3683)
							(mid -0.321484 -0.511984)
							(end -0.1778 -0.5715)
						)
						(arc
							(start 0.1778 -0.5715)
							(mid 0.321484 -0.511984)
							(end 0.381 -0.3683)
						)
						(arc
							(start 0.381 0.3683)
							(mid 0.321484 0.511984)
							(end 0.1778 0.5715)
						)
					)
					(width 0)
					(fill yes)
				)
			)
		)
		(pad "G" smd custom
			(at -0.98425 0.9525)
			(size 0.1905 0.1905)
			(layers "F.Cu" "F.Mask" "F.Paste")
			(net "P3V3_STBY_G8")
			(options
				(clearance outline)
				(anchor circle)
			)
			(primitives
				(gr_poly
					(pts
						(arc
							(start -0.1778 0.5715)
							(mid -0.321484 0.511984)
							(end -0.381 0.3683)
						)
						(arc
							(start -0.381 -0.3683)
							(mid -0.321484 -0.511984)
							(end -0.1778 -0.5715)
						)
						(arc
							(start 0.1778 -0.5715)
							(mid 0.321484 -0.511984)
							(end 0.381 -0.3683)
						)
						(arc
							(start 0.381 0.3683)
							(mid 0.321484 0.511984)
							(end 0.1778 0.5715)
						)
					)
					(width 0)
					(fill yes)
				)
			)
		)
		(pad "S" smd custom
			(at 0.98425 0.9525)
			(size 0.1905 0.1905)
			(layers "F.Cu" "F.Mask" "F.Paste")
			(net "GND")
			(options
				(clearance outline)
				(anchor circle)
			)
			(primitives
				(gr_poly
					(pts
						(arc
							(start -0.1778 0.5715)
							(mid -0.321484 0.511984)
							(end -0.381 0.3683)
						)
						(arc
							(start -0.381 -0.3683)
							(mid -0.321484 -0.511984)
							(end -0.1778 -0.5715)
						)
						(arc
							(start 0.1778 -0.5715)
							(mid 0.321484 -0.511984)
							(end 0.381 -0.3683)
						)
						(arc
							(start 0.381 0.3683)
							(mid 0.321484 0.511984)
							(end 0.1778 0.5715)
						)
					)
					(width 0)
					(fill yes)
				)
			)
		)
	)
	(footprint ""
		(layer "F.Cu")
		(at 9.856216 -228.65588 180)
		(property "Reference" "R519"
			(at 0 0 180)
			(layer "F.SilkS")
			(hide yes)
			(effects
				(font
					(size 1.27 1.27)
				)
			)
		)
		(property "Value" "10KR2F-2-GP"
			(at 0.064008 -3.993896 180)
			(unlocked yes)
			(layer "F.Fab")
			(hide yes)
			(effects
				(font
					(size 1.016 1.016)
					(thickness 0.1524)
				)
			)
		)
		(property "Device Type" "R402H16"
			(at 0.064008 -5.517896 180)
			(unlocked yes)
			(layer "F.Fab")
			(hide yes)
			(effects
				(font
					(size 1.016 1.016)
					(thickness 0.1524)
				)
			)
		)
		(duplicate_pad_numbers_are_jumpers no)
		(fp_line
			(start 0.508 -0.9398)
			(end -0.508 -0.9398)
			(stroke
				(width 0.1524)
				(type default)
			)
			(layer "F.SilkS")
		)
		(fp_line
			(start -0.508 -0.9398)
			(end -0.508 0.9398)
			(stroke
				(width 0.1524)
				(type default)
			)
			(layer "F.SilkS")
		)
		(fp_rect
			(start -0.508 0.9398)
			(end 0.508 -0.9398)
			(stroke
				(width 0)
				(type default)
			)
			(fill no)
			(layer "F.CrtYd")
		)
		(fp_rect
			(start -0.508 0.9398)
			(end 0.508 -0.9398)
			(stroke
				(width 0)
				(type default)
			)
			(fill no)
			(layer "F.Fab")
		)
		(pad "1" smd custom
			(at 0 -0.4445 180)
			(size 0.1397 0.1397)
			(layers "F.Cu" "F.Mask" "F.Paste")
			(net "PCIE_MATED#_A")
			(options
				(clearance outline)
				(anchor circle)
			)
			(primitives
				(gr_poly
					(pts
						(arc
							(start -0.1778 -0.2794)
							(mid -0.249642 -0.249642)
							(end -0.2794 -0.1778)
						)
						(arc
							(start -0.2794 0.1778)
							(mid -0.249642 0.249642)
							(end -0.1778 0.2794)
						)
						(arc
							(start 0.1778 0.2794)
							(mid 0.249642 0.249642)
							(end 0.2794 0.1778)
						)
						(arc
							(start 0.2794 -0.1778)
							(mid 0.249642 -0.249642)
							(end 0.1778 -0.2794)
						)
					)
					(width 0)
					(fill yes)
				)
			)
		)
		(pad "2" smd custom
			(at 0 0.4445 180)
			(size 0.1397 0.1397)
			(layers "F.Cu" "F.Mask" "F.Paste")
			(net "GND")
			(options
				(clearance outline)
				(anchor circle)
			)
			(primitives
				(gr_poly
					(pts
						(arc
							(start -0.1778 -0.2794)
							(mid -0.249642 -0.249642)
							(end -0.2794 -0.1778)
						)
						(arc
							(start -0.2794 0.1778)
							(mid -0.249642 0.249642)
							(end -0.1778 0.2794)
						)
						(arc
							(start 0.1778 0.2794)
							(mid 0.249642 0.249642)
							(end 0.2794 0.1778)
						)
						(arc
							(start 0.2794 -0.1778)
							(mid 0.249642 -0.249642)
							(end 0.1778 -0.2794)
						)
					)
					(width 0)
					(fill yes)
				)
			)
		)
	)
	(footprint ""
		(layer "F.Cu")
		(at 86.49716 -36.322 -90)
		(property "Reference" "SC882"
			(at 0 0 270)
			(layer "F.SilkS")
			(hide yes)
			(effects
				(font
					(size 1.27 1.27)
				)
			)
		)
		(property "Value" "SCD01U10V1KX-GP"
			(at -2.8321 -1.7399 270)
			(unlocked yes)
			(layer "F.Fab")
			(hide yes)
			(effects
				(font
					(size 1.016 1.016)
					(thickness 0.1524)
				)
			)
		)
		(property "Device Type" "C0201H13"
			(at -2.8321 -3.2639 270)
			(unlocked yes)
			(layer "F.Fab")
			(hide yes)
			(effects
				(font
					(size 1.016 1.016)
					(thickness 0.1524)
				)
			)
		)
		(duplicate_pad_numbers_are_jumpers no)
		(fp_rect
			(start -0.2794 0.6477)
			(end 0.2794 -0.6477)
			(stroke
				(width 0)
				(type default)
			)
			(fill no)
			(layer "F.CrtYd")
		)
		(fp_rect
			(start -0.2794 0.6477)
			(end 0.2794 -0.6477)
			(stroke
				(width 0)
				(type default)
			)
			(fill no)
			(layer "F.Fab")
		)
		(pad "1" smd custom
			(at 0 -0.2794 270)
			(size 0.0762 0.0762)
			(layers "F.Cu" "F.Mask" "F.Paste")
			(net "SAS3008_RAID_TX_C_N2")
			(options
				(clearance outline)
				(anchor circle)
			)
			(primitives
				(gr_poly
					(pts
						(arc
							(start 0.1524 -0.127)
							(mid 0.137521 -0.162921)
							(end 0.1016 -0.1778)
						)
						(arc
							(start -0.1016 -0.1778)
							(mid -0.137521 -0.162921)
							(end -0.1524 -0.127)
						)
						(arc
							(start -0.1524 0.127)
							(mid -0.137521 0.162921)
							(end -0.1016 0.1778)
						)
						(arc
							(start 0.1016 0.1778)
							(mid 0.137521 0.162921)
							(end 0.1524 0.127)
						)
					)
					(width 0)
					(fill yes)
				)
			)
		)
		(pad "2" smd custom
			(at 0 0.2794 270)
			(size 0.0762 0.0762)
			(layers "F.Cu" "F.Mask" "F.Paste")
			(net "SAS3008_RAID_TX_N2")
			(options
				(clearance outline)
				(anchor circle)
			)
			(primitives
				(gr_poly
					(pts
						(arc
							(start 0.1524 -0.127)
							(mid 0.137521 -0.162921)
							(end 0.1016 -0.1778)
						)
						(arc
							(start -0.1016 -0.1778)
							(mid -0.137521 -0.162921)
							(end -0.1524 -0.127)
						)
						(arc
							(start -0.1524 0.127)
							(mid -0.137521 0.162921)
							(end -0.1016 0.1778)
						)
						(arc
							(start 0.1016 0.1778)
							(mid 0.137521 0.162921)
							(end 0.1524 0.127)
						)
					)
					(width 0)
					(fill yes)
				)
			)
		)
	)
	(footprint ""
		(layer "F.Cu")
		(at 197.484492 -175.019716)
		(property "Reference" "Q10"
			(at 0 0 0)
			(layer "F.SilkS")
			(hide yes)
			(effects
				(font
					(size 1.27 1.27)
				)
			)
		)
		(property "Value" "2N7002DW-7F-GP"
			(at -2.3622 -8.2042 0)
			(unlocked yes)
			(layer "F.Fab")
			(hide yes)
			(effects
				(font
					(size 1.016 1.016)
					(thickness 0.1524)
				)
			)
		)
		(property "Device Type" "SOT-363H44"
			(at -2.3622 -10.1092 0)
			(unlocked yes)
			(layer "F.Fab")
			(hide yes)
			(effects
				(font
					(size 1.016 1.016)
					(thickness 0.1524)
				)
			)
		)
		(duplicate_pad_numbers_are_jumpers no)
		(fp_line
			(start -1.4478 -1.7018)
			(end -1.4478 1.7018)
			(stroke
				(width 0.1524)
				(type default)
			)
			(layer "F.SilkS")
		)
		(fp_line
			(start -1.4478 1.7018)
			(end 1.4478 1.7018)
			(stroke
				(width 0.1524)
				(type default)
			)
			(layer "F.SilkS")
		)
		(fp_line
			(start -1.27 1.524)
			(end -1.27 0.6604)
			(stroke
				(width 0.4826)
				(type default)
			)
			(layer "F.SilkS")
		)
		(fp_line
			(start 1.4478 -1.7018)
			(end -1.4478 -1.7018)
			(stroke
				(width 0.1524)
				(type default)
			)
			(layer "F.SilkS")
		)
		(fp_line
			(start 1.4478 1.7018)
			(end 1.4478 -1.7018)
			(stroke
				(width 0.1524)
				(type default)
			)
			(layer "F.SilkS")
		)
		(fp_poly
			(pts
				(xy -1.524 -1.778) (xy 1.524 -1.778) (xy 1.524 1.778) (xy -1.524 1.778)
			)
			(stroke
				(width 0)
				(type default)
			)
			(fill no)
			(layer "F.CrtYd")
		)
		(fp_poly
			(pts
				(xy -1.524 -1.778) (xy 1.524 -1.778) (xy 1.524 1.778) (xy -1.524 1.778)
			)
			(stroke
				(width 0)
				(type default)
			)
			(fill no)
			(layer "F.Fab")
		)
		(pad "1" smd rect
			(at -0.65024 0.9398)
			(size 0.4064 1.016)
			(layers "F.Cu" "F.Mask" "F.Paste")
			(net "GND")
		)
		(pad "2" smd rect
			(at 0 0.9398)
			(size 0.4064 1.016)
			(layers "F.Cu" "F.Mask" "F.Paste")
			(net "INVERTER_G2")
		)
		(pad "3" smd rect
			(at 0.65024 0.9398)
			(size 0.4064 1.016)
			(layers "F.Cu" "F.Mask" "F.Paste")
			(net "INVERTER_G2")
		)
		(pad "4" smd rect
			(at 0.65024 -0.9398)
			(size 0.4064 1.016)
			(layers "F.Cu" "F.Mask" "F.Paste")
			(net "GND")
		)
		(pad "5" smd rect
			(at 0 -0.9398)
			(size 0.4064 1.016)
			(layers "F.Cu" "F.Mask" "F.Paste")
			(net "INVERTER_G1")
		)
		(pad "6" smd rect
			(at -0.65024 -0.9398)
			(size 0.4064 1.016)
			(layers "F.Cu" "F.Mask" "F.Paste")
			(net "HB_OUT")
		)
	)
	(footprint ""
		(layer "F.Cu")
		(at 103.886 -231.521 90)
		(property "Reference" "R628"
			(at 0 0 90)
			(layer "F.SilkS")
			(hide yes)
			(effects
				(font
					(size 1.27 1.27)
				)
			)
		)
		(property "Value" "0R2J-2-GP"
			(at 0.064008 -3.993896 90)
			(unlocked yes)
			(layer "F.Fab")
			(hide yes)
			(effects
				(font
					(size 1.016 1.016)
					(thickness 0.1524)
				)
			)
		)
		(property "Device Type" "R402H16"
			(at 0.064008 -5.517896 90)
			(unlocked yes)
			(layer "F.Fab")
			(hide yes)
			(effects
				(font
					(size 1.016 1.016)
					(thickness 0.1524)
				)
			)
		)
		(duplicate_pad_numbers_are_jumpers no)
		(fp_line
			(start 0.508 -0.9398)
			(end -0.508 -0.9398)
			(stroke
				(width 0.1524)
				(type default)
			)
			(layer "F.SilkS")
		)
		(fp_line
			(start -0.508 -0.9398)
			(end -0.508 0.9398)
			(stroke
				(width 0.1524)
				(type default)
			)
			(layer "F.SilkS")
		)
		(fp_rect
			(start -0.508 0.9398)
			(end 0.508 -0.9398)
			(stroke
				(width 0)
				(type default)
			)
			(fill no)
			(layer "F.CrtYd")
		)
		(fp_rect
			(start -0.508 0.9398)
			(end 0.508 -0.9398)
			(stroke
				(width 0)
				(type default)
			)
			(fill no)
			(layer "F.Fab")
		)
		(pad "1" smd custom
			(at 0 -0.4445 90)
			(size 0.1397 0.1397)
			(layers "F.Cu" "F.Mask" "F.Paste")
			(net "SAS_FAULT_LED7")
			(options
				(clearance outline)
				(anchor circle)
			)
			(primitives
				(gr_poly
					(pts
						(arc
							(start -0.1778 -0.2794)
							(mid -0.249642 -0.249642)
							(end -0.2794 -0.1778)
						)
						(arc
							(start -0.2794 0.1778)
							(mid -0.249642 0.249642)
							(end -0.1778 0.2794)
						)
						(arc
							(start 0.1778 0.2794)
							(mid 0.249642 0.249642)
							(end 0.2794 0.1778)
						)
						(arc
							(start 0.2794 -0.1778)
							(mid 0.249642 -0.249642)
							(end 0.1778 -0.2794)
						)
					)
					(width 0)
					(fill yes)
				)
			)
		)
		(pad "2" smd custom
			(at 0 0.4445 90)
			(size 0.1397 0.1397)
			(layers "F.Cu" "F.Mask" "F.Paste")
			(net "SAS_HDD_LED_7")
			(options
				(clearance outline)
				(anchor circle)
			)
			(primitives
				(gr_poly
					(pts
						(arc
							(start -0.1778 -0.2794)
							(mid -0.249642 -0.249642)
							(end -0.2794 -0.1778)
						)
						(arc
							(start -0.2794 0.1778)
							(mid -0.249642 0.249642)
							(end -0.1778 0.2794)
						)
						(arc
							(start 0.1778 0.2794)
							(mid 0.249642 0.249642)
							(end 0.2794 0.1778)
						)
						(arc
							(start 0.2794 -0.1778)
							(mid 0.249642 -0.249642)
							(end 0.1778 -0.2794)
						)
					)
					(width 0)
					(fill yes)
				)
			)
		)
	)
	(footprint ""
		(layer "F.Cu")
		(at 288.925 -158.496)
		(property "Reference" "R476"
			(at 0 0 0)
			(layer "F.SilkS")
			(hide yes)
			(effects
				(font
					(size 1.27 1.27)
				)
			)
		)
		(property "Value" "0R2J-2-GP"
			(at 0.064008 -3.993896 0)
			(unlocked yes)
			(layer "F.Fab")
			(hide yes)
			(effects
				(font
					(size 1.016 1.016)
					(thickness 0.1524)
				)
			)
		)
		(property "Device Type" "R402H16"
			(at 0.064008 -5.517896 0)
			(unlocked yes)
			(layer "F.Fab")
			(hide yes)
			(effects
				(font
					(size 1.016 1.016)
					(thickness 0.1524)
				)
			)
		)
		(duplicate_pad_numbers_are_jumpers no)
		(fp_line
			(start -0.508 -0.9398)
			(end -0.508 0.9398)
			(stroke
				(width 0.1524)
				(type default)
			)
			(layer "F.SilkS")
		)
		(fp_line
			(start 0.508 -0.9398)
			(end -0.508 -0.9398)
			(stroke
				(width 0.1524)
				(type default)
			)
			(layer "F.SilkS")
		)
		(fp_rect
			(start -0.508 0.9398)
			(end 0.508 -0.9398)
			(stroke
				(width 0)
				(type default)
			)
			(fill no)
			(layer "F.CrtYd")
		)
		(fp_rect
			(start -0.508 0.9398)
			(end 0.508 -0.9398)
			(stroke
				(width 0)
				(type default)
			)
			(fill no)
			(layer "F.Fab")
		)
		(pad "1" smd custom
			(at 0 -0.4445)
			(size 0.1397 0.1397)
			(layers "F.Cu" "F.Mask" "F.Paste")
			(net "BMC_TXD1")
			(options
				(clearance outline)
				(anchor circle)
			)
			(primitives
				(gr_poly
					(pts
						(arc
							(start -0.1778 -0.2794)
							(mid -0.249642 -0.249642)
							(end -0.2794 -0.1778)
						)
						(arc
							(start -0.2794 0.1778)
							(mid -0.249642 0.249642)
							(end -0.1778 0.2794)
						)
						(arc
							(start 0.1778 0.2794)
							(mid 0.249642 0.249642)
							(end 0.2794 0.1778)
						)
						(arc
							(start 0.2794 -0.1778)
							(mid 0.249642 -0.249642)
							(end 0.1778 -0.2794)
						)
					)
					(width 0)
					(fill yes)
				)
			)
		)
		(pad "2" smd custom
			(at 0 0.4445)
			(size 0.1397 0.1397)
			(layers "F.Cu" "F.Mask" "F.Paste")
			(net "CPU_BMC_UART_TX")
			(options
				(clearance outline)
				(anchor circle)
			)
			(primitives
				(gr_poly
					(pts
						(arc
							(start -0.1778 -0.2794)
							(mid -0.249642 -0.249642)
							(end -0.2794 -0.1778)
						)
						(arc
							(start -0.2794 0.1778)
							(mid -0.249642 0.249642)
							(end -0.1778 0.2794)
						)
						(arc
							(start 0.1778 0.2794)
							(mid 0.249642 0.249642)
							(end 0.2794 0.1778)
						)
						(arc
							(start 0.2794 -0.1778)
							(mid 0.249642 -0.249642)
							(end 0.1778 -0.2794)
						)
					)
					(width 0)
					(fill yes)
				)
			)
		)
	)
	(footprint ""
		(layer "F.Cu")
		(at 83.420966 -91.44 180)
		(property "Reference" "SC1198"
			(at 0 0 180)
			(layer "F.SilkS")
			(hide yes)
			(effects
				(font
					(size 1.27 1.27)
				)
			)
		)
		(property "Value" "SC22U6D3V5MX-2GP"
			(at -0.0762 -6.1214 180)
			(unlocked yes)
			(layer "F.Fab")
			(hide yes)
			(effects
				(font
					(size 1.016 1.016)
					(thickness 0.1524)
				)
			)
		)
		(property "Device Type" "C805H58"
			(at -0.0762 -8.1534 180)
			(unlocked yes)
			(layer "F.Fab")
			(hide yes)
			(effects
				(font
					(size 1.016 1.016)
					(thickness 0.1524)
				)
			)
		)
		(duplicate_pad_numbers_are_jumpers no)
		(fp_line
			(start 0.635 0)
			(end -0.635 0)
			(stroke
				(width 0.508)
				(type default)
			)
			(layer "F.SilkS")
		)
		(fp_rect
			(start -0.9652 1.778)
			(end 0.9652 -1.778)
			(stroke
				(width 0)
				(type default)
			)
			(fill no)
			(layer "F.CrtYd")
		)
		(fp_poly
			(pts
				(xy -0.9652 -1.778) (xy 0.9652 -1.778) (xy 0.9652 1.778) (xy -0.9652 1.778)
			)
			(stroke
				(width 0)
				(type default)
			)
			(fill no)
			(layer "F.Fab")
		)
		(pad "1" smd rect
			(at 0 -0.9652 180)
			(size 1.397 1.143)
			(layers "F.Cu" "F.Mask" "F.Paste")
			(net "SYSPLL_VDDA09")
		)
		(pad "2" smd rect
			(at 0 0.9652 180)
			(size 1.397 1.143)
			(layers "F.Cu" "F.Mask" "F.Paste")
			(net "GND")
		)
	)
	(footprint ""
		(layer "F.Cu")
		(at 320.675 -7.62 90)
		(property "Reference" "R433"
			(at 0 0 90)
			(layer "F.SilkS")
			(hide yes)
			(effects
				(font
					(size 1.27 1.27)
				)
			)
		)
		(property "Value" "1KR2F-3-GP"
			(at 0.064008 -3.993896 90)
			(unlocked yes)
			(layer "F.Fab")
			(hide yes)
			(effects
				(font
					(size 1.016 1.016)
					(thickness 0.1524)
				)
			)
		)
		(property "Device Type" "R402H16"
			(at 0.064008 -5.517896 90)
			(unlocked yes)
			(layer "F.Fab")
			(hide yes)
			(effects
				(font
					(size 1.016 1.016)
					(thickness 0.1524)
				)
			)
		)
		(duplicate_pad_numbers_are_jumpers no)
		(fp_line
			(start 0.508 -0.9398)
			(end -0.508 -0.9398)
			(stroke
				(width 0.1524)
				(type default)
			)
			(layer "F.SilkS")
		)
		(fp_line
			(start -0.508 -0.9398)
			(end -0.508 0.9398)
			(stroke
				(width 0.1524)
				(type default)
			)
			(layer "F.SilkS")
		)
		(fp_rect
			(start -0.508 0.9398)
			(end 0.508 -0.9398)
			(stroke
				(width 0)
				(type default)
			)
			(fill no)
			(layer "F.CrtYd")
		)
		(fp_rect
			(start -0.508 0.9398)
			(end 0.508 -0.9398)
			(stroke
				(width 0)
				(type default)
			)
			(fill no)
			(layer "F.Fab")
		)
		(pad "1" smd custom
			(at 0 -0.4445 90)
			(size 0.1397 0.1397)
			(layers "F.Cu" "F.Mask" "F.Paste")
			(net "P3V3_STBY")
			(options
				(clearance outline)
				(anchor circle)
			)
			(primitives
				(gr_poly
					(pts
						(arc
							(start -0.1778 -0.2794)
							(mid -0.249642 -0.249642)
							(end -0.2794 -0.1778)
						)
						(arc
							(start -0.2794 0.1778)
							(mid -0.249642 0.249642)
							(end -0.1778 0.2794)
						)
						(arc
							(start 0.1778 0.2794)
							(mid 0.249642 0.249642)
							(end 0.2794 0.1778)
						)
						(arc
							(start 0.2794 -0.1778)
							(mid 0.249642 -0.249642)
							(end 0.1778 -0.2794)
						)
					)
					(width 0)
					(fill yes)
				)
			)
		)
		(pad "2" smd custom
			(at 0 0.4445 90)
			(size 0.1397 0.1397)
			(layers "F.Cu" "F.Mask" "F.Paste")
			(net "DEBUG_LED_SW_H")
			(options
				(clearance outline)
				(anchor circle)
			)
			(primitives
				(gr_poly
					(pts
						(arc
							(start -0.1778 -0.2794)
							(mid -0.249642 -0.249642)
							(end -0.2794 -0.1778)
						)
						(arc
							(start -0.2794 0.1778)
							(mid -0.249642 0.249642)
							(end -0.1778 0.2794)
						)
						(arc
							(start 0.1778 0.2794)
							(mid 0.249642 0.249642)
							(end 0.2794 0.1778)
						)
						(arc
							(start 0.2794 -0.1778)
							(mid 0.249642 -0.249642)
							(end 0.1778 -0.2794)
						)
					)
					(width 0)
					(fill yes)
				)
			)
		)
	)
	(footprint ""
		(layer "F.Cu")
		(at 340.106 -29.464 180)
		(property "Reference" "Q20"
			(at 0 0 180)
			(layer "F.SilkS")
			(hide yes)
			(effects
				(font
					(size 1.27 1.27)
				)
			)
		)
		(property "Value" "2N7002A-7-GP"
			(at 0.127 -8.9662 180)
			(unlocked yes)
			(layer "F.Fab")
			(hide yes)
			(effects
				(font
					(size 1.016 1.016)
					(thickness 0.1524)
				)
			)
		)
		(property "Device Type" "SOT23DGS2D4H48"
			(at 0.127 -10.4902 180)
			(unlocked yes)
			(layer "F.Fab")
			(hide yes)
			(effects
				(font
					(size 1.016 1.016)
					(thickness 0.1524)
				)
			)
		)
		(duplicate_pad_numbers_are_jumpers no)
		(fp_line
			(start 1.651 1.778)
			(end 1.651 -1.778)
			(stroke
				(width 0.1524)
				(type default)
			)
			(layer "F.SilkS")
		)
		(fp_line
			(start 1.651 -1.778)
			(end -1.651 -1.778)
			(stroke
				(width 0.1524)
				(type default)
			)
			(layer "F.SilkS")
		)
		(fp_line
			(start -1.651 1.778)
			(end 1.651 1.778)
			(stroke
				(width 0.1524)
				(type default)
			)
			(layer "F.SilkS")
		)
		(fp_line
			(start -1.651 -1.778)
			(end -1.651 1.778)
			(stroke
				(width 0.1524)
				(type default)
			)
			(layer "F.SilkS")
		)
		(fp_poly
			(pts
				(xy -1.778 1.8796) (xy -1.778 -1.8796) (xy 1.778 -1.8796) (xy 1.778 1.8796)
			)
			(stroke
				(width 0)
				(type default)
			)
			(fill no)
			(layer "F.CrtYd")
		)
		(fp_poly
			(pts
				(xy -1.778 1.8796) (xy -1.778 -1.8796) (xy 1.778 -1.8796) (xy 1.778 1.8796)
			)
			(stroke
				(width 0)
				(type default)
			)
			(fill no)
			(layer "F.Fab")
		)
		(pad "D" smd custom
			(at 0 -0.9525 180)
			(size 0.1905 0.1905)
			(layers "F.Cu" "F.Mask" "F.Paste")
			(net "DEBUG CONSOLE_LED_1")
			(options
				(clearance outline)
				(anchor circle)
			)
			(primitives
				(gr_poly
					(pts
						(arc
							(start -0.1778 0.5715)
							(mid -0.321484 0.511984)
							(end -0.381 0.3683)
						)
						(arc
							(start -0.381 -0.3683)
							(mid -0.321484 -0.511984)
							(end -0.1778 -0.5715)
						)
						(arc
							(start 0.1778 -0.5715)
							(mid 0.321484 -0.511984)
							(end 0.381 -0.3683)
						)
						(arc
							(start 0.381 0.3683)
							(mid 0.321484 0.511984)
							(end 0.1778 0.5715)
						)
					)
					(width 0)
					(fill yes)
				)
			)
		)
		(pad "G" smd custom
			(at -0.98425 0.9525 180)
			(size 0.1905 0.1905)
			(layers "F.Cu" "F.Mask" "F.Paste")
			(net "BMC_CONSOLE_LED1_R")
			(options
				(clearance outline)
				(anchor circle)
			)
			(primitives
				(gr_poly
					(pts
						(arc
							(start -0.1778 0.5715)
							(mid -0.321484 0.511984)
							(end -0.381 0.3683)
						)
						(arc
							(start -0.381 -0.3683)
							(mid -0.321484 -0.511984)
							(end -0.1778 -0.5715)
						)
						(arc
							(start 0.1778 -0.5715)
							(mid 0.321484 -0.511984)
							(end 0.381 -0.3683)
						)
						(arc
							(start 0.381 0.3683)
							(mid 0.321484 0.511984)
							(end 0.1778 0.5715)
						)
					)
					(width 0)
					(fill yes)
				)
			)
		)
		(pad "S" smd custom
			(at 0.98425 0.9525 180)
			(size 0.1905 0.1905)
			(layers "F.Cu" "F.Mask" "F.Paste")
			(net "GND")
			(options
				(clearance outline)
				(anchor circle)
			)
			(primitives
				(gr_poly
					(pts
						(arc
							(start -0.1778 0.5715)
							(mid -0.321484 0.511984)
							(end -0.381 0.3683)
						)
						(arc
							(start -0.381 -0.3683)
							(mid -0.321484 -0.511984)
							(end -0.1778 -0.5715)
						)
						(arc
							(start 0.1778 -0.5715)
							(mid 0.321484 -0.511984)
							(end 0.381 -0.3683)
						)
						(arc
							(start 0.381 0.3683)
							(mid 0.321484 0.511984)
							(end 0.1778 0.5715)
						)
					)
					(width 0)
					(fill yes)
				)
			)
		)
	)
	(footprint ""
		(layer "F.Cu")
		(at 260.731 -36.703 180)
		(property "Reference" "PR47"
			(at 0 0 180)
			(layer "F.SilkS")
			(hide yes)
			(effects
				(font
					(size 1.27 1.27)
				)
			)
		)
		(property "Value" "10R3F-GP"
			(at -0.0254 -2.5146 180)
			(unlocked yes)
			(layer "F.Fab")
			(hide yes)
			(effects
				(font
					(size 1.016 1.016)
					(thickness 0.1524)
				)
			)
		)
		(property "Device Type" "R603H22"
			(at -0.0254 -4.0386 180)
			(unlocked yes)
			(layer "F.Fab")
			(hide yes)
			(effects
				(font
					(size 1.016 1.016)
					(thickness 0.1524)
				)
			)
		)
		(duplicate_pad_numbers_are_jumpers no)
		(fp_line
			(start 0.2032 0)
			(end 0.4826 0)
			(stroke
				(width 0.2032)
				(type default)
			)
			(layer "F.SilkS")
		)
		(fp_line
			(start -0.4826 0)
			(end -0.2032 0)
			(stroke
				(width 0.2032)
				(type default)
			)
			(layer "F.SilkS")
		)
		(fp_rect
			(start -0.5842 1.3335)
			(end 0.5842 -1.3335)
			(stroke
				(width 0)
				(type default)
			)
			(fill no)
			(layer "F.CrtYd")
		)
		(fp_rect
			(start -0.5842 1.3335)
			(end 0.5842 -1.3335)
			(stroke
				(width 0)
				(type default)
			)
			(fill no)
			(layer "F.Fab")
		)
		(pad "1" smd custom
			(at 0 -0.762 180)
			(size 0.2159 0.2159)
			(layers "F.Cu" "F.Mask" "F.Paste")
			(net "P1V8_STBY")
			(options
				(clearance outline)
				(anchor circle)
			)
			(primitives
				(gr_poly
					(pts
						(arc
							(start -0.3302 -0.4318)
							(mid -0.402042 -0.402042)
							(end -0.4318 -0.3302)
						)
						(arc
							(start -0.4318 0.3302)
							(mid -0.402042 0.402042)
							(end -0.3302 0.4318)
						)
						(arc
							(start 0.3302 0.4318)
							(mid 0.402042 0.402042)
							(end 0.4318 0.3302)
						)
						(arc
							(start 0.4318 -0.3302)
							(mid 0.402042 -0.402042)
							(end 0.3302 -0.4318)
						)
					)
					(width 0)
					(fill yes)
				)
			)
		)
		(pad "2" smd custom
			(at 0 0.762 180)
			(size 0.2159 0.2159)
			(layers "F.Cu" "F.Mask" "F.Paste")
			(net "P1V8_STBY_VFB_R")
			(options
				(clearance outline)
				(anchor circle)
			)
			(primitives
				(gr_poly
					(pts
						(arc
							(start -0.3302 -0.4318)
							(mid -0.402042 -0.402042)
							(end -0.4318 -0.3302)
						)
						(arc
							(start -0.4318 0.3302)
							(mid -0.402042 0.402042)
							(end -0.3302 0.4318)
						)
						(arc
							(start 0.3302 0.4318)
							(mid 0.402042 0.402042)
							(end 0.4318 0.3302)
						)
						(arc
							(start 0.4318 -0.3302)
							(mid 0.402042 -0.402042)
							(end 0.3302 -0.4318)
						)
					)
					(width 0)
					(fill yes)
				)
			)
		)
	)
	(footprint ""
		(layer "F.Cu")
		(at 55.88 -211.074)
		(property "Reference" "PR9006"
			(at 0 0 0)
			(layer "F.SilkS")
			(hide yes)
			(effects
				(font
					(size 1.27 1.27)
				)
			)
		)
		(property "Value" "0R2J-2-GP"
			(at 0.064008 -3.993896 0)
			(unlocked yes)
			(layer "F.Fab")
			(hide yes)
			(effects
				(font
					(size 1.016 1.016)
					(thickness 0.1524)
				)
			)
		)
		(property "Device Type" "R402H16"
			(at 0.064008 -5.517896 0)
			(unlocked yes)
			(layer "F.Fab")
			(hide yes)
			(effects
				(font
					(size 1.016 1.016)
					(thickness 0.1524)
				)
			)
		)
		(duplicate_pad_numbers_are_jumpers no)
		(fp_line
			(start -0.508 -0.9398)
			(end -0.508 0.9398)
			(stroke
				(width 0.1524)
				(type default)
			)
			(layer "F.SilkS")
		)
		(fp_line
			(start 0.508 -0.9398)
			(end -0.508 -0.9398)
			(stroke
				(width 0.1524)
				(type default)
			)
			(layer "F.SilkS")
		)
		(fp_rect
			(start -0.508 0.9398)
			(end 0.508 -0.9398)
			(stroke
				(width 0)
				(type default)
			)
			(fill no)
			(layer "F.CrtYd")
		)
		(fp_rect
			(start -0.508 0.9398)
			(end 0.508 -0.9398)
			(stroke
				(width 0)
				(type default)
			)
			(fill no)
			(layer "F.Fab")
		)
		(pad "1" smd custom
			(at 0 -0.4445)
			(size 0.1397 0.1397)
			(layers "F.Cu" "F.Mask" "F.Paste")
			(net "HSW_SDA_2")
			(options
				(clearance outline)
				(anchor circle)
			)
			(primitives
				(gr_poly
					(pts
						(arc
							(start -0.1778 -0.2794)
							(mid -0.249642 -0.249642)
							(end -0.2794 -0.1778)
						)
						(arc
							(start -0.2794 0.1778)
							(mid -0.249642 0.249642)
							(end -0.1778 0.2794)
						)
						(arc
							(start 0.1778 0.2794)
							(mid 0.249642 0.249642)
							(end 0.2794 0.1778)
						)
						(arc
							(start 0.2794 -0.1778)
							(mid 0.249642 -0.249642)
							(end 0.1778 -0.2794)
						)
					)
					(width 0)
					(fill yes)
				)
			)
		)
		(pad "2" smd custom
			(at 0 0.4445)
			(size 0.1397 0.1397)
			(layers "F.Cu" "F.Mask" "F.Paste")
			(net "BMC_I2C_A_SDA")
			(options
				(clearance outline)
				(anchor circle)
			)
			(primitives
				(gr_poly
					(pts
						(arc
							(start -0.1778 -0.2794)
							(mid -0.249642 -0.249642)
							(end -0.2794 -0.1778)
						)
						(arc
							(start -0.2794 0.1778)
							(mid -0.249642 0.249642)
							(end -0.1778 0.2794)
						)
						(arc
							(start 0.1778 0.2794)
							(mid 0.249642 0.249642)
							(end 0.2794 0.1778)
						)
						(arc
							(start 0.2794 -0.1778)
							(mid 0.249642 -0.249642)
							(end 0.1778 -0.2794)
						)
					)
					(width 0)
					(fill yes)
				)
			)
		)
	)
	(footprint ""
		(layer "F.Cu")
		(at 172.339 -102.743)
		(property "Reference" "PL9"
			(at 0 0 0)
			(layer "F.SilkS")
			(hide yes)
			(effects
				(font
					(size 1.27 1.27)
				)
			)
		)
		(property "Value" "IND-300NH-8-GP"
			(at -5.6769 -0.4572 0)
			(unlocked yes)
			(layer "F.Fab")
			(hide yes)
			(effects
				(font
					(size 1.016 1.016)
					(thickness 0.1524)
				)
			)
		)
		(property "Device Type" "L102078-254224H296"
			(at -5.6769 -1.9812 0)
			(unlocked yes)
			(layer "F.Fab")
			(hide yes)
			(effects
				(font
					(size 1.016 1.016)
					(thickness 0.1524)
				)
			)
		)
		(duplicate_pad_numbers_are_jumpers no)
		(fp_line
			(start -4.1529 -5.9944)
			(end -4.1529 5.9944)
			(stroke
				(width 0.1524)
				(type default)
			)
			(layer "F.SilkS")
		)
		(fp_line
			(start -4.1529 5.9944)
			(end 4.1529 5.9944)
			(stroke
				(width 0.1524)
				(type default)
			)
			(layer "F.SilkS")
		)
		(fp_line
			(start 4.1529 -5.9944)
			(end -4.1529 -5.9944)
			(stroke
				(width 0.1524)
				(type default)
			)
			(layer "F.SilkS")
		)
		(fp_line
			(start 4.1529 5.9944)
			(end 4.1529 -5.9944)
			(stroke
				(width 0.1524)
				(type default)
			)
			(layer "F.SilkS")
		)
		(fp_poly
			(pts
				(xy -3.8989 -5.1054) (xy -3.8989 5.1054) (xy 3.8989 5.1054) (xy 3.8989 -5.1054)
			)
			(stroke
				(width 0)
				(type default)
			)
			(fill no)
			(layer "F.CrtYd")
		)
		(fp_poly
			(pts
				(xy -3.8989 -5.1054) (xy 4.4069 -5.1054) (xy 4.4069 -6.0706) (xy -4.4069 -6.0706) (xy -4.4069 6.0706)
				(xy 4.4069 6.0706) (xy 4.4069 -5.0927) (xy 3.8989 -5.0927) (xy 3.8989 5.1054) (xy -3.8989 5.1054)
			)
			(stroke
				(width 0)
				(type default)
			)
			(fill no)
			(layer "F.CrtYd")
		)
		(fp_rect
			(start -4.4069 6.0706)
			(end 4.4069 -6.0706)
			(stroke
				(width 0)
				(type default)
			)
			(fill no)
			(layer "F.Fab")
		)
		(pad "1" smd rect
			(at 0 -4.020566)
			(size 2.4892 3.429)
			(layers "F.Cu" "F.Mask" "F.Paste")
			(net "P0V9_E_LX")
		)
		(pad "2" smd rect
			(at 0 4.020566)
			(size 2.4892 3.429)
			(layers "F.Cu" "F.Mask" "F.Paste")
			(net "P0V9_E")
		)
	)
	(footprint ""
		(layer "F.Cu")
		(at 77.47 -22.733 180)
		(property "Reference" "PR189"
			(at 0 0 180)
			(layer "F.SilkS")
			(hide yes)
			(effects
				(font
					(size 1.27 1.27)
				)
			)
		)
		(property "Value" "10KR2F-2-GP"
			(at 0.064008 -3.993896 180)
			(unlocked yes)
			(layer "F.Fab")
			(hide yes)
			(effects
				(font
					(size 1.016 1.016)
					(thickness 0.1524)
				)
			)
		)
		(property "Device Type" "R402H16"
			(at 0.064008 -5.517896 180)
			(unlocked yes)
			(layer "F.Fab")
			(hide yes)
			(effects
				(font
					(size 1.016 1.016)
					(thickness 0.1524)
				)
			)
		)
		(duplicate_pad_numbers_are_jumpers no)
		(fp_line
			(start 0.508 -0.9398)
			(end -0.508 -0.9398)
			(stroke
				(width 0.1524)
				(type default)
			)
			(layer "F.SilkS")
		)
		(fp_line
			(start -0.508 -0.9398)
			(end -0.508 0.9398)
			(stroke
				(width 0.1524)
				(type default)
			)
			(layer "F.SilkS")
		)
		(fp_rect
			(start -0.508 0.9398)
			(end 0.508 -0.9398)
			(stroke
				(width 0)
				(type default)
			)
			(fill no)
			(layer "F.CrtYd")
		)
		(fp_rect
			(start -0.508 0.9398)
			(end 0.508 -0.9398)
			(stroke
				(width 0)
				(type default)
			)
			(fill no)
			(layer "F.Fab")
		)
		(pad "1" smd custom
			(at 0 -0.4445 180)
			(size 0.1397 0.1397)
			(layers "F.Cu" "F.Mask" "F.Paste")
			(net "VT235_EN")
			(options
				(clearance outline)
				(anchor circle)
			)
			(primitives
				(gr_poly
					(pts
						(arc
							(start -0.1778 -0.2794)
							(mid -0.249642 -0.249642)
							(end -0.2794 -0.1778)
						)
						(arc
							(start -0.2794 0.1778)
							(mid -0.249642 0.249642)
							(end -0.1778 0.2794)
						)
						(arc
							(start 0.1778 0.2794)
							(mid 0.249642 0.249642)
							(end 0.2794 0.1778)
						)
						(arc
							(start 0.2794 -0.1778)
							(mid 0.249642 -0.249642)
							(end 0.1778 -0.2794)
						)
					)
					(width 0)
					(fill yes)
				)
			)
		)
		(pad "2" smd custom
			(at 0 0.4445 180)
			(size 0.1397 0.1397)
			(layers "F.Cu" "F.Mask" "F.Paste")
			(net "P3V3")
			(options
				(clearance outline)
				(anchor circle)
			)
			(primitives
				(gr_poly
					(pts
						(arc
							(start -0.1778 -0.2794)
							(mid -0.249642 -0.249642)
							(end -0.2794 -0.1778)
						)
						(arc
							(start -0.2794 0.1778)
							(mid -0.249642 0.249642)
							(end -0.1778 0.2794)
						)
						(arc
							(start 0.1778 0.2794)
							(mid 0.249642 0.249642)
							(end 0.2794 0.1778)
						)
						(arc
							(start 0.2794 -0.1778)
							(mid 0.249642 -0.249642)
							(end 0.1778 -0.2794)
						)
					)
					(width 0)
					(fill yes)
				)
			)
		)
	)
	(footprint ""
		(layer "F.Cu")
		(at 274.193 -173.609 90)
		(property "Reference" "R368"
			(at 0 0 90)
			(layer "F.SilkS")
			(hide yes)
			(effects
				(font
					(size 1.27 1.27)
				)
			)
		)
		(property "Value" "3K3R2F-2-GP"
			(at 0.064008 -3.993896 90)
			(unlocked yes)
			(layer "F.Fab")
			(hide yes)
			(effects
				(font
					(size 1.016 1.016)
					(thickness 0.1524)
				)
			)
		)
		(property "Device Type" "R402H16"
			(at 0.064008 -5.517896 90)
			(unlocked yes)
			(layer "F.Fab")
			(hide yes)
			(effects
				(font
					(size 1.016 1.016)
					(thickness 0.1524)
				)
			)
		)
		(duplicate_pad_numbers_are_jumpers no)
		(fp_line
			(start 0.508 -0.9398)
			(end -0.508 -0.9398)
			(stroke
				(width 0.1524)
				(type default)
			)
			(layer "F.SilkS")
		)
		(fp_line
			(start -0.508 -0.9398)
			(end -0.508 0.9398)
			(stroke
				(width 0.1524)
				(type default)
			)
			(layer "F.SilkS")
		)
		(fp_rect
			(start -0.508 0.9398)
			(end 0.508 -0.9398)
			(stroke
				(width 0)
				(type default)
			)
			(fill no)
			(layer "F.CrtYd")
		)
		(fp_rect
			(start -0.508 0.9398)
			(end 0.508 -0.9398)
			(stroke
				(width 0)
				(type default)
			)
			(fill no)
			(layer "F.Fab")
		)
		(pad "1" smd custom
			(at 0 -0.4445 90)
			(size 0.1397 0.1397)
			(layers "F.Cu" "F.Mask" "F.Paste")
			(net "P3V3_STBY")
			(options
				(clearance outline)
				(anchor circle)
			)
			(primitives
				(gr_poly
					(pts
						(arc
							(start -0.1778 -0.2794)
							(mid -0.249642 -0.249642)
							(end -0.2794 -0.1778)
						)
						(arc
							(start -0.2794 0.1778)
							(mid -0.249642 0.249642)
							(end -0.1778 0.2794)
						)
						(arc
							(start 0.1778 0.2794)
							(mid 0.249642 0.249642)
							(end 0.2794 0.1778)
						)
						(arc
							(start 0.2794 -0.1778)
							(mid 0.249642 -0.249642)
							(end 0.1778 -0.2794)
						)
					)
					(width 0)
					(fill yes)
				)
			)
		)
		(pad "2" smd custom
			(at 0 0.4445 90)
			(size 0.1397 0.1397)
			(layers "F.Cu" "F.Mask" "F.Paste")
			(net "ROMA15")
			(options
				(clearance outline)
				(anchor circle)
			)
			(primitives
				(gr_poly
					(pts
						(arc
							(start -0.1778 -0.2794)
							(mid -0.249642 -0.249642)
							(end -0.2794 -0.1778)
						)
						(arc
							(start -0.2794 0.1778)
							(mid -0.249642 0.249642)
							(end -0.1778 0.2794)
						)
						(arc
							(start 0.1778 0.2794)
							(mid 0.249642 0.249642)
							(end 0.2794 0.1778)
						)
						(arc
							(start 0.2794 -0.1778)
							(mid 0.249642 -0.249642)
							(end 0.1778 -0.2794)
						)
					)
					(width 0)
					(fill yes)
				)
			)
		)
	)
	(footprint ""
		(layer "F.Cu")
		(at 94.996 -99.695)
		(property "Reference" "STP87"
			(at 0 0 0)
			(layer "F.SilkS")
			(hide yes)
			(effects
				(font
					(size 1.27 1.27)
				)
			)
		)
		(property "Value" "TPAD28"
			(at 0.0127 -1.8034 0)
			(unlocked yes)
			(layer "F.Fab")
			(hide yes)
			(effects
				(font
					(size 1.016 1.016)
					(thickness 0.1524)
				)
			)
		)
		(property "Device Type" "TPAD28"
			(at 0.0127 -3.3274 0)
			(unlocked yes)
			(layer "F.Fab")
			(hide yes)
			(effects
				(font
					(size 1.016 1.016)
					(thickness 0.1524)
				)
			)
		)
		(duplicate_pad_numbers_are_jumpers no)
		(fp_poly
			(pts
				(arc
					(start 0.3556 0)
					(mid -0.3556 0)
					(end 0.3556 0)
				)
			)
			(stroke
				(width 0)
				(type default)
			)
			(fill no)
			(layer "F.CrtYd")
		)
		(fp_poly
			(pts
				(arc
					(start 0.6096 0)
					(mid -0.6096 0)
					(end 0.6096 0)
				)
			)
			(stroke
				(width 0)
				(type default)
			)
			(fill no)
			(layer "F.Fab")
		)
		(pad "1" smd circle
			(at 0 0)
			(size 0.7112 0.7112)
			(layers "F.Cu" "F.Mask" "F.Paste")
			(net "EXP_PWM_OUT1")
		)
	)
	(footprint ""
		(layer "F.Cu")
		(at 41.402 -175.94834)
		(property "Reference" "SQ14"
			(at 0 0 0)
			(layer "F.SilkS")
			(hide yes)
			(effects
				(font
					(size 1.27 1.27)
				)
			)
		)
		(property "Value" "2N7002A-7-GP"
			(at 0.127 -8.9662 0)
			(unlocked yes)
			(layer "F.Fab")
			(hide yes)
			(effects
				(font
					(size 1.016 1.016)
					(thickness 0.1524)
				)
			)
		)
		(property "Device Type" "SOT23DGS2D4H48"
			(at 0.127 -10.4902 0)
			(unlocked yes)
			(layer "F.Fab")
			(hide yes)
			(effects
				(font
					(size 1.016 1.016)
					(thickness 0.1524)
				)
			)
		)
		(duplicate_pad_numbers_are_jumpers no)
		(fp_line
			(start -1.651 -1.778)
			(end -1.651 1.778)
			(stroke
				(width 0.1524)
				(type default)
			)
			(layer "F.SilkS")
		)
		(fp_line
			(start -1.651 1.778)
			(end 1.651 1.778)
			(stroke
				(width 0.1524)
				(type default)
			)
			(layer "F.SilkS")
		)
		(fp_line
			(start 1.651 -1.778)
			(end -1.651 -1.778)
			(stroke
				(width 0.1524)
				(type default)
			)
			(layer "F.SilkS")
		)
		(fp_line
			(start 1.651 1.778)
			(end 1.651 -1.778)
			(stroke
				(width 0.1524)
				(type default)
			)
			(layer "F.SilkS")
		)
		(fp_poly
			(pts
				(xy -1.778 1.8796) (xy -1.778 -1.8796) (xy 1.778 -1.8796) (xy 1.778 1.8796)
			)
			(stroke
				(width 0)
				(type default)
			)
			(fill no)
			(layer "F.CrtYd")
		)
		(fp_poly
			(pts
				(xy -1.778 1.8796) (xy -1.778 -1.8796) (xy 1.778 -1.8796) (xy 1.778 1.8796)
			)
			(stroke
				(width 0)
				(type default)
			)
			(fill no)
			(layer "F.Fab")
		)
		(pad "D" smd custom
			(at 0 -0.9525)
			(size 0.1905 0.1905)
			(layers "F.Cu" "F.Mask" "F.Paste")
			(net "RST_BTN_R")
			(options
				(clearance outline)
				(anchor circle)
			)
			(primitives
				(gr_poly
					(pts
						(arc
							(start -0.1778 0.5715)
							(mid -0.321484 0.511984)
							(end -0.381 0.3683)
						)
						(arc
							(start -0.381 -0.3683)
							(mid -0.321484 -0.511984)
							(end -0.1778 -0.5715)
						)
						(arc
							(start 0.1778 -0.5715)
							(mid 0.321484 -0.511984)
							(end 0.381 -0.3683)
						)
						(arc
							(start 0.381 0.3683)
							(mid 0.321484 0.511984)
							(end 0.1778 0.5715)
						)
					)
					(width 0)
					(fill yes)
				)
			)
		)
		(pad "G" smd custom
			(at -0.98425 0.9525)
			(size 0.1905 0.1905)
			(layers "F.Cu" "F.Mask" "F.Paste")
			(net "P3V3_STBY_G7")
			(options
				(clearance outline)
				(anchor circle)
			)
			(primitives
				(gr_poly
					(pts
						(arc
							(start -0.1778 0.5715)
							(mid -0.321484 0.511984)
							(end -0.381 0.3683)
						)
						(arc
							(start -0.381 -0.3683)
							(mid -0.321484 -0.511984)
							(end -0.1778 -0.5715)
						)
						(arc
							(start 0.1778 -0.5715)
							(mid 0.321484 -0.511984)
							(end 0.381 -0.3683)
						)
						(arc
							(start 0.381 0.3683)
							(mid 0.321484 0.511984)
							(end 0.1778 0.5715)
						)
					)
					(width 0)
					(fill yes)
				)
			)
		)
		(pad "S" smd custom
			(at 0.98425 0.9525)
			(size 0.1905 0.1905)
			(layers "F.Cu" "F.Mask" "F.Paste")
			(net "GND")
			(options
				(clearance outline)
				(anchor circle)
			)
			(primitives
				(gr_poly
					(pts
						(arc
							(start -0.1778 0.5715)
							(mid -0.321484 0.511984)
							(end -0.381 0.3683)
						)
						(arc
							(start -0.381 -0.3683)
							(mid -0.321484 -0.511984)
							(end -0.1778 -0.5715)
						)
						(arc
							(start 0.1778 -0.5715)
							(mid 0.321484 -0.511984)
							(end 0.381 -0.3683)
						)
						(arc
							(start 0.381 0.3683)
							(mid 0.321484 0.511984)
							(end 0.1778 0.5715)
						)
					)
					(width 0)
					(fill yes)
				)
			)
		)
	)
	(footprint ""
		(layer "F.Cu")
		(at 63.5 -180.086 180)
		(property "Reference" "SR813"
			(at 0 0 180)
			(layer "F.SilkS")
			(hide yes)
			(effects
				(font
					(size 1.27 1.27)
				)
			)
		)
		(property "Value" "4K75R2F-1-GP"
			(at 0.064008 -3.993896 180)
			(unlocked yes)
			(layer "F.Fab")
			(hide yes)
			(effects
				(font
					(size 1.016 1.016)
					(thickness 0.1524)
				)
			)
		)
		(property "Device Type" "R402H16"
			(at 0.064008 -5.517896 180)
			(unlocked yes)
			(layer "F.Fab")
			(hide yes)
			(effects
				(font
					(size 1.016 1.016)
					(thickness 0.1524)
				)
			)
		)
		(duplicate_pad_numbers_are_jumpers no)
		(fp_line
			(start 0.508 -0.9398)
			(end -0.508 -0.9398)
			(stroke
				(width 0.1524)
				(type default)
			)
			(layer "F.SilkS")
		)
		(fp_line
			(start -0.508 -0.9398)
			(end -0.508 0.9398)
			(stroke
				(width 0.1524)
				(type default)
			)
			(layer "F.SilkS")
		)
		(fp_rect
			(start -0.508 0.9398)
			(end 0.508 -0.9398)
			(stroke
				(width 0)
				(type default)
			)
			(fill no)
			(layer "F.CrtYd")
		)
		(fp_rect
			(start -0.508 0.9398)
			(end 0.508 -0.9398)
			(stroke
				(width 0)
				(type default)
			)
			(fill no)
			(layer "F.Fab")
		)
		(pad "1" smd custom
			(at 0 -0.4445 180)
			(size 0.1397 0.1397)
			(layers "F.Cu" "F.Mask" "F.Paste")
			(net "P1V8_E")
			(options
				(clearance outline)
				(anchor circle)
			)
			(primitives
				(gr_poly
					(pts
						(arc
							(start -0.1778 -0.2794)
							(mid -0.249642 -0.249642)
							(end -0.2794 -0.1778)
						)
						(arc
							(start -0.2794 0.1778)
							(mid -0.249642 0.249642)
							(end -0.1778 0.2794)
						)
						(arc
							(start 0.1778 0.2794)
							(mid 0.249642 0.249642)
							(end 0.2794 0.1778)
						)
						(arc
							(start 0.2794 -0.1778)
							(mid 0.249642 -0.249642)
							(end 0.1778 -0.2794)
						)
					)
					(width 0)
					(fill yes)
				)
			)
		)
		(pad "2" smd custom
			(at 0 0.4445 180)
			(size 0.1397 0.1397)
			(layers "F.Cu" "F.Mask" "F.Paste")
			(net "ICE_RESET_N")
			(options
				(clearance outline)
				(anchor circle)
			)
			(primitives
				(gr_poly
					(pts
						(arc
							(start -0.1778 -0.2794)
							(mid -0.249642 -0.249642)
							(end -0.2794 -0.1778)
						)
						(arc
							(start -0.2794 0.1778)
							(mid -0.249642 0.249642)
							(end -0.1778 0.2794)
						)
						(arc
							(start 0.1778 0.2794)
							(mid 0.249642 0.249642)
							(end 0.2794 0.1778)
						)
						(arc
							(start 0.2794 -0.1778)
							(mid 0.249642 -0.249642)
							(end 0.1778 -0.2794)
						)
					)
					(width 0)
					(fill yes)
				)
			)
		)
	)
	(footprint ""
		(layer "F.Cu")
		(at 18.746216 -195.12788 180)
		(property "Reference" "R653"
			(at 0 0 180)
			(layer "F.SilkS")
			(hide yes)
			(effects
				(font
					(size 1.27 1.27)
				)
			)
		)
		(property "Value" "4K7R2F-GP"
			(at 0.064008 -3.993896 180)
			(unlocked yes)
			(layer "F.Fab")
			(hide yes)
			(effects
				(font
					(size 1.016 1.016)
					(thickness 0.1524)
				)
			)
		)
		(property "Device Type" "R402H16"
			(at 0.064008 -5.517896 180)
			(unlocked yes)
			(layer "F.Fab")
			(hide yes)
			(effects
				(font
					(size 1.016 1.016)
					(thickness 0.1524)
				)
			)
		)
		(duplicate_pad_numbers_are_jumpers no)
		(fp_line
			(start 0.508 -0.9398)
			(end -0.508 -0.9398)
			(stroke
				(width 0.1524)
				(type default)
			)
			(layer "F.SilkS")
		)
		(fp_line
			(start -0.508 -0.9398)
			(end -0.508 0.9398)
			(stroke
				(width 0.1524)
				(type default)
			)
			(layer "F.SilkS")
		)
		(fp_rect
			(start -0.508 0.9398)
			(end 0.508 -0.9398)
			(stroke
				(width 0)
				(type default)
			)
			(fill no)
			(layer "F.CrtYd")
		)
		(fp_rect
			(start -0.508 0.9398)
			(end 0.508 -0.9398)
			(stroke
				(width 0)
				(type default)
			)
			(fill no)
			(layer "F.Fab")
		)
		(pad "1" smd custom
			(at 0 -0.4445 180)
			(size 0.1397 0.1397)
			(layers "F.Cu" "F.Mask" "F.Paste")
			(net "P3V3_STBY")
			(options
				(clearance outline)
				(anchor circle)
			)
			(primitives
				(gr_poly
					(pts
						(arc
							(start -0.1778 -0.2794)
							(mid -0.249642 -0.249642)
							(end -0.2794 -0.1778)
						)
						(arc
							(start -0.2794 0.1778)
							(mid -0.249642 0.249642)
							(end -0.1778 0.2794)
						)
						(arc
							(start 0.1778 0.2794)
							(mid 0.249642 0.249642)
							(end 0.2794 0.1778)
						)
						(arc
							(start 0.2794 -0.1778)
							(mid 0.249642 -0.249642)
							(end 0.1778 -0.2794)
						)
					)
					(width 0)
					(fill yes)
				)
			)
		)
		(pad "2" smd custom
			(at 0 0.4445 180)
			(size 0.1397 0.1397)
			(layers "F.Cu" "F.Mask" "F.Paste")
			(net "IO_EXP_HDD_PRE_A1")
			(options
				(clearance outline)
				(anchor circle)
			)
			(primitives
				(gr_poly
					(pts
						(arc
							(start -0.1778 -0.2794)
							(mid -0.249642 -0.249642)
							(end -0.2794 -0.1778)
						)
						(arc
							(start -0.2794 0.1778)
							(mid -0.249642 0.249642)
							(end -0.1778 0.2794)
						)
						(arc
							(start 0.1778 0.2794)
							(mid 0.249642 0.249642)
							(end 0.2794 0.1778)
						)
						(arc
							(start 0.2794 -0.1778)
							(mid 0.249642 -0.249642)
							(end 0.1778 -0.2794)
						)
					)
					(width 0)
					(fill yes)
				)
			)
		)
	)
	(footprint ""
		(layer "F.Cu")
		(at 250.259596 -54.502812 -90)
		(property "Reference" "SR723"
			(at 0 0 270)
			(layer "F.SilkS")
			(hide yes)
			(effects
				(font
					(size 1.27 1.27)
				)
			)
		)
		(property "Value" "0R2J-2-GP"
			(at 0.064008 -3.993896 270)
			(unlocked yes)
			(layer "F.Fab")
			(hide yes)
			(effects
				(font
					(size 1.016 1.016)
					(thickness 0.1524)
				)
			)
		)
		(property "Device Type" "R402H16"
			(at 0.064008 -5.517896 270)
			(unlocked yes)
			(layer "F.Fab")
			(hide yes)
			(effects
				(font
					(size 1.016 1.016)
					(thickness 0.1524)
				)
			)
		)
		(duplicate_pad_numbers_are_jumpers no)
		(fp_line
			(start -0.508 -0.9398)
			(end -0.508 0.9398)
			(stroke
				(width 0.1524)
				(type default)
			)
			(layer "F.SilkS")
		)
		(fp_line
			(start 0.508 -0.9398)
			(end -0.508 -0.9398)
			(stroke
				(width 0.1524)
				(type default)
			)
			(layer "F.SilkS")
		)
		(fp_rect
			(start -0.508 0.9398)
			(end 0.508 -0.9398)
			(stroke
				(width 0)
				(type default)
			)
			(fill no)
			(layer "F.CrtYd")
		)
		(fp_rect
			(start -0.508 0.9398)
			(end 0.508 -0.9398)
			(stroke
				(width 0)
				(type default)
			)
			(fill no)
			(layer "F.Fab")
		)
		(pad "1" smd custom
			(at 0 -0.4445 270)
			(size 0.1397 0.1397)
			(layers "F.Cu" "F.Mask" "F.Paste")
			(net "IOC_EEPROM_SDA")
			(options
				(clearance outline)
				(anchor circle)
			)
			(primitives
				(gr_poly
					(pts
						(arc
							(start -0.1778 -0.2794)
							(mid -0.249642 -0.249642)
							(end -0.2794 -0.1778)
						)
						(arc
							(start -0.2794 0.1778)
							(mid -0.249642 0.249642)
							(end -0.1778 0.2794)
						)
						(arc
							(start 0.1778 0.2794)
							(mid 0.249642 0.249642)
							(end 0.2794 0.1778)
						)
						(arc
							(start 0.2794 -0.1778)
							(mid 0.249642 -0.249642)
							(end 0.1778 -0.2794)
						)
					)
					(width 0)
					(fill yes)
				)
			)
		)
		(pad "2" smd custom
			(at 0 0.4445 270)
			(size 0.1397 0.1397)
			(layers "F.Cu" "F.Mask" "F.Paste")
			(net "SBL_SDA")
			(options
				(clearance outline)
				(anchor circle)
			)
			(primitives
				(gr_poly
					(pts
						(arc
							(start -0.1778 -0.2794)
							(mid -0.249642 -0.249642)
							(end -0.2794 -0.1778)
						)
						(arc
							(start -0.2794 0.1778)
							(mid -0.249642 0.249642)
							(end -0.1778 0.2794)
						)
						(arc
							(start 0.1778 0.2794)
							(mid 0.249642 0.249642)
							(end 0.2794 0.1778)
						)
						(arc
							(start 0.2794 -0.1778)
							(mid 0.249642 -0.249642)
							(end 0.1778 -0.2794)
						)
					)
					(width 0)
					(fill yes)
				)
			)
		)
	)
	(footprint ""
		(layer "F.Cu")
		(at 88.138 -242.443 180)
		(property "Reference" "SR953"
			(at 0 0 180)
			(layer "F.SilkS")
			(hide yes)
			(effects
				(font
					(size 1.27 1.27)
				)
			)
		)
		(property "Value" "4K7R2F-GP"
			(at 0.064008 -3.993896 180)
			(unlocked yes)
			(layer "F.Fab")
			(hide yes)
			(effects
				(font
					(size 1.016 1.016)
					(thickness 0.1524)
				)
			)
		)
		(property "Device Type" "R402H16"
			(at 0.064008 -5.517896 180)
			(unlocked yes)
			(layer "F.Fab")
			(hide yes)
			(effects
				(font
					(size 1.016 1.016)
					(thickness 0.1524)
				)
			)
		)
		(duplicate_pad_numbers_are_jumpers no)
		(fp_line
			(start 0.508 -0.9398)
			(end -0.508 -0.9398)
			(stroke
				(width 0.1524)
				(type default)
			)
			(layer "F.SilkS")
		)
		(fp_line
			(start -0.508 -0.9398)
			(end -0.508 0.9398)
			(stroke
				(width 0.1524)
				(type default)
			)
			(layer "F.SilkS")
		)
		(fp_rect
			(start -0.508 0.9398)
			(end 0.508 -0.9398)
			(stroke
				(width 0)
				(type default)
			)
			(fill no)
			(layer "F.CrtYd")
		)
		(fp_rect
			(start -0.508 0.9398)
			(end 0.508 -0.9398)
			(stroke
				(width 0)
				(type default)
			)
			(fill no)
			(layer "F.Fab")
		)
		(pad "1" smd custom
			(at 0 -0.4445 180)
			(size 0.1397 0.1397)
			(layers "F.Cu" "F.Mask" "F.Paste")
			(net "SAS_FAULT_LED12")
			(options
				(clearance outline)
				(anchor circle)
			)
			(primitives
				(gr_poly
					(pts
						(arc
							(start -0.1778 -0.2794)
							(mid -0.249642 -0.249642)
							(end -0.2794 -0.1778)
						)
						(arc
							(start -0.2794 0.1778)
							(mid -0.249642 0.249642)
							(end -0.1778 0.2794)
						)
						(arc
							(start 0.1778 0.2794)
							(mid 0.249642 0.249642)
							(end 0.2794 0.1778)
						)
						(arc
							(start 0.2794 -0.1778)
							(mid 0.249642 -0.249642)
							(end 0.1778 -0.2794)
						)
					)
					(width 0)
					(fill yes)
				)
			)
		)
		(pad "2" smd custom
			(at 0 0.4445 180)
			(size 0.1397 0.1397)
			(layers "F.Cu" "F.Mask" "F.Paste")
			(net "P3V3_STBY")
			(options
				(clearance outline)
				(anchor circle)
			)
			(primitives
				(gr_poly
					(pts
						(arc
							(start -0.1778 -0.2794)
							(mid -0.249642 -0.249642)
							(end -0.2794 -0.1778)
						)
						(arc
							(start -0.2794 0.1778)
							(mid -0.249642 0.249642)
							(end -0.1778 0.2794)
						)
						(arc
							(start 0.1778 0.2794)
							(mid 0.249642 0.249642)
							(end 0.2794 0.1778)
						)
						(arc
							(start 0.2794 -0.1778)
							(mid 0.249642 -0.249642)
							(end 0.1778 -0.2794)
						)
					)
					(width 0)
					(fill yes)
				)
			)
		)
	)
	(footprint ""
		(layer "F.Cu")
		(at 324.485 -118.491 180)
		(property "Reference" "PC23"
			(at 0 0 180)
			(layer "F.SilkS")
			(hide yes)
			(effects
				(font
					(size 1.27 1.27)
				)
			)
		)
		(property "Value" "SC22U25V5MX-GP"
			(at -0.0762 -6.1214 180)
			(unlocked yes)
			(layer "F.Fab")
			(hide yes)
			(effects
				(font
					(size 1.016 1.016)
					(thickness 0.1524)
				)
			)
		)
		(property "Device Type" "C805H58"
			(at -0.0762 -8.1534 180)
			(unlocked yes)
			(layer "F.Fab")
			(hide yes)
			(effects
				(font
					(size 1.016 1.016)
					(thickness 0.1524)
				)
			)
		)
		(duplicate_pad_numbers_are_jumpers no)
		(fp_line
			(start 0.635 0)
			(end -0.635 0)
			(stroke
				(width 0.508)
				(type default)
			)
			(layer "F.SilkS")
		)
		(fp_rect
			(start -0.9652 1.778)
			(end 0.9652 -1.778)
			(stroke
				(width 0)
				(type default)
			)
			(fill no)
			(layer "F.CrtYd")
		)
		(fp_poly
			(pts
				(xy -0.9652 -1.778) (xy 0.9652 -1.778) (xy 0.9652 1.778) (xy -0.9652 1.778)
			)
			(stroke
				(width 0)
				(type default)
			)
			(fill no)
			(layer "F.Fab")
		)
		(pad "1" smd rect
			(at 0 -0.9652 180)
			(size 1.397 1.143)
			(layers "F.Cu" "F.Mask" "F.Paste")
			(net "P3V3_STBY_VIN")
		)
		(pad "2" smd rect
			(at 0 0.9652 180)
			(size 1.397 1.143)
			(layers "F.Cu" "F.Mask" "F.Paste")
			(net "GND")
		)
	)
	(footprint ""
		(layer "F.Cu")
		(at 328.413872 -214.702136 180)
		(property "Reference" "R181"
			(at 0 0 180)
			(layer "F.SilkS")
			(hide yes)
			(effects
				(font
					(size 1.27 1.27)
				)
			)
		)
		(property "Value" "0R2J-2-GP"
			(at 0.064008 -3.993896 180)
			(unlocked yes)
			(layer "F.Fab")
			(hide yes)
			(effects
				(font
					(size 1.016 1.016)
					(thickness 0.1524)
				)
			)
		)
		(property "Device Type" "R402H16"
			(at 0.064008 -5.517896 180)
			(unlocked yes)
			(layer "F.Fab")
			(hide yes)
			(effects
				(font
					(size 1.016 1.016)
					(thickness 0.1524)
				)
			)
		)
		(duplicate_pad_numbers_are_jumpers no)
		(fp_line
			(start 0.508 -0.9398)
			(end -0.508 -0.9398)
			(stroke
				(width 0.1524)
				(type default)
			)
			(layer "F.SilkS")
		)
		(fp_line
			(start -0.508 -0.9398)
			(end -0.508 0.9398)
			(stroke
				(width 0.1524)
				(type default)
			)
			(layer "F.SilkS")
		)
		(fp_rect
			(start -0.508 0.9398)
			(end 0.508 -0.9398)
			(stroke
				(width 0)
				(type default)
			)
			(fill no)
			(layer "F.CrtYd")
		)
		(fp_rect
			(start -0.508 0.9398)
			(end 0.508 -0.9398)
			(stroke
				(width 0)
				(type default)
			)
			(fill no)
			(layer "F.Fab")
		)
		(pad "1" smd custom
			(at 0 -0.4445 180)
			(size 0.1397 0.1397)
			(layers "F.Cu" "F.Mask" "F.Paste")
			(net "ADC_P3V3_STBY")
			(options
				(clearance outline)
				(anchor circle)
			)
			(primitives
				(gr_poly
					(pts
						(arc
							(start -0.1778 -0.2794)
							(mid -0.249642 -0.249642)
							(end -0.2794 -0.1778)
						)
						(arc
							(start -0.2794 0.1778)
							(mid -0.249642 0.249642)
							(end -0.1778 0.2794)
						)
						(arc
							(start 0.1778 0.2794)
							(mid 0.249642 0.249642)
							(end 0.2794 0.1778)
						)
						(arc
							(start 0.2794 -0.1778)
							(mid 0.249642 -0.249642)
							(end 0.1778 -0.2794)
						)
					)
					(width 0)
					(fill yes)
				)
			)
		)
		(pad "2" smd custom
			(at 0 0.4445 180)
			(size 0.1397 0.1397)
			(layers "F.Cu" "F.Mask" "F.Paste")
			(net "3V3_STBY_SENSE")
			(options
				(clearance outline)
				(anchor circle)
			)
			(primitives
				(gr_poly
					(pts
						(arc
							(start -0.1778 -0.2794)
							(mid -0.249642 -0.249642)
							(end -0.2794 -0.1778)
						)
						(arc
							(start -0.2794 0.1778)
							(mid -0.249642 0.249642)
							(end -0.1778 0.2794)
						)
						(arc
							(start 0.1778 0.2794)
							(mid 0.249642 0.249642)
							(end 0.2794 0.1778)
						)
						(arc
							(start 0.2794 -0.1778)
							(mid 0.249642 -0.249642)
							(end 0.1778 -0.2794)
						)
					)
					(width 0)
					(fill yes)
				)
			)
		)
	)
	(footprint ""
		(layer "F.Cu")
		(at 280.9748 -183.6674)
		(property "Reference" "TP144"
			(at 0 0 0)
			(layer "F.SilkS")
			(hide yes)
			(effects
				(font
					(size 1.27 1.27)
				)
			)
		)
		(property "Value" "TPAD28"
			(at 0.0127 -1.8034 0)
			(unlocked yes)
			(layer "F.Fab")
			(hide yes)
			(effects
				(font
					(size 1.016 1.016)
					(thickness 0.1524)
				)
			)
		)
		(property "Device Type" "TPAD28"
			(at 0.0127 -3.3274 0)
			(unlocked yes)
			(layer "F.Fab")
			(hide yes)
			(effects
				(font
					(size 1.016 1.016)
					(thickness 0.1524)
				)
			)
		)
		(duplicate_pad_numbers_are_jumpers no)
		(fp_poly
			(pts
				(arc
					(start 0.3556 0)
					(mid -0.3556 0)
					(end 0.3556 0)
				)
			)
			(stroke
				(width 0)
				(type default)
			)
			(fill no)
			(layer "F.CrtYd")
		)
		(fp_poly
			(pts
				(arc
					(start 0.6096 0)
					(mid -0.6096 0)
					(end 0.6096 0)
				)
			)
			(stroke
				(width 0)
				(type default)
			)
			(fill no)
			(layer "F.Fab")
		)
		(pad "1" smd circle
			(at 0 0)
			(size 0.7112 0.7112)
			(layers "F.Cu" "F.Mask" "F.Paste")
			(net "TP_BMC_GPIOR2")
		)
	)
	(footprint ""
		(layer "F.Cu")
		(at 104.53497 -78.613)
		(property "Reference" "STP148"
			(at 0 0 0)
			(layer "F.SilkS")
			(hide yes)
			(effects
				(font
					(size 1.27 1.27)
				)
			)
		)
		(property "Value" "TPAD28"
			(at 0.0127 -1.8034 0)
			(unlocked yes)
			(layer "F.Fab")
			(hide yes)
			(effects
				(font
					(size 1.016 1.016)
					(thickness 0.1524)
				)
			)
		)
		(property "Device Type" "TPAD28"
			(at 0.0127 -3.3274 0)
			(unlocked yes)
			(layer "F.Fab")
			(hide yes)
			(effects
				(font
					(size 1.016 1.016)
					(thickness 0.1524)
				)
			)
		)
		(duplicate_pad_numbers_are_jumpers no)
		(fp_poly
			(pts
				(arc
					(start 0.3556 0)
					(mid -0.3556 0)
					(end 0.3556 0)
				)
			)
			(stroke
				(width 0)
				(type default)
			)
			(fill no)
			(layer "F.CrtYd")
		)
		(fp_poly
			(pts
				(arc
					(start 0.6096 0)
					(mid -0.6096 0)
					(end 0.6096 0)
				)
			)
			(stroke
				(width 0)
				(type default)
			)
			(fill no)
			(layer "F.Fab")
		)
		(pad "1" smd circle
			(at 0 0)
			(size 0.7112 0.7112)
			(layers "F.Cu" "F.Mask" "F.Paste")
			(net "JTAG_EXP_TMS")
		)
	)
	(footprint ""
		(layer "F.Cu")
		(at 83.45297 -129.159)
		(property "Reference" "SC308"
			(at 0 0 0)
			(layer "F.SilkS")
			(hide yes)
			(effects
				(font
					(size 1.27 1.27)
				)
			)
		)
		(property "Value" "SCD1U16V2KX-3GP"
			(at 1.1811 -2.7051 0)
			(unlocked yes)
			(layer "F.Fab")
			(hide yes)
			(effects
				(font
					(size 1.016 1.016)
					(thickness 0.1524)
				)
			)
		)
		(property "Device Type" "C402H22"
			(at 1.1811 -4.2291 0)
			(unlocked yes)
			(layer "F.Fab")
			(hide yes)
			(effects
				(font
					(size 1.016 1.016)
					(thickness 0.1524)
				)
			)
		)
		(duplicate_pad_numbers_are_jumpers no)
		(fp_rect
			(start -0.4318 0.9525)
			(end 0.4318 -0.9525)
			(stroke
				(width 0)
				(type default)
			)
			(fill no)
			(layer "F.CrtYd")
		)
		(fp_rect
			(start -0.4318 0.9525)
			(end 0.4318 -0.9525)
			(stroke
				(width 0)
				(type default)
			)
			(fill no)
			(layer "F.Fab")
		)
		(pad "1" smd custom
			(at 0 -0.4445)
			(size 0.1524 0.1524)
			(layers "F.Cu" "F.Mask" "F.Paste")
			(net "P1V8_E")
			(options
				(clearance outline)
				(anchor circle)
			)
			(primitives
				(gr_poly
					(pts
						(arc
							(start 0.3048 -0.2032)
							(mid 0.275042 -0.275042)
							(end 0.2032 -0.3048)
						)
						(arc
							(start -0.2032 -0.3048)
							(mid -0.275042 -0.275042)
							(end -0.3048 -0.2032)
						)
						(arc
							(start -0.3048 0.2032)
							(mid -0.275042 0.275042)
							(end -0.2032 0.3048)
						)
						(arc
							(start 0.2032 0.3048)
							(mid 0.275042 0.275042)
							(end 0.3048 0.2032)
						)
					)
					(width 0)
					(fill yes)
				)
			)
		)
		(pad "2" smd custom
			(at 0 0.4445)
			(size 0.1524 0.1524)
			(layers "F.Cu" "F.Mask" "F.Paste")
			(net "GND")
			(options
				(clearance outline)
				(anchor circle)
			)
			(primitives
				(gr_poly
					(pts
						(arc
							(start 0.3048 -0.2032)
							(mid 0.275042 -0.275042)
							(end 0.2032 -0.3048)
						)
						(arc
							(start -0.2032 -0.3048)
							(mid -0.275042 -0.275042)
							(end -0.3048 -0.2032)
						)
						(arc
							(start -0.3048 0.2032)
							(mid -0.275042 0.275042)
							(end -0.2032 0.3048)
						)
						(arc
							(start 0.2032 0.3048)
							(mid 0.275042 0.275042)
							(end 0.3048 0.2032)
						)
					)
					(width 0)
					(fill yes)
				)
			)
		)
	)
	(footprint ""
		(layer "F.Cu")
		(at 212.09 -114.935 90)
		(property "Reference" "PR9009"
			(at 0 0 90)
			(layer "F.SilkS")
			(hide yes)
			(effects
				(font
					(size 1.27 1.27)
				)
			)
		)
		(property "Value" "0R6J-3-GP"
			(at -0.0508 -4.8514 90)
			(unlocked yes)
			(layer "F.Fab")
			(hide yes)
			(effects
				(font
					(size 1.016 1.016)
					(thickness 0.1524)
				)
			)
		)
		(property "Device Type" "R1206H28"
			(at 0 -6.3754 90)
			(unlocked yes)
			(layer "F.Fab")
			(hide yes)
			(effects
				(font
					(size 1.016 1.016)
					(thickness 0.1524)
				)
			)
		)
		(duplicate_pad_numbers_are_jumpers no)
		(fp_line
			(start 1.016 -2.2352)
			(end 1.016 2.2352)
			(stroke
				(width 0.1524)
				(type default)
			)
			(layer "F.SilkS")
		)
		(fp_line
			(start -1.016 -2.2352)
			(end 1.016 -2.2352)
			(stroke
				(width 0.1524)
				(type default)
			)
			(layer "F.SilkS")
		)
		(fp_line
			(start 1.016 2.2352)
			(end -1.016 2.2352)
			(stroke
				(width 0.1524)
				(type default)
			)
			(layer "F.SilkS")
		)
		(fp_line
			(start -1.016 2.2352)
			(end -1.016 -2.2352)
			(stroke
				(width 0.1524)
				(type default)
			)
			(layer "F.SilkS")
		)
		(fp_rect
			(start -1.0922 2.3114)
			(end 1.0922 -2.3114)
			(stroke
				(width 0)
				(type default)
			)
			(fill no)
			(layer "F.CrtYd")
		)
		(fp_poly
			(pts
				(xy -1.0922 -2.3114) (xy 1.0922 -2.3114) (xy 1.0922 2.3114) (xy -1.0922 2.3114)
			)
			(stroke
				(width 0)
				(type default)
			)
			(fill no)
			(layer "F.Fab")
		)
		(pad "1" smd rect
			(at 0 -1.397 90)
			(size 1.651 1.27)
			(layers "F.Cu" "F.Mask" "F.Paste")
			(net "P1V5_E_VIN")
		)
		(pad "2" smd rect
			(at 0 1.397 90)
			(size 1.651 1.27)
			(layers "F.Cu" "F.Mask" "F.Paste")
			(net "P12V")
		)
	)
	(footprint ""
		(layer "F.Cu")
		(at 346.075 -112.014 180)
		(property "Reference" "PR4"
			(at 0 0 180)
			(layer "F.SilkS")
			(hide yes)
			(effects
				(font
					(size 1.27 1.27)
				)
			)
		)
		(property "Value" "2D2R3J-2-GP"
			(at -0.0254 -2.5146 180)
			(unlocked yes)
			(layer "F.Fab")
			(hide yes)
			(effects
				(font
					(size 1.016 1.016)
					(thickness 0.1524)
				)
			)
		)
		(property "Device Type" "R603H22"
			(at -0.0254 -4.0386 180)
			(unlocked yes)
			(layer "F.Fab")
			(hide yes)
			(effects
				(font
					(size 1.016 1.016)
					(thickness 0.1524)
				)
			)
		)
		(duplicate_pad_numbers_are_jumpers no)
		(fp_line
			(start 0.2032 0)
			(end 0.4826 0)
			(stroke
				(width 0.2032)
				(type default)
			)
			(layer "F.SilkS")
		)
		(fp_line
			(start -0.4826 0)
			(end -0.2032 0)
			(stroke
				(width 0.2032)
				(type default)
			)
			(layer "F.SilkS")
		)
		(fp_rect
			(start -0.5842 1.3335)
			(end 0.5842 -1.3335)
			(stroke
				(width 0)
				(type default)
			)
			(fill no)
			(layer "F.CrtYd")
		)
		(fp_rect
			(start -0.5842 1.3335)
			(end 0.5842 -1.3335)
			(stroke
				(width 0)
				(type default)
			)
			(fill no)
			(layer "F.Fab")
		)
		(pad "1" smd custom
			(at 0 -0.762 180)
			(size 0.2159 0.2159)
			(layers "F.Cu" "F.Mask" "F.Paste")
			(net "P5V_STBY_VIN")
			(options
				(clearance outline)
				(anchor circle)
			)
			(primitives
				(gr_poly
					(pts
						(arc
							(start -0.3302 -0.4318)
							(mid -0.402042 -0.402042)
							(end -0.4318 -0.3302)
						)
						(arc
							(start -0.4318 0.3302)
							(mid -0.402042 0.402042)
							(end -0.3302 0.4318)
						)
						(arc
							(start 0.3302 0.4318)
							(mid 0.402042 0.402042)
							(end 0.4318 0.3302)
						)
						(arc
							(start 0.4318 -0.3302)
							(mid 0.402042 -0.402042)
							(end 0.3302 -0.4318)
						)
					)
					(width 0)
					(fill yes)
				)
			)
		)
		(pad "2" smd custom
			(at 0 0.762 180)
			(size 0.2159 0.2159)
			(layers "F.Cu" "F.Mask" "F.Paste")
			(net "P5V_STBY_VCC")
			(options
				(clearance outline)
				(anchor circle)
			)
			(primitives
				(gr_poly
					(pts
						(arc
							(start -0.3302 -0.4318)
							(mid -0.402042 -0.402042)
							(end -0.4318 -0.3302)
						)
						(arc
							(start -0.4318 0.3302)
							(mid -0.402042 0.402042)
							(end -0.3302 0.4318)
						)
						(arc
							(start 0.3302 0.4318)
							(mid 0.402042 0.402042)
							(end 0.4318 0.3302)
						)
						(arc
							(start 0.4318 -0.3302)
							(mid 0.402042 -0.402042)
							(end 0.3302 -0.4318)
						)
					)
					(width 0)
					(fill yes)
				)
			)
		)
	)
	(footprint ""
		(layer "F.Cu")
		(at 201.699876 -148.200872 90)
		(property "Reference" "SC1283"
			(at 0 0 90)
			(layer "F.SilkS")
			(hide yes)
			(effects
				(font
					(size 1.27 1.27)
				)
			)
		)
		(property "Value" "SCD1U16V2KX-3GP"
			(at 1.1811 -2.7051 90)
			(unlocked yes)
			(layer "F.Fab")
			(hide yes)
			(effects
				(font
					(size 1.016 1.016)
					(thickness 0.1524)
				)
			)
		)
		(property "Device Type" "C402H22"
			(at 1.1811 -4.2291 90)
			(unlocked yes)
			(layer "F.Fab")
			(hide yes)
			(effects
				(font
					(size 1.016 1.016)
					(thickness 0.1524)
				)
			)
		)
		(duplicate_pad_numbers_are_jumpers no)
		(fp_rect
			(start -0.4318 0.9525)
			(end 0.4318 -0.9525)
			(stroke
				(width 0)
				(type default)
			)
			(fill no)
			(layer "F.CrtYd")
		)
		(fp_rect
			(start -0.4318 0.9525)
			(end 0.4318 -0.9525)
			(stroke
				(width 0)
				(type default)
			)
			(fill no)
			(layer "F.Fab")
		)
		(pad "1" smd custom
			(at 0 -0.4445 90)
			(size 0.1524 0.1524)
			(layers "F.Cu" "F.Mask" "F.Paste")
			(net "EXP_I2C_VREF_2")
			(options
				(clearance outline)
				(anchor circle)
			)
			(primitives
				(gr_poly
					(pts
						(arc
							(start 0.3048 -0.2032)
							(mid 0.275042 -0.275042)
							(end 0.2032 -0.3048)
						)
						(arc
							(start -0.2032 -0.3048)
							(mid -0.275042 -0.275042)
							(end -0.3048 -0.2032)
						)
						(arc
							(start -0.3048 0.2032)
							(mid -0.275042 0.275042)
							(end -0.2032 0.3048)
						)
						(arc
							(start 0.2032 0.3048)
							(mid 0.275042 0.275042)
							(end 0.3048 0.2032)
						)
					)
					(width 0)
					(fill yes)
				)
			)
		)
		(pad "2" smd custom
			(at 0 0.4445 90)
			(size 0.1524 0.1524)
			(layers "F.Cu" "F.Mask" "F.Paste")
			(net "GND")
			(options
				(clearance outline)
				(anchor circle)
			)
			(primitives
				(gr_poly
					(pts
						(arc
							(start 0.3048 -0.2032)
							(mid 0.275042 -0.275042)
							(end 0.2032 -0.3048)
						)
						(arc
							(start -0.2032 -0.3048)
							(mid -0.275042 -0.275042)
							(end -0.3048 -0.2032)
						)
						(arc
							(start -0.3048 0.2032)
							(mid -0.275042 0.275042)
							(end -0.2032 0.3048)
						)
						(arc
							(start 0.2032 0.3048)
							(mid 0.275042 0.275042)
							(end 0.3048 0.2032)
						)
					)
					(width 0)
					(fill yes)
				)
			)
		)
	)
	(footprint ""
		(layer "F.Cu")
		(at 54.356 -206.248 90)
		(property "Reference" "R691"
			(at 0 0 90)
			(layer "F.SilkS")
			(hide yes)
			(effects
				(font
					(size 1.27 1.27)
				)
			)
		)
		(property "Value" "0R2J-2-GP"
			(at 0.064008 -3.993896 90)
			(unlocked yes)
			(layer "F.Fab")
			(hide yes)
			(effects
				(font
					(size 1.016 1.016)
					(thickness 0.1524)
				)
			)
		)
		(property "Device Type" "R402H16"
			(at 0.064008 -5.517896 90)
			(unlocked yes)
			(layer "F.Fab")
			(hide yes)
			(effects
				(font
					(size 1.016 1.016)
					(thickness 0.1524)
				)
			)
		)
		(duplicate_pad_numbers_are_jumpers no)
		(fp_line
			(start 0.508 -0.9398)
			(end -0.508 -0.9398)
			(stroke
				(width 0.1524)
				(type default)
			)
			(layer "F.SilkS")
		)
		(fp_line
			(start -0.508 -0.9398)
			(end -0.508 0.9398)
			(stroke
				(width 0.1524)
				(type default)
			)
			(layer "F.SilkS")
		)
		(fp_rect
			(start -0.508 0.9398)
			(end 0.508 -0.9398)
			(stroke
				(width 0)
				(type default)
			)
			(fill no)
			(layer "F.CrtYd")
		)
		(fp_rect
			(start -0.508 0.9398)
			(end 0.508 -0.9398)
			(stroke
				(width 0)
				(type default)
			)
			(fill no)
			(layer "F.Fab")
		)
		(pad "1" smd custom
			(at 0 -0.4445 90)
			(size 0.1397 0.1397)
			(layers "F.Cu" "F.Mask" "F.Paste")
			(net "MATED_P12V_EN")
			(options
				(clearance outline)
				(anchor circle)
			)
			(primitives
				(gr_poly
					(pts
						(arc
							(start -0.1778 -0.2794)
							(mid -0.249642 -0.249642)
							(end -0.2794 -0.1778)
						)
						(arc
							(start -0.2794 0.1778)
							(mid -0.249642 0.249642)
							(end -0.1778 0.2794)
						)
						(arc
							(start 0.1778 0.2794)
							(mid 0.249642 0.249642)
							(end 0.2794 0.1778)
						)
						(arc
							(start 0.2794 -0.1778)
							(mid 0.249642 -0.249642)
							(end 0.1778 -0.2794)
						)
					)
					(width 0)
					(fill yes)
				)
			)
		)
		(pad "2" smd custom
			(at 0 0.4445 90)
			(size 0.1397 0.1397)
			(layers "F.Cu" "F.Mask" "F.Paste")
			(net "MB0_HS_ENABLE")
			(options
				(clearance outline)
				(anchor circle)
			)
			(primitives
				(gr_poly
					(pts
						(arc
							(start -0.1778 -0.2794)
							(mid -0.249642 -0.249642)
							(end -0.2794 -0.1778)
						)
						(arc
							(start -0.2794 0.1778)
							(mid -0.249642 0.249642)
							(end -0.1778 0.2794)
						)
						(arc
							(start 0.1778 0.2794)
							(mid 0.249642 0.249642)
							(end 0.2794 0.1778)
						)
						(arc
							(start 0.2794 -0.1778)
							(mid 0.249642 -0.249642)
							(end 0.1778 -0.2794)
						)
					)
					(width 0)
					(fill yes)
				)
			)
		)
	)
	(footprint ""
		(layer "F.Cu")
		(at 292.083236 -148.125688)
		(property "Reference" "R399"
			(at 0 0 0)
			(layer "F.SilkS")
			(hide yes)
			(effects
				(font
					(size 1.27 1.27)
				)
			)
		)
		(property "Value" "10KR2F-2-GP"
			(at 0.064008 -3.993896 0)
			(unlocked yes)
			(layer "F.Fab")
			(hide yes)
			(effects
				(font
					(size 1.016 1.016)
					(thickness 0.1524)
				)
			)
		)
		(property "Device Type" "R402H16"
			(at 0.064008 -5.517896 0)
			(unlocked yes)
			(layer "F.Fab")
			(hide yes)
			(effects
				(font
					(size 1.016 1.016)
					(thickness 0.1524)
				)
			)
		)
		(duplicate_pad_numbers_are_jumpers no)
		(fp_line
			(start -0.508 -0.9398)
			(end -0.508 0.9398)
			(stroke
				(width 0.1524)
				(type default)
			)
			(layer "F.SilkS")
		)
		(fp_line
			(start 0.508 -0.9398)
			(end -0.508 -0.9398)
			(stroke
				(width 0.1524)
				(type default)
			)
			(layer "F.SilkS")
		)
		(fp_rect
			(start -0.508 0.9398)
			(end 0.508 -0.9398)
			(stroke
				(width 0)
				(type default)
			)
			(fill no)
			(layer "F.CrtYd")
		)
		(fp_rect
			(start -0.508 0.9398)
			(end 0.508 -0.9398)
			(stroke
				(width 0)
				(type default)
			)
			(fill no)
			(layer "F.Fab")
		)
		(pad "1" smd custom
			(at 0 -0.4445)
			(size 0.1397 0.1397)
			(layers "F.Cu" "F.Mask" "F.Paste")
			(net "P3V3_STBY")
			(options
				(clearance outline)
				(anchor circle)
			)
			(primitives
				(gr_poly
					(pts
						(arc
							(start -0.1778 -0.2794)
							(mid -0.249642 -0.249642)
							(end -0.2794 -0.1778)
						)
						(arc
							(start -0.2794 0.1778)
							(mid -0.249642 0.249642)
							(end -0.1778 0.2794)
						)
						(arc
							(start 0.1778 0.2794)
							(mid 0.249642 0.249642)
							(end 0.2794 0.1778)
						)
						(arc
							(start 0.2794 -0.1778)
							(mid 0.249642 -0.249642)
							(end 0.1778 -0.2794)
						)
					)
					(width 0)
					(fill yes)
				)
			)
		)
		(pad "2" smd custom
			(at 0 0.4445)
			(size 0.1397 0.1397)
			(layers "F.Cu" "F.Mask" "F.Paste")
			(net "FM_OSC_50M_EN")
			(options
				(clearance outline)
				(anchor circle)
			)
			(primitives
				(gr_poly
					(pts
						(arc
							(start -0.1778 -0.2794)
							(mid -0.249642 -0.249642)
							(end -0.2794 -0.1778)
						)
						(arc
							(start -0.2794 0.1778)
							(mid -0.249642 0.249642)
							(end -0.1778 0.2794)
						)
						(arc
							(start 0.1778 0.2794)
							(mid 0.249642 0.249642)
							(end 0.2794 0.1778)
						)
						(arc
							(start 0.2794 -0.1778)
							(mid 0.249642 -0.249642)
							(end 0.1778 -0.2794)
						)
					)
					(width 0)
					(fill yes)
				)
			)
		)
	)
	(footprint ""
		(layer "F.Cu")
		(at 92.21597 -100.076 -90)
		(property "Reference" "SR776"
			(at 0 0 270)
			(layer "F.SilkS")
			(hide yes)
			(effects
				(font
					(size 1.27 1.27)
				)
			)
		)
		(property "Value" "4K7R2F-GP"
			(at 0.064008 -3.993896 270)
			(unlocked yes)
			(layer "F.Fab")
			(hide yes)
			(effects
				(font
					(size 1.016 1.016)
					(thickness 0.1524)
				)
			)
		)
		(property "Device Type" "R402H16"
			(at 0.064008 -5.517896 270)
			(unlocked yes)
			(layer "F.Fab")
			(hide yes)
			(effects
				(font
					(size 1.016 1.016)
					(thickness 0.1524)
				)
			)
		)
		(duplicate_pad_numbers_are_jumpers no)
		(fp_line
			(start -0.508 -0.9398)
			(end -0.508 0.9398)
			(stroke
				(width 0.1524)
				(type default)
			)
			(layer "F.SilkS")
		)
		(fp_line
			(start 0.508 -0.9398)
			(end -0.508 -0.9398)
			(stroke
				(width 0.1524)
				(type default)
			)
			(layer "F.SilkS")
		)
		(fp_rect
			(start -0.508 0.9398)
			(end 0.508 -0.9398)
			(stroke
				(width 0)
				(type default)
			)
			(fill no)
			(layer "F.CrtYd")
		)
		(fp_rect
			(start -0.508 0.9398)
			(end 0.508 -0.9398)
			(stroke
				(width 0)
				(type default)
			)
			(fill no)
			(layer "F.Fab")
		)
		(pad "1" smd custom
			(at 0 -0.4445 270)
			(size 0.1397 0.1397)
			(layers "F.Cu" "F.Mask" "F.Paste")
			(net "EXP_XM_ADDR_15")
			(options
				(clearance outline)
				(anchor circle)
			)
			(primitives
				(gr_poly
					(pts
						(arc
							(start -0.1778 -0.2794)
							(mid -0.249642 -0.249642)
							(end -0.2794 -0.1778)
						)
						(arc
							(start -0.2794 0.1778)
							(mid -0.249642 0.249642)
							(end -0.1778 0.2794)
						)
						(arc
							(start 0.1778 0.2794)
							(mid 0.249642 0.249642)
							(end 0.2794 0.1778)
						)
						(arc
							(start 0.2794 -0.1778)
							(mid 0.249642 -0.249642)
							(end 0.1778 -0.2794)
						)
					)
					(width 0)
					(fill yes)
				)
			)
		)
		(pad "2" smd custom
			(at 0 0.4445 270)
			(size 0.1397 0.1397)
			(layers "F.Cu" "F.Mask" "F.Paste")
			(net "GND")
			(options
				(clearance outline)
				(anchor circle)
			)
			(primitives
				(gr_poly
					(pts
						(arc
							(start -0.1778 -0.2794)
							(mid -0.249642 -0.249642)
							(end -0.2794 -0.1778)
						)
						(arc
							(start -0.2794 0.1778)
							(mid -0.249642 0.249642)
							(end -0.1778 0.2794)
						)
						(arc
							(start 0.1778 0.2794)
							(mid 0.249642 0.249642)
							(end 0.2794 0.1778)
						)
						(arc
							(start 0.2794 -0.1778)
							(mid 0.249642 -0.249642)
							(end 0.1778 -0.2794)
						)
					)
					(width 0)
					(fill yes)
				)
			)
		)
	)
	(footprint ""
		(layer "F.Cu")
		(at 22.302216 -213.79688)
		(property "Reference" "R633"
			(at 0 0 0)
			(layer "F.SilkS")
			(hide yes)
			(effects
				(font
					(size 1.27 1.27)
				)
			)
		)
		(property "Value" "4K7R2F-GP"
			(at 0.064008 -3.993896 0)
			(unlocked yes)
			(layer "F.Fab")
			(hide yes)
			(effects
				(font
					(size 1.016 1.016)
					(thickness 0.1524)
				)
			)
		)
		(property "Device Type" "R402H16"
			(at 0.064008 -5.517896 0)
			(unlocked yes)
			(layer "F.Fab")
			(hide yes)
			(effects
				(font
					(size 1.016 1.016)
					(thickness 0.1524)
				)
			)
		)
		(duplicate_pad_numbers_are_jumpers no)
		(fp_line
			(start -0.508 -0.9398)
			(end -0.508 0.9398)
			(stroke
				(width 0.1524)
				(type default)
			)
			(layer "F.SilkS")
		)
		(fp_line
			(start 0.508 -0.9398)
			(end -0.508 -0.9398)
			(stroke
				(width 0.1524)
				(type default)
			)
			(layer "F.SilkS")
		)
		(fp_rect
			(start -0.508 0.9398)
			(end 0.508 -0.9398)
			(stroke
				(width 0)
				(type default)
			)
			(fill no)
			(layer "F.CrtYd")
		)
		(fp_rect
			(start -0.508 0.9398)
			(end 0.508 -0.9398)
			(stroke
				(width 0)
				(type default)
			)
			(fill no)
			(layer "F.Fab")
		)
		(pad "1" smd custom
			(at 0 -0.4445)
			(size 0.1397 0.1397)
			(layers "F.Cu" "F.Mask" "F.Paste")
			(net "IO_EXP_HDD_PWR_A1")
			(options
				(clearance outline)
				(anchor circle)
			)
			(primitives
				(gr_poly
					(pts
						(arc
							(start -0.1778 -0.2794)
							(mid -0.249642 -0.249642)
							(end -0.2794 -0.1778)
						)
						(arc
							(start -0.2794 0.1778)
							(mid -0.249642 0.249642)
							(end -0.1778 0.2794)
						)
						(arc
							(start 0.1778 0.2794)
							(mid 0.249642 0.249642)
							(end 0.2794 0.1778)
						)
						(arc
							(start 0.2794 -0.1778)
							(mid 0.249642 -0.249642)
							(end 0.1778 -0.2794)
						)
					)
					(width 0)
					(fill yes)
				)
			)
		)
		(pad "2" smd custom
			(at 0 0.4445)
			(size 0.1397 0.1397)
			(layers "F.Cu" "F.Mask" "F.Paste")
			(net "GND")
			(options
				(clearance outline)
				(anchor circle)
			)
			(primitives
				(gr_poly
					(pts
						(arc
							(start -0.1778 -0.2794)
							(mid -0.249642 -0.249642)
							(end -0.2794 -0.1778)
						)
						(arc
							(start -0.2794 0.1778)
							(mid -0.249642 0.249642)
							(end -0.1778 0.2794)
						)
						(arc
							(start 0.1778 0.2794)
							(mid 0.249642 0.249642)
							(end 0.2794 0.1778)
						)
						(arc
							(start 0.2794 -0.1778)
							(mid 0.249642 -0.249642)
							(end 0.1778 -0.2794)
						)
					)
					(width 0)
					(fill yes)
				)
			)
		)
	)
	(footprint ""
		(layer "F.Cu")
		(at 78.10119 -62.705488 180)
		(property "Reference" "SL5"
			(at 0 0 180)
			(layer "F.SilkS")
			(hide yes)
			(effects
				(font
					(size 1.27 1.27)
				)
			)
		)
		(property "Value" "MPZ2012S601AT-GP"
			(at 0 -4.2418 180)
			(unlocked yes)
			(layer "F.Fab")
			(hide yes)
			(effects
				(font
					(size 1.016 1.016)
					(thickness 0.1524)
				)
			)
		)
		(property "Device Type" "L805H42"
			(at 0 -5.7912 180)
			(unlocked yes)
			(layer "F.Fab")
			(hide yes)
			(effects
				(font
					(size 1.016 1.016)
					(thickness 0.1524)
				)
			)
		)
		(duplicate_pad_numbers_are_jumpers no)
		(fp_line
			(start 0.889 1.7018)
			(end -0.889 1.7018)
			(stroke
				(width 0.1524)
				(type default)
			)
			(layer "F.SilkS")
		)
		(fp_line
			(start 0.889 -1.7018)
			(end 0.889 1.7018)
			(stroke
				(width 0.1524)
				(type default)
			)
			(layer "F.SilkS")
		)
		(fp_line
			(start -0.889 1.7018)
			(end -0.889 -1.7018)
			(stroke
				(width 0.1524)
				(type default)
			)
			(layer "F.SilkS")
		)
		(fp_line
			(start -0.889 -1.7018)
			(end 0.889 -1.7018)
			(stroke
				(width 0.1524)
				(type default)
			)
			(layer "F.SilkS")
		)
		(fp_rect
			(start -0.9652 1.778)
			(end 0.9652 -1.778)
			(stroke
				(width 0)
				(type default)
			)
			(fill no)
			(layer "F.CrtYd")
		)
		(fp_rect
			(start -0.9652 1.778)
			(end 0.9652 -1.778)
			(stroke
				(width 0)
				(type default)
			)
			(fill no)
			(layer "F.Fab")
		)
		(pad "1" smd rect
			(at 0 -0.9652 180)
			(size 1.397 1.143)
			(layers "F.Cu" "F.Mask" "F.Paste")
			(net "SHELL_PLL_VDD")
		)
		(pad "2" smd rect
			(at 0 0.9652 180)
			(size 1.397 1.143)
			(layers "F.Cu" "F.Mask" "F.Paste")
			(net "P1V8_C")
		)
	)
	(footprint ""
		(layer "F.Cu")
		(at 118.237 -31.115)
		(property "Reference" "STP131"
			(at 0 0 0)
			(layer "F.SilkS")
			(hide yes)
			(effects
				(font
					(size 1.27 1.27)
				)
			)
		)
		(property "Value" "TPAD28"
			(at 0.0127 -1.8034 0)
			(unlocked yes)
			(layer "F.Fab")
			(hide yes)
			(effects
				(font
					(size 1.016 1.016)
					(thickness 0.1524)
				)
			)
		)
		(property "Device Type" "TPAD28"
			(at 0.0127 -3.3274 0)
			(unlocked yes)
			(layer "F.Fab")
			(hide yes)
			(effects
				(font
					(size 1.016 1.016)
					(thickness 0.1524)
				)
			)
		)
		(duplicate_pad_numbers_are_jumpers no)
		(fp_poly
			(pts
				(arc
					(start 0.3556 0)
					(mid -0.3556 0)
					(end 0.3556 0)
				)
			)
			(stroke
				(width 0)
				(type default)
			)
			(fill no)
			(layer "F.CrtYd")
		)
		(fp_poly
			(pts
				(arc
					(start 0.6096 0)
					(mid -0.6096 0)
					(end 0.6096 0)
				)
			)
			(stroke
				(width 0)
				(type default)
			)
			(fill no)
			(layer "F.Fab")
		)
		(pad "1" smd circle
			(at 0 0)
			(size 0.7112 0.7112)
			(layers "F.Cu" "F.Mask" "F.Paste")
			(net "IOC_GPIO_4")
		)
	)
	(footprint ""
		(layer "F.Cu")
		(at 116.85397 -79.248)
		(property "Reference" "STP110"
			(at 0 0 0)
			(layer "F.SilkS")
			(hide yes)
			(effects
				(font
					(size 1.27 1.27)
				)
			)
		)
		(property "Value" "TPAD28"
			(at 0.0127 -1.8034 0)
			(unlocked yes)
			(layer "F.Fab")
			(hide yes)
			(effects
				(font
					(size 1.016 1.016)
					(thickness 0.1524)
				)
			)
		)
		(property "Device Type" "TPAD28"
			(at 0.0127 -3.3274 0)
			(unlocked yes)
			(layer "F.Fab")
			(hide yes)
			(effects
				(font
					(size 1.016 1.016)
					(thickness 0.1524)
				)
			)
		)
		(duplicate_pad_numbers_are_jumpers no)
		(fp_poly
			(pts
				(arc
					(start 0.3556 0)
					(mid -0.3556 0)
					(end 0.3556 0)
				)
			)
			(stroke
				(width 0)
				(type default)
			)
			(fill no)
			(layer "F.CrtYd")
		)
		(fp_poly
			(pts
				(arc
					(start 0.6096 0)
					(mid -0.6096 0)
					(end 0.6096 0)
				)
			)
			(stroke
				(width 0)
				(type default)
			)
			(fill no)
			(layer "F.Fab")
		)
		(pad "1" smd circle
			(at 0 0)
			(size 0.7112 0.7112)
			(layers "F.Cu" "F.Mask" "F.Paste")
			(net "TEST_MUX_43")
		)
	)
	(footprint ""
		(layer "F.Cu")
		(at 347.345 -92.075 90)
		(property "Reference" "PC18"
			(at 0 0 90)
			(layer "F.SilkS")
			(hide yes)
			(effects
				(font
					(size 1.27 1.27)
				)
			)
		)
		(property "Value" "SC47U10V6MX-GP"
			(at -0.0762 -5.1308 90)
			(unlocked yes)
			(layer "F.Fab")
			(hide yes)
			(effects
				(font
					(size 1.016 1.016)
					(thickness 0.1524)
				)
			)
		)
		(property "Device Type" "C1206H71"
			(at -0.127 -6.6548 90)
			(unlocked yes)
			(layer "F.Fab")
			(hide yes)
			(effects
				(font
					(size 1.016 1.016)
					(thickness 0.1524)
				)
			)
		)
		(duplicate_pad_numbers_are_jumpers no)
		(fp_line
			(start 1.016 -2.2352)
			(end 1.016 -0.8382)
			(stroke
				(width 0.1524)
				(type default)
			)
			(layer "F.SilkS")
		)
		(fp_line
			(start -1.016 -2.2352)
			(end 1.016 -2.2352)
			(stroke
				(width 0.1524)
				(type default)
			)
			(layer "F.SilkS")
		)
		(fp_line
			(start -1.016 -0.8382)
			(end -1.016 -2.2352)
			(stroke
				(width 0.1524)
				(type default)
			)
			(layer "F.SilkS")
		)
		(fp_line
			(start 1.016 0.8382)
			(end 1.016 2.2352)
			(stroke
				(width 0.1524)
				(type default)
			)
			(layer "F.SilkS")
		)
		(fp_line
			(start 1.016 2.2352)
			(end -1.016 2.2352)
			(stroke
				(width 0.1524)
				(type default)
			)
			(layer "F.SilkS")
		)
		(fp_line
			(start -1.016 2.2352)
			(end -1.016 0.8382)
			(stroke
				(width 0.1524)
				(type default)
			)
			(layer "F.SilkS")
		)
		(fp_rect
			(start -1.0922 2.3114)
			(end 1.0922 -2.3114)
			(stroke
				(width 0)
				(type default)
			)
			(fill no)
			(layer "F.CrtYd")
		)
		(fp_poly
			(pts
				(xy 1.0922 -2.3114) (xy 1.0922 2.3114) (xy -1.0922 2.3114) (xy -1.0922 -2.3114)
			)
			(stroke
				(width 0)
				(type default)
			)
			(fill no)
			(layer "F.Fab")
		)
		(pad "1" smd rect
			(at 0 -1.397 90)
			(size 1.651 1.27)
			(layers "F.Cu" "F.Mask" "F.Paste")
			(net "P5V_STBY")
		)
		(pad "2" smd rect
			(at 0 1.397 90)
			(size 1.651 1.27)
			(layers "F.Cu" "F.Mask" "F.Paste")
			(net "GND")
		)
	)
	(footprint ""
		(layer "F.Cu")
		(at 344.805 -117.729)
		(property "Reference" "PR9"
			(at 0 0 0)
			(layer "F.SilkS")
			(hide yes)
			(effects
				(font
					(size 1.27 1.27)
				)
			)
		)
		(property "Value" "10R3F-GP"
			(at -0.0254 -2.5146 0)
			(unlocked yes)
			(layer "F.Fab")
			(hide yes)
			(effects
				(font
					(size 1.016 1.016)
					(thickness 0.1524)
				)
			)
		)
		(property "Device Type" "R603H22"
			(at -0.0254 -4.0386 0)
			(unlocked yes)
			(layer "F.Fab")
			(hide yes)
			(effects
				(font
					(size 1.016 1.016)
					(thickness 0.1524)
				)
			)
		)
		(duplicate_pad_numbers_are_jumpers no)
		(fp_line
			(start -0.4826 0)
			(end -0.2032 0)
			(stroke
				(width 0.2032)
				(type default)
			)
			(layer "F.SilkS")
		)
		(fp_line
			(start 0.2032 0)
			(end 0.4826 0)
			(stroke
				(width 0.2032)
				(type default)
			)
			(layer "F.SilkS")
		)
		(fp_rect
			(start -0.5842 1.3335)
			(end 0.5842 -1.3335)
			(stroke
				(width 0)
				(type default)
			)
			(fill no)
			(layer "F.CrtYd")
		)
		(fp_rect
			(start -0.5842 1.3335)
			(end 0.5842 -1.3335)
			(stroke
				(width 0)
				(type default)
			)
			(fill no)
			(layer "F.Fab")
		)
		(pad "1" smd custom
			(at 0 -0.762)
			(size 0.2159 0.2159)
			(layers "F.Cu" "F.Mask" "F.Paste")
			(net "P5V_STBY_CC")
			(options
				(clearance outline)
				(anchor circle)
			)
			(primitives
				(gr_poly
					(pts
						(arc
							(start -0.3302 -0.4318)
							(mid -0.402042 -0.402042)
							(end -0.4318 -0.3302)
						)
						(arc
							(start -0.4318 0.3302)
							(mid -0.402042 0.402042)
							(end -0.3302 0.4318)
						)
						(arc
							(start 0.3302 0.4318)
							(mid 0.402042 0.402042)
							(end 0.4318 0.3302)
						)
						(arc
							(start 0.4318 -0.3302)
							(mid 0.402042 -0.402042)
							(end 0.3302 -0.4318)
						)
					)
					(width 0)
					(fill yes)
				)
			)
		)
		(pad "2" smd custom
			(at 0 0.762)
			(size 0.2159 0.2159)
			(layers "F.Cu" "F.Mask" "F.Paste")
			(net "P5V_STBY_CC_R")
			(options
				(clearance outline)
				(anchor circle)
			)
			(primitives
				(gr_poly
					(pts
						(arc
							(start -0.3302 -0.4318)
							(mid -0.402042 -0.402042)
							(end -0.4318 -0.3302)
						)
						(arc
							(start -0.4318 0.3302)
							(mid -0.402042 0.402042)
							(end -0.3302 0.4318)
						)
						(arc
							(start 0.3302 0.4318)
							(mid 0.402042 0.402042)
							(end 0.4318 0.3302)
						)
						(arc
							(start 0.4318 -0.3302)
							(mid 0.402042 -0.402042)
							(end 0.3302 -0.4318)
						)
					)
					(width 0)
					(fill yes)
				)
			)
		)
	)
	(footprint ""
		(layer "F.Cu")
		(at 85.852 -242.443 180)
		(property "Reference" "SR951"
			(at 0 0 180)
			(layer "F.SilkS")
			(hide yes)
			(effects
				(font
					(size 1.27 1.27)
				)
			)
		)
		(property "Value" "4K7R2F-GP"
			(at 0.064008 -3.993896 180)
			(unlocked yes)
			(layer "F.Fab")
			(hide yes)
			(effects
				(font
					(size 1.016 1.016)
					(thickness 0.1524)
				)
			)
		)
		(property "Device Type" "R402H16"
			(at 0.064008 -5.517896 180)
			(unlocked yes)
			(layer "F.Fab")
			(hide yes)
			(effects
				(font
					(size 1.016 1.016)
					(thickness 0.1524)
				)
			)
		)
		(duplicate_pad_numbers_are_jumpers no)
		(fp_line
			(start 0.508 -0.9398)
			(end -0.508 -0.9398)
			(stroke
				(width 0.1524)
				(type default)
			)
			(layer "F.SilkS")
		)
		(fp_line
			(start -0.508 -0.9398)
			(end -0.508 0.9398)
			(stroke
				(width 0.1524)
				(type default)
			)
			(layer "F.SilkS")
		)
		(fp_rect
			(start -0.508 0.9398)
			(end 0.508 -0.9398)
			(stroke
				(width 0)
				(type default)
			)
			(fill no)
			(layer "F.CrtYd")
		)
		(fp_rect
			(start -0.508 0.9398)
			(end 0.508 -0.9398)
			(stroke
				(width 0)
				(type default)
			)
			(fill no)
			(layer "F.Fab")
		)
		(pad "1" smd custom
			(at 0 -0.4445 180)
			(size 0.1397 0.1397)
			(layers "F.Cu" "F.Mask" "F.Paste")
			(net "SAS_FAULT_LED10")
			(options
				(clearance outline)
				(anchor circle)
			)
			(primitives
				(gr_poly
					(pts
						(arc
							(start -0.1778 -0.2794)
							(mid -0.249642 -0.249642)
							(end -0.2794 -0.1778)
						)
						(arc
							(start -0.2794 0.1778)
							(mid -0.249642 0.249642)
							(end -0.1778 0.2794)
						)
						(arc
							(start 0.1778 0.2794)
							(mid 0.249642 0.249642)
							(end 0.2794 0.1778)
						)
						(arc
							(start 0.2794 -0.1778)
							(mid 0.249642 -0.249642)
							(end 0.1778 -0.2794)
						)
					)
					(width 0)
					(fill yes)
				)
			)
		)
		(pad "2" smd custom
			(at 0 0.4445 180)
			(size 0.1397 0.1397)
			(layers "F.Cu" "F.Mask" "F.Paste")
			(net "P3V3_STBY")
			(options
				(clearance outline)
				(anchor circle)
			)
			(primitives
				(gr_poly
					(pts
						(arc
							(start -0.1778 -0.2794)
							(mid -0.249642 -0.249642)
							(end -0.2794 -0.1778)
						)
						(arc
							(start -0.2794 0.1778)
							(mid -0.249642 0.249642)
							(end -0.1778 0.2794)
						)
						(arc
							(start 0.1778 0.2794)
							(mid 0.249642 0.249642)
							(end 0.2794 0.1778)
						)
						(arc
							(start 0.2794 -0.1778)
							(mid 0.249642 -0.249642)
							(end 0.1778 -0.2794)
						)
					)
					(width 0)
					(fill yes)
				)
			)
		)
	)
	(footprint ""
		(layer "F.Cu")
		(at 184.776872 -203.703936 -90)
		(property "Reference" "R425"
			(at 0 0 270)
			(layer "F.SilkS")
			(hide yes)
			(effects
				(font
					(size 1.27 1.27)
				)
			)
		)
		(property "Value" "4K7R2J-2-GP"
			(at 0.064008 -3.993896 270)
			(unlocked yes)
			(layer "F.Fab")
			(hide yes)
			(effects
				(font
					(size 1.016 1.016)
					(thickness 0.1524)
				)
			)
		)
		(property "Device Type" "R402H16"
			(at 0.064008 -5.517896 270)
			(unlocked yes)
			(layer "F.Fab")
			(hide yes)
			(effects
				(font
					(size 1.016 1.016)
					(thickness 0.1524)
				)
			)
		)
		(duplicate_pad_numbers_are_jumpers no)
		(fp_line
			(start -0.508 -0.9398)
			(end -0.508 0.9398)
			(stroke
				(width 0.1524)
				(type default)
			)
			(layer "F.SilkS")
		)
		(fp_line
			(start 0.508 -0.9398)
			(end -0.508 -0.9398)
			(stroke
				(width 0.1524)
				(type default)
			)
			(layer "F.SilkS")
		)
		(fp_rect
			(start -0.508 0.9398)
			(end 0.508 -0.9398)
			(stroke
				(width 0)
				(type default)
			)
			(fill no)
			(layer "F.CrtYd")
		)
		(fp_rect
			(start -0.508 0.9398)
			(end 0.508 -0.9398)
			(stroke
				(width 0)
				(type default)
			)
			(fill no)
			(layer "F.Fab")
		)
		(pad "1" smd custom
			(at 0 -0.4445 270)
			(size 0.1397 0.1397)
			(layers "F.Cu" "F.Mask" "F.Paste")
			(net "P3V3_STBY")
			(options
				(clearance outline)
				(anchor circle)
			)
			(primitives
				(gr_poly
					(pts
						(arc
							(start -0.1778 -0.2794)
							(mid -0.249642 -0.249642)
							(end -0.2794 -0.1778)
						)
						(arc
							(start -0.2794 0.1778)
							(mid -0.249642 0.249642)
							(end -0.1778 0.2794)
						)
						(arc
							(start 0.1778 0.2794)
							(mid 0.249642 0.249642)
							(end 0.2794 0.1778)
						)
						(arc
							(start 0.2794 -0.1778)
							(mid 0.249642 -0.249642)
							(end 0.1778 -0.2794)
						)
					)
					(width 0)
					(fill yes)
				)
			)
		)
		(pad "2" smd custom
			(at 0 0.4445 270)
			(size 0.1397 0.1397)
			(layers "F.Cu" "F.Mask" "F.Paste")
			(net "SAS_I2C_B_BUF_SDA")
			(options
				(clearance outline)
				(anchor circle)
			)
			(primitives
				(gr_poly
					(pts
						(arc
							(start -0.1778 -0.2794)
							(mid -0.249642 -0.249642)
							(end -0.2794 -0.1778)
						)
						(arc
							(start -0.2794 0.1778)
							(mid -0.249642 0.249642)
							(end -0.1778 0.2794)
						)
						(arc
							(start 0.1778 0.2794)
							(mid 0.249642 0.249642)
							(end 0.2794 0.1778)
						)
						(arc
							(start 0.2794 -0.1778)
							(mid 0.249642 -0.249642)
							(end 0.1778 -0.2794)
						)
					)
					(width 0)
					(fill yes)
				)
			)
		)
	)
	(footprint ""
		(layer "F.Cu")
		(at 91.567 -242.443 180)
		(property "Reference" "SR956"
			(at 0 0 180)
			(layer "F.SilkS")
			(hide yes)
			(effects
				(font
					(size 1.27 1.27)
				)
			)
		)
		(property "Value" "4K7R2F-GP"
			(at 0.064008 -3.993896 180)
			(unlocked yes)
			(layer "F.Fab")
			(hide yes)
			(effects
				(font
					(size 1.016 1.016)
					(thickness 0.1524)
				)
			)
		)
		(property "Device Type" "R402H16"
			(at 0.064008 -5.517896 180)
			(unlocked yes)
			(layer "F.Fab")
			(hide yes)
			(effects
				(font
					(size 1.016 1.016)
					(thickness 0.1524)
				)
			)
		)
		(duplicate_pad_numbers_are_jumpers no)
		(fp_line
			(start 0.508 -0.9398)
			(end -0.508 -0.9398)
			(stroke
				(width 0.1524)
				(type default)
			)
			(layer "F.SilkS")
		)
		(fp_line
			(start -0.508 -0.9398)
			(end -0.508 0.9398)
			(stroke
				(width 0.1524)
				(type default)
			)
			(layer "F.SilkS")
		)
		(fp_rect
			(start -0.508 0.9398)
			(end 0.508 -0.9398)
			(stroke
				(width 0)
				(type default)
			)
			(fill no)
			(layer "F.CrtYd")
		)
		(fp_rect
			(start -0.508 0.9398)
			(end 0.508 -0.9398)
			(stroke
				(width 0)
				(type default)
			)
			(fill no)
			(layer "F.Fab")
		)
		(pad "1" smd custom
			(at 0 -0.4445 180)
			(size 0.1397 0.1397)
			(layers "F.Cu" "F.Mask" "F.Paste")
			(net "SAS_FAULT_LED15")
			(options
				(clearance outline)
				(anchor circle)
			)
			(primitives
				(gr_poly
					(pts
						(arc
							(start -0.1778 -0.2794)
							(mid -0.249642 -0.249642)
							(end -0.2794 -0.1778)
						)
						(arc
							(start -0.2794 0.1778)
							(mid -0.249642 0.249642)
							(end -0.1778 0.2794)
						)
						(arc
							(start 0.1778 0.2794)
							(mid 0.249642 0.249642)
							(end 0.2794 0.1778)
						)
						(arc
							(start 0.2794 -0.1778)
							(mid 0.249642 -0.249642)
							(end 0.1778 -0.2794)
						)
					)
					(width 0)
					(fill yes)
				)
			)
		)
		(pad "2" smd custom
			(at 0 0.4445 180)
			(size 0.1397 0.1397)
			(layers "F.Cu" "F.Mask" "F.Paste")
			(net "P3V3_STBY")
			(options
				(clearance outline)
				(anchor circle)
			)
			(primitives
				(gr_poly
					(pts
						(arc
							(start -0.1778 -0.2794)
							(mid -0.249642 -0.249642)
							(end -0.2794 -0.1778)
						)
						(arc
							(start -0.2794 0.1778)
							(mid -0.249642 0.249642)
							(end -0.1778 0.2794)
						)
						(arc
							(start 0.1778 0.2794)
							(mid 0.249642 0.249642)
							(end 0.2794 0.1778)
						)
						(arc
							(start 0.2794 -0.1778)
							(mid 0.249642 -0.249642)
							(end 0.1778 -0.2794)
						)
					)
					(width 0)
					(fill yes)
				)
			)
		)
	)
	(footprint ""
		(layer "F.Cu")
		(at 67.691 -54.102 180)
		(property "Reference" "SC982"
			(at 0 0 180)
			(layer "F.SilkS")
			(hide yes)
			(effects
				(font
					(size 1.27 1.27)
				)
			)
		)
		(property "Value" "SCD1U16V2KX-3GP"
			(at 1.1811 -2.7051 180)
			(unlocked yes)
			(layer "F.Fab")
			(hide yes)
			(effects
				(font
					(size 1.016 1.016)
					(thickness 0.1524)
				)
			)
		)
		(property "Device Type" "C402H22"
			(at 1.1811 -4.2291 180)
			(unlocked yes)
			(layer "F.Fab")
			(hide yes)
			(effects
				(font
					(size 1.016 1.016)
					(thickness 0.1524)
				)
			)
		)
		(duplicate_pad_numbers_are_jumpers no)
		(fp_rect
			(start -0.4318 0.9525)
			(end 0.4318 -0.9525)
			(stroke
				(width 0)
				(type default)
			)
			(fill no)
			(layer "F.CrtYd")
		)
		(fp_rect
			(start -0.4318 0.9525)
			(end 0.4318 -0.9525)
			(stroke
				(width 0)
				(type default)
			)
			(fill no)
			(layer "F.Fab")
		)
		(pad "1" smd custom
			(at 0 -0.4445 180)
			(size 0.1524 0.1524)
			(layers "F.Cu" "F.Mask" "F.Paste")
			(net "P1V8_C")
			(options
				(clearance outline)
				(anchor circle)
			)
			(primitives
				(gr_poly
					(pts
						(arc
							(start 0.3048 -0.2032)
							(mid 0.275042 -0.275042)
							(end 0.2032 -0.3048)
						)
						(arc
							(start -0.2032 -0.3048)
							(mid -0.275042 -0.275042)
							(end -0.3048 -0.2032)
						)
						(arc
							(start -0.3048 0.2032)
							(mid -0.275042 0.275042)
							(end -0.2032 0.3048)
						)
						(arc
							(start 0.2032 0.3048)
							(mid 0.275042 0.275042)
							(end 0.3048 0.2032)
						)
					)
					(width 0)
					(fill yes)
				)
			)
		)
		(pad "2" smd custom
			(at 0 0.4445 180)
			(size 0.1524 0.1524)
			(layers "F.Cu" "F.Mask" "F.Paste")
			(net "GND")
			(options
				(clearance outline)
				(anchor circle)
			)
			(primitives
				(gr_poly
					(pts
						(arc
							(start 0.3048 -0.2032)
							(mid 0.275042 -0.275042)
							(end 0.2032 -0.3048)
						)
						(arc
							(start -0.2032 -0.3048)
							(mid -0.275042 -0.275042)
							(end -0.3048 -0.2032)
						)
						(arc
							(start -0.3048 0.2032)
							(mid -0.275042 0.275042)
							(end -0.2032 0.3048)
						)
						(arc
							(start 0.2032 0.3048)
							(mid 0.275042 0.275042)
							(end 0.3048 0.2032)
						)
					)
					(width 0)
					(fill yes)
				)
			)
		)
	)
	(footprint ""
		(layer "F.Cu")
		(at 330.699872 -232.482136)
		(property "Reference" "R180"
			(at 0 0 0)
			(layer "F.SilkS")
			(hide yes)
			(effects
				(font
					(size 1.27 1.27)
				)
			)
		)
		(property "Value" "0R2J-2-GP"
			(at 0.064008 -3.993896 0)
			(unlocked yes)
			(layer "F.Fab")
			(hide yes)
			(effects
				(font
					(size 1.016 1.016)
					(thickness 0.1524)
				)
			)
		)
		(property "Device Type" "R402H16"
			(at 0.064008 -5.517896 0)
			(unlocked yes)
			(layer "F.Fab")
			(hide yes)
			(effects
				(font
					(size 1.016 1.016)
					(thickness 0.1524)
				)
			)
		)
		(duplicate_pad_numbers_are_jumpers no)
		(fp_line
			(start -0.508 -0.9398)
			(end -0.508 0.9398)
			(stroke
				(width 0.1524)
				(type default)
			)
			(layer "F.SilkS")
		)
		(fp_line
			(start 0.508 -0.9398)
			(end -0.508 -0.9398)
			(stroke
				(width 0.1524)
				(type default)
			)
			(layer "F.SilkS")
		)
		(fp_rect
			(start -0.508 0.9398)
			(end 0.508 -0.9398)
			(stroke
				(width 0)
				(type default)
			)
			(fill no)
			(layer "F.CrtYd")
		)
		(fp_rect
			(start -0.508 0.9398)
			(end 0.508 -0.9398)
			(stroke
				(width 0)
				(type default)
			)
			(fill no)
			(layer "F.Fab")
		)
		(pad "1" smd custom
			(at 0 -0.4445)
			(size 0.1397 0.1397)
			(layers "F.Cu" "F.Mask" "F.Paste")
			(net "ADC_P5V_STBY")
			(options
				(clearance outline)
				(anchor circle)
			)
			(primitives
				(gr_poly
					(pts
						(arc
							(start -0.1778 -0.2794)
							(mid -0.249642 -0.249642)
							(end -0.2794 -0.1778)
						)
						(arc
							(start -0.2794 0.1778)
							(mid -0.249642 0.249642)
							(end -0.1778 0.2794)
						)
						(arc
							(start 0.1778 0.2794)
							(mid 0.249642 0.249642)
							(end 0.2794 0.1778)
						)
						(arc
							(start 0.2794 -0.1778)
							(mid 0.249642 -0.249642)
							(end 0.1778 -0.2794)
						)
					)
					(width 0)
					(fill yes)
				)
			)
		)
		(pad "2" smd custom
			(at 0 0.4445)
			(size 0.1397 0.1397)
			(layers "F.Cu" "F.Mask" "F.Paste")
			(net "5V_STBY_SENSE")
			(options
				(clearance outline)
				(anchor circle)
			)
			(primitives
				(gr_poly
					(pts
						(arc
							(start -0.1778 -0.2794)
							(mid -0.249642 -0.249642)
							(end -0.2794 -0.1778)
						)
						(arc
							(start -0.2794 0.1778)
							(mid -0.249642 0.249642)
							(end -0.1778 0.2794)
						)
						(arc
							(start 0.1778 0.2794)
							(mid 0.249642 0.249642)
							(end 0.2794 0.1778)
						)
						(arc
							(start 0.2794 -0.1778)
							(mid 0.249642 -0.249642)
							(end 0.1778 -0.2794)
						)
					)
					(width 0)
					(fill yes)
				)
			)
		)
	)
	(footprint ""
		(layer "F.Cu")
		(at 202.888596 -120.669812 -90)
		(property "Reference" "PC228"
			(at 0 0 270)
			(layer "F.SilkS")
			(hide yes)
			(effects
				(font
					(size 1.27 1.27)
				)
			)
		)
		(property "Value" "SC1U10V2KX-1GP"
			(at 1.1811 -2.7051 270)
			(unlocked yes)
			(layer "F.Fab")
			(hide yes)
			(effects
				(font
					(size 1.016 1.016)
					(thickness 0.1524)
				)
			)
		)
		(property "Device Type" "C402H22"
			(at 1.1811 -4.2291 270)
			(unlocked yes)
			(layer "F.Fab")
			(hide yes)
			(effects
				(font
					(size 1.016 1.016)
					(thickness 0.1524)
				)
			)
		)
		(duplicate_pad_numbers_are_jumpers no)
		(fp_rect
			(start -0.4318 0.9525)
			(end 0.4318 -0.9525)
			(stroke
				(width 0)
				(type default)
			)
			(fill no)
			(layer "F.CrtYd")
		)
		(fp_rect
			(start -0.4318 0.9525)
			(end 0.4318 -0.9525)
			(stroke
				(width 0)
				(type default)
			)
			(fill no)
			(layer "F.Fab")
		)
		(pad "1" smd custom
			(at 0 -0.4445 270)
			(size 0.1524 0.1524)
			(layers "F.Cu" "F.Mask" "F.Paste")
			(net "P1V5_E_CC_R")
			(options
				(clearance outline)
				(anchor circle)
			)
			(primitives
				(gr_poly
					(pts
						(arc
							(start 0.3048 -0.2032)
							(mid 0.275042 -0.275042)
							(end 0.2032 -0.3048)
						)
						(arc
							(start -0.2032 -0.3048)
							(mid -0.275042 -0.275042)
							(end -0.3048 -0.2032)
						)
						(arc
							(start -0.3048 0.2032)
							(mid -0.275042 0.275042)
							(end -0.2032 0.3048)
						)
						(arc
							(start 0.2032 0.3048)
							(mid 0.275042 0.275042)
							(end 0.3048 0.2032)
						)
					)
					(width 0)
					(fill yes)
				)
			)
		)
		(pad "2" smd custom
			(at 0 0.4445 270)
			(size 0.1524 0.1524)
			(layers "F.Cu" "F.Mask" "F.Paste")
			(net "P1V5_E_VFB")
			(options
				(clearance outline)
				(anchor circle)
			)
			(primitives
				(gr_poly
					(pts
						(arc
							(start 0.3048 -0.2032)
							(mid 0.275042 -0.275042)
							(end 0.2032 -0.3048)
						)
						(arc
							(start -0.2032 -0.3048)
							(mid -0.275042 -0.275042)
							(end -0.3048 -0.2032)
						)
						(arc
							(start -0.3048 0.2032)
							(mid -0.275042 0.275042)
							(end -0.2032 0.3048)
						)
						(arc
							(start 0.2032 0.3048)
							(mid 0.275042 0.275042)
							(end 0.3048 0.2032)
						)
					)
					(width 0)
					(fill yes)
				)
			)
		)
	)
	(footprint ""
		(layer "F.Cu")
		(at 318.008 -165.354 -90)
		(property "Reference" "R249"
			(at 0 0 270)
			(layer "F.SilkS")
			(hide yes)
			(effects
				(font
					(size 1.27 1.27)
				)
			)
		)
		(property "Value" "0R2J-2-GP"
			(at 0.064008 -3.993896 270)
			(unlocked yes)
			(layer "F.Fab")
			(hide yes)
			(effects
				(font
					(size 1.016 1.016)
					(thickness 0.1524)
				)
			)
		)
		(property "Device Type" "R402H16"
			(at 0.064008 -5.517896 270)
			(unlocked yes)
			(layer "F.Fab")
			(hide yes)
			(effects
				(font
					(size 1.016 1.016)
					(thickness 0.1524)
				)
			)
		)
		(duplicate_pad_numbers_are_jumpers no)
		(fp_line
			(start -0.508 -0.9398)
			(end -0.508 0.9398)
			(stroke
				(width 0.1524)
				(type default)
			)
			(layer "F.SilkS")
		)
		(fp_line
			(start 0.508 -0.9398)
			(end -0.508 -0.9398)
			(stroke
				(width 0.1524)
				(type default)
			)
			(layer "F.SilkS")
		)
		(fp_rect
			(start -0.508 0.9398)
			(end 0.508 -0.9398)
			(stroke
				(width 0)
				(type default)
			)
			(fill no)
			(layer "F.CrtYd")
		)
		(fp_rect
			(start -0.508 0.9398)
			(end 0.508 -0.9398)
			(stroke
				(width 0)
				(type default)
			)
			(fill no)
			(layer "F.Fab")
		)
		(pad "1" smd custom
			(at 0 -0.4445 270)
			(size 0.1397 0.1397)
			(layers "F.Cu" "F.Mask" "F.Paste")
			(net "BMC_I2C_C_SCL")
			(options
				(clearance outline)
				(anchor circle)
			)
			(primitives
				(gr_poly
					(pts
						(arc
							(start -0.1778 -0.2794)
							(mid -0.249642 -0.249642)
							(end -0.2794 -0.1778)
						)
						(arc
							(start -0.2794 0.1778)
							(mid -0.249642 0.249642)
							(end -0.1778 0.2794)
						)
						(arc
							(start 0.1778 0.2794)
							(mid 0.249642 0.249642)
							(end 0.2794 0.1778)
						)
						(arc
							(start 0.2794 -0.1778)
							(mid 0.249642 -0.249642)
							(end 0.1778 -0.2794)
						)
					)
					(width 0)
					(fill yes)
				)
			)
		)
		(pad "2" smd custom
			(at 0 0.4445 270)
			(size 0.1397 0.1397)
			(layers "F.Cu" "F.Mask" "F.Paste")
			(net "BMC0_SMB6_CLK")
			(options
				(clearance outline)
				(anchor circle)
			)
			(primitives
				(gr_poly
					(pts
						(arc
							(start -0.1778 -0.2794)
							(mid -0.249642 -0.249642)
							(end -0.2794 -0.1778)
						)
						(arc
							(start -0.2794 0.1778)
							(mid -0.249642 0.249642)
							(end -0.1778 0.2794)
						)
						(arc
							(start 0.1778 0.2794)
							(mid 0.249642 0.249642)
							(end 0.2794 0.1778)
						)
						(arc
							(start 0.2794 -0.1778)
							(mid 0.249642 -0.249642)
							(end 0.1778 -0.2794)
						)
					)
					(width 0)
					(fill yes)
				)
			)
		)
	)
	(footprint ""
		(layer "F.Cu")
		(at 305.816 -191.262 -90)
		(property "Reference" "C89"
			(at 0 0 270)
			(layer "F.SilkS")
			(hide yes)
			(effects
				(font
					(size 1.27 1.27)
				)
			)
		)
		(property "Value" "SCD1U16V2KX-3GP"
			(at 1.1811 -2.7051 270)
			(unlocked yes)
			(layer "F.Fab")
			(hide yes)
			(effects
				(font
					(size 1.016 1.016)
					(thickness 0.1524)
				)
			)
		)
		(property "Device Type" "C402H22"
			(at 1.1811 -4.2291 270)
			(unlocked yes)
			(layer "F.Fab")
			(hide yes)
			(effects
				(font
					(size 1.016 1.016)
					(thickness 0.1524)
				)
			)
		)
		(duplicate_pad_numbers_are_jumpers no)
		(fp_rect
			(start -0.4318 0.9525)
			(end 0.4318 -0.9525)
			(stroke
				(width 0)
				(type default)
			)
			(fill no)
			(layer "F.CrtYd")
		)
		(fp_rect
			(start -0.4318 0.9525)
			(end 0.4318 -0.9525)
			(stroke
				(width 0)
				(type default)
			)
			(fill no)
			(layer "F.Fab")
		)
		(pad "1" smd custom
			(at 0 -0.4445 270)
			(size 0.1524 0.1524)
			(layers "F.Cu" "F.Mask" "F.Paste")
			(net "P3V3_STBY")
			(options
				(clearance outline)
				(anchor circle)
			)
			(primitives
				(gr_poly
					(pts
						(arc
							(start 0.3048 -0.2032)
							(mid 0.275042 -0.275042)
							(end 0.2032 -0.3048)
						)
						(arc
							(start -0.2032 -0.3048)
							(mid -0.275042 -0.275042)
							(end -0.3048 -0.2032)
						)
						(arc
							(start -0.3048 0.2032)
							(mid -0.275042 0.275042)
							(end -0.2032 0.3048)
						)
						(arc
							(start 0.2032 0.3048)
							(mid 0.275042 0.275042)
							(end 0.3048 0.2032)
						)
					)
					(width 0)
					(fill yes)
				)
			)
		)
		(pad "2" smd custom
			(at 0 0.4445 270)
			(size 0.1524 0.1524)
			(layers "F.Cu" "F.Mask" "F.Paste")
			(net "GND")
			(options
				(clearance outline)
				(anchor circle)
			)
			(primitives
				(gr_poly
					(pts
						(arc
							(start 0.3048 -0.2032)
							(mid 0.275042 -0.275042)
							(end 0.2032 -0.3048)
						)
						(arc
							(start -0.2032 -0.3048)
							(mid -0.275042 -0.275042)
							(end -0.3048 -0.2032)
						)
						(arc
							(start -0.3048 0.2032)
							(mid -0.275042 0.275042)
							(end -0.2032 0.3048)
						)
						(arc
							(start 0.2032 0.3048)
							(mid 0.275042 0.275042)
							(end 0.3048 0.2032)
						)
					)
					(width 0)
					(fill yes)
				)
			)
		)
	)
	(footprint ""
		(layer "F.Cu")
		(at 275.708872 -225.116136 180)
		(property "Reference" "PC80"
			(at 0 0 180)
			(layer "F.SilkS")
			(hide yes)
			(effects
				(font
					(size 1.27 1.27)
				)
			)
		)
		(property "Value" "SC10U6D3V5KX-1GP"
			(at -0.0762 -6.1214 180)
			(unlocked yes)
			(layer "F.Fab")
			(hide yes)
			(effects
				(font
					(size 1.016 1.016)
					(thickness 0.1524)
				)
			)
		)
		(property "Device Type" "C805H54"
			(at -0.0762 -8.1534 180)
			(unlocked yes)
			(layer "F.Fab")
			(hide yes)
			(effects
				(font
					(size 1.016 1.016)
					(thickness 0.1524)
				)
			)
		)
		(duplicate_pad_numbers_are_jumpers no)
		(fp_line
			(start 0.635 0)
			(end -0.635 0)
			(stroke
				(width 0.508)
				(type default)
			)
			(layer "F.SilkS")
		)
		(fp_rect
			(start -0.9652 1.778)
			(end 0.9652 -1.778)
			(stroke
				(width 0)
				(type default)
			)
			(fill no)
			(layer "F.CrtYd")
		)
		(fp_poly
			(pts
				(xy -0.9652 -1.778) (xy 0.9652 -1.778) (xy 0.9652 1.778) (xy -0.9652 1.778)
			)
			(stroke
				(width 0)
				(type default)
			)
			(fill no)
			(layer "F.Fab")
		)
		(pad "1" smd rect
			(at 0 -0.9652 180)
			(size 1.397 1.143)
			(layers "F.Cu" "F.Mask" "F.Paste")
			(net "TPS74801_P1V53_STBY_IN")
		)
		(pad "2" smd rect
			(at 0 0.9652 180)
			(size 1.397 1.143)
			(layers "F.Cu" "F.Mask" "F.Paste")
			(net "GND")
		)
	)
	(footprint ""
		(layer "F.Cu")
		(at 20.135088 -188.215016 180)
		(property "Reference" "SU17"
			(at 0 0 180)
			(layer "F.SilkS")
			(hide yes)
			(effects
				(font
					(size 1.27 1.27)
				)
			)
		)
		(property "Value" "PCA9575PW2-GP"
			(at 0.635 -8.0772 180)
			(unlocked yes)
			(layer "F.Fab")
			(hide yes)
			(effects
				(font
					(size 1.016 1.016)
					(thickness 0.1524)
				)
			)
		)
		(property "Device Type" "TSOIC28H44"
			(at 0.635 -9.9822 180)
			(unlocked yes)
			(layer "F.Fab")
			(hide yes)
			(effects
				(font
					(size 1.016 1.016)
					(thickness 0.1524)
				)
			)
		)
		(duplicate_pad_numbers_are_jumpers no)
		(fp_line
			(start 4.4704 1.3716)
			(end -5.3467 1.3716)
			(stroke
				(width 0.1524)
				(type default)
			)
			(layer "F.SilkS")
		)
		(fp_line
			(start 4.4704 -1.3716)
			(end 4.4704 1.3716)
			(stroke
				(width 0.1524)
				(type default)
			)
			(layer "F.SilkS")
		)
		(fp_line
			(start -4.84632 0.00254)
			(end -5.3467 0.50292)
			(stroke
				(width 0.1524)
				(type default)
			)
			(layer "F.SilkS")
		)
		(fp_line
			(start -4.84632 0)
			(end -4.84632 0.00254)
			(stroke
				(width 0.1524)
				(type default)
			)
			(layer "F.SilkS")
		)
		(fp_line
			(start -5.3467 4.572)
			(end -5.3467 -1.3716)
			(stroke
				(width 0.1524)
				(type default)
			)
			(layer "F.SilkS")
		)
		(fp_line
			(start -5.3467 1.7907)
			(end -5.3467 4.572)
			(stroke
				(width 0.508)
				(type default)
			)
			(layer "F.SilkS")
		)
		(fp_line
			(start -5.3467 -0.50038)
			(end -4.84632 0)
			(stroke
				(width 0.1524)
				(type default)
			)
			(layer "F.SilkS")
		)
		(fp_line
			(start -5.3467 -0.50292)
			(end -5.3467 -0.50038)
			(stroke
				(width 0.1524)
				(type default)
			)
			(layer "F.SilkS")
		)
		(fp_line
			(start -5.3467 -1.3716)
			(end 4.4704 -1.3716)
			(stroke
				(width 0.1524)
				(type default)
			)
			(layer "F.SilkS")
		)
		(fp_poly
			(pts
				(xy -4.55549 -1.8288) (xy -4.55549 1.8288) (xy 4.55549 1.8288) (xy 4.55549 -1.8288)
			)
			(stroke
				(width 0)
				(type default)
			)
			(fill yes)
			(layer "F.SilkS")
		)
		(fp_poly
			(pts
				(xy -5.3594 -4.0767) (xy 5.3594 -4.0767) (xy 5.3594 4.0767) (xy -5.3594 4.0767)
			)
			(stroke
				(width 0)
				(type default)
			)
			(fill no)
			(layer "F.CrtYd")
		)
		(fp_poly
			(pts
				(xy -5.3594 -4.0767) (xy 5.3594 -4.0767) (xy 5.3594 4.0767) (xy -5.3594 4.0767)
			)
			(stroke
				(width 0)
				(type default)
			)
			(fill no)
			(layer "F.Fab")
		)
		(pad "1" smd rect
			(at -4.22529 2.80543 180)
			(size 0.3556 1.524)
			(layers "F.Cu" "F.Mask" "F.Paste")
			(net "IO_EXP_HDD_PRE_A0")
		)
		(pad "2" smd rect
			(at -3.57505 2.80543 180)
			(size 0.3556 1.524)
			(layers "F.Cu" "F.Mask" "F.Paste")
			(net "P1V8_E")
		)
		(pad "3" smd rect
			(at -2.92481 2.80543 180)
			(size 0.3556 1.524)
			(layers "F.Cu" "F.Mask" "F.Paste")
			(net "I2C_IO_EXP_RESET#_PRST")
		)
		(pad "4" smd rect
			(at -2.27457 2.80543 180)
			(size 0.3556 1.524)
			(layers "F.Cu" "F.Mask" "F.Paste")
			(net "SAS_HDD_PRE0")
		)
		(pad "5" smd rect
			(at -1.6256 2.80543 180)
			(size 0.3556 1.524)
			(layers "F.Cu" "F.Mask" "F.Paste")
			(net "SAS_HDD_PRE1")
		)
		(pad "6" smd rect
			(at -0.97536 2.80543 180)
			(size 0.3556 1.524)
			(layers "F.Cu" "F.Mask" "F.Paste")
			(net "SAS_HDD_PRE2")
		)
		(pad "7" smd rect
			(at -0.32512 2.80543 180)
			(size 0.3556 1.524)
			(layers "F.Cu" "F.Mask" "F.Paste")
			(net "SAS_HDD_PRE3")
		)
		(pad "8" smd rect
			(at 0.32512 2.80543 180)
			(size 0.3556 1.524)
			(layers "F.Cu" "F.Mask" "F.Paste")
			(net "IO_EXP_HDD_PRE_A1")
		)
		(pad "9" smd rect
			(at 0.97536 2.80543 180)
			(size 0.3556 1.524)
			(layers "F.Cu" "F.Mask" "F.Paste")
			(net "P3V3_STBY")
		)
		(pad "10" smd rect
			(at 1.6256 2.80543 180)
			(size 0.3556 1.524)
			(layers "F.Cu" "F.Mask" "F.Paste")
			(net "SAS_HDD_PRE4")
		)
		(pad "11" smd rect
			(at 2.27457 2.80543 180)
			(size 0.3556 1.524)
			(layers "F.Cu" "F.Mask" "F.Paste")
			(net "SAS_HDD_PRE5")
		)
		(pad "12" smd rect
			(at 2.92481 2.80543 180)
			(size 0.3556 1.524)
			(layers "F.Cu" "F.Mask" "F.Paste")
			(net "SAS_HDD_PRE6")
		)
		(pad "13" smd rect
			(at 3.57505 2.80543 180)
			(size 0.3556 1.524)
			(layers "F.Cu" "F.Mask" "F.Paste")
			(net "SAS_HDD_PRE7")
		)
		(pad "14" smd rect
			(at 4.22529 2.80543 180)
			(size 0.3556 1.524)
			(layers "F.Cu" "F.Mask" "F.Paste")
			(net "HDD_PRE_IO_INT_N")
		)
		(pad "15" smd rect
			(at 4.22529 -2.80543 180)
			(size 0.3556 1.524)
			(layers "F.Cu" "F.Mask" "F.Paste")
			(net "IO_EXP_HDD_PRE_A2")
		)
		(pad "16" smd rect
			(at 3.57505 -2.80543 180)
			(size 0.3556 1.524)
			(layers "F.Cu" "F.Mask" "F.Paste")
			(net "GND")
		)
		(pad "17" smd rect
			(at 2.92481 -2.80543 180)
			(size 0.3556 1.524)
			(layers "F.Cu" "F.Mask" "F.Paste")
			(net "SAS_HDD_PRE15")
		)
		(pad "18" smd rect
			(at 2.27457 -2.80543 180)
			(size 0.3556 1.524)
			(layers "F.Cu" "F.Mask" "F.Paste")
			(net "SAS_HDD_PRE14")
		)
		(pad "19" smd rect
			(at 1.6256 -2.80543 180)
			(size 0.3556 1.524)
			(layers "F.Cu" "F.Mask" "F.Paste")
			(net "SAS_HDD_PRE13")
		)
		(pad "20" smd rect
			(at 0.97536 -2.80543 180)
			(size 0.3556 1.524)
			(layers "F.Cu" "F.Mask" "F.Paste")
			(net "SAS_HDD_PRE12")
		)
		(pad "21" smd rect
			(at 0.32512 -2.80543 180)
			(size 0.3556 1.524)
			(layers "F.Cu" "F.Mask" "F.Paste")
			(net "P3V3_STBY")
		)
		(pad "22" smd rect
			(at -0.32512 -2.80543 180)
			(size 0.3556 1.524)
			(layers "F.Cu" "F.Mask" "F.Paste")
			(net "IO_EXP_HDD_PRE_A3")
		)
		(pad "23" smd rect
			(at -0.97536 -2.80543 180)
			(size 0.3556 1.524)
			(layers "F.Cu" "F.Mask" "F.Paste")
			(net "SAS_HDD_PRE11")
		)
		(pad "24" smd rect
			(at -1.6256 -2.80543 180)
			(size 0.3556 1.524)
			(layers "F.Cu" "F.Mask" "F.Paste")
			(net "SAS_HDD_PRE10")
		)
		(pad "25" smd rect
			(at -2.27457 -2.80543 180)
			(size 0.3556 1.524)
			(layers "F.Cu" "F.Mask" "F.Paste")
			(net "SAS_HDD_PRE9")
		)
		(pad "26" smd rect
			(at -2.92481 -2.80543 180)
			(size 0.3556 1.524)
			(layers "F.Cu" "F.Mask" "F.Paste")
			(net "SAS_HDD_PRE8")
		)
		(pad "27" smd rect
			(at -3.57505 -2.80543 180)
			(size 0.3556 1.524)
			(layers "F.Cu" "F.Mask" "F.Paste")
			(net "PRE_SDA")
		)
		(pad "28" smd rect
			(at -4.22529 -2.80543 180)
			(size 0.3556 1.524)
			(layers "F.Cu" "F.Mask" "F.Paste")
			(net "PRE_SCL")
		)
	)
	(footprint ""
		(layer "F.Cu")
		(at 303.318672 -68.21424 -90)
		(property "Reference" "R271"
			(at 0 0 270)
			(layer "F.SilkS")
			(hide yes)
			(effects
				(font
					(size 1.27 1.27)
				)
			)
		)
		(property "Value" "0R2J-2-GP"
			(at 0.064008 -3.993896 270)
			(unlocked yes)
			(layer "F.Fab")
			(hide yes)
			(effects
				(font
					(size 1.016 1.016)
					(thickness 0.1524)
				)
			)
		)
		(property "Device Type" "R402H16"
			(at 0.064008 -5.517896 270)
			(unlocked yes)
			(layer "F.Fab")
			(hide yes)
			(effects
				(font
					(size 1.016 1.016)
					(thickness 0.1524)
				)
			)
		)
		(duplicate_pad_numbers_are_jumpers no)
		(fp_line
			(start -0.508 -0.9398)
			(end -0.508 0.9398)
			(stroke
				(width 0.1524)
				(type default)
			)
			(layer "F.SilkS")
		)
		(fp_line
			(start 0.508 -0.9398)
			(end -0.508 -0.9398)
			(stroke
				(width 0.1524)
				(type default)
			)
			(layer "F.SilkS")
		)
		(fp_rect
			(start -0.508 0.9398)
			(end 0.508 -0.9398)
			(stroke
				(width 0)
				(type default)
			)
			(fill no)
			(layer "F.CrtYd")
		)
		(fp_rect
			(start -0.508 0.9398)
			(end 0.508 -0.9398)
			(stroke
				(width 0)
				(type default)
			)
			(fill no)
			(layer "F.Fab")
		)
		(pad "1" smd custom
			(at 0 -0.4445 270)
			(size 0.1397 0.1397)
			(layers "F.Cu" "F.Mask" "F.Paste")
			(net "PCIE_10G_REFCLK_N")
			(options
				(clearance outline)
				(anchor circle)
			)
			(primitives
				(gr_poly
					(pts
						(arc
							(start -0.1778 -0.2794)
							(mid -0.249642 -0.249642)
							(end -0.2794 -0.1778)
						)
						(arc
							(start -0.2794 0.1778)
							(mid -0.249642 0.249642)
							(end -0.1778 0.2794)
						)
						(arc
							(start 0.1778 0.2794)
							(mid 0.249642 0.249642)
							(end 0.2794 0.1778)
						)
						(arc
							(start 0.2794 -0.1778)
							(mid 0.249642 -0.249642)
							(end 0.1778 -0.2794)
						)
					)
					(width 0)
					(fill yes)
				)
			)
		)
		(pad "2" smd custom
			(at 0 0.4445 270)
			(size 0.1397 0.1397)
			(layers "F.Cu" "F.Mask" "F.Paste")
			(net "CLK_100M_CLKBUFF_ENET1_DN")
			(options
				(clearance outline)
				(anchor circle)
			)
			(primitives
				(gr_poly
					(pts
						(arc
							(start -0.1778 -0.2794)
							(mid -0.249642 -0.249642)
							(end -0.2794 -0.1778)
						)
						(arc
							(start -0.2794 0.1778)
							(mid -0.249642 0.249642)
							(end -0.1778 0.2794)
						)
						(arc
							(start 0.1778 0.2794)
							(mid 0.249642 0.249642)
							(end 0.2794 0.1778)
						)
						(arc
							(start 0.2794 -0.1778)
							(mid 0.249642 -0.249642)
							(end 0.1778 -0.2794)
						)
					)
					(width 0)
					(fill yes)
				)
			)
		)
	)
	(footprint ""
		(layer "F.Cu")
		(at 183.315864 -30.806136)
		(property "Reference" "U20"
			(at 0 0 0)
			(layer "F.SilkS")
			(hide yes)
			(effects
				(font
					(size 1.27 1.27)
				)
			)
		)
		(property "Value" "BCM5221A4KMLG-2-GP-U"
			(at -5.3975 -7.2263 0)
			(unlocked yes)
			(layer "F.Fab")
			(hide yes)
			(effects
				(font
					(size 1.016 1.016)
					(thickness 0.1524)
				)
			)
		)
		(property "Device Type" "QFN48-1G4D8H40"
			(at -5.3975 -8.7503 0)
			(unlocked yes)
			(layer "F.Fab")
			(hide yes)
			(effects
				(font
					(size 1.016 1.016)
					(thickness 0.1524)
				)
			)
		)
		(duplicate_pad_numbers_are_jumpers no)
		(fp_line
			(start -4.5212 -4.5212)
			(end -4.5212 -3.2512)
			(stroke
				(width 0.1524)
				(type default)
			)
			(layer "F.SilkS")
		)
		(fp_line
			(start -4.5212 3.2512)
			(end -4.5212 4.5212)
			(stroke
				(width 0.1524)
				(type default)
			)
			(layer "F.SilkS")
		)
		(fp_line
			(start -4.5212 4.5212)
			(end -3.2512 4.5212)
			(stroke
				(width 0.1524)
				(type default)
			)
			(layer "F.SilkS")
		)
		(fp_line
			(start -4.2926 -1.749552)
			(end -4.8006 -1.749552)
			(stroke
				(width 0.1524)
				(type default)
			)
			(layer "F.SilkS")
		)
		(fp_line
			(start -4.2926 0.749808)
			(end -5.0546 0.749808)
			(stroke
				(width 0.1524)
				(type default)
			)
			(layer "F.SilkS")
		)
		(fp_line
			(start -3.2512 -4.5212)
			(end -4.5212 -4.5212)
			(stroke
				(width 0.1524)
				(type default)
			)
			(layer "F.SilkS")
		)
		(fp_line
			(start -2.749296 4.2926)
			(end -2.749296 4.8006)
			(stroke
				(width 0.1524)
				(type default)
			)
			(layer "F.SilkS")
		)
		(fp_line
			(start -1.749552 -4.2926)
			(end -1.749552 -5.0546)
			(stroke
				(width 0.1524)
				(type default)
			)
			(layer "F.SilkS")
		)
		(fp_line
			(start -0.249936 4.2926)
			(end -0.249936 5.0546)
			(stroke
				(width 0.1524)
				(type default)
			)
			(layer "F.SilkS")
		)
		(fp_line
			(start 0.749808 -4.2926)
			(end 0.749808 -4.8006)
			(stroke
				(width 0.1524)
				(type default)
			)
			(layer "F.SilkS")
		)
		(fp_line
			(start 2.249424 4.2926)
			(end 2.249424 4.8006)
			(stroke
				(width 0.1524)
				(type default)
			)
			(layer "F.SilkS")
		)
		(fp_line
			(start 3.2512 4.5212)
			(end 4.5212 4.5212)
			(stroke
				(width 0.1524)
				(type default)
			)
			(layer "F.SilkS")
		)
		(fp_line
			(start 4.2926 -1.24968)
			(end 4.8006 -1.24968)
			(stroke
				(width 0.1524)
				(type default)
			)
			(layer "F.SilkS")
		)
		(fp_line
			(start 4.2926 1.24968)
			(end 5.0546 1.24968)
			(stroke
				(width 0.1524)
				(type default)
			)
			(layer "F.SilkS")
		)
		(fp_line
			(start 4.5212 4.5212)
			(end 4.5212 3.2512)
			(stroke
				(width 0.1524)
				(type default)
			)
			(layer "F.SilkS")
		)
		(fp_poly
			(pts
				(xy 4.5212 -4.5212) (xy 3.2512 -4.5212) (xy 4.5212 -3.2512)
			)
			(stroke
				(width 0)
				(type default)
			)
			(fill yes)
			(layer "F.SilkS")
		)
		(fp_rect
			(start -3.5052 3.5052)
			(end 3.5052 -3.5052)
			(stroke
				(width 0)
				(type default)
			)
			(fill no)
			(layer "F.CrtYd")
		)
		(fp_poly
			(pts
				(xy -4.5212 4.5212) (xy -4.5212 -4.5212) (xy 4.5212 -4.5212) (xy 4.5212 -0.00254) (xy 3.5052 -0.00254)
				(xy 3.5052 -3.5052) (xy -3.5052 -3.5052) (xy -3.5052 3.5052) (xy 3.5052 3.5052) (xy 3.5052 0.00254)
				(xy 4.5212 0.00254) (xy 4.5212 4.5212)
			)
			(stroke
				(width 0)
				(type default)
			)
			(fill no)
			(layer "F.CrtYd")
		)
		(fp_rect
			(start -4.5212 4.5212)
			(end 4.5212 -4.5212)
			(stroke
				(width 0)
				(type default)
			)
			(fill no)
			(layer "F.Fab")
		)
		(pad "1" smd rect
			(at 2.750058 -3.556)
			(size 0.3048 0.9144)
			(layers "F.Cu" "F.Mask" "F.Paste")
			(net "RMII_BMC_CRS_DV_R")
		)
		(pad "2" smd rect
			(at 2.249932 -3.429)
			(size 0.3048 1.1684)
			(layers "F.Cu" "F.Mask" "F.Paste")
			(net "P3V3_STBY")
		)
		(pad "3" smd rect
			(at 1.75006 -3.429)
			(size 0.3048 1.1684)
			(layers "F.Cu" "F.Mask" "F.Paste")
			(net "CLK_50M_RMII_PHY")
		)
		(pad "4" smd rect
			(at 1.249934 -3.429)
			(size 0.3048 1.1684)
			(layers "F.Cu" "F.Mask" "F.Paste")
			(net "GND")
		)
		(pad "5" smd rect
			(at 0.750062 -3.429)
			(size 0.3048 1.1684)
			(layers "F.Cu" "F.Mask" "F.Paste")
			(net "Net_2069")
		)
		(pad "6" smd rect
			(at 0.249936 -3.429)
			(size 0.3048 1.1684)
			(layers "F.Cu" "F.Mask" "F.Paste")
			(net "PHY_RESET#")
		)
		(pad "7" smd rect
			(at -0.249936 -3.429)
			(size 0.3048 1.1684)
			(layers "F.Cu" "F.Mask" "F.Paste")
			(net "PHY_AD0")
		)
		(pad "8" smd rect
			(at -0.750062 -3.429)
			(size 0.3048 1.1684)
			(layers "F.Cu" "F.Mask" "F.Paste")
			(net "PHY_AD1")
		)
		(pad "9" smd rect
			(at -1.249934 -3.429)
			(size 0.3048 1.1684)
			(layers "F.Cu" "F.Mask" "F.Paste")
			(net "PHY_AD3")
		)
		(pad "10" smd rect
			(at -1.75006 -3.429)
			(size 0.3048 1.1684)
			(layers "F.Cu" "F.Mask" "F.Paste")
			(net "PHY_AD4")
		)
		(pad "11" smd rect
			(at -2.249932 -3.429)
			(size 0.3048 1.1684)
			(layers "F.Cu" "F.Mask" "F.Paste")
			(net "PHY_TEST_EN")
		)
		(pad "12" smd rect
			(at -2.750058 -3.556)
			(size 0.3048 0.9144)
			(layers "F.Cu" "F.Mask" "F.Paste")
			(net "PHY_LOW_PWR")
		)
		(pad "13" smd rect
			(at -3.556 -2.750058)
			(size 0.9144 0.3048)
			(layers "F.Cu" "F.Mask" "F.Paste")
			(net "NC_PHY_ENGY_DET")
		)
		(pad "14" smd rect
			(at -3.429 -2.249932)
			(size 1.1684 0.3048)
			(layers "F.Cu" "F.Mask" "F.Paste")
			(net "GND")
		)
		(pad "15" smd rect
			(at -3.429 -1.75006)
			(size 1.1684 0.3048)
			(layers "F.Cu" "F.Mask" "F.Paste")
			(net "P3V3_STBY")
		)
		(pad "16" smd rect
			(at -3.429 -1.249934)
			(size 1.1684 0.3048)
			(layers "F.Cu" "F.Mask" "F.Paste")
			(net "PHY_AVDD")
		)
		(pad "17" smd rect
			(at -3.429 -0.750062)
			(size 1.1684 0.3048)
			(layers "F.Cu" "F.Mask" "F.Paste")
			(net "BMC_PHY_RDAC")
		)
		(pad "18" smd rect
			(at -3.429 -0.249936)
			(size 1.1684 0.3048)
			(layers "F.Cu" "F.Mask" "F.Paste")
			(net "BCM5221_RX_C_DN")
		)
		(pad "19" smd rect
			(at -3.429 0.249936)
			(size 1.1684 0.3048)
			(layers "F.Cu" "F.Mask" "F.Paste")
			(net "BCM5221_RX_C_DP")
		)
		(pad "20" smd rect
			(at -3.429 0.750062)
			(size 1.1684 0.3048)
			(layers "F.Cu" "F.Mask" "F.Paste")
			(net "PHY_AVDD")
		)
		(pad "21" smd rect
			(at -3.429 1.249934)
			(size 1.1684 0.3048)
			(layers "F.Cu" "F.Mask" "F.Paste")
			(net "BCM5221_TX_C_DN")
		)
		(pad "22" smd rect
			(at -3.429 1.75006)
			(size 1.1684 0.3048)
			(layers "F.Cu" "F.Mask" "F.Paste")
			(net "BCM5221_TX_C_DP")
		)
		(pad "23" smd rect
			(at -3.429 2.249932)
			(size 1.1684 0.3048)
			(layers "F.Cu" "F.Mask" "F.Paste")
			(net "PHY_ACTLED_N")
		)
		(pad "24" smd rect
			(at -3.556 2.750058)
			(size 0.9144 0.3048)
			(layers "F.Cu" "F.Mask" "F.Paste")
			(net "NC_PHY_BMC_INTR_N")
		)
		(pad "25" smd rect
			(at -2.750058 3.556)
			(size 0.3048 0.9144)
			(layers "F.Cu" "F.Mask" "F.Paste")
			(net "PHY_LNKLED_N")
		)
		(pad "26" smd rect
			(at -2.249932 3.429)
			(size 0.3048 1.1684)
			(layers "F.Cu" "F.Mask" "F.Paste")
			(net "NC_PHYSPLOED_N")
		)
		(pad "27" smd rect
			(at -1.75006 3.429)
			(size 0.3048 1.1684)
			(layers "F.Cu" "F.Mask" "F.Paste")
			(net "PHY_F100")
		)
		(pad "28" smd rect
			(at -1.249934 3.429)
			(size 0.3048 1.1684)
			(layers "F.Cu" "F.Mask" "F.Paste")
			(net "PHY_ANEN")
		)
		(pad "29" smd rect
			(at -0.750062 3.429)
			(size 0.3048 1.1684)
			(layers "F.Cu" "F.Mask" "F.Paste")
			(net "PHY_FDX")
		)
		(pad "30" smd rect
			(at -0.249936 3.429)
			(size 0.3048 1.1684)
			(layers "F.Cu" "F.Mask" "F.Paste")
			(net "RMII_BMC_MDIO_R")
		)
		(pad "31" smd rect
			(at 0.249936 3.429)
			(size 0.3048 1.1684)
			(layers "F.Cu" "F.Mask" "F.Paste")
			(net "RMII_BMC_MDC_R")
		)
		(pad "32" smd rect
			(at 0.750062 3.429)
			(size 0.3048 1.1684)
			(layers "F.Cu" "F.Mask" "F.Paste")
			(net "Net_2072")
		)
		(pad "33" smd rect
			(at 1.249934 3.429)
			(size 0.3048 1.1684)
			(layers "F.Cu" "F.Mask" "F.Paste")
			(net "Net_2073")
		)
		(pad "34" smd rect
			(at 1.75006 3.429)
			(size 0.3048 1.1684)
			(layers "F.Cu" "F.Mask" "F.Paste")
			(net "P3V3_STBY")
		)
		(pad "35" smd rect
			(at 2.249932 3.429)
			(size 0.3048 1.1684)
			(layers "F.Cu" "F.Mask" "F.Paste")
			(net "RMII_PHY_BMC_RXD1_R")
		)
		(pad "36" smd rect
			(at 2.750058 3.556)
			(size 0.3048 0.9144)
			(layers "F.Cu" "F.Mask" "F.Paste")
			(net "RMII_PHY_BMC_RXD0_R")
		)
		(pad "37" smd rect
			(at 3.556 2.750058)
			(size 0.9144 0.3048)
			(layers "F.Cu" "F.Mask" "F.Paste")
			(net "Net_2074")
		)
		(pad "38" smd rect
			(at 3.429 2.249932)
			(size 1.1684 0.3048)
			(layers "F.Cu" "F.Mask" "F.Paste")
			(net "NC_PHY_RXC")
		)
		(pad "39" smd rect
			(at 3.429 1.75006)
			(size 1.1684 0.3048)
			(layers "F.Cu" "F.Mask" "F.Paste")
			(net "RMII_BMC_RX_ER_R")
		)
		(pad "40" smd rect
			(at 3.429 1.249934)
			(size 1.1684 0.3048)
			(layers "F.Cu" "F.Mask" "F.Paste")
			(net "PHY_TX_ER_PD")
		)
		(pad "41" smd rect
			(at 3.429 0.750062)
			(size 1.1684 0.3048)
			(layers "F.Cu" "F.Mask" "F.Paste")
			(net "NC_PHY_TXC")
		)
		(pad "42" smd rect
			(at 3.429 0.249936)
			(size 1.1684 0.3048)
			(layers "F.Cu" "F.Mask" "F.Paste")
			(net "PHY_DVDD")
		)
		(pad "43" smd rect
			(at 3.429 -0.249936)
			(size 1.1684 0.3048)
			(layers "F.Cu" "F.Mask" "F.Paste")
			(net "RMII_BMC_TX_EN")
		)
		(pad "44" smd rect
			(at 3.429 -0.750062)
			(size 1.1684 0.3048)
			(layers "F.Cu" "F.Mask" "F.Paste")
			(net "RMII_BMC_PHY_TXD0")
		)
		(pad "45" smd rect
			(at 3.429 -1.249934)
			(size 1.1684 0.3048)
			(layers "F.Cu" "F.Mask" "F.Paste")
			(net "RMII_BMC_PHY_TXD1")
		)
		(pad "46" smd rect
			(at 3.429 -1.75006)
			(size 1.1684 0.3048)
			(layers "F.Cu" "F.Mask" "F.Paste")
			(net "Net_2075")
		)
		(pad "47" smd rect
			(at 3.429 -2.249932)
			(size 1.1684 0.3048)
			(layers "F.Cu" "F.Mask" "F.Paste")
			(net "Net_2070")
		)
		(pad "48" smd rect
			(at 3.556 -2.750058)
			(size 0.9144 0.3048)
			(layers "F.Cu" "F.Mask" "F.Paste")
			(net "Net_2071")
		)
		(pad "49" smd rect
			(at 0 0)
			(size 4.8006 4.8006)
			(layers "F.Cu" "F.Mask" "F.Paste")
			(net "GND")
		)
	)
	(footprint ""
		(layer "F.Cu")
		(at 162.687 -101.473 180)
		(property "Reference" "PC181"
			(at 0 0 180)
			(layer "F.SilkS")
			(hide yes)
			(effects
				(font
					(size 1.27 1.27)
				)
			)
		)
		(property "Value" "SC47U6D3V5MX-1-GP"
			(at -0.0762 -6.1214 180)
			(unlocked yes)
			(layer "F.Fab")
			(hide yes)
			(effects
				(font
					(size 1.016 1.016)
					(thickness 0.1524)
				)
			)
		)
		(property "Device Type" "C805H54"
			(at -0.0762 -8.1534 180)
			(unlocked yes)
			(layer "F.Fab")
			(hide yes)
			(effects
				(font
					(size 1.016 1.016)
					(thickness 0.1524)
				)
			)
		)
		(duplicate_pad_numbers_are_jumpers no)
		(fp_line
			(start 0.635 0)
			(end -0.635 0)
			(stroke
				(width 0.508)
				(type default)
			)
			(layer "F.SilkS")
		)
		(fp_rect
			(start -0.9652 1.778)
			(end 0.9652 -1.778)
			(stroke
				(width 0)
				(type default)
			)
			(fill no)
			(layer "F.CrtYd")
		)
		(fp_poly
			(pts
				(xy -0.9652 -1.778) (xy 0.9652 -1.778) (xy 0.9652 1.778) (xy -0.9652 1.778)
			)
			(stroke
				(width 0)
				(type default)
			)
			(fill no)
			(layer "F.Fab")
		)
		(pad "1" smd rect
			(at 0 -0.9652 180)
			(size 1.397 1.143)
			(layers "F.Cu" "F.Mask" "F.Paste")
			(net "P0V9_E")
		)
		(pad "2" smd rect
			(at 0 0.9652 180)
			(size 1.397 1.143)
			(layers "F.Cu" "F.Mask" "F.Paste")
			(net "GND")
		)
	)
	(footprint ""
		(layer "F.Cu")
		(at 299.466 -102.108)
		(property "Reference" "R589"
			(at 0 0 0)
			(layer "F.SilkS")
			(hide yes)
			(effects
				(font
					(size 1.27 1.27)
				)
			)
		)
		(property "Value" "4K7R2F-GP"
			(at 0.064008 -3.993896 0)
			(unlocked yes)
			(layer "F.Fab")
			(hide yes)
			(effects
				(font
					(size 1.016 1.016)
					(thickness 0.1524)
				)
			)
		)
		(property "Device Type" "R402H16"
			(at 0.064008 -5.517896 0)
			(unlocked yes)
			(layer "F.Fab")
			(hide yes)
			(effects
				(font
					(size 1.016 1.016)
					(thickness 0.1524)
				)
			)
		)
		(duplicate_pad_numbers_are_jumpers no)
		(fp_line
			(start -0.508 -0.9398)
			(end -0.508 0.9398)
			(stroke
				(width 0.1524)
				(type default)
			)
			(layer "F.SilkS")
		)
		(fp_line
			(start 0.508 -0.9398)
			(end -0.508 -0.9398)
			(stroke
				(width 0.1524)
				(type default)
			)
			(layer "F.SilkS")
		)
		(fp_rect
			(start -0.508 0.9398)
			(end 0.508 -0.9398)
			(stroke
				(width 0)
				(type default)
			)
			(fill no)
			(layer "F.CrtYd")
		)
		(fp_rect
			(start -0.508 0.9398)
			(end 0.508 -0.9398)
			(stroke
				(width 0)
				(type default)
			)
			(fill no)
			(layer "F.Fab")
		)
		(pad "1" smd custom
			(at 0 -0.4445)
			(size 0.1397 0.1397)
			(layers "F.Cu" "F.Mask" "F.Paste")
			(net "P3V3_STBY")
			(options
				(clearance outline)
				(anchor circle)
			)
			(primitives
				(gr_poly
					(pts
						(arc
							(start -0.1778 -0.2794)
							(mid -0.249642 -0.249642)
							(end -0.2794 -0.1778)
						)
						(arc
							(start -0.2794 0.1778)
							(mid -0.249642 0.249642)
							(end -0.1778 0.2794)
						)
						(arc
							(start 0.1778 0.2794)
							(mid 0.249642 0.249642)
							(end 0.2794 0.1778)
						)
						(arc
							(start 0.2794 -0.1778)
							(mid 0.249642 -0.249642)
							(end 0.1778 -0.2794)
						)
					)
					(width 0)
					(fill yes)
				)
			)
		)
		(pad "2" smd custom
			(at 0 0.4445)
			(size 0.1397 0.1397)
			(layers "F.Cu" "F.Mask" "F.Paste")
			(net "TEMP_2_A0")
			(options
				(clearance outline)
				(anchor circle)
			)
			(primitives
				(gr_poly
					(pts
						(arc
							(start -0.1778 -0.2794)
							(mid -0.249642 -0.249642)
							(end -0.2794 -0.1778)
						)
						(arc
							(start -0.2794 0.1778)
							(mid -0.249642 0.249642)
							(end -0.1778 0.2794)
						)
						(arc
							(start 0.1778 0.2794)
							(mid 0.249642 0.249642)
							(end 0.2794 0.1778)
						)
						(arc
							(start 0.2794 -0.1778)
							(mid 0.249642 -0.249642)
							(end 0.1778 -0.2794)
						)
					)
					(width 0)
					(fill yes)
				)
			)
		)
	)
	(footprint ""
		(layer "F.Cu")
		(at 53.975 -201.549)
		(property "Reference" "C7274"
			(at 0 0 0)
			(layer "F.SilkS")
			(hide yes)
			(effects
				(font
					(size 1.27 1.27)
				)
			)
		)
		(property "Value" "SCD1U25V3KX-GP"
			(at 0 -2.8194 0)
			(unlocked yes)
			(layer "F.Fab")
			(hide yes)
			(effects
				(font
					(size 1.016 1.016)
					(thickness 0.1524)
				)
			)
		)
		(property "Device Type" "C603H36"
			(at 0 -4.3434 0)
			(unlocked yes)
			(layer "F.Fab")
			(hide yes)
			(effects
				(font
					(size 1.016 1.016)
					(thickness 0.1524)
				)
			)
		)
		(duplicate_pad_numbers_are_jumpers no)
		(fp_line
			(start 0.508 0)
			(end -0.508 0)
			(stroke
				(width 0.2032)
				(type default)
			)
			(layer "F.SilkS")
		)
		(fp_rect
			(start -0.5842 1.3335)
			(end 0.5842 -1.3335)
			(stroke
				(width 0)
				(type default)
			)
			(fill no)
			(layer "F.CrtYd")
		)
		(fp_rect
			(start -0.5842 1.3335)
			(end 0.5842 -1.3335)
			(stroke
				(width 0)
				(type default)
			)
			(fill no)
			(layer "F.Fab")
		)
		(pad "1" smd custom
			(at 0 -0.762)
			(size 0.2159 0.2159)
			(layers "F.Cu" "F.Mask" "F.Paste")
			(net "P12V_PCIE")
			(options
				(clearance outline)
				(anchor circle)
			)
			(primitives
				(gr_poly
					(pts
						(arc
							(start -0.3302 -0.4318)
							(mid -0.402042 -0.402042)
							(end -0.4318 -0.3302)
						)
						(arc
							(start -0.4318 0.3302)
							(mid -0.402042 0.402042)
							(end -0.3302 0.4318)
						)
						(arc
							(start 0.3302 0.4318)
							(mid 0.402042 0.402042)
							(end 0.4318 0.3302)
						)
						(arc
							(start 0.4318 -0.3302)
							(mid 0.402042 -0.402042)
							(end 0.3302 -0.4318)
						)
					)
					(width 0)
					(fill yes)
				)
			)
		)
		(pad "2" smd custom
			(at 0 0.762)
			(size 0.2159 0.2159)
			(layers "F.Cu" "F.Mask" "F.Paste")
			(net "GND")
			(options
				(clearance outline)
				(anchor circle)
			)
			(primitives
				(gr_poly
					(pts
						(arc
							(start -0.3302 -0.4318)
							(mid -0.402042 -0.402042)
							(end -0.4318 -0.3302)
						)
						(arc
							(start -0.4318 0.3302)
							(mid -0.402042 0.402042)
							(end -0.3302 0.4318)
						)
						(arc
							(start 0.3302 0.4318)
							(mid 0.402042 0.402042)
							(end 0.4318 0.3302)
						)
						(arc
							(start 0.4318 -0.3302)
							(mid 0.402042 -0.402042)
							(end 0.3302 -0.4318)
						)
					)
					(width 0)
					(fill yes)
				)
			)
		)
	)
	(footprint ""
		(layer "F.Cu")
		(at 36.83 -169.291 -90)
		(property "Reference" "R805"
			(at 0 0 270)
			(layer "F.SilkS")
			(hide yes)
			(effects
				(font
					(size 1.27 1.27)
				)
			)
		)
		(property "Value" "0R2J-2-GP"
			(at 0.064008 -3.993896 270)
			(unlocked yes)
			(layer "F.Fab")
			(hide yes)
			(effects
				(font
					(size 1.016 1.016)
					(thickness 0.1524)
				)
			)
		)
		(property "Device Type" "R402H16"
			(at 0.064008 -5.517896 270)
			(unlocked yes)
			(layer "F.Fab")
			(hide yes)
			(effects
				(font
					(size 1.016 1.016)
					(thickness 0.1524)
				)
			)
		)
		(duplicate_pad_numbers_are_jumpers no)
		(fp_line
			(start -0.508 -0.9398)
			(end -0.508 0.9398)
			(stroke
				(width 0.1524)
				(type default)
			)
			(layer "F.SilkS")
		)
		(fp_line
			(start 0.508 -0.9398)
			(end -0.508 -0.9398)
			(stroke
				(width 0.1524)
				(type default)
			)
			(layer "F.SilkS")
		)
		(fp_rect
			(start -0.508 0.9398)
			(end 0.508 -0.9398)
			(stroke
				(width 0)
				(type default)
			)
			(fill no)
			(layer "F.CrtYd")
		)
		(fp_rect
			(start -0.508 0.9398)
			(end 0.508 -0.9398)
			(stroke
				(width 0)
				(type default)
			)
			(fill no)
			(layer "F.Fab")
		)
		(pad "1" smd custom
			(at 0 -0.4445 270)
			(size 0.1397 0.1397)
			(layers "F.Cu" "F.Mask" "F.Paste")
			(net "DP_BMC_EXP_RST_N_R")
			(options
				(clearance outline)
				(anchor circle)
			)
			(primitives
				(gr_poly
					(pts
						(arc
							(start -0.1778 -0.2794)
							(mid -0.249642 -0.249642)
							(end -0.2794 -0.1778)
						)
						(arc
							(start -0.2794 0.1778)
							(mid -0.249642 0.249642)
							(end -0.1778 0.2794)
						)
						(arc
							(start 0.1778 0.2794)
							(mid 0.249642 0.249642)
							(end 0.2794 0.1778)
						)
						(arc
							(start 0.2794 -0.1778)
							(mid 0.249642 -0.249642)
							(end 0.1778 -0.2794)
						)
					)
					(width 0)
					(fill yes)
				)
			)
		)
		(pad "2" smd custom
			(at 0 0.4445 270)
			(size 0.1397 0.1397)
			(layers "F.Cu" "F.Mask" "F.Paste")
			(net "DP_BMC_EXP_RST_N")
			(options
				(clearance outline)
				(anchor circle)
			)
			(primitives
				(gr_poly
					(pts
						(arc
							(start -0.1778 -0.2794)
							(mid -0.249642 -0.249642)
							(end -0.2794 -0.1778)
						)
						(arc
							(start -0.2794 0.1778)
							(mid -0.249642 0.249642)
							(end -0.1778 0.2794)
						)
						(arc
							(start 0.1778 0.2794)
							(mid 0.249642 0.249642)
							(end 0.2794 0.1778)
						)
						(arc
							(start 0.2794 -0.1778)
							(mid 0.249642 -0.249642)
							(end 0.1778 -0.2794)
						)
					)
					(width 0)
					(fill yes)
				)
			)
		)
	)
	(footprint ""
		(layer "F.Cu")
		(at 314.4774 -212.7504)
		(property "Reference" "U179"
			(at 0 0 0)
			(layer "F.SilkS")
			(hide yes)
			(effects
				(font
					(size 1.27 1.27)
				)
			)
		)
		(property "Value" "SNLVC1G126DCKR-GP"
			(at -2.3368 -8.6868 0)
			(unlocked yes)
			(layer "F.Fab")
			(hide yes)
			(effects
				(font
					(size 1.016 1.016)
					(thickness 0.1524)
				)
			)
		)
		(property "Device Type" "SC70-5H44"
			(at -2.3114 -10.414 0)
			(unlocked yes)
			(layer "F.Fab")
			(hide yes)
			(effects
				(font
					(size 1.016 1.016)
					(thickness 0.1524)
				)
			)
		)
		(duplicate_pad_numbers_are_jumpers no)
		(fp_line
			(start -1.27 -1.7018)
			(end 1.27 -1.7018)
			(stroke
				(width 0.1524)
				(type default)
			)
			(layer "F.SilkS")
		)
		(fp_line
			(start -1.27 1.7018)
			(end -1.27 -1.7018)
			(stroke
				(width 0.1524)
				(type default)
			)
			(layer "F.SilkS")
		)
		(fp_line
			(start 0.6604 -1.8034)
			(end 1.3843 -1.8034)
			(stroke
				(width 0.3302)
				(type default)
			)
			(layer "F.SilkS")
		)
		(fp_line
			(start 1.27 -1.7018)
			(end 1.27 1.7018)
			(stroke
				(width 0.1524)
				(type default)
			)
			(layer "F.SilkS")
		)
		(fp_line
			(start 1.27 1.7018)
			(end -1.27 1.7018)
			(stroke
				(width 0.1524)
				(type default)
			)
			(layer "F.SilkS")
		)
		(fp_line
			(start 1.3843 -1.8034)
			(end 1.3843 -1.1176)
			(stroke
				(width 0.3302)
				(type default)
			)
			(layer "F.SilkS")
		)
		(fp_rect
			(start -1.524 1.9558)
			(end 1.524 -1.9558)
			(stroke
				(width 0)
				(type default)
			)
			(fill no)
			(layer "F.CrtYd")
		)
		(fp_poly
			(pts
				(xy -1.524 -1.9558) (xy 1.524 -1.9558) (xy 1.524 1.9558) (xy -1.524 1.9558)
			)
			(stroke
				(width 0)
				(type default)
			)
			(fill no)
			(layer "F.Fab")
		)
		(pad "1" smd rect
			(at 0.65024 -0.8255)
			(size 0.4064 1.2192)
			(layers "F.Cu" "F.Mask" "F.Paste")
			(net "EXP_TDO_EN")
		)
		(pad "2" smd rect
			(at 0 -0.8255)
			(size 0.4064 1.2192)
			(layers "F.Cu" "F.Mask" "F.Paste")
			(net "JTAG_EXP_R_TDO")
		)
		(pad "3" smd rect
			(at -0.65024 -0.8255)
			(size 0.4064 1.2192)
			(layers "F.Cu" "F.Mask" "F.Paste")
			(net "GND")
		)
		(pad "4" smd rect
			(at -0.65024 0.8255)
			(size 0.4064 1.2192)
			(layers "F.Cu" "F.Mask" "F.Paste")
			(net "JTAG_IOC_L_TDI_R")
		)
		(pad "5" smd rect
			(at 0.65024 0.8255)
			(size 0.4064 1.2192)
			(layers "F.Cu" "F.Mask" "F.Paste")
			(net "P1V8_STBY")
		)
	)
	(footprint ""
		(layer "F.Cu")
		(at 277.866094 -25.791668)
		(property "Reference" "R409"
			(at 0 0 0)
			(layer "F.SilkS")
			(hide yes)
			(effects
				(font
					(size 1.27 1.27)
				)
			)
		)
		(property "Value" "0R2J-2-GP"
			(at 0.064008 -3.993896 0)
			(unlocked yes)
			(layer "F.Fab")
			(hide yes)
			(effects
				(font
					(size 1.016 1.016)
					(thickness 0.1524)
				)
			)
		)
		(property "Device Type" "R402H16"
			(at 0.064008 -5.517896 0)
			(unlocked yes)
			(layer "F.Fab")
			(hide yes)
			(effects
				(font
					(size 1.016 1.016)
					(thickness 0.1524)
				)
			)
		)
		(duplicate_pad_numbers_are_jumpers no)
		(fp_line
			(start -0.508 -0.9398)
			(end -0.508 0.9398)
			(stroke
				(width 0.1524)
				(type default)
			)
			(layer "F.SilkS")
		)
		(fp_line
			(start 0.508 -0.9398)
			(end -0.508 -0.9398)
			(stroke
				(width 0.1524)
				(type default)
			)
			(layer "F.SilkS")
		)
		(fp_rect
			(start -0.508 0.9398)
			(end 0.508 -0.9398)
			(stroke
				(width 0)
				(type default)
			)
			(fill no)
			(layer "F.CrtYd")
		)
		(fp_rect
			(start -0.508 0.9398)
			(end 0.508 -0.9398)
			(stroke
				(width 0)
				(type default)
			)
			(fill no)
			(layer "F.Fab")
		)
		(pad "1" smd custom
			(at 0 -0.4445)
			(size 0.1397 0.1397)
			(layers "F.Cu" "F.Mask" "F.Paste")
			(net "USB_DP_R")
			(options
				(clearance outline)
				(anchor circle)
			)
			(primitives
				(gr_poly
					(pts
						(arc
							(start -0.1778 -0.2794)
							(mid -0.249642 -0.249642)
							(end -0.2794 -0.1778)
						)
						(arc
							(start -0.2794 0.1778)
							(mid -0.249642 0.249642)
							(end -0.1778 0.2794)
						)
						(arc
							(start 0.1778 0.2794)
							(mid 0.249642 0.249642)
							(end 0.2794 0.1778)
						)
						(arc
							(start 0.2794 -0.1778)
							(mid 0.249642 -0.249642)
							(end 0.1778 -0.2794)
						)
					)
					(width 0)
					(fill yes)
				)
			)
		)
		(pad "2" smd custom
			(at 0 0.4445)
			(size 0.1397 0.1397)
			(layers "F.Cu" "F.Mask" "F.Paste")
			(net "USB_P1_F_DP1")
			(options
				(clearance outline)
				(anchor circle)
			)
			(primitives
				(gr_poly
					(pts
						(arc
							(start -0.1778 -0.2794)
							(mid -0.249642 -0.249642)
							(end -0.2794 -0.1778)
						)
						(arc
							(start -0.2794 0.1778)
							(mid -0.249642 0.249642)
							(end -0.1778 0.2794)
						)
						(arc
							(start 0.1778 0.2794)
							(mid 0.249642 0.249642)
							(end 0.2794 0.1778)
						)
						(arc
							(start 0.2794 -0.1778)
							(mid 0.249642 -0.249642)
							(end 0.1778 -0.2794)
						)
					)
					(width 0)
					(fill yes)
				)
			)
		)
	)
	(footprint ""
		(layer "F.Cu")
		(at 66.715386 -110.408212 -90)
		(property "Reference" "PR167"
			(at 0 0 270)
			(layer "F.SilkS")
			(hide yes)
			(effects
				(font
					(size 1.27 1.27)
				)
			)
		)
		(property "Value" "4K02R2F-GP"
			(at 0.064008 -3.993896 270)
			(unlocked yes)
			(layer "F.Fab")
			(hide yes)
			(effects
				(font
					(size 1.016 1.016)
					(thickness 0.1524)
				)
			)
		)
		(property "Device Type" "R402H16"
			(at 0.064008 -5.517896 270)
			(unlocked yes)
			(layer "F.Fab")
			(hide yes)
			(effects
				(font
					(size 1.016 1.016)
					(thickness 0.1524)
				)
			)
		)
		(duplicate_pad_numbers_are_jumpers no)
		(fp_line
			(start -0.508 -0.9398)
			(end -0.508 0.9398)
			(stroke
				(width 0.1524)
				(type default)
			)
			(layer "F.SilkS")
		)
		(fp_line
			(start 0.508 -0.9398)
			(end -0.508 -0.9398)
			(stroke
				(width 0.1524)
				(type default)
			)
			(layer "F.SilkS")
		)
		(fp_rect
			(start -0.508 0.9398)
			(end 0.508 -0.9398)
			(stroke
				(width 0)
				(type default)
			)
			(fill no)
			(layer "F.CrtYd")
		)
		(fp_rect
			(start -0.508 0.9398)
			(end 0.508 -0.9398)
			(stroke
				(width 0)
				(type default)
			)
			(fill no)
			(layer "F.Fab")
		)
		(pad "1" smd custom
			(at 0 -0.4445 270)
			(size 0.1397 0.1397)
			(layers "F.Cu" "F.Mask" "F.Paste")
			(net "P1V8_EN_G")
			(options
				(clearance outline)
				(anchor circle)
			)
			(primitives
				(gr_poly
					(pts
						(arc
							(start -0.1778 -0.2794)
							(mid -0.249642 -0.249642)
							(end -0.2794 -0.1778)
						)
						(arc
							(start -0.2794 0.1778)
							(mid -0.249642 0.249642)
							(end -0.1778 0.2794)
						)
						(arc
							(start 0.1778 0.2794)
							(mid 0.249642 0.249642)
							(end 0.2794 0.1778)
						)
						(arc
							(start 0.2794 -0.1778)
							(mid 0.249642 -0.249642)
							(end 0.1778 -0.2794)
						)
					)
					(width 0)
					(fill yes)
				)
			)
		)
		(pad "2" smd custom
			(at 0 0.4445 270)
			(size 0.1397 0.1397)
			(layers "F.Cu" "F.Mask" "F.Paste")
			(net "P3V3_STBY")
			(options
				(clearance outline)
				(anchor circle)
			)
			(primitives
				(gr_poly
					(pts
						(arc
							(start -0.1778 -0.2794)
							(mid -0.249642 -0.249642)
							(end -0.2794 -0.1778)
						)
						(arc
							(start -0.2794 0.1778)
							(mid -0.249642 0.249642)
							(end -0.1778 0.2794)
						)
						(arc
							(start 0.1778 0.2794)
							(mid 0.249642 0.249642)
							(end 0.2794 0.1778)
						)
						(arc
							(start 0.2794 -0.1778)
							(mid 0.249642 -0.249642)
							(end 0.1778 -0.2794)
						)
					)
					(width 0)
					(fill yes)
				)
			)
		)
	)
	(footprint ""
		(layer "F.Cu")
		(at 50.546 -224.917)
		(property "Reference" "R2106"
			(at 0 0 0)
			(layer "F.SilkS")
			(hide yes)
			(effects
				(font
					(size 1.27 1.27)
				)
			)
		)
		(property "Value" "49K9R2F-L-GP"
			(at 0.064008 -3.993896 0)
			(unlocked yes)
			(layer "F.Fab")
			(hide yes)
			(effects
				(font
					(size 1.016 1.016)
					(thickness 0.1524)
				)
			)
		)
		(property "Device Type" "R402H16"
			(at 0.064008 -5.517896 0)
			(unlocked yes)
			(layer "F.Fab")
			(hide yes)
			(effects
				(font
					(size 1.016 1.016)
					(thickness 0.1524)
				)
			)
		)
		(duplicate_pad_numbers_are_jumpers no)
		(fp_line
			(start -0.508 -0.9398)
			(end -0.508 0.9398)
			(stroke
				(width 0.1524)
				(type default)
			)
			(layer "F.SilkS")
		)
		(fp_line
			(start 0.508 -0.9398)
			(end -0.508 -0.9398)
			(stroke
				(width 0.1524)
				(type default)
			)
			(layer "F.SilkS")
		)
		(fp_rect
			(start -0.508 0.9398)
			(end 0.508 -0.9398)
			(stroke
				(width 0)
				(type default)
			)
			(fill no)
			(layer "F.CrtYd")
		)
		(fp_rect
			(start -0.508 0.9398)
			(end 0.508 -0.9398)
			(stroke
				(width 0)
				(type default)
			)
			(fill no)
			(layer "F.Fab")
		)
		(pad "1" smd custom
			(at 0 -0.4445)
			(size 0.1397 0.1397)
			(layers "F.Cu" "F.Mask" "F.Paste")
			(net "P12V_PCIE")
			(options
				(clearance outline)
				(anchor circle)
			)
			(primitives
				(gr_poly
					(pts
						(arc
							(start -0.1778 -0.2794)
							(mid -0.249642 -0.249642)
							(end -0.2794 -0.1778)
						)
						(arc
							(start -0.2794 0.1778)
							(mid -0.249642 0.249642)
							(end -0.1778 0.2794)
						)
						(arc
							(start 0.1778 0.2794)
							(mid 0.249642 0.249642)
							(end 0.2794 0.1778)
						)
						(arc
							(start 0.2794 -0.1778)
							(mid 0.249642 -0.249642)
							(end 0.1778 -0.2794)
						)
					)
					(width 0)
					(fill yes)
				)
			)
		)
		(pad "2" smd custom
			(at 0 0.4445)
			(size 0.1397 0.1397)
			(layers "F.Cu" "F.Mask" "F.Paste")
			(net "MB0_CM_OV_R")
			(options
				(clearance outline)
				(anchor circle)
			)
			(primitives
				(gr_poly
					(pts
						(arc
							(start -0.1778 -0.2794)
							(mid -0.249642 -0.249642)
							(end -0.2794 -0.1778)
						)
						(arc
							(start -0.2794 0.1778)
							(mid -0.249642 0.249642)
							(end -0.1778 0.2794)
						)
						(arc
							(start 0.1778 0.2794)
							(mid 0.249642 0.249642)
							(end 0.2794 0.1778)
						)
						(arc
							(start 0.2794 -0.1778)
							(mid 0.249642 -0.249642)
							(end 0.1778 -0.2794)
						)
					)
					(width 0)
					(fill yes)
				)
			)
		)
	)
	(footprint ""
		(layer "F.Cu")
		(at 212.217 -219.964 90)
		(property "Reference" "U176"
			(at 0 0 90)
			(layer "F.SilkS")
			(hide yes)
			(effects
				(font
					(size 1.27 1.27)
				)
			)
		)
		(property "Value" "SNLVC1G126DCKR-GP"
			(at -2.3368 -8.6868 90)
			(unlocked yes)
			(layer "F.Fab")
			(hide yes)
			(effects
				(font
					(size 1.016 1.016)
					(thickness 0.1524)
				)
			)
		)
		(property "Device Type" "SC70-5H44"
			(at -2.3114 -10.414 90)
			(unlocked yes)
			(layer "F.Fab")
			(hide yes)
			(effects
				(font
					(size 1.016 1.016)
					(thickness 0.1524)
				)
			)
		)
		(duplicate_pad_numbers_are_jumpers no)
		(fp_line
			(start 1.3843 -1.8034)
			(end 1.3843 -1.1176)
			(stroke
				(width 0.3302)
				(type default)
			)
			(layer "F.SilkS")
		)
		(fp_line
			(start 0.6604 -1.8034)
			(end 1.3843 -1.8034)
			(stroke
				(width 0.3302)
				(type default)
			)
			(layer "F.SilkS")
		)
		(fp_line
			(start 1.27 -1.7018)
			(end 1.27 1.7018)
			(stroke
				(width 0.1524)
				(type default)
			)
			(layer "F.SilkS")
		)
		(fp_line
			(start -1.27 -1.7018)
			(end 1.27 -1.7018)
			(stroke
				(width 0.1524)
				(type default)
			)
			(layer "F.SilkS")
		)
		(fp_line
			(start 1.27 1.7018)
			(end -1.27 1.7018)
			(stroke
				(width 0.1524)
				(type default)
			)
			(layer "F.SilkS")
		)
		(fp_line
			(start -1.27 1.7018)
			(end -1.27 -1.7018)
			(stroke
				(width 0.1524)
				(type default)
			)
			(layer "F.SilkS")
		)
		(fp_rect
			(start -1.524 1.9558)
			(end 1.524 -1.9558)
			(stroke
				(width 0)
				(type default)
			)
			(fill no)
			(layer "F.CrtYd")
		)
		(fp_poly
			(pts
				(xy -1.524 -1.9558) (xy 1.524 -1.9558) (xy 1.524 1.9558) (xy -1.524 1.9558)
			)
			(stroke
				(width 0)
				(type default)
			)
			(fill no)
			(layer "F.Fab")
		)
		(pad "1" smd rect
			(at 0.65024 -0.8255 90)
			(size 0.4064 1.2192)
			(layers "F.Cu" "F.Mask" "F.Paste")
			(net "OE_BMC_RSET")
		)
		(pad "2" smd rect
			(at 0 -0.8255 90)
			(size 0.4064 1.2192)
			(layers "F.Cu" "F.Mask" "F.Paste")
			(net "DP_BMC_CPU_RST_N_U177_OUT")
		)
		(pad "3" smd rect
			(at -0.65024 -0.8255 90)
			(size 0.4064 1.2192)
			(layers "F.Cu" "F.Mask" "F.Paste")
			(net "GND")
		)
		(pad "4" smd rect
			(at -0.65024 0.8255 90)
			(size 0.4064 1.2192)
			(layers "F.Cu" "F.Mask" "F.Paste")
			(net "CPU_RESET_N")
		)
		(pad "5" smd rect
			(at 0.65024 0.8255 90)
			(size 0.4064 1.2192)
			(layers "F.Cu" "F.Mask" "F.Paste")
			(net "P3V3_STBY")
		)
	)
	(footprint ""
		(layer "F.Cu")
		(at 101.74097 -76.454)
		(property "Reference" "SR923"
			(at 0 0 0)
			(layer "F.SilkS")
			(hide yes)
			(effects
				(font
					(size 1.27 1.27)
				)
			)
		)
		(property "Value" "0R2J-2-GP"
			(at 0.064008 -3.993896 0)
			(unlocked yes)
			(layer "F.Fab")
			(hide yes)
			(effects
				(font
					(size 1.016 1.016)
					(thickness 0.1524)
				)
			)
		)
		(property "Device Type" "R402H16"
			(at 0.064008 -5.517896 0)
			(unlocked yes)
			(layer "F.Fab")
			(hide yes)
			(effects
				(font
					(size 1.016 1.016)
					(thickness 0.1524)
				)
			)
		)
		(duplicate_pad_numbers_are_jumpers no)
		(fp_line
			(start -0.508 -0.9398)
			(end -0.508 0.9398)
			(stroke
				(width 0.1524)
				(type default)
			)
			(layer "F.SilkS")
		)
		(fp_line
			(start 0.508 -0.9398)
			(end -0.508 -0.9398)
			(stroke
				(width 0.1524)
				(type default)
			)
			(layer "F.SilkS")
		)
		(fp_rect
			(start -0.508 0.9398)
			(end 0.508 -0.9398)
			(stroke
				(width 0)
				(type default)
			)
			(fill no)
			(layer "F.CrtYd")
		)
		(fp_rect
			(start -0.508 0.9398)
			(end 0.508 -0.9398)
			(stroke
				(width 0)
				(type default)
			)
			(fill no)
			(layer "F.Fab")
		)
		(pad "1" smd custom
			(at 0 -0.4445)
			(size 0.1397 0.1397)
			(layers "F.Cu" "F.Mask" "F.Paste")
			(net "JTAG_EXP_TDO_R")
			(options
				(clearance outline)
				(anchor circle)
			)
			(primitives
				(gr_poly
					(pts
						(arc
							(start -0.1778 -0.2794)
							(mid -0.249642 -0.249642)
							(end -0.2794 -0.1778)
						)
						(arc
							(start -0.2794 0.1778)
							(mid -0.249642 0.249642)
							(end -0.1778 0.2794)
						)
						(arc
							(start 0.1778 0.2794)
							(mid 0.249642 0.249642)
							(end 0.2794 0.1778)
						)
						(arc
							(start 0.2794 -0.1778)
							(mid 0.249642 -0.249642)
							(end 0.1778 -0.2794)
						)
					)
					(width 0)
					(fill yes)
				)
			)
		)
		(pad "2" smd custom
			(at 0 0.4445)
			(size 0.1397 0.1397)
			(layers "F.Cu" "F.Mask" "F.Paste")
			(net "JTAG_EXP_TDO")
			(options
				(clearance outline)
				(anchor circle)
			)
			(primitives
				(gr_poly
					(pts
						(arc
							(start -0.1778 -0.2794)
							(mid -0.249642 -0.249642)
							(end -0.2794 -0.1778)
						)
						(arc
							(start -0.2794 0.1778)
							(mid -0.249642 0.249642)
							(end -0.1778 0.2794)
						)
						(arc
							(start 0.1778 0.2794)
							(mid 0.249642 0.249642)
							(end 0.2794 0.1778)
						)
						(arc
							(start 0.2794 -0.1778)
							(mid 0.249642 -0.249642)
							(end 0.1778 -0.2794)
						)
					)
					(width 0)
					(fill yes)
				)
			)
		)
	)
	(footprint ""
		(layer "F.Cu")
		(at 167.503348 -122.545856)
		(property "Reference" "PR158"
			(at 0 0 0)
			(layer "F.SilkS")
			(hide yes)
			(effects
				(font
					(size 1.27 1.27)
				)
			)
		)
		(property "Value" "100KR2F-L1-GP"
			(at 0.064008 -3.993896 0)
			(unlocked yes)
			(layer "F.Fab")
			(hide yes)
			(effects
				(font
					(size 1.016 1.016)
					(thickness 0.1524)
				)
			)
		)
		(property "Device Type" "R402H16"
			(at 0.064008 -5.517896 0)
			(unlocked yes)
			(layer "F.Fab")
			(hide yes)
			(effects
				(font
					(size 1.016 1.016)
					(thickness 0.1524)
				)
			)
		)
		(duplicate_pad_numbers_are_jumpers no)
		(fp_line
			(start -0.508 -0.9398)
			(end -0.508 0.9398)
			(stroke
				(width 0.1524)
				(type default)
			)
			(layer "F.SilkS")
		)
		(fp_line
			(start 0.508 -0.9398)
			(end -0.508 -0.9398)
			(stroke
				(width 0.1524)
				(type default)
			)
			(layer "F.SilkS")
		)
		(fp_rect
			(start -0.508 0.9398)
			(end 0.508 -0.9398)
			(stroke
				(width 0)
				(type default)
			)
			(fill no)
			(layer "F.CrtYd")
		)
		(fp_rect
			(start -0.508 0.9398)
			(end 0.508 -0.9398)
			(stroke
				(width 0)
				(type default)
			)
			(fill no)
			(layer "F.Fab")
		)
		(pad "1" smd custom
			(at 0 -0.4445)
			(size 0.1397 0.1397)
			(layers "F.Cu" "F.Mask" "F.Paste")
			(net "P0V9_E_VREG")
			(options
				(clearance outline)
				(anchor circle)
			)
			(primitives
				(gr_poly
					(pts
						(arc
							(start -0.1778 -0.2794)
							(mid -0.249642 -0.249642)
							(end -0.2794 -0.1778)
						)
						(arc
							(start -0.2794 0.1778)
							(mid -0.249642 0.249642)
							(end -0.1778 0.2794)
						)
						(arc
							(start 0.1778 0.2794)
							(mid 0.249642 0.249642)
							(end 0.2794 0.1778)
						)
						(arc
							(start 0.2794 -0.1778)
							(mid 0.249642 -0.249642)
							(end 0.1778 -0.2794)
						)
					)
					(width 0)
					(fill yes)
				)
			)
		)
		(pad "2" smd custom
			(at 0 0.4445)
			(size 0.1397 0.1397)
			(layers "F.Cu" "F.Mask" "F.Paste")
			(net "P0V9_E_RF")
			(options
				(clearance outline)
				(anchor circle)
			)
			(primitives
				(gr_poly
					(pts
						(arc
							(start -0.1778 -0.2794)
							(mid -0.249642 -0.249642)
							(end -0.2794 -0.1778)
						)
						(arc
							(start -0.2794 0.1778)
							(mid -0.249642 0.249642)
							(end -0.1778 0.2794)
						)
						(arc
							(start 0.1778 0.2794)
							(mid 0.249642 0.249642)
							(end 0.2794 0.1778)
						)
						(arc
							(start 0.2794 -0.1778)
							(mid 0.249642 -0.249642)
							(end 0.1778 -0.2794)
						)
					)
					(width 0)
					(fill yes)
				)
			)
		)
	)
	(footprint ""
		(layer "F.Cu")
		(at 269.739872 -56.714136 -90)
		(property "Reference" "PR115"
			(at 0 0 270)
			(layer "F.SilkS")
			(hide yes)
			(effects
				(font
					(size 1.27 1.27)
				)
			)
		)
		(property "Value" "4K02R2F-GP"
			(at 0.064008 -3.993896 270)
			(unlocked yes)
			(layer "F.Fab")
			(hide yes)
			(effects
				(font
					(size 1.016 1.016)
					(thickness 0.1524)
				)
			)
		)
		(property "Device Type" "R402H16"
			(at 0.064008 -5.517896 270)
			(unlocked yes)
			(layer "F.Fab")
			(hide yes)
			(effects
				(font
					(size 1.016 1.016)
					(thickness 0.1524)
				)
			)
		)
		(duplicate_pad_numbers_are_jumpers no)
		(fp_line
			(start -0.508 -0.9398)
			(end -0.508 0.9398)
			(stroke
				(width 0.1524)
				(type default)
			)
			(layer "F.SilkS")
		)
		(fp_line
			(start 0.508 -0.9398)
			(end -0.508 -0.9398)
			(stroke
				(width 0.1524)
				(type default)
			)
			(layer "F.SilkS")
		)
		(fp_rect
			(start -0.508 0.9398)
			(end 0.508 -0.9398)
			(stroke
				(width 0)
				(type default)
			)
			(fill no)
			(layer "F.CrtYd")
		)
		(fp_rect
			(start -0.508 0.9398)
			(end 0.508 -0.9398)
			(stroke
				(width 0)
				(type default)
			)
			(fill no)
			(layer "F.Fab")
		)
		(pad "1" smd custom
			(at 0 -0.4445 270)
			(size 0.1397 0.1397)
			(layers "F.Cu" "F.Mask" "F.Paste")
			(net "P3V3_EN_B")
			(options
				(clearance outline)
				(anchor circle)
			)
			(primitives
				(gr_poly
					(pts
						(arc
							(start -0.1778 -0.2794)
							(mid -0.249642 -0.249642)
							(end -0.2794 -0.1778)
						)
						(arc
							(start -0.2794 0.1778)
							(mid -0.249642 0.249642)
							(end -0.1778 0.2794)
						)
						(arc
							(start 0.1778 0.2794)
							(mid 0.249642 0.249642)
							(end 0.2794 0.1778)
						)
						(arc
							(start 0.2794 -0.1778)
							(mid 0.249642 -0.249642)
							(end 0.1778 -0.2794)
						)
					)
					(width 0)
					(fill yes)
				)
			)
		)
		(pad "2" smd custom
			(at 0 0.4445 270)
			(size 0.1397 0.1397)
			(layers "F.Cu" "F.Mask" "F.Paste")
			(net "P3V3_STBY")
			(options
				(clearance outline)
				(anchor circle)
			)
			(primitives
				(gr_poly
					(pts
						(arc
							(start -0.1778 -0.2794)
							(mid -0.249642 -0.249642)
							(end -0.2794 -0.1778)
						)
						(arc
							(start -0.2794 0.1778)
							(mid -0.249642 0.249642)
							(end -0.1778 0.2794)
						)
						(arc
							(start 0.1778 0.2794)
							(mid 0.249642 0.249642)
							(end 0.2794 0.1778)
						)
						(arc
							(start 0.2794 -0.1778)
							(mid 0.249642 -0.249642)
							(end 0.1778 -0.2794)
						)
					)
					(width 0)
					(fill yes)
				)
			)
		)
	)
	(footprint ""
		(layer "F.Cu")
		(at 87.103966 -61.341 90)
		(property "Reference" "SC886"
			(at 0 0 90)
			(layer "F.SilkS")
			(hide yes)
			(effects
				(font
					(size 1.27 1.27)
				)
			)
		)
		(property "Value" "SC12P50V2JN-3GP"
			(at 1.1811 -2.7051 90)
			(unlocked yes)
			(layer "F.Fab")
			(hide yes)
			(effects
				(font
					(size 1.016 1.016)
					(thickness 0.1524)
				)
			)
		)
		(property "Device Type" "C402H24"
			(at 1.1811 -4.2291 90)
			(unlocked yes)
			(layer "F.Fab")
			(hide yes)
			(effects
				(font
					(size 1.016 1.016)
					(thickness 0.1524)
				)
			)
		)
		(duplicate_pad_numbers_are_jumpers no)
		(fp_rect
			(start -0.4318 0.9525)
			(end 0.4318 -0.9525)
			(stroke
				(width 0)
				(type default)
			)
			(fill no)
			(layer "F.CrtYd")
		)
		(fp_rect
			(start -0.4318 0.9525)
			(end 0.4318 -0.9525)
			(stroke
				(width 0)
				(type default)
			)
			(fill no)
			(layer "F.Fab")
		)
		(pad "1" smd custom
			(at 0 -0.4445 90)
			(size 0.1524 0.1524)
			(layers "F.Cu" "F.Mask" "F.Paste")
			(net "REF_CLK")
			(options
				(clearance outline)
				(anchor circle)
			)
			(primitives
				(gr_poly
					(pts
						(arc
							(start 0.3048 -0.2032)
							(mid 0.275042 -0.275042)
							(end 0.2032 -0.3048)
						)
						(arc
							(start -0.2032 -0.3048)
							(mid -0.275042 -0.275042)
							(end -0.3048 -0.2032)
						)
						(arc
							(start -0.3048 0.2032)
							(mid -0.275042 0.275042)
							(end -0.2032 0.3048)
						)
						(arc
							(start 0.2032 0.3048)
							(mid 0.275042 0.275042)
							(end 0.3048 0.2032)
						)
					)
					(width 0)
					(fill yes)
				)
			)
		)
		(pad "2" smd custom
			(at 0 0.4445 90)
			(size 0.1524 0.1524)
			(layers "F.Cu" "F.Mask" "F.Paste")
			(net "GND")
			(options
				(clearance outline)
				(anchor circle)
			)
			(primitives
				(gr_poly
					(pts
						(arc
							(start 0.3048 -0.2032)
							(mid 0.275042 -0.275042)
							(end 0.2032 -0.3048)
						)
						(arc
							(start -0.2032 -0.3048)
							(mid -0.275042 -0.275042)
							(end -0.3048 -0.2032)
						)
						(arc
							(start -0.3048 0.2032)
							(mid -0.275042 0.275042)
							(end -0.2032 0.3048)
						)
						(arc
							(start 0.2032 0.3048)
							(mid 0.275042 0.275042)
							(end 0.3048 0.2032)
						)
					)
					(width 0)
					(fill yes)
				)
			)
		)
	)
	(footprint ""
		(layer "F.Cu")
		(at 270.764 -187.325 90)
		(property "Reference" "C322"
			(at 0 0 90)
			(layer "F.SilkS")
			(hide yes)
			(effects
				(font
					(size 1.27 1.27)
				)
			)
		)
		(property "Value" "SCD1U16V2KX-3GP"
			(at 1.1811 -2.7051 90)
			(unlocked yes)
			(layer "F.Fab")
			(hide yes)
			(effects
				(font
					(size 1.016 1.016)
					(thickness 0.1524)
				)
			)
		)
		(property "Device Type" "C402H22"
			(at 1.1811 -4.2291 90)
			(unlocked yes)
			(layer "F.Fab")
			(hide yes)
			(effects
				(font
					(size 1.016 1.016)
					(thickness 0.1524)
				)
			)
		)
		(duplicate_pad_numbers_are_jumpers no)
		(fp_rect
			(start -0.4318 0.9525)
			(end 0.4318 -0.9525)
			(stroke
				(width 0)
				(type default)
			)
			(fill no)
			(layer "F.CrtYd")
		)
		(fp_rect
			(start -0.4318 0.9525)
			(end 0.4318 -0.9525)
			(stroke
				(width 0)
				(type default)
			)
			(fill no)
			(layer "F.Fab")
		)
		(pad "1" smd custom
			(at 0 -0.4445 90)
			(size 0.1524 0.1524)
			(layers "F.Cu" "F.Mask" "F.Paste")
			(net "DP_RST_N")
			(options
				(clearance outline)
				(anchor circle)
			)
			(primitives
				(gr_poly
					(pts
						(arc
							(start 0.3048 -0.2032)
							(mid 0.275042 -0.275042)
							(end 0.2032 -0.3048)
						)
						(arc
							(start -0.2032 -0.3048)
							(mid -0.275042 -0.275042)
							(end -0.3048 -0.2032)
						)
						(arc
							(start -0.3048 0.2032)
							(mid -0.275042 0.275042)
							(end -0.2032 0.3048)
						)
						(arc
							(start 0.2032 0.3048)
							(mid 0.275042 0.275042)
							(end 0.3048 0.2032)
						)
					)
					(width 0)
					(fill yes)
				)
			)
		)
		(pad "2" smd custom
			(at 0 0.4445 90)
			(size 0.1524 0.1524)
			(layers "F.Cu" "F.Mask" "F.Paste")
			(net "GND")
			(options
				(clearance outline)
				(anchor circle)
			)
			(primitives
				(gr_poly
					(pts
						(arc
							(start 0.3048 -0.2032)
							(mid 0.275042 -0.275042)
							(end 0.2032 -0.3048)
						)
						(arc
							(start -0.2032 -0.3048)
							(mid -0.275042 -0.275042)
							(end -0.3048 -0.2032)
						)
						(arc
							(start -0.3048 0.2032)
							(mid -0.275042 0.275042)
							(end -0.2032 0.3048)
						)
						(arc
							(start 0.2032 0.3048)
							(mid 0.275042 0.275042)
							(end 0.3048 0.2032)
						)
					)
					(width 0)
					(fill yes)
				)
			)
		)
	)
	(footprint ""
		(layer "F.Cu")
		(at 164.973 -87.884)
		(property "Reference" "PTC7"
			(at 0 0 0)
			(layer "F.SilkS")
			(hide yes)
			(effects
				(font
					(size 1.27 1.27)
				)
			)
		)
		(property "Value" "SE470UF2VDM-GP"
			(at 0 -9.6012 0)
			(unlocked yes)
			(layer "F.Fab")
			(hide yes)
			(effects
				(font
					(size 1.016 1.016)
					(thickness 0.1524)
				)
			)
		)
		(property "Device Type" "CT7343H83"
			(at 0 -11.1252 0)
			(unlocked yes)
			(layer "F.Fab")
			(hide yes)
			(effects
				(font
					(size 1.016 1.016)
					(thickness 0.1524)
				)
			)
		)
		(duplicate_pad_numbers_are_jumpers no)
		(fp_line
			(start -2.286 -4.8768)
			(end -2.286 -2.032)
			(stroke
				(width 0.1524)
				(type default)
			)
			(layer "F.SilkS")
		)
		(fp_line
			(start -2.286 4.8768)
			(end -2.286 2.032)
			(stroke
				(width 0.1524)
				(type default)
			)
			(layer "F.SilkS")
		)
		(fp_line
			(start 2.1082 -4.699)
			(end -2.1082 -4.699)
			(stroke
				(width 0.508)
				(type default)
			)
			(layer "F.SilkS")
		)
		(fp_line
			(start 2.286 -4.8768)
			(end -2.286 -4.8768)
			(stroke
				(width 0.1524)
				(type default)
			)
			(layer "F.SilkS")
		)
		(fp_line
			(start 2.286 -2.032)
			(end 2.286 -4.8768)
			(stroke
				(width 0.1524)
				(type default)
			)
			(layer "F.SilkS")
		)
		(fp_line
			(start 2.286 2.032)
			(end 2.286 4.8768)
			(stroke
				(width 0.1524)
				(type default)
			)
			(layer "F.SilkS")
		)
		(fp_line
			(start 2.286 4.8768)
			(end -2.286 4.8768)
			(stroke
				(width 0.1524)
				(type default)
			)
			(layer "F.SilkS")
		)
		(fp_rect
			(start -2.1463 3.6449)
			(end 2.1463 -3.6449)
			(stroke
				(width 0)
				(type default)
			)
			(fill no)
			(layer "F.CrtYd")
		)
		(fp_poly
			(pts
				(xy -2.54 4.953) (xy -2.54 4.2926) (xy -3.81 4.2926) (xy -3.81 -4.2926) (xy -2.54 -4.2926) (xy -2.54 -4.953)
				(xy 2.54 -4.953) (xy 2.54 -4.2926) (xy 3.81 -4.2926) (xy 3.81 -1.6256) (xy 2.1463 -1.6256) (xy 2.1463 -3.6449)
				(xy -2.1463 -3.6449) (xy -2.1463 3.6449) (xy 2.1463 3.6449) (xy 2.1463 -1.6129) (xy 3.81 -1.6129)
				(xy 3.81 4.2926) (xy 2.54 4.2926) (xy 2.54 4.953)
			)
			(stroke
				(width 0)
				(type default)
			)
			(fill no)
			(layer "F.CrtYd")
		)
		(fp_rect
			(start -3.81 4.2926)
			(end -2.54 -4.2926)
			(stroke
				(width 0)
				(type default)
			)
			(fill no)
			(layer "F.Fab")
		)
		(fp_rect
			(start -2.54 4.953)
			(end 2.54 -4.953)
			(stroke
				(width 0)
				(type default)
			)
			(fill no)
			(layer "F.Fab")
		)
		(fp_rect
			(start 2.54 4.2926)
			(end 3.81 -4.2926)
			(stroke
				(width 0)
				(type default)
			)
			(fill no)
			(layer "F.Fab")
		)
		(pad "1" smd rect
			(at 0 -3.1496)
			(size 2.413 2.286)
			(layers "F.Cu" "F.Mask" "F.Paste")
			(net "P0V9_E")
		)
		(pad "2" smd rect
			(at 0 3.1496)
			(size 2.413 2.286)
			(layers "F.Cu" "F.Mask" "F.Paste")
			(net "GND")
		)
		(zone
			(layer "F.Cu")
			(hatch none 0.5)
			(connect_pads
				(clearance 0)
			)
			(min_thickness 0.25)
			(keepout
				(tracks allowed)
				(vias not_allowed)
				(pads allowed)
				(copperpour not_allowed)
				(footprints allowed)
			)
			(placement
				(enabled no)
				(sheetname "")
			)
			(fill
				(thermal_gap 0.5)
				(thermal_bridge_width 0.5)
				(island_removal_mode 0)
			)
			(polygon
				(pts
					(xy 163.4617 -83.2866) (xy 166.4843 -83.2866) (xy 166.4843 -86.1822) (xy 166.4843 -86.5124) (xy 163.4617 -86.5124)
					(xy 163.4617 -86.1822)
				)
			)
		)
		(zone
			(layer "F.Cu")
			(hatch none 0.5)
			(connect_pads
				(clearance 0)
			)
			(min_thickness 0.25)
			(keepout
				(tracks allowed)
				(vias not_allowed)
				(pads allowed)
				(copperpour not_allowed)
				(footprints allowed)
			)
			(placement
				(enabled no)
				(sheetname "")
			)
			(fill
				(thermal_gap 0.5)
				(thermal_bridge_width 0.5)
				(island_removal_mode 0)
			)
			(polygon
				(pts
					(xy 166.4843 -89.5731) (xy 166.4843 -92.4814) (xy 163.4617 -92.4814) (xy 163.4617 -89.5858) (xy 163.4617 -89.2556)
					(xy 166.4843 -89.2556)
				)
			)
		)
	)
	(footprint ""
		(layer "F.Cu")
		(at 199.39 -142.494 90)
		(property "Reference" "SR767"
			(at 0 0 90)
			(layer "F.SilkS")
			(hide yes)
			(effects
				(font
					(size 1.27 1.27)
				)
			)
		)
		(property "Value" "4K7R2F-GP"
			(at 0.064008 -3.993896 90)
			(unlocked yes)
			(layer "F.Fab")
			(hide yes)
			(effects
				(font
					(size 1.016 1.016)
					(thickness 0.1524)
				)
			)
		)
		(property "Device Type" "R402H16"
			(at 0.064008 -5.517896 90)
			(unlocked yes)
			(layer "F.Fab")
			(hide yes)
			(effects
				(font
					(size 1.016 1.016)
					(thickness 0.1524)
				)
			)
		)
		(duplicate_pad_numbers_are_jumpers no)
		(fp_line
			(start 0.508 -0.9398)
			(end -0.508 -0.9398)
			(stroke
				(width 0.1524)
				(type default)
			)
			(layer "F.SilkS")
		)
		(fp_line
			(start -0.508 -0.9398)
			(end -0.508 0.9398)
			(stroke
				(width 0.1524)
				(type default)
			)
			(layer "F.SilkS")
		)
		(fp_rect
			(start -0.508 0.9398)
			(end 0.508 -0.9398)
			(stroke
				(width 0)
				(type default)
			)
			(fill no)
			(layer "F.CrtYd")
		)
		(fp_rect
			(start -0.508 0.9398)
			(end 0.508 -0.9398)
			(stroke
				(width 0)
				(type default)
			)
			(fill no)
			(layer "F.Fab")
		)
		(pad "1" smd custom
			(at 0 -0.4445 90)
			(size 0.1397 0.1397)
			(layers "F.Cu" "F.Mask" "F.Paste")
			(net "EXP_EEPROM_A2")
			(options
				(clearance outline)
				(anchor circle)
			)
			(primitives
				(gr_poly
					(pts
						(arc
							(start -0.1778 -0.2794)
							(mid -0.249642 -0.249642)
							(end -0.2794 -0.1778)
						)
						(arc
							(start -0.2794 0.1778)
							(mid -0.249642 0.249642)
							(end -0.1778 0.2794)
						)
						(arc
							(start 0.1778 0.2794)
							(mid 0.249642 0.249642)
							(end 0.2794 0.1778)
						)
						(arc
							(start 0.2794 -0.1778)
							(mid 0.249642 -0.249642)
							(end 0.1778 -0.2794)
						)
					)
					(width 0)
					(fill yes)
				)
			)
		)
		(pad "2" smd custom
			(at 0 0.4445 90)
			(size 0.1397 0.1397)
			(layers "F.Cu" "F.Mask" "F.Paste")
			(net "GND")
			(options
				(clearance outline)
				(anchor circle)
			)
			(primitives
				(gr_poly
					(pts
						(arc
							(start -0.1778 -0.2794)
							(mid -0.249642 -0.249642)
							(end -0.2794 -0.1778)
						)
						(arc
							(start -0.2794 0.1778)
							(mid -0.249642 0.249642)
							(end -0.1778 0.2794)
						)
						(arc
							(start 0.1778 0.2794)
							(mid 0.249642 0.249642)
							(end 0.2794 0.1778)
						)
						(arc
							(start 0.2794 -0.1778)
							(mid 0.249642 -0.249642)
							(end 0.1778 -0.2794)
						)
					)
					(width 0)
					(fill yes)
				)
			)
		)
	)
	(footprint ""
		(layer "F.Cu")
		(at 333.375 -4.318 90)
		(property "Reference" "LED14"
			(at 0 0 90)
			(layer "F.SilkS")
			(hide yes)
			(effects
				(font
					(size 1.27 1.27)
				)
			)
		)
		(property "Value" "LED-Y-11-GP"
			(at -0.1016 -8.1788 90)
			(unlocked yes)
			(layer "F.Fab")
			(hide yes)
			(effects
				(font
					(size 1.016 1.016)
					(thickness 0.1524)
				)
			)
		)
		(property "Device Type" "19-21UBC-1"
			(at -0.0508 -9.8552 90)
			(unlocked yes)
			(layer "F.Fab")
			(hide yes)
			(effects
				(font
					(size 1.016 1.016)
					(thickness 0.1524)
				)
			)
		)
		(duplicate_pad_numbers_are_jumpers no)
		(fp_line
			(start 1.4351 -0.7747)
			(end 1.4351 0.7747)
			(stroke
				(width 0.1524)
				(type default)
			)
			(layer "F.SilkS")
		)
		(fp_line
			(start -1.4351 -0.7747)
			(end 1.4351 -0.7747)
			(stroke
				(width 0.1524)
				(type default)
			)
			(layer "F.SilkS")
		)
		(fp_line
			(start -1.7653 -0.7747)
			(end -1.7653 0.7747)
			(stroke
				(width 0.508)
				(type default)
			)
			(layer "F.SilkS")
		)
		(fp_line
			(start 1.4351 0.7747)
			(end -1.4351 0.7747)
			(stroke
				(width 0.1524)
				(type default)
			)
			(layer "F.SilkS")
		)
		(fp_line
			(start -1.4351 0.7747)
			(end -1.4351 -0.7747)
			(stroke
				(width 0.1524)
				(type default)
			)
			(layer "F.SilkS")
		)
		(fp_rect
			(start -2.0193 1.0287)
			(end 1.6891 -1.0287)
			(stroke
				(width 0)
				(type default)
			)
			(fill no)
			(layer "F.CrtYd")
		)
		(fp_poly
			(pts
				(xy -2.0193 -1.0287) (xy -2.0193 1.0287) (xy 1.6891 1.0287) (xy 1.6891 -1.0287)
			)
			(stroke
				(width 0)
				(type default)
			)
			(fill no)
			(layer "F.Fab")
		)
		(pad "1" smd rect
			(at -0.7112 0 90)
			(size 0.9398 1.0668)
			(layers "F.Cu" "F.Mask" "F.Paste")
			(net "DEBUG CONSOLE_LED_0")
		)
		(pad "2" smd rect
			(at 0.7112 0 90)
			(size 0.9398 1.0668)
			(layers "F.Cu" "F.Mask" "F.Paste")
			(net "CONSOLE_LED_0")
		)
	)
	(footprint ""
		(layer "F.Cu")
		(at 262.944864 -224.654872 -90)
		(property "Reference" "PU6"
			(at 0 0 270)
			(layer "F.SilkS")
			(hide yes)
			(effects
				(font
					(size 1.27 1.27)
				)
			)
		)
		(property "Value" "TPS74801RGW-GP"
			(at -4.7244 -6.223 270)
			(unlocked yes)
			(layer "F.Fab")
			(hide yes)
			(effects
				(font
					(size 1.016 1.016)
					(thickness 0.1524)
				)
			)
		)
		(property "Device Type" "QFN20-1G3D15H40"
			(at -4.7244 -7.747 270)
			(unlocked yes)
			(layer "F.Fab")
			(hide yes)
			(effects
				(font
					(size 1.016 1.016)
					(thickness 0.1524)
				)
			)
		)
		(duplicate_pad_numbers_are_jumpers no)
		(fp_line
			(start -3.5179 3.5179)
			(end -2.2479 3.5179)
			(stroke
				(width 0.1524)
				(type default)
			)
			(layer "F.SilkS")
		)
		(fp_line
			(start 2.2479 3.5179)
			(end 3.5179 3.5179)
			(stroke
				(width 0.1524)
				(type default)
			)
			(layer "F.SilkS")
		)
		(fp_line
			(start 3.5179 3.5179)
			(end 3.5179 2.2479)
			(stroke
				(width 0.1524)
				(type default)
			)
			(layer "F.SilkS")
		)
		(fp_line
			(start 1.299972 3.160522)
			(end 1.299972 3.668522)
			(stroke
				(width 0.1524)
				(type default)
			)
			(layer "F.SilkS")
		)
		(fp_line
			(start -3.5179 2.2479)
			(end -3.5179 3.5179)
			(stroke
				(width 0.1524)
				(type default)
			)
			(layer "F.SilkS")
		)
		(fp_line
			(start -3.160522 1.299972)
			(end -3.922522 1.299972)
			(stroke
				(width 0.1524)
				(type default)
			)
			(layer "F.SilkS")
		)
		(fp_line
			(start 3.160522 -1.299972)
			(end 3.922522 -1.299972)
			(stroke
				(width 0.1524)
				(type default)
			)
			(layer "F.SilkS")
		)
		(fp_line
			(start -1.299972 -3.160522)
			(end -1.299972 -3.668522)
			(stroke
				(width 0.1524)
				(type default)
			)
			(layer "F.SilkS")
		)
		(fp_line
			(start -3.5179 -3.5179)
			(end -3.5179 -2.2479)
			(stroke
				(width 0.1524)
				(type default)
			)
			(layer "F.SilkS")
		)
		(fp_line
			(start -2.2479 -3.5179)
			(end -3.5179 -3.5179)
			(stroke
				(width 0.1524)
				(type default)
			)
			(layer "F.SilkS")
		)
		(fp_poly
			(pts
				(xy 3.5179 -3.5179) (xy 2.2479 -3.5179) (xy 3.5179 -2.2479)
			)
			(stroke
				(width 0)
				(type default)
			)
			(fill yes)
			(layer "F.SilkS")
		)
		(fp_rect
			(start -2.5019 2.5019)
			(end 2.5019 -2.5019)
			(stroke
				(width 0)
				(type default)
			)
			(fill no)
			(layer "F.CrtYd")
		)
		(fp_poly
			(pts
				(xy -3.5179 3.5179) (xy -3.5179 -3.5179) (xy 3.5179 -3.5179) (xy 3.5179 -2.5019) (xy -2.5019 -2.5019)
				(xy -2.5019 2.5019) (xy 2.5019 2.5019) (xy 2.5019 -2.49682) (xy 3.5179 -2.49682) (xy 3.5179 3.5179)
			)
			(stroke
				(width 0)
				(type default)
			)
			(fill no)
			(layer "F.CrtYd")
		)
		(fp_rect
			(start -3.5179 3.5179)
			(end 3.5179 -3.5179)
			(stroke
				(width 0)
				(type default)
			)
			(fill no)
			(layer "F.Fab")
		)
		(pad "1" smd rect
			(at 1.299972 -2.474722 270)
			(size 0.3556 1.0668)
			(layers "F.Cu" "F.Mask" "F.Paste")
			(net "TPS74801_1V26_STBY_OUT")
		)
		(pad "2" smd rect
			(at 0.649986 -2.474722 270)
			(size 0.3556 1.0668)
			(layers "F.Cu" "F.Mask" "F.Paste")
			(net "GND")
		)
		(pad "3" smd rect
			(at 0 -2.474722 270)
			(size 0.3556 1.0668)
			(layers "F.Cu" "F.Mask" "F.Paste")
			(net "GND")
		)
		(pad "4" smd rect
			(at -0.649986 -2.474722 270)
			(size 0.3556 1.0668)
			(layers "F.Cu" "F.Mask" "F.Paste")
			(net "GND")
		)
		(pad "5" smd rect
			(at -1.299972 -2.474722 270)
			(size 0.3556 1.0668)
			(layers "F.Cu" "F.Mask" "F.Paste")
			(net "TPS74801_P1V26_STBY_IN")
		)
		(pad "6" smd rect
			(at -2.474722 -1.299972 270)
			(size 1.0668 0.3556)
			(layers "F.Cu" "F.Mask" "F.Paste")
			(net "TPS74801_P1V26_STBY_IN")
		)
		(pad "7" smd rect
			(at -2.474722 -0.649986 270)
			(size 1.0668 0.3556)
			(layers "F.Cu" "F.Mask" "F.Paste")
			(net "TPS74801_P1V26_STBY_IN")
		)
		(pad "8" smd rect
			(at -2.474722 0 270)
			(size 1.0668 0.3556)
			(layers "F.Cu" "F.Mask" "F.Paste")
			(net "TPS74801_P1V26_STBY_IN")
		)
		(pad "9" smd rect
			(at -2.474722 0.649986 270)
			(size 1.0668 0.3556)
			(layers "F.Cu" "F.Mask" "F.Paste")
			(net "P1V26_STBY_PG")
		)
		(pad "10" smd rect
			(at -2.474722 1.299972 270)
			(size 1.0668 0.3556)
			(layers "F.Cu" "F.Mask" "F.Paste")
			(net "TPS74801_1V26_STBY_BIAS")
		)
		(pad "11" smd rect
			(at -1.299972 2.474722 270)
			(size 0.3556 1.0668)
			(layers "F.Cu" "F.Mask" "F.Paste")
			(net "TPS74801_1V26_STBY_EN")
		)
		(pad "12" smd rect
			(at -0.649986 2.474722 270)
			(size 0.3556 1.0668)
			(layers "F.Cu" "F.Mask" "F.Paste")
			(net "GND")
		)
		(pad "13" smd rect
			(at 0 2.474722 270)
			(size 0.3556 1.0668)
			(layers "F.Cu" "F.Mask" "F.Paste")
			(net "GND")
		)
		(pad "14" smd rect
			(at 0.649986 2.474722 270)
			(size 0.3556 1.0668)
			(layers "F.Cu" "F.Mask" "F.Paste")
			(net "GND")
		)
		(pad "15" smd rect
			(at 1.299972 2.474722 270)
			(size 0.3556 1.0668)
			(layers "F.Cu" "F.Mask" "F.Paste")
			(net "TPS74801_1V26_STBY_SS")
		)
		(pad "16" smd rect
			(at 2.474722 1.299972 270)
			(size 1.0668 0.3556)
			(layers "F.Cu" "F.Mask" "F.Paste")
			(net "TPS74801_1V26_STBY_FB")
		)
		(pad "17" smd rect
			(at 2.474722 0.649986 270)
			(size 1.0668 0.3556)
			(layers "F.Cu" "F.Mask" "F.Paste")
			(net "GND")
		)
		(pad "18" smd rect
			(at 2.474722 0 270)
			(size 1.0668 0.3556)
			(layers "F.Cu" "F.Mask" "F.Paste")
			(net "TPS74801_1V26_STBY_OUT")
		)
		(pad "19" smd rect
			(at 2.474722 -0.649986 270)
			(size 1.0668 0.3556)
			(layers "F.Cu" "F.Mask" "F.Paste")
			(net "TPS74801_1V26_STBY_OUT")
		)
		(pad "20" smd rect
			(at 2.474722 -1.299972 270)
			(size 1.0668 0.3556)
			(layers "F.Cu" "F.Mask" "F.Paste")
			(net "TPS74801_1V26_STBY_OUT")
		)
		(pad "21" smd rect
			(at 0 0 270)
			(size 3.2512 3.2512)
			(layers "F.Cu" "F.Mask" "F.Paste")
			(net "GND")
		)
	)
	(footprint ""
		(layer "F.Cu")
		(at 220.976698 -21.876004 180)
		(property "Reference" "Q6"
			(at 0 0 180)
			(layer "F.SilkS")
			(hide yes)
			(effects
				(font
					(size 1.27 1.27)
				)
			)
		)
		(property "Value" "2N7002A-7-GP"
			(at 0.127 -8.9662 180)
			(unlocked yes)
			(layer "F.Fab")
			(hide yes)
			(effects
				(font
					(size 1.016 1.016)
					(thickness 0.1524)
				)
			)
		)
		(property "Device Type" "SOT23DGS2D4H48"
			(at 0.127 -10.4902 180)
			(unlocked yes)
			(layer "F.Fab")
			(hide yes)
			(effects
				(font
					(size 1.016 1.016)
					(thickness 0.1524)
				)
			)
		)
		(duplicate_pad_numbers_are_jumpers no)
		(fp_line
			(start 1.651 1.778)
			(end 1.651 -1.778)
			(stroke
				(width 0.1524)
				(type default)
			)
			(layer "F.SilkS")
		)
		(fp_line
			(start 1.651 -1.778)
			(end -1.651 -1.778)
			(stroke
				(width 0.1524)
				(type default)
			)
			(layer "F.SilkS")
		)
		(fp_line
			(start -1.651 1.778)
			(end 1.651 1.778)
			(stroke
				(width 0.1524)
				(type default)
			)
			(layer "F.SilkS")
		)
		(fp_line
			(start -1.651 -1.778)
			(end -1.651 1.778)
			(stroke
				(width 0.1524)
				(type default)
			)
			(layer "F.SilkS")
		)
		(fp_poly
			(pts
				(xy -1.778 1.8796) (xy -1.778 -1.8796) (xy 1.778 -1.8796) (xy 1.778 1.8796)
			)
			(stroke
				(width 0)
				(type default)
			)
			(fill no)
			(layer "F.CrtYd")
		)
		(fp_poly
			(pts
				(xy -1.778 1.8796) (xy -1.778 -1.8796) (xy 1.778 -1.8796) (xy 1.778 1.8796)
			)
			(stroke
				(width 0)
				(type default)
			)
			(fill no)
			(layer "F.Fab")
		)
		(pad "D" smd custom
			(at 0 -0.9525 180)
			(size 0.1905 0.1905)
			(layers "F.Cu" "F.Mask" "F.Paste")
			(net "LED_PWR_N_ON")
			(options
				(clearance outline)
				(anchor circle)
			)
			(primitives
				(gr_poly
					(pts
						(arc
							(start -0.1778 0.5715)
							(mid -0.321484 0.511984)
							(end -0.381 0.3683)
						)
						(arc
							(start -0.381 -0.3683)
							(mid -0.321484 -0.511984)
							(end -0.1778 -0.5715)
						)
						(arc
							(start 0.1778 -0.5715)
							(mid 0.321484 -0.511984)
							(end 0.381 -0.3683)
						)
						(arc
							(start 0.381 0.3683)
							(mid 0.321484 0.511984)
							(end 0.1778 0.5715)
						)
					)
					(width 0)
					(fill yes)
				)
			)
		)
		(pad "G" smd custom
			(at -0.98425 0.9525 180)
			(size 0.1905 0.1905)
			(layers "F.Cu" "F.Mask" "F.Paste")
			(net "BMC_ID_LED_R")
			(options
				(clearance outline)
				(anchor circle)
			)
			(primitives
				(gr_poly
					(pts
						(arc
							(start -0.1778 0.5715)
							(mid -0.321484 0.511984)
							(end -0.381 0.3683)
						)
						(arc
							(start -0.381 -0.3683)
							(mid -0.321484 -0.511984)
							(end -0.1778 -0.5715)
						)
						(arc
							(start 0.1778 -0.5715)
							(mid 0.321484 -0.511984)
							(end 0.381 -0.3683)
						)
						(arc
							(start 0.381 0.3683)
							(mid 0.321484 0.511984)
							(end 0.1778 0.5715)
						)
					)
					(width 0)
					(fill yes)
				)
			)
		)
		(pad "S" smd custom
			(at 0.98425 0.9525 180)
			(size 0.1905 0.1905)
			(layers "F.Cu" "F.Mask" "F.Paste")
			(net "GND")
			(options
				(clearance outline)
				(anchor circle)
			)
			(primitives
				(gr_poly
					(pts
						(arc
							(start -0.1778 0.5715)
							(mid -0.321484 0.511984)
							(end -0.381 0.3683)
						)
						(arc
							(start -0.381 -0.3683)
							(mid -0.321484 -0.511984)
							(end -0.1778 -0.5715)
						)
						(arc
							(start 0.1778 -0.5715)
							(mid 0.321484 -0.511984)
							(end 0.381 -0.3683)
						)
						(arc
							(start 0.381 0.3683)
							(mid 0.321484 0.511984)
							(end 0.1778 0.5715)
						)
					)
					(width 0)
					(fill yes)
				)
			)
		)
	)
	(footprint ""
		(layer "F.Cu")
		(at 183.134 -49.149 90)
		(property "Reference" "R490"
			(at 0 0 90)
			(layer "F.SilkS")
			(hide yes)
			(effects
				(font
					(size 1.27 1.27)
				)
			)
		)
		(property "Value" "4K7R2F-GP"
			(at 0.064008 -3.993896 90)
			(unlocked yes)
			(layer "F.Fab")
			(hide yes)
			(effects
				(font
					(size 1.016 1.016)
					(thickness 0.1524)
				)
			)
		)
		(property "Device Type" "R402H16"
			(at 0.064008 -5.517896 90)
			(unlocked yes)
			(layer "F.Fab")
			(hide yes)
			(effects
				(font
					(size 1.016 1.016)
					(thickness 0.1524)
				)
			)
		)
		(duplicate_pad_numbers_are_jumpers no)
		(fp_line
			(start 0.508 -0.9398)
			(end -0.508 -0.9398)
			(stroke
				(width 0.1524)
				(type default)
			)
			(layer "F.SilkS")
		)
		(fp_line
			(start -0.508 -0.9398)
			(end -0.508 0.9398)
			(stroke
				(width 0.1524)
				(type default)
			)
			(layer "F.SilkS")
		)
		(fp_rect
			(start -0.508 0.9398)
			(end 0.508 -0.9398)
			(stroke
				(width 0)
				(type default)
			)
			(fill no)
			(layer "F.CrtYd")
		)
		(fp_rect
			(start -0.508 0.9398)
			(end 0.508 -0.9398)
			(stroke
				(width 0)
				(type default)
			)
			(fill no)
			(layer "F.Fab")
		)
		(pad "1" smd custom
			(at 0 -0.4445 90)
			(size 0.1397 0.1397)
			(layers "F.Cu" "F.Mask" "F.Paste")
			(net "P3V3_STBY")
			(options
				(clearance outline)
				(anchor circle)
			)
			(primitives
				(gr_poly
					(pts
						(arc
							(start -0.1778 -0.2794)
							(mid -0.249642 -0.249642)
							(end -0.2794 -0.1778)
						)
						(arc
							(start -0.2794 0.1778)
							(mid -0.249642 0.249642)
							(end -0.1778 0.2794)
						)
						(arc
							(start 0.1778 0.2794)
							(mid 0.249642 0.249642)
							(end 0.2794 0.1778)
						)
						(arc
							(start 0.2794 -0.1778)
							(mid 0.249642 -0.249642)
							(end 0.1778 -0.2794)
						)
					)
					(width 0)
					(fill yes)
				)
			)
		)
		(pad "2" smd custom
			(at 0 0.4445 90)
			(size 0.1397 0.1397)
			(layers "F.Cu" "F.Mask" "F.Paste")
			(net "PRSNT_AND_2")
			(options
				(clearance outline)
				(anchor circle)
			)
			(primitives
				(gr_poly
					(pts
						(arc
							(start -0.1778 -0.2794)
							(mid -0.249642 -0.249642)
							(end -0.2794 -0.1778)
						)
						(arc
							(start -0.2794 0.1778)
							(mid -0.249642 0.249642)
							(end -0.1778 0.2794)
						)
						(arc
							(start 0.1778 0.2794)
							(mid 0.249642 0.249642)
							(end 0.2794 0.1778)
						)
						(arc
							(start 0.2794 -0.1778)
							(mid 0.249642 -0.249642)
							(end 0.1778 -0.2794)
						)
					)
					(width 0)
					(fill yes)
				)
			)
		)
	)
	(footprint ""
		(layer "F.Cu")
		(at 292.481 -159.639)
		(property "Reference" "R617"
			(at 0 0 0)
			(layer "F.SilkS")
			(hide yes)
			(effects
				(font
					(size 1.27 1.27)
				)
			)
		)
		(property "Value" "0R2J-2-GP"
			(at 0.064008 -3.993896 0)
			(unlocked yes)
			(layer "F.Fab")
			(hide yes)
			(effects
				(font
					(size 1.016 1.016)
					(thickness 0.1524)
				)
			)
		)
		(property "Device Type" "R402H16"
			(at 0.064008 -5.517896 0)
			(unlocked yes)
			(layer "F.Fab")
			(hide yes)
			(effects
				(font
					(size 1.016 1.016)
					(thickness 0.1524)
				)
			)
		)
		(duplicate_pad_numbers_are_jumpers no)
		(fp_line
			(start -0.508 -0.9398)
			(end -0.508 0.9398)
			(stroke
				(width 0.1524)
				(type default)
			)
			(layer "F.SilkS")
		)
		(fp_line
			(start 0.508 -0.9398)
			(end -0.508 -0.9398)
			(stroke
				(width 0.1524)
				(type default)
			)
			(layer "F.SilkS")
		)
		(fp_rect
			(start -0.508 0.9398)
			(end 0.508 -0.9398)
			(stroke
				(width 0)
				(type default)
			)
			(fill no)
			(layer "F.CrtYd")
		)
		(fp_rect
			(start -0.508 0.9398)
			(end 0.508 -0.9398)
			(stroke
				(width 0)
				(type default)
			)
			(fill no)
			(layer "F.Fab")
		)
		(pad "1" smd custom
			(at 0 -0.4445)
			(size 0.1397 0.1397)
			(layers "F.Cu" "F.Mask" "F.Paste")
			(net "BMC_HDD_PRE_INT_N")
			(options
				(clearance outline)
				(anchor circle)
			)
			(primitives
				(gr_poly
					(pts
						(arc
							(start -0.1778 -0.2794)
							(mid -0.249642 -0.249642)
							(end -0.2794 -0.1778)
						)
						(arc
							(start -0.2794 0.1778)
							(mid -0.249642 0.249642)
							(end -0.1778 0.2794)
						)
						(arc
							(start 0.1778 0.2794)
							(mid 0.249642 0.249642)
							(end 0.2794 0.1778)
						)
						(arc
							(start 0.2794 -0.1778)
							(mid 0.249642 -0.249642)
							(end 0.1778 -0.2794)
						)
					)
					(width 0)
					(fill yes)
				)
			)
		)
		(pad "2" smd custom
			(at 0 0.4445)
			(size 0.1397 0.1397)
			(layers "F.Cu" "F.Mask" "F.Paste")
			(net "HDD_PRE_IO_INT_N")
			(options
				(clearance outline)
				(anchor circle)
			)
			(primitives
				(gr_poly
					(pts
						(arc
							(start -0.1778 -0.2794)
							(mid -0.249642 -0.249642)
							(end -0.2794 -0.1778)
						)
						(arc
							(start -0.2794 0.1778)
							(mid -0.249642 0.249642)
							(end -0.1778 0.2794)
						)
						(arc
							(start 0.1778 0.2794)
							(mid 0.249642 0.249642)
							(end 0.2794 0.1778)
						)
						(arc
							(start 0.2794 -0.1778)
							(mid 0.249642 -0.249642)
							(end 0.1778 -0.2794)
						)
					)
					(width 0)
					(fill yes)
				)
			)
		)
	)
	(footprint ""
		(layer "F.Cu")
		(at 336.071718 -157.584648 180)
		(property "Reference" "R7899"
			(at 0 0 180)
			(layer "F.SilkS")
			(hide yes)
			(effects
				(font
					(size 1.27 1.27)
				)
			)
		)
		(property "Value" "4K7R2F-GP"
			(at 0.064008 -3.993896 180)
			(unlocked yes)
			(layer "F.Fab")
			(hide yes)
			(effects
				(font
					(size 1.016 1.016)
					(thickness 0.1524)
				)
			)
		)
		(property "Device Type" "R402H16"
			(at 0.064008 -5.517896 180)
			(unlocked yes)
			(layer "F.Fab")
			(hide yes)
			(effects
				(font
					(size 1.016 1.016)
					(thickness 0.1524)
				)
			)
		)
		(duplicate_pad_numbers_are_jumpers no)
		(fp_line
			(start 0.508 -0.9398)
			(end -0.508 -0.9398)
			(stroke
				(width 0.1524)
				(type default)
			)
			(layer "F.SilkS")
		)
		(fp_line
			(start -0.508 -0.9398)
			(end -0.508 0.9398)
			(stroke
				(width 0.1524)
				(type default)
			)
			(layer "F.SilkS")
		)
		(fp_rect
			(start -0.508 0.9398)
			(end 0.508 -0.9398)
			(stroke
				(width 0)
				(type default)
			)
			(fill no)
			(layer "F.CrtYd")
		)
		(fp_rect
			(start -0.508 0.9398)
			(end 0.508 -0.9398)
			(stroke
				(width 0)
				(type default)
			)
			(fill no)
			(layer "F.Fab")
		)
		(pad "1" smd custom
			(at 0 -0.4445 180)
			(size 0.1397 0.1397)
			(layers "F.Cu" "F.Mask" "F.Paste")
			(net "USB_EN_3")
			(options
				(clearance outline)
				(anchor circle)
			)
			(primitives
				(gr_poly
					(pts
						(arc
							(start -0.1778 -0.2794)
							(mid -0.249642 -0.249642)
							(end -0.2794 -0.1778)
						)
						(arc
							(start -0.2794 0.1778)
							(mid -0.249642 0.249642)
							(end -0.1778 0.2794)
						)
						(arc
							(start 0.1778 0.2794)
							(mid 0.249642 0.249642)
							(end 0.2794 0.1778)
						)
						(arc
							(start 0.2794 -0.1778)
							(mid 0.249642 -0.249642)
							(end 0.1778 -0.2794)
						)
					)
					(width 0)
					(fill yes)
				)
			)
		)
		(pad "2" smd custom
			(at 0 0.4445 180)
			(size 0.1397 0.1397)
			(layers "F.Cu" "F.Mask" "F.Paste")
			(net "GND")
			(options
				(clearance outline)
				(anchor circle)
			)
			(primitives
				(gr_poly
					(pts
						(arc
							(start -0.1778 -0.2794)
							(mid -0.249642 -0.249642)
							(end -0.2794 -0.1778)
						)
						(arc
							(start -0.2794 0.1778)
							(mid -0.249642 0.249642)
							(end -0.1778 0.2794)
						)
						(arc
							(start 0.1778 0.2794)
							(mid 0.249642 0.249642)
							(end 0.2794 0.1778)
						)
						(arc
							(start 0.2794 -0.1778)
							(mid 0.249642 -0.249642)
							(end 0.1778 -0.2794)
						)
					)
					(width 0)
					(fill yes)
				)
			)
		)
	)
	(footprint ""
		(layer "F.Cu")
		(at 58.928 -211.074)
		(property "Reference" "PR9004"
			(at 0 0 0)
			(layer "F.SilkS")
			(hide yes)
			(effects
				(font
					(size 1.27 1.27)
				)
			)
		)
		(property "Value" "0R2J-2-GP"
			(at 0.064008 -3.993896 0)
			(unlocked yes)
			(layer "F.Fab")
			(hide yes)
			(effects
				(font
					(size 1.016 1.016)
					(thickness 0.1524)
				)
			)
		)
		(property "Device Type" "R402H16"
			(at 0.064008 -5.517896 0)
			(unlocked yes)
			(layer "F.Fab")
			(hide yes)
			(effects
				(font
					(size 1.016 1.016)
					(thickness 0.1524)
				)
			)
		)
		(duplicate_pad_numbers_are_jumpers no)
		(fp_line
			(start -0.508 -0.9398)
			(end -0.508 0.9398)
			(stroke
				(width 0.1524)
				(type default)
			)
			(layer "F.SilkS")
		)
		(fp_line
			(start 0.508 -0.9398)
			(end -0.508 -0.9398)
			(stroke
				(width 0.1524)
				(type default)
			)
			(layer "F.SilkS")
		)
		(fp_rect
			(start -0.508 0.9398)
			(end 0.508 -0.9398)
			(stroke
				(width 0)
				(type default)
			)
			(fill no)
			(layer "F.CrtYd")
		)
		(fp_rect
			(start -0.508 0.9398)
			(end 0.508 -0.9398)
			(stroke
				(width 0)
				(type default)
			)
			(fill no)
			(layer "F.Fab")
		)
		(pad "1" smd custom
			(at 0 -0.4445)
			(size 0.1397 0.1397)
			(layers "F.Cu" "F.Mask" "F.Paste")
			(net "HSW_SCL_2")
			(options
				(clearance outline)
				(anchor circle)
			)
			(primitives
				(gr_poly
					(pts
						(arc
							(start -0.1778 -0.2794)
							(mid -0.249642 -0.249642)
							(end -0.2794 -0.1778)
						)
						(arc
							(start -0.2794 0.1778)
							(mid -0.249642 0.249642)
							(end -0.1778 0.2794)
						)
						(arc
							(start 0.1778 0.2794)
							(mid 0.249642 0.249642)
							(end 0.2794 0.1778)
						)
						(arc
							(start 0.2794 -0.1778)
							(mid 0.249642 -0.249642)
							(end 0.1778 -0.2794)
						)
					)
					(width 0)
					(fill yes)
				)
			)
		)
		(pad "2" smd custom
			(at 0 0.4445)
			(size 0.1397 0.1397)
			(layers "F.Cu" "F.Mask" "F.Paste")
			(net "BMC_I2C_A_SCL")
			(options
				(clearance outline)
				(anchor circle)
			)
			(primitives
				(gr_poly
					(pts
						(arc
							(start -0.1778 -0.2794)
							(mid -0.249642 -0.249642)
							(end -0.2794 -0.1778)
						)
						(arc
							(start -0.2794 0.1778)
							(mid -0.249642 0.249642)
							(end -0.1778 0.2794)
						)
						(arc
							(start 0.1778 0.2794)
							(mid 0.249642 0.249642)
							(end 0.2794 0.1778)
						)
						(arc
							(start 0.2794 -0.1778)
							(mid 0.249642 -0.249642)
							(end 0.1778 -0.2794)
						)
					)
					(width 0)
					(fill yes)
				)
			)
		)
	)
	(footprint ""
		(layer "F.Cu")
		(at 280.289 -200.914)
		(property "Reference" "L5"
			(at 0 0 0)
			(layer "F.SilkS")
			(hide yes)
			(effects
				(font
					(size 1.27 1.27)
				)
			)
		)
		(property "Value" "MMZ2012S601ATA1N-GP"
			(at 0 -4.2418 0)
			(unlocked yes)
			(layer "F.Fab")
			(hide yes)
			(effects
				(font
					(size 1.016 1.016)
					(thickness 0.1524)
				)
			)
		)
		(property "Device Type" "L805H42"
			(at 0 -5.7912 0)
			(unlocked yes)
			(layer "F.Fab")
			(hide yes)
			(effects
				(font
					(size 1.016 1.016)
					(thickness 0.1524)
				)
			)
		)
		(duplicate_pad_numbers_are_jumpers no)
		(fp_line
			(start -0.889 -1.7018)
			(end 0.889 -1.7018)
			(stroke
				(width 0.1524)
				(type default)
			)
			(layer "F.SilkS")
		)
		(fp_line
			(start -0.889 1.7018)
			(end -0.889 -1.7018)
			(stroke
				(width 0.1524)
				(type default)
			)
			(layer "F.SilkS")
		)
		(fp_line
			(start 0.889 -1.7018)
			(end 0.889 1.7018)
			(stroke
				(width 0.1524)
				(type default)
			)
			(layer "F.SilkS")
		)
		(fp_line
			(start 0.889 1.7018)
			(end -0.889 1.7018)
			(stroke
				(width 0.1524)
				(type default)
			)
			(layer "F.SilkS")
		)
		(fp_rect
			(start -0.9652 1.778)
			(end 0.9652 -1.778)
			(stroke
				(width 0)
				(type default)
			)
			(fill no)
			(layer "F.CrtYd")
		)
		(fp_rect
			(start -0.9652 1.778)
			(end 0.9652 -1.778)
			(stroke
				(width 0)
				(type default)
			)
			(fill no)
			(layer "F.Fab")
		)
		(pad "1" smd rect
			(at 0 -0.9652)
			(size 1.397 1.143)
			(layers "F.Cu" "F.Mask" "F.Paste")
			(net "P3V3_STBY")
		)
		(pad "2" smd rect
			(at 0 0.9652)
			(size 1.397 1.143)
			(layers "F.Cu" "F.Mask" "F.Paste")
			(net "MPLLAV33")
		)
	)
	(footprint ""
		(layer "F.Cu")
		(at 268.351 -222.123 90)
		(property "Reference" "PC94"
			(at 0 0 90)
			(layer "F.SilkS")
			(hide yes)
			(effects
				(font
					(size 1.27 1.27)
				)
			)
		)
		(property "Value" "SC10U6D3V5KX-1GP"
			(at -0.0762 -6.1214 90)
			(unlocked yes)
			(layer "F.Fab")
			(hide yes)
			(effects
				(font
					(size 1.016 1.016)
					(thickness 0.1524)
				)
			)
		)
		(property "Device Type" "C805H54"
			(at -0.0762 -8.1534 90)
			(unlocked yes)
			(layer "F.Fab")
			(hide yes)
			(effects
				(font
					(size 1.016 1.016)
					(thickness 0.1524)
				)
			)
		)
		(duplicate_pad_numbers_are_jumpers no)
		(fp_line
			(start 0.635 0)
			(end -0.635 0)
			(stroke
				(width 0.508)
				(type default)
			)
			(layer "F.SilkS")
		)
		(fp_rect
			(start -0.9652 1.778)
			(end 0.9652 -1.778)
			(stroke
				(width 0)
				(type default)
			)
			(fill no)
			(layer "F.CrtYd")
		)
		(fp_poly
			(pts
				(xy -0.9652 -1.778) (xy 0.9652 -1.778) (xy 0.9652 1.778) (xy -0.9652 1.778)
			)
			(stroke
				(width 0)
				(type default)
			)
			(fill no)
			(layer "F.Fab")
		)
		(pad "1" smd rect
			(at 0 -0.9652 90)
			(size 1.397 1.143)
			(layers "F.Cu" "F.Mask" "F.Paste")
			(net "TPS74801_1V26_STBY_OUT")
		)
		(pad "2" smd rect
			(at 0 0.9652 90)
			(size 1.397 1.143)
			(layers "F.Cu" "F.Mask" "F.Paste")
			(net "GND")
		)
	)
	(footprint ""
		(layer "F.Cu")
		(at 262.89 -44.958)
		(property "Reference" "PR51"
			(at 0 0 0)
			(layer "F.SilkS")
			(hide yes)
			(effects
				(font
					(size 1.27 1.27)
				)
			)
		)
		(property "Value" "73K2R2F-GP"
			(at 0.064008 -3.993896 0)
			(unlocked yes)
			(layer "F.Fab")
			(hide yes)
			(effects
				(font
					(size 1.016 1.016)
					(thickness 0.1524)
				)
			)
		)
		(property "Device Type" "R402H16"
			(at 0.064008 -5.517896 0)
			(unlocked yes)
			(layer "F.Fab")
			(hide yes)
			(effects
				(font
					(size 1.016 1.016)
					(thickness 0.1524)
				)
			)
		)
		(duplicate_pad_numbers_are_jumpers no)
		(fp_line
			(start -0.508 -0.9398)
			(end -0.508 0.9398)
			(stroke
				(width 0.1524)
				(type default)
			)
			(layer "F.SilkS")
		)
		(fp_line
			(start 0.508 -0.9398)
			(end -0.508 -0.9398)
			(stroke
				(width 0.1524)
				(type default)
			)
			(layer "F.SilkS")
		)
		(fp_rect
			(start -0.508 0.9398)
			(end 0.508 -0.9398)
			(stroke
				(width 0)
				(type default)
			)
			(fill no)
			(layer "F.CrtYd")
		)
		(fp_rect
			(start -0.508 0.9398)
			(end 0.508 -0.9398)
			(stroke
				(width 0)
				(type default)
			)
			(fill no)
			(layer "F.Fab")
		)
		(pad "1" smd custom
			(at 0 -0.4445)
			(size 0.1397 0.1397)
			(layers "F.Cu" "F.Mask" "F.Paste")
			(net "AGND_P1V8_STBY")
			(options
				(clearance outline)
				(anchor circle)
			)
			(primitives
				(gr_poly
					(pts
						(arc
							(start -0.1778 -0.2794)
							(mid -0.249642 -0.249642)
							(end -0.2794 -0.1778)
						)
						(arc
							(start -0.2794 0.1778)
							(mid -0.249642 0.249642)
							(end -0.1778 0.2794)
						)
						(arc
							(start 0.1778 0.2794)
							(mid 0.249642 0.249642)
							(end 0.2794 0.1778)
						)
						(arc
							(start 0.2794 -0.1778)
							(mid 0.249642 -0.249642)
							(end 0.1778 -0.2794)
						)
					)
					(width 0)
					(fill yes)
				)
			)
		)
		(pad "2" smd custom
			(at 0 0.4445)
			(size 0.1397 0.1397)
			(layers "F.Cu" "F.Mask" "F.Paste")
			(net "P1V8_STBY_TRIP")
			(options
				(clearance outline)
				(anchor circle)
			)
			(primitives
				(gr_poly
					(pts
						(arc
							(start -0.1778 -0.2794)
							(mid -0.249642 -0.249642)
							(end -0.2794 -0.1778)
						)
						(arc
							(start -0.2794 0.1778)
							(mid -0.249642 0.249642)
							(end -0.1778 0.2794)
						)
						(arc
							(start 0.1778 0.2794)
							(mid 0.249642 0.249642)
							(end 0.2794 0.1778)
						)
						(arc
							(start 0.2794 -0.1778)
							(mid 0.249642 -0.249642)
							(end 0.1778 -0.2794)
						)
					)
					(width 0)
					(fill yes)
				)
			)
		)
	)
	(footprint ""
		(layer "F.Cu")
		(at 179.451 -218.821)
		(property "Reference" "C41"
			(at 0 0 0)
			(layer "F.SilkS")
			(hide yes)
			(effects
				(font
					(size 1.27 1.27)
				)
			)
		)
		(property "Value" "SCD1U16V2KX-3GP"
			(at 1.1811 -2.7051 0)
			(unlocked yes)
			(layer "F.Fab")
			(hide yes)
			(effects
				(font
					(size 1.016 1.016)
					(thickness 0.1524)
				)
			)
		)
		(property "Device Type" "C402H22"
			(at 1.1811 -4.2291 0)
			(unlocked yes)
			(layer "F.Fab")
			(hide yes)
			(effects
				(font
					(size 1.016 1.016)
					(thickness 0.1524)
				)
			)
		)
		(duplicate_pad_numbers_are_jumpers no)
		(fp_rect
			(start -0.4318 0.9525)
			(end 0.4318 -0.9525)
			(stroke
				(width 0)
				(type default)
			)
			(fill no)
			(layer "F.CrtYd")
		)
		(fp_rect
			(start -0.4318 0.9525)
			(end 0.4318 -0.9525)
			(stroke
				(width 0)
				(type default)
			)
			(fill no)
			(layer "F.Fab")
		)
		(pad "1" smd custom
			(at 0 -0.4445)
			(size 0.1524 0.1524)
			(layers "F.Cu" "F.Mask" "F.Paste")
			(net "P3V3_STBY")
			(options
				(clearance outline)
				(anchor circle)
			)
			(primitives
				(gr_poly
					(pts
						(arc
							(start 0.3048 -0.2032)
							(mid 0.275042 -0.275042)
							(end 0.2032 -0.3048)
						)
						(arc
							(start -0.2032 -0.3048)
							(mid -0.275042 -0.275042)
							(end -0.3048 -0.2032)
						)
						(arc
							(start -0.3048 0.2032)
							(mid -0.275042 0.275042)
							(end -0.2032 0.3048)
						)
						(arc
							(start 0.2032 0.3048)
							(mid 0.275042 0.275042)
							(end 0.3048 0.2032)
						)
					)
					(width 0)
					(fill yes)
				)
			)
		)
		(pad "2" smd custom
			(at 0 0.4445)
			(size 0.1524 0.1524)
			(layers "F.Cu" "F.Mask" "F.Paste")
			(net "GND")
			(options
				(clearance outline)
				(anchor circle)
			)
			(primitives
				(gr_poly
					(pts
						(arc
							(start 0.3048 -0.2032)
							(mid 0.275042 -0.275042)
							(end 0.2032 -0.3048)
						)
						(arc
							(start -0.2032 -0.3048)
							(mid -0.275042 -0.275042)
							(end -0.3048 -0.2032)
						)
						(arc
							(start -0.3048 0.2032)
							(mid -0.275042 0.275042)
							(end -0.2032 0.3048)
						)
						(arc
							(start 0.2032 0.3048)
							(mid 0.275042 0.275042)
							(end 0.3048 0.2032)
						)
					)
					(width 0)
					(fill yes)
				)
			)
		)
	)
	(footprint ""
		(layer "F.Cu")
		(at 305.308 -180.086)
		(property "Reference" "TP90"
			(at 0 0 0)
			(layer "F.SilkS")
			(hide yes)
			(effects
				(font
					(size 1.27 1.27)
				)
			)
		)
		(property "Value" "TPAD28"
			(at 0.0127 -1.8034 0)
			(unlocked yes)
			(layer "F.Fab")
			(hide yes)
			(effects
				(font
					(size 1.016 1.016)
					(thickness 0.1524)
				)
			)
		)
		(property "Device Type" "TPAD28"
			(at 0.0127 -3.3274 0)
			(unlocked yes)
			(layer "F.Fab")
			(hide yes)
			(effects
				(font
					(size 1.016 1.016)
					(thickness 0.1524)
				)
			)
		)
		(duplicate_pad_numbers_are_jumpers no)
		(fp_poly
			(pts
				(arc
					(start 0.3556 0)
					(mid -0.3556 0)
					(end 0.3556 0)
				)
			)
			(stroke
				(width 0)
				(type default)
			)
			(fill no)
			(layer "F.CrtYd")
		)
		(fp_poly
			(pts
				(arc
					(start 0.6096 0)
					(mid -0.6096 0)
					(end 0.6096 0)
				)
			)
			(stroke
				(width 0)
				(type default)
			)
			(fill no)
			(layer "F.Fab")
		)
		(pad "1" smd circle
			(at 0 0)
			(size 0.7112 0.7112)
			(layers "F.Cu" "F.Mask" "F.Paste")
			(net "TP_BMC_GPIOL0")
		)
	)
	(footprint ""
		(layer "F.Cu")
		(at 91.32697 -112.014 180)
		(property "Reference" "SC1240"
			(at 0 0 180)
			(layer "F.SilkS")
			(hide yes)
			(effects
				(font
					(size 1.27 1.27)
				)
			)
		)
		(property "Value" "SCD1U6D3V1KX-GP"
			(at -2.8321 -1.7399 180)
			(unlocked yes)
			(layer "F.Fab")
			(hide yes)
			(effects
				(font
					(size 1.016 1.016)
					(thickness 0.1524)
				)
			)
		)
		(property "Device Type" "C0201H13"
			(at -2.8321 -3.2639 180)
			(unlocked yes)
			(layer "F.Fab")
			(hide yes)
			(effects
				(font
					(size 1.016 1.016)
					(thickness 0.1524)
				)
			)
		)
		(duplicate_pad_numbers_are_jumpers no)
		(fp_rect
			(start -0.2794 0.6477)
			(end 0.2794 -0.6477)
			(stroke
				(width 0)
				(type default)
			)
			(fill no)
			(layer "F.CrtYd")
		)
		(fp_rect
			(start -0.2794 0.6477)
			(end 0.2794 -0.6477)
			(stroke
				(width 0)
				(type default)
			)
			(fill no)
			(layer "F.Fab")
		)
		(pad "1" smd custom
			(at 0 -0.2794 180)
			(size 0.0762 0.0762)
			(layers "F.Cu" "F.Mask" "F.Paste")
			(net "P1V8_E")
			(options
				(clearance outline)
				(anchor circle)
			)
			(primitives
				(gr_poly
					(pts
						(arc
							(start 0.1524 -0.127)
							(mid 0.137521 -0.162921)
							(end 0.1016 -0.1778)
						)
						(arc
							(start -0.1016 -0.1778)
							(mid -0.137521 -0.162921)
							(end -0.1524 -0.127)
						)
						(arc
							(start -0.1524 0.127)
							(mid -0.137521 0.162921)
							(end -0.1016 0.1778)
						)
						(arc
							(start 0.1016 0.1778)
							(mid 0.137521 0.162921)
							(end 0.1524 0.127)
						)
					)
					(width 0)
					(fill yes)
				)
			)
		)
		(pad "2" smd custom
			(at 0 0.2794 180)
			(size 0.0762 0.0762)
			(layers "F.Cu" "F.Mask" "F.Paste")
			(net "GND")
			(options
				(clearance outline)
				(anchor circle)
			)
			(primitives
				(gr_poly
					(pts
						(arc
							(start 0.1524 -0.127)
							(mid 0.137521 -0.162921)
							(end 0.1016 -0.1778)
						)
						(arc
							(start -0.1016 -0.1778)
							(mid -0.137521 -0.162921)
							(end -0.1524 -0.127)
						)
						(arc
							(start -0.1524 0.127)
							(mid -0.137521 0.162921)
							(end -0.1016 0.1778)
						)
						(arc
							(start 0.1016 0.1778)
							(mid 0.137521 0.162921)
							(end 0.1524 0.127)
						)
					)
					(width 0)
					(fill yes)
				)
			)
		)
	)
	(footprint ""
		(layer "F.Cu")
		(at 14.047216 -191.06388)
		(property "Reference" "SR271"
			(at 0 0 0)
			(layer "F.SilkS")
			(hide yes)
			(effects
				(font
					(size 1.27 1.27)
				)
			)
		)
		(property "Value" "4K7R2F-GP"
			(at 0.064008 -3.993896 0)
			(unlocked yes)
			(layer "F.Fab")
			(hide yes)
			(effects
				(font
					(size 1.016 1.016)
					(thickness 0.1524)
				)
			)
		)
		(property "Device Type" "R402H16"
			(at 0.064008 -5.517896 0)
			(unlocked yes)
			(layer "F.Fab")
			(hide yes)
			(effects
				(font
					(size 1.016 1.016)
					(thickness 0.1524)
				)
			)
		)
		(duplicate_pad_numbers_are_jumpers no)
		(fp_line
			(start -0.508 -0.9398)
			(end -0.508 0.9398)
			(stroke
				(width 0.1524)
				(type default)
			)
			(layer "F.SilkS")
		)
		(fp_line
			(start 0.508 -0.9398)
			(end -0.508 -0.9398)
			(stroke
				(width 0.1524)
				(type default)
			)
			(layer "F.SilkS")
		)
		(fp_rect
			(start -0.508 0.9398)
			(end 0.508 -0.9398)
			(stroke
				(width 0)
				(type default)
			)
			(fill no)
			(layer "F.CrtYd")
		)
		(fp_rect
			(start -0.508 0.9398)
			(end 0.508 -0.9398)
			(stroke
				(width 0)
				(type default)
			)
			(fill no)
			(layer "F.Fab")
		)
		(pad "1" smd custom
			(at 0 -0.4445)
			(size 0.1397 0.1397)
			(layers "F.Cu" "F.Mask" "F.Paste")
			(net "P1V8_E")
			(options
				(clearance outline)
				(anchor circle)
			)
			(primitives
				(gr_poly
					(pts
						(arc
							(start -0.1778 -0.2794)
							(mid -0.249642 -0.249642)
							(end -0.2794 -0.1778)
						)
						(arc
							(start -0.2794 0.1778)
							(mid -0.249642 0.249642)
							(end -0.1778 0.2794)
						)
						(arc
							(start 0.1778 0.2794)
							(mid 0.249642 0.249642)
							(end 0.2794 0.1778)
						)
						(arc
							(start 0.2794 -0.1778)
							(mid 0.249642 -0.249642)
							(end 0.1778 -0.2794)
						)
					)
					(width 0)
					(fill yes)
				)
			)
		)
		(pad "2" smd custom
			(at 0 0.4445)
			(size 0.1397 0.1397)
			(layers "F.Cu" "F.Mask" "F.Paste")
			(net "HDD_PRE_IO_INT_N")
			(options
				(clearance outline)
				(anchor circle)
			)
			(primitives
				(gr_poly
					(pts
						(arc
							(start -0.1778 -0.2794)
							(mid -0.249642 -0.249642)
							(end -0.2794 -0.1778)
						)
						(arc
							(start -0.2794 0.1778)
							(mid -0.249642 0.249642)
							(end -0.1778 0.2794)
						)
						(arc
							(start 0.1778 0.2794)
							(mid 0.249642 0.249642)
							(end 0.2794 0.1778)
						)
						(arc
							(start 0.2794 -0.1778)
							(mid 0.249642 -0.249642)
							(end 0.1778 -0.2794)
						)
					)
					(width 0)
					(fill yes)
				)
			)
		)
	)
	(footprint ""
		(layer "F.Cu")
		(at 194.491864 -46.681136 90)
		(property "Reference" "Q7"
			(at 0 0 90)
			(layer "F.SilkS")
			(hide yes)
			(effects
				(font
					(size 1.27 1.27)
				)
			)
		)
		(property "Value" "2N7002A-7-GP"
			(at 0.127 -8.9662 90)
			(unlocked yes)
			(layer "F.Fab")
			(hide yes)
			(effects
				(font
					(size 1.016 1.016)
					(thickness 0.1524)
				)
			)
		)
		(property "Device Type" "SOT23DGS2D4H48"
			(at 0.127 -10.4902 90)
			(unlocked yes)
			(layer "F.Fab")
			(hide yes)
			(effects
				(font
					(size 1.016 1.016)
					(thickness 0.1524)
				)
			)
		)
		(duplicate_pad_numbers_are_jumpers no)
		(fp_line
			(start 1.651 -1.778)
			(end -1.651 -1.778)
			(stroke
				(width 0.1524)
				(type default)
			)
			(layer "F.SilkS")
		)
		(fp_line
			(start -1.651 -1.778)
			(end -1.651 1.778)
			(stroke
				(width 0.1524)
				(type default)
			)
			(layer "F.SilkS")
		)
		(fp_line
			(start 1.651 1.778)
			(end 1.651 -1.778)
			(stroke
				(width 0.1524)
				(type default)
			)
			(layer "F.SilkS")
		)
		(fp_line
			(start -1.651 1.778)
			(end 1.651 1.778)
			(stroke
				(width 0.1524)
				(type default)
			)
			(layer "F.SilkS")
		)
		(fp_poly
			(pts
				(xy -1.778 1.8796) (xy -1.778 -1.8796) (xy 1.778 -1.8796) (xy 1.778 1.8796)
			)
			(stroke
				(width 0)
				(type default)
			)
			(fill no)
			(layer "F.CrtYd")
		)
		(fp_poly
			(pts
				(xy -1.778 1.8796) (xy -1.778 -1.8796) (xy 1.778 -1.8796) (xy 1.778 1.8796)
			)
			(stroke
				(width 0)
				(type default)
			)
			(fill no)
			(layer "F.Fab")
		)
		(pad "D" smd custom
			(at 0 -0.9525 90)
			(size 0.1905 0.1905)
			(layers "F.Cu" "F.Mask" "F.Paste")
			(net "PRSNT_MSB_AND_1")
			(options
				(clearance outline)
				(anchor circle)
			)
			(primitives
				(gr_poly
					(pts
						(arc
							(start -0.1778 0.5715)
							(mid -0.321484 0.511984)
							(end -0.381 0.3683)
						)
						(arc
							(start -0.381 -0.3683)
							(mid -0.321484 -0.511984)
							(end -0.1778 -0.5715)
						)
						(arc
							(start 0.1778 -0.5715)
							(mid 0.321484 -0.511984)
							(end 0.381 -0.3683)
						)
						(arc
							(start 0.381 0.3683)
							(mid 0.321484 0.511984)
							(end 0.1778 0.5715)
						)
					)
					(width 0)
					(fill yes)
				)
			)
		)
		(pad "G" smd custom
			(at -0.98425 0.9525 90)
			(size 0.1905 0.1905)
			(layers "F.Cu" "F.Mask" "F.Paste")
			(net "PRSNT_MSB_B81")
			(options
				(clearance outline)
				(anchor circle)
			)
			(primitives
				(gr_poly
					(pts
						(arc
							(start -0.1778 0.5715)
							(mid -0.321484 0.511984)
							(end -0.381 0.3683)
						)
						(arc
							(start -0.381 -0.3683)
							(mid -0.321484 -0.511984)
							(end -0.1778 -0.5715)
						)
						(arc
							(start 0.1778 -0.5715)
							(mid 0.321484 -0.511984)
							(end 0.381 -0.3683)
						)
						(arc
							(start 0.381 0.3683)
							(mid 0.321484 0.511984)
							(end 0.1778 0.5715)
						)
					)
					(width 0)
					(fill yes)
				)
			)
		)
		(pad "S" smd custom
			(at 0.98425 0.9525 90)
			(size 0.1905 0.1905)
			(layers "F.Cu" "F.Mask" "F.Paste")
			(net "GND")
			(options
				(clearance outline)
				(anchor circle)
			)
			(primitives
				(gr_poly
					(pts
						(arc
							(start -0.1778 0.5715)
							(mid -0.321484 0.511984)
							(end -0.381 0.3683)
						)
						(arc
							(start -0.381 -0.3683)
							(mid -0.321484 -0.511984)
							(end -0.1778 -0.5715)
						)
						(arc
							(start 0.1778 -0.5715)
							(mid 0.321484 -0.511984)
							(end 0.381 -0.3683)
						)
						(arc
							(start 0.381 0.3683)
							(mid 0.321484 0.511984)
							(end 0.1778 0.5715)
						)
					)
					(width 0)
					(fill yes)
				)
			)
		)
	)
	(footprint ""
		(layer "F.Cu")
		(at 117.964966 -45.847 -90)
		(property "Reference" "SR668"
			(at 0 0 270)
			(layer "F.SilkS")
			(hide yes)
			(effects
				(font
					(size 1.27 1.27)
				)
			)
		)
		(property "Value" "10KR2F-2-GP"
			(at 0.064008 -3.993896 270)
			(unlocked yes)
			(layer "F.Fab")
			(hide yes)
			(effects
				(font
					(size 1.016 1.016)
					(thickness 0.1524)
				)
			)
		)
		(property "Device Type" "R402H16"
			(at 0.064008 -5.517896 270)
			(unlocked yes)
			(layer "F.Fab")
			(hide yes)
			(effects
				(font
					(size 1.016 1.016)
					(thickness 0.1524)
				)
			)
		)
		(duplicate_pad_numbers_are_jumpers no)
		(fp_line
			(start -0.508 -0.9398)
			(end -0.508 0.9398)
			(stroke
				(width 0.1524)
				(type default)
			)
			(layer "F.SilkS")
		)
		(fp_line
			(start 0.508 -0.9398)
			(end -0.508 -0.9398)
			(stroke
				(width 0.1524)
				(type default)
			)
			(layer "F.SilkS")
		)
		(fp_rect
			(start -0.508 0.9398)
			(end 0.508 -0.9398)
			(stroke
				(width 0)
				(type default)
			)
			(fill no)
			(layer "F.CrtYd")
		)
		(fp_rect
			(start -0.508 0.9398)
			(end 0.508 -0.9398)
			(stroke
				(width 0)
				(type default)
			)
			(fill no)
			(layer "F.Fab")
		)
		(pad "1" smd custom
			(at 0 -0.4445 270)
			(size 0.1397 0.1397)
			(layers "F.Cu" "F.Mask" "F.Paste")
			(net "P1V8_C")
			(options
				(clearance outline)
				(anchor circle)
			)
			(primitives
				(gr_poly
					(pts
						(arc
							(start -0.1778 -0.2794)
							(mid -0.249642 -0.249642)
							(end -0.2794 -0.1778)
						)
						(arc
							(start -0.2794 0.1778)
							(mid -0.249642 0.249642)
							(end -0.1778 0.2794)
						)
						(arc
							(start 0.1778 0.2794)
							(mid 0.249642 0.249642)
							(end 0.2794 0.1778)
						)
						(arc
							(start 0.2794 -0.1778)
							(mid 0.249642 -0.249642)
							(end 0.1778 -0.2794)
						)
					)
					(width 0)
					(fill yes)
				)
			)
		)
		(pad "2" smd custom
			(at 0 0.4445 270)
			(size 0.1397 0.1397)
			(layers "F.Cu" "F.Mask" "F.Paste")
			(net "SYS_CORE_TRI#")
			(options
				(clearance outline)
				(anchor circle)
			)
			(primitives
				(gr_poly
					(pts
						(arc
							(start -0.1778 -0.2794)
							(mid -0.249642 -0.249642)
							(end -0.2794 -0.1778)
						)
						(arc
							(start -0.2794 0.1778)
							(mid -0.249642 0.249642)
							(end -0.1778 0.2794)
						)
						(arc
							(start 0.1778 0.2794)
							(mid 0.249642 0.249642)
							(end 0.2794 0.1778)
						)
						(arc
							(start 0.2794 -0.1778)
							(mid 0.249642 -0.249642)
							(end 0.1778 -0.2794)
						)
					)
					(width 0)
					(fill yes)
				)
			)
		)
	)
	(footprint ""
		(layer "F.Cu")
		(at 97.536 -233.807)
		(property "Reference" "R660"
			(at 0 0 0)
			(layer "F.SilkS")
			(hide yes)
			(effects
				(font
					(size 1.27 1.27)
				)
			)
		)
		(property "Value" "0R2J-2-GP"
			(at 0.064008 -3.993896 0)
			(unlocked yes)
			(layer "F.Fab")
			(hide yes)
			(effects
				(font
					(size 1.016 1.016)
					(thickness 0.1524)
				)
			)
		)
		(property "Device Type" "R402H16"
			(at 0.064008 -5.517896 0)
			(unlocked yes)
			(layer "F.Fab")
			(hide yes)
			(effects
				(font
					(size 1.016 1.016)
					(thickness 0.1524)
				)
			)
		)
		(duplicate_pad_numbers_are_jumpers no)
		(fp_line
			(start -0.508 -0.9398)
			(end -0.508 0.9398)
			(stroke
				(width 0.1524)
				(type default)
			)
			(layer "F.SilkS")
		)
		(fp_line
			(start 0.508 -0.9398)
			(end -0.508 -0.9398)
			(stroke
				(width 0.1524)
				(type default)
			)
			(layer "F.SilkS")
		)
		(fp_rect
			(start -0.508 0.9398)
			(end 0.508 -0.9398)
			(stroke
				(width 0)
				(type default)
			)
			(fill no)
			(layer "F.CrtYd")
		)
		(fp_rect
			(start -0.508 0.9398)
			(end 0.508 -0.9398)
			(stroke
				(width 0)
				(type default)
			)
			(fill no)
			(layer "F.Fab")
		)
		(pad "1" smd custom
			(at 0 -0.4445)
			(size 0.1397 0.1397)
			(layers "F.Cu" "F.Mask" "F.Paste")
			(net "SAS_FAULT_LED8")
			(options
				(clearance outline)
				(anchor circle)
			)
			(primitives
				(gr_poly
					(pts
						(arc
							(start -0.1778 -0.2794)
							(mid -0.249642 -0.249642)
							(end -0.2794 -0.1778)
						)
						(arc
							(start -0.2794 0.1778)
							(mid -0.249642 0.249642)
							(end -0.1778 0.2794)
						)
						(arc
							(start 0.1778 0.2794)
							(mid 0.249642 0.249642)
							(end 0.2794 0.1778)
						)
						(arc
							(start 0.2794 -0.1778)
							(mid 0.249642 -0.249642)
							(end 0.1778 -0.2794)
						)
					)
					(width 0)
					(fill yes)
				)
			)
		)
		(pad "2" smd custom
			(at 0 0.4445)
			(size 0.1397 0.1397)
			(layers "F.Cu" "F.Mask" "F.Paste")
			(net "SAS_HDD_LED_8")
			(options
				(clearance outline)
				(anchor circle)
			)
			(primitives
				(gr_poly
					(pts
						(arc
							(start -0.1778 -0.2794)
							(mid -0.249642 -0.249642)
							(end -0.2794 -0.1778)
						)
						(arc
							(start -0.2794 0.1778)
							(mid -0.249642 0.249642)
							(end -0.1778 0.2794)
						)
						(arc
							(start 0.1778 0.2794)
							(mid 0.249642 0.249642)
							(end 0.2794 0.1778)
						)
						(arc
							(start 0.2794 -0.1778)
							(mid 0.249642 -0.249642)
							(end 0.1778 -0.2794)
						)
					)
					(width 0)
					(fill yes)
				)
			)
		)
	)
	(footprint ""
		(layer "F.Cu")
		(at 333.912718 -154.409648 90)
		(property "Reference" "R217"
			(at 0 0 90)
			(layer "F.SilkS")
			(hide yes)
			(effects
				(font
					(size 1.27 1.27)
				)
			)
		)
		(property "Value" "4K7R2F-GP"
			(at 0.064008 -3.993896 90)
			(unlocked yes)
			(layer "F.Fab")
			(hide yes)
			(effects
				(font
					(size 1.016 1.016)
					(thickness 0.1524)
				)
			)
		)
		(property "Device Type" "R402H16"
			(at 0.064008 -5.517896 90)
			(unlocked yes)
			(layer "F.Fab")
			(hide yes)
			(effects
				(font
					(size 1.016 1.016)
					(thickness 0.1524)
				)
			)
		)
		(duplicate_pad_numbers_are_jumpers no)
		(fp_line
			(start 0.508 -0.9398)
			(end -0.508 -0.9398)
			(stroke
				(width 0.1524)
				(type default)
			)
			(layer "F.SilkS")
		)
		(fp_line
			(start -0.508 -0.9398)
			(end -0.508 0.9398)
			(stroke
				(width 0.1524)
				(type default)
			)
			(layer "F.SilkS")
		)
		(fp_rect
			(start -0.508 0.9398)
			(end 0.508 -0.9398)
			(stroke
				(width 0)
				(type default)
			)
			(fill no)
			(layer "F.CrtYd")
		)
		(fp_rect
			(start -0.508 0.9398)
			(end 0.508 -0.9398)
			(stroke
				(width 0)
				(type default)
			)
			(fill no)
			(layer "F.Fab")
		)
		(pad "1" smd custom
			(at 0 -0.4445 90)
			(size 0.1397 0.1397)
			(layers "F.Cu" "F.Mask" "F.Paste")
			(net "P3V3_STBY")
			(options
				(clearance outline)
				(anchor circle)
			)
			(primitives
				(gr_poly
					(pts
						(arc
							(start -0.1778 -0.2794)
							(mid -0.249642 -0.249642)
							(end -0.2794 -0.1778)
						)
						(arc
							(start -0.2794 0.1778)
							(mid -0.249642 0.249642)
							(end -0.1778 0.2794)
						)
						(arc
							(start 0.1778 0.2794)
							(mid 0.249642 0.249642)
							(end 0.2794 0.1778)
						)
						(arc
							(start 0.2794 -0.1778)
							(mid 0.249642 -0.249642)
							(end 0.1778 -0.2794)
						)
					)
					(width 0)
					(fill yes)
				)
			)
		)
		(pad "2" smd custom
			(at 0 0.4445 90)
			(size 0.1397 0.1397)
			(layers "F.Cu" "F.Mask" "F.Paste")
			(net "USB_OCS_N4")
			(options
				(clearance outline)
				(anchor circle)
			)
			(primitives
				(gr_poly
					(pts
						(arc
							(start -0.1778 -0.2794)
							(mid -0.249642 -0.249642)
							(end -0.2794 -0.1778)
						)
						(arc
							(start -0.2794 0.1778)
							(mid -0.249642 0.249642)
							(end -0.1778 0.2794)
						)
						(arc
							(start 0.1778 0.2794)
							(mid 0.249642 0.249642)
							(end 0.2794 0.1778)
						)
						(arc
							(start 0.2794 -0.1778)
							(mid 0.249642 -0.249642)
							(end 0.1778 -0.2794)
						)
					)
					(width 0)
					(fill yes)
				)
			)
		)
	)
	(footprint ""
		(layer "F.Cu")
		(at 297.163236 -147.617688)
		(property "Reference" "X1"
			(at 0 0 0)
			(layer "F.SilkS")
			(hide yes)
			(effects
				(font
					(size 1.27 1.27)
				)
			)
		)
		(property "Value" "OSC-50MHZ-8-GP-U"
			(at -5.183886 1.282192 0)
			(unlocked yes)
			(layer "F.Fab")
			(hide yes)
			(effects
				(font
					(size 1.016 1.016)
					(thickness 0.1524)
				)
			)
		)
		(property "Device Type" "S-OSC4-7349H75"
			(at -5.183886 -0.241808 0)
			(unlocked yes)
			(layer "F.Fab")
			(hide yes)
			(effects
				(font
					(size 1.016 1.016)
					(thickness 0.1524)
				)
			)
		)
		(duplicate_pad_numbers_are_jumpers no)
		(fp_line
			(start -3.9878 2.0447)
			(end -3.9878 3.3147)
			(stroke
				(width 0.3302)
				(type default)
			)
			(layer "F.SilkS")
		)
		(fp_line
			(start -3.9878 3.3147)
			(end -2.7178 3.3147)
			(stroke
				(width 0.3302)
				(type default)
			)
			(layer "F.SilkS")
		)
		(fp_line
			(start -3.8989 -3.2131)
			(end 3.8989 -3.2131)
			(stroke
				(width 0.1524)
				(type default)
			)
			(layer "F.SilkS")
		)
		(fp_line
			(start -3.8989 3.2131)
			(end -3.8989 -3.2131)
			(stroke
				(width 0.1524)
				(type default)
			)
			(layer "F.SilkS")
		)
		(fp_line
			(start 3.8989 -3.2131)
			(end 3.8989 3.2131)
			(stroke
				(width 0.1524)
				(type default)
			)
			(layer "F.SilkS")
		)
		(fp_line
			(start 3.8989 3.2131)
			(end -3.8989 3.2131)
			(stroke
				(width 0.1524)
				(type default)
			)
			(layer "F.SilkS")
		)
		(fp_poly
			(pts
				(xy -4.879848 1.931924) (xy -4.879848 3.201924) (xy -4.244848 2.566924)
			)
			(stroke
				(width 0)
				(type default)
			)
			(fill yes)
			(layer "F.SilkS")
		)
		(fp_rect
			(start -3.6449 2.4511)
			(end 3.6449 -2.4511)
			(stroke
				(width 0)
				(type default)
			)
			(fill no)
			(layer "F.CrtYd")
		)
		(fp_poly
			(pts
				(xy -4.1529 3.4671) (xy -4.1529 -0.5842) (xy -3.6449 -0.5842) (xy -3.6449 2.4511) (xy 3.6449 2.4511)
				(xy 3.6449 -2.4511) (xy -3.6449 -2.4511) (xy -3.6449 -0.5969) (xy -4.1529 -0.5969) (xy -4.1529 -3.4671)
				(xy 4.1529 -3.4671) (xy 4.1529 3.4671)
			)
			(stroke
				(width 0)
				(type default)
			)
			(fill no)
			(layer "F.CrtYd")
		)
		(fp_rect
			(start -4.1529 3.4671)
			(end 4.1529 -3.4671)
			(stroke
				(width 0)
				(type default)
			)
			(fill no)
			(layer "F.Fab")
		)
		(pad "1" smd rect
			(at -2.54 2.005584)
			(size 1.651 1.905)
			(layers "F.Cu" "F.Mask" "F.Paste")
			(net "FM_OSC_50M_EN")
		)
		(pad "2" smd rect
			(at 2.54 2.005584)
			(size 1.651 1.905)
			(layers "F.Cu" "F.Mask" "F.Paste")
			(net "GND")
		)
		(pad "3" smd rect
			(at 2.54 -2.005584)
			(size 1.651 1.905)
			(layers "F.Cu" "F.Mask" "F.Paste")
			(net "50M_CLK_OUT")
		)
		(pad "4" smd rect
			(at -2.54 -2.005584)
			(size 1.651 1.905)
			(layers "F.Cu" "F.Mask" "F.Paste")
			(net "P3V3_STBY")
		)
		(zone
			(layer "F.Cu")
			(hatch none 0.5)
			(connect_pads
				(clearance 0)
			)
			(min_thickness 0.25)
			(keepout
				(tracks not_allowed)
				(vias allowed)
				(pads allowed)
				(copperpour not_allowed)
				(footprints allowed)
			)
			(placement
				(enabled no)
				(sheetname "")
			)
			(fill
				(thermal_gap 0.5)
				(thermal_bridge_width 0.5)
				(island_removal_mode 0)
			)
			(polygon
				(pts
					(xy 295.766236 -146.893788) (xy 295.766236 -148.341588) (xy 298.560236 -148.341588) (xy 298.560236 -146.893788)
				)
			)
		)
		(zone
			(layer "F.Cu")
			(hatch none 0.5)
			(connect_pads
				(clearance 0)
			)
			(min_thickness 0.25)
			(keepout
				(tracks allowed)
				(vias not_allowed)
				(pads allowed)
				(copperpour not_allowed)
				(footprints allowed)
			)
			(placement
				(enabled no)
				(sheetname "")
			)
			(fill
				(thermal_gap 0.5)
				(thermal_bridge_width 0.5)
				(island_removal_mode 0)
			)
			(polygon
				(pts
					(xy 295.448736 -144.659604) (xy 295.448736 -146.564604) (xy 293.797736 -146.564604) (xy 293.797736 -148.670772)
					(xy 295.448736 -148.670772) (xy 295.448736 -150.575772) (xy 298.877736 -150.575772) (xy 298.877736 -148.670772)
					(xy 300.528736 -148.670772) (xy 300.528736 -146.564604) (xy 298.877736 -146.564604) (xy 298.877736 -144.659604)
				)
			)
		)
	)
	(footprint ""
		(layer "F.Cu")
		(at 218.094814 -179.403248 90)
		(property "Reference" "R500"
			(at 0 0 90)
			(layer "F.SilkS")
			(hide yes)
			(effects
				(font
					(size 1.27 1.27)
				)
			)
		)
		(property "Value" "1KR2F-3-GP"
			(at 0.064008 -3.993896 90)
			(unlocked yes)
			(layer "F.Fab")
			(hide yes)
			(effects
				(font
					(size 1.016 1.016)
					(thickness 0.1524)
				)
			)
		)
		(property "Device Type" "R402H16"
			(at 0.064008 -5.517896 90)
			(unlocked yes)
			(layer "F.Fab")
			(hide yes)
			(effects
				(font
					(size 1.016 1.016)
					(thickness 0.1524)
				)
			)
		)
		(duplicate_pad_numbers_are_jumpers no)
		(fp_line
			(start 0.508 -0.9398)
			(end -0.508 -0.9398)
			(stroke
				(width 0.1524)
				(type default)
			)
			(layer "F.SilkS")
		)
		(fp_line
			(start -0.508 -0.9398)
			(end -0.508 0.9398)
			(stroke
				(width 0.1524)
				(type default)
			)
			(layer "F.SilkS")
		)
		(fp_rect
			(start -0.508 0.9398)
			(end 0.508 -0.9398)
			(stroke
				(width 0)
				(type default)
			)
			(fill no)
			(layer "F.CrtYd")
		)
		(fp_rect
			(start -0.508 0.9398)
			(end 0.508 -0.9398)
			(stroke
				(width 0)
				(type default)
			)
			(fill no)
			(layer "F.Fab")
		)
		(pad "1" smd custom
			(at 0 -0.4445 90)
			(size 0.1397 0.1397)
			(layers "F.Cu" "F.Mask" "F.Paste")
			(net "P3V3_STBY")
			(options
				(clearance outline)
				(anchor circle)
			)
			(primitives
				(gr_poly
					(pts
						(arc
							(start -0.1778 -0.2794)
							(mid -0.249642 -0.249642)
							(end -0.2794 -0.1778)
						)
						(arc
							(start -0.2794 0.1778)
							(mid -0.249642 0.249642)
							(end -0.1778 0.2794)
						)
						(arc
							(start 0.1778 0.2794)
							(mid 0.249642 0.249642)
							(end 0.2794 0.1778)
						)
						(arc
							(start 0.2794 -0.1778)
							(mid 0.249642 -0.249642)
							(end 0.1778 -0.2794)
						)
					)
					(width 0)
					(fill yes)
				)
			)
		)
		(pad "2" smd custom
			(at 0 0.4445 90)
			(size 0.1397 0.1397)
			(layers "F.Cu" "F.Mask" "F.Paste")
			(net "DIVIDER 1_IN_EXP")
			(options
				(clearance outline)
				(anchor circle)
			)
			(primitives
				(gr_poly
					(pts
						(arc
							(start -0.1778 -0.2794)
							(mid -0.249642 -0.249642)
							(end -0.2794 -0.1778)
						)
						(arc
							(start -0.2794 0.1778)
							(mid -0.249642 0.249642)
							(end -0.1778 0.2794)
						)
						(arc
							(start 0.1778 0.2794)
							(mid 0.249642 0.249642)
							(end 0.2794 0.1778)
						)
						(arc
							(start 0.2794 -0.1778)
							(mid 0.249642 -0.249642)
							(end 0.1778 -0.2794)
						)
					)
					(width 0)
					(fill yes)
				)
			)
		)
	)
	(footprint ""
		(layer "F.Cu")
		(at 204.724 -185.42)
		(property "Reference" "R477"
			(at 0 0 0)
			(layer "F.SilkS")
			(hide yes)
			(effects
				(font
					(size 1.27 1.27)
				)
			)
		)
		(property "Value" "4K7R2F-GP"
			(at 0.064008 -3.993896 0)
			(unlocked yes)
			(layer "F.Fab")
			(hide yes)
			(effects
				(font
					(size 1.016 1.016)
					(thickness 0.1524)
				)
			)
		)
		(property "Device Type" "R402H16"
			(at 0.064008 -5.517896 0)
			(unlocked yes)
			(layer "F.Fab")
			(hide yes)
			(effects
				(font
					(size 1.016 1.016)
					(thickness 0.1524)
				)
			)
		)
		(duplicate_pad_numbers_are_jumpers no)
		(fp_line
			(start -0.508 -0.9398)
			(end -0.508 0.9398)
			(stroke
				(width 0.1524)
				(type default)
			)
			(layer "F.SilkS")
		)
		(fp_line
			(start 0.508 -0.9398)
			(end -0.508 -0.9398)
			(stroke
				(width 0.1524)
				(type default)
			)
			(layer "F.SilkS")
		)
		(fp_rect
			(start -0.508 0.9398)
			(end 0.508 -0.9398)
			(stroke
				(width 0)
				(type default)
			)
			(fill no)
			(layer "F.CrtYd")
		)
		(fp_rect
			(start -0.508 0.9398)
			(end 0.508 -0.9398)
			(stroke
				(width 0)
				(type default)
			)
			(fill no)
			(layer "F.Fab")
		)
		(pad "1" smd custom
			(at 0 -0.4445)
			(size 0.1397 0.1397)
			(layers "F.Cu" "F.Mask" "F.Paste")
			(net "DIVIDER 1_IN")
			(options
				(clearance outline)
				(anchor circle)
			)
			(primitives
				(gr_poly
					(pts
						(arc
							(start -0.1778 -0.2794)
							(mid -0.249642 -0.249642)
							(end -0.2794 -0.1778)
						)
						(arc
							(start -0.2794 0.1778)
							(mid -0.249642 0.249642)
							(end -0.1778 0.2794)
						)
						(arc
							(start 0.1778 0.2794)
							(mid 0.249642 0.249642)
							(end 0.2794 0.1778)
						)
						(arc
							(start 0.2794 -0.1778)
							(mid 0.249642 -0.249642)
							(end 0.1778 -0.2794)
						)
					)
					(width 0)
					(fill yes)
				)
			)
		)
		(pad "2" smd custom
			(at 0 0.4445)
			(size 0.1397 0.1397)
			(layers "F.Cu" "F.Mask" "F.Paste")
			(net "DIVIDER 2_IN")
			(options
				(clearance outline)
				(anchor circle)
			)
			(primitives
				(gr_poly
					(pts
						(arc
							(start -0.1778 -0.2794)
							(mid -0.249642 -0.249642)
							(end -0.2794 -0.1778)
						)
						(arc
							(start -0.2794 0.1778)
							(mid -0.249642 0.249642)
							(end -0.1778 0.2794)
						)
						(arc
							(start 0.1778 0.2794)
							(mid 0.249642 0.249642)
							(end 0.2794 0.1778)
						)
						(arc
							(start 0.2794 -0.1778)
							(mid 0.249642 -0.249642)
							(end 0.1778 -0.2794)
						)
					)
					(width 0)
					(fill yes)
				)
			)
		)
	)
	(footprint ""
		(layer "F.Cu")
		(at 93.218 -112.014 180)
		(property "Reference" "SC1235"
			(at 0 0 180)
			(layer "F.SilkS")
			(hide yes)
			(effects
				(font
					(size 1.27 1.27)
				)
			)
		)
		(property "Value" "SCD1U6D3V1KX-GP"
			(at -2.8321 -1.7399 180)
			(unlocked yes)
			(layer "F.Fab")
			(hide yes)
			(effects
				(font
					(size 1.016 1.016)
					(thickness 0.1524)
				)
			)
		)
		(property "Device Type" "C0201H13"
			(at -2.8321 -3.2639 180)
			(unlocked yes)
			(layer "F.Fab")
			(hide yes)
			(effects
				(font
					(size 1.016 1.016)
					(thickness 0.1524)
				)
			)
		)
		(duplicate_pad_numbers_are_jumpers no)
		(fp_rect
			(start -0.2794 0.6477)
			(end 0.2794 -0.6477)
			(stroke
				(width 0)
				(type default)
			)
			(fill no)
			(layer "F.CrtYd")
		)
		(fp_rect
			(start -0.2794 0.6477)
			(end 0.2794 -0.6477)
			(stroke
				(width 0)
				(type default)
			)
			(fill no)
			(layer "F.Fab")
		)
		(pad "1" smd custom
			(at 0 -0.2794 180)
			(size 0.0762 0.0762)
			(layers "F.Cu" "F.Mask" "F.Paste")
			(net "P1V8_E")
			(options
				(clearance outline)
				(anchor circle)
			)
			(primitives
				(gr_poly
					(pts
						(arc
							(start 0.1524 -0.127)
							(mid 0.137521 -0.162921)
							(end 0.1016 -0.1778)
						)
						(arc
							(start -0.1016 -0.1778)
							(mid -0.137521 -0.162921)
							(end -0.1524 -0.127)
						)
						(arc
							(start -0.1524 0.127)
							(mid -0.137521 0.162921)
							(end -0.1016 0.1778)
						)
						(arc
							(start 0.1016 0.1778)
							(mid 0.137521 0.162921)
							(end 0.1524 0.127)
						)
					)
					(width 0)
					(fill yes)
				)
			)
		)
		(pad "2" smd custom
			(at 0 0.2794 180)
			(size 0.0762 0.0762)
			(layers "F.Cu" "F.Mask" "F.Paste")
			(net "GND")
			(options
				(clearance outline)
				(anchor circle)
			)
			(primitives
				(gr_poly
					(pts
						(arc
							(start 0.1524 -0.127)
							(mid 0.137521 -0.162921)
							(end 0.1016 -0.1778)
						)
						(arc
							(start -0.1016 -0.1778)
							(mid -0.137521 -0.162921)
							(end -0.1524 -0.127)
						)
						(arc
							(start -0.1524 0.127)
							(mid -0.137521 0.162921)
							(end -0.1016 0.1778)
						)
						(arc
							(start 0.1016 0.1778)
							(mid 0.137521 0.162921)
							(end 0.1524 0.127)
						)
					)
					(width 0)
					(fill yes)
				)
			)
		)
	)
	(footprint ""
		(layer "F.Cu")
		(at 26.224738 -172.926756)
		(property "Reference" "SU69"
			(at 0 0 0)
			(layer "F.SilkS")
			(hide yes)
			(effects
				(font
					(size 1.27 1.27)
				)
			)
		)
		(property "Value" "SNLVC8T245DGVR-GP"
			(at 0 -11.1252 0)
			(unlocked yes)
			(layer "F.Fab")
			(hide yes)
			(effects
				(font
					(size 1.016 1.016)
					(thickness 0.1524)
				)
			)
		)
		(property "Device Type" "TVSOP24H48"
			(at 0 -12.6492 0)
			(unlocked yes)
			(layer "F.Fab")
			(hide yes)
			(effects
				(font
					(size 1.016 1.016)
					(thickness 0.1524)
				)
			)
		)
		(duplicate_pad_numbers_are_jumpers no)
		(fp_line
			(start -2.9337 -1.397)
			(end -2.9337 1.397)
			(stroke
				(width 0.1524)
				(type default)
			)
			(layer "F.SilkS")
		)
		(fp_line
			(start -2.9337 -0.3683)
			(end -2.5654 0)
			(stroke
				(width 0.1524)
				(type default)
			)
			(layer "F.SilkS")
		)
		(fp_line
			(start -2.9337 1.397)
			(end 2.2987 1.397)
			(stroke
				(width 0.1524)
				(type default)
			)
			(layer "F.SilkS")
		)
		(fp_line
			(start -2.7559 1.397)
			(end -2.7559 3.8354)
			(stroke
				(width 0.508)
				(type default)
			)
			(layer "F.SilkS")
		)
		(fp_line
			(start -2.5654 0)
			(end -2.9337 0.3683)
			(stroke
				(width 0.1524)
				(type default)
			)
			(layer "F.SilkS")
		)
		(fp_line
			(start 2.2987 -1.397)
			(end -2.9337 -1.397)
			(stroke
				(width 0.1524)
				(type default)
			)
			(layer "F.SilkS")
		)
		(fp_line
			(start 2.2987 1.397)
			(end 2.2987 -1.397)
			(stroke
				(width 0.1524)
				(type default)
			)
			(layer "F.SilkS")
		)
		(fp_rect
			(start -3.0099 4.0894)
			(end 3.0099 -4.0894)
			(stroke
				(width 0)
				(type default)
			)
			(fill no)
			(layer "F.CrtYd")
		)
		(fp_poly
			(pts
				(xy -3.0099 -4.0894) (xy 3.0099 -4.0894) (xy 3.0099 4.0894) (xy -3.0099 4.0894)
			)
			(stroke
				(width 0)
				(type default)
			)
			(fill no)
			(layer "F.Fab")
		)
		(pad "1" smd rect
			(at -2.19964 2.8194)
			(size 0.2032 1.524)
			(layers "F.Cu" "F.Mask" "F.Paste")
			(net "P1V8_E")
		)
		(pad "2" smd rect
			(at -1.79959 2.8194)
			(size 0.2032 1.524)
			(layers "F.Cu" "F.Mask" "F.Paste")
			(net "GND")
		)
		(pad "3" smd rect
			(at -1.39954 2.8194)
			(size 0.2032 1.524)
			(layers "F.Cu" "F.Mask" "F.Paste")
			(net "SAS_HDD_LED20")
		)
		(pad "4" smd rect
			(at -0.99949 2.8194)
			(size 0.2032 1.524)
			(layers "F.Cu" "F.Mask" "F.Paste")
			(net "SAS_HDD_LED21")
		)
		(pad "5" smd rect
			(at -0.59944 2.8194)
			(size 0.2032 1.524)
			(layers "F.Cu" "F.Mask" "F.Paste")
			(net "SAS_HDD_LED22")
		)
		(pad "6" smd rect
			(at -0.19939 2.8194)
			(size 0.2032 1.524)
			(layers "F.Cu" "F.Mask" "F.Paste")
			(net "SAS_HDD_LED23")
		)
		(pad "7" smd rect
			(at 0.19939 2.8194)
			(size 0.2032 1.524)
			(layers "F.Cu" "F.Mask" "F.Paste")
			(net "SAS_HDD_LED0")
		)
		(pad "8" smd rect
			(at 0.59944 2.8194)
			(size 0.2032 1.524)
			(layers "F.Cu" "F.Mask" "F.Paste")
			(net "SAS_HDD_LED1")
		)
		(pad "9" smd rect
			(at 0.99949 2.8194)
			(size 0.2032 1.524)
			(layers "F.Cu" "F.Mask" "F.Paste")
			(net "SAS_HDD_LED2")
		)
		(pad "10" smd rect
			(at 1.39954 2.8194)
			(size 0.2032 1.524)
			(layers "F.Cu" "F.Mask" "F.Paste")
			(net "SAS_HDD_LED3")
		)
		(pad "11" smd rect
			(at 1.79959 2.8194)
			(size 0.2032 1.524)
			(layers "F.Cu" "F.Mask" "F.Paste")
			(net "GND")
		)
		(pad "12" smd rect
			(at 2.19964 2.8194)
			(size 0.2032 1.524)
			(layers "F.Cu" "F.Mask" "F.Paste")
			(net "GND")
		)
		(pad "13" smd rect
			(at 2.19964 -2.8194)
			(size 0.2032 1.524)
			(layers "F.Cu" "F.Mask" "F.Paste")
			(net "GND")
		)
		(pad "14" smd rect
			(at 1.79959 -2.8194)
			(size 0.2032 1.524)
			(layers "F.Cu" "F.Mask" "F.Paste")
			(net "SAS_HDD_PRE7")
		)
		(pad "15" smd rect
			(at 1.39954 -2.8194)
			(size 0.2032 1.524)
			(layers "F.Cu" "F.Mask" "F.Paste")
			(net "SAS_HDD_PRE6")
		)
		(pad "16" smd rect
			(at 0.99949 -2.8194)
			(size 0.2032 1.524)
			(layers "F.Cu" "F.Mask" "F.Paste")
			(net "SAS_HDD_PRE5")
		)
		(pad "17" smd rect
			(at 0.59944 -2.8194)
			(size 0.2032 1.524)
			(layers "F.Cu" "F.Mask" "F.Paste")
			(net "SAS_HDD_PRE4")
		)
		(pad "18" smd rect
			(at 0.19939 -2.8194)
			(size 0.2032 1.524)
			(layers "F.Cu" "F.Mask" "F.Paste")
			(net "SAS_HDD_PRE3")
		)
		(pad "19" smd rect
			(at -0.19939 -2.8194)
			(size 0.2032 1.524)
			(layers "F.Cu" "F.Mask" "F.Paste")
			(net "SAS_HDD_PRE2")
		)
		(pad "20" smd rect
			(at -0.59944 -2.8194)
			(size 0.2032 1.524)
			(layers "F.Cu" "F.Mask" "F.Paste")
			(net "SAS_HDD_PRE1")
		)
		(pad "21" smd rect
			(at -0.99949 -2.8194)
			(size 0.2032 1.524)
			(layers "F.Cu" "F.Mask" "F.Paste")
			(net "SAS_HDD_PRE0")
		)
		(pad "22" smd rect
			(at -1.39954 -2.8194)
			(size 0.2032 1.524)
			(layers "F.Cu" "F.Mask" "F.Paste")
			(net "GND")
		)
		(pad "23" smd rect
			(at -1.79959 -2.8194)
			(size 0.2032 1.524)
			(layers "F.Cu" "F.Mask" "F.Paste")
			(net "P3V3_STBY")
		)
		(pad "24" smd rect
			(at -2.19964 -2.8194)
			(size 0.2032 1.524)
			(layers "F.Cu" "F.Mask" "F.Paste")
			(net "P3V3_STBY")
		)
	)
	(footprint ""
		(layer "F.Cu")
		(at 91.929966 -69.342 180)
		(property "Reference" "SC1002"
			(at 0 0 180)
			(layer "F.SilkS")
			(hide yes)
			(effects
				(font
					(size 1.27 1.27)
				)
			)
		)
		(property "Value" "SCD1U16V2KX-3GP"
			(at 1.1811 -2.7051 180)
			(unlocked yes)
			(layer "F.Fab")
			(hide yes)
			(effects
				(font
					(size 1.016 1.016)
					(thickness 0.1524)
				)
			)
		)
		(property "Device Type" "C402H22"
			(at 1.1811 -4.2291 180)
			(unlocked yes)
			(layer "F.Fab")
			(hide yes)
			(effects
				(font
					(size 1.016 1.016)
					(thickness 0.1524)
				)
			)
		)
		(duplicate_pad_numbers_are_jumpers no)
		(fp_rect
			(start -0.4318 0.9525)
			(end 0.4318 -0.9525)
			(stroke
				(width 0)
				(type default)
			)
			(fill no)
			(layer "F.CrtYd")
		)
		(fp_rect
			(start -0.4318 0.9525)
			(end 0.4318 -0.9525)
			(stroke
				(width 0)
				(type default)
			)
			(fill no)
			(layer "F.Fab")
		)
		(pad "1" smd custom
			(at 0 -0.4445 180)
			(size 0.1524 0.1524)
			(layers "F.Cu" "F.Mask" "F.Paste")
			(net "P1V8_C")
			(options
				(clearance outline)
				(anchor circle)
			)
			(primitives
				(gr_poly
					(pts
						(arc
							(start 0.3048 -0.2032)
							(mid 0.275042 -0.275042)
							(end 0.2032 -0.3048)
						)
						(arc
							(start -0.2032 -0.3048)
							(mid -0.275042 -0.275042)
							(end -0.3048 -0.2032)
						)
						(arc
							(start -0.3048 0.2032)
							(mid -0.275042 0.275042)
							(end -0.2032 0.3048)
						)
						(arc
							(start 0.2032 0.3048)
							(mid 0.275042 0.275042)
							(end 0.3048 0.2032)
						)
					)
					(width 0)
					(fill yes)
				)
			)
		)
		(pad "2" smd custom
			(at 0 0.4445 180)
			(size 0.1524 0.1524)
			(layers "F.Cu" "F.Mask" "F.Paste")
			(net "GND")
			(options
				(clearance outline)
				(anchor circle)
			)
			(primitives
				(gr_poly
					(pts
						(arc
							(start 0.3048 -0.2032)
							(mid 0.275042 -0.275042)
							(end 0.2032 -0.3048)
						)
						(arc
							(start -0.2032 -0.3048)
							(mid -0.275042 -0.275042)
							(end -0.3048 -0.2032)
						)
						(arc
							(start -0.3048 0.2032)
							(mid -0.275042 0.275042)
							(end -0.2032 0.3048)
						)
						(arc
							(start 0.2032 0.3048)
							(mid 0.275042 0.275042)
							(end 0.3048 0.2032)
						)
					)
					(width 0)
					(fill yes)
				)
			)
		)
	)
	(footprint ""
		(layer "F.Cu")
		(at 12.142216 -237.29188 180)
		(property "Reference" "SR262"
			(at 0 0 180)
			(layer "F.SilkS")
			(hide yes)
			(effects
				(font
					(size 1.27 1.27)
				)
			)
		)
		(property "Value" "0R2J-2-GP"
			(at 0.064008 -3.993896 180)
			(unlocked yes)
			(layer "F.Fab")
			(hide yes)
			(effects
				(font
					(size 1.016 1.016)
					(thickness 0.1524)
				)
			)
		)
		(property "Device Type" "R402H16"
			(at 0.064008 -5.517896 180)
			(unlocked yes)
			(layer "F.Fab")
			(hide yes)
			(effects
				(font
					(size 1.016 1.016)
					(thickness 0.1524)
				)
			)
		)
		(duplicate_pad_numbers_are_jumpers no)
		(fp_line
			(start 0.508 -0.9398)
			(end -0.508 -0.9398)
			(stroke
				(width 0.1524)
				(type default)
			)
			(layer "F.SilkS")
		)
		(fp_line
			(start -0.508 -0.9398)
			(end -0.508 0.9398)
			(stroke
				(width 0.1524)
				(type default)
			)
			(layer "F.SilkS")
		)
		(fp_rect
			(start -0.508 0.9398)
			(end 0.508 -0.9398)
			(stroke
				(width 0)
				(type default)
			)
			(fill no)
			(layer "F.CrtYd")
		)
		(fp_rect
			(start -0.508 0.9398)
			(end 0.508 -0.9398)
			(stroke
				(width 0)
				(type default)
			)
			(fill no)
			(layer "F.Fab")
		)
		(pad "1" smd custom
			(at 0 -0.4445 180)
			(size 0.1397 0.1397)
			(layers "F.Cu" "F.Mask" "F.Paste")
			(net "PCIE_MATED#_AB")
			(options
				(clearance outline)
				(anchor circle)
			)
			(primitives
				(gr_poly
					(pts
						(arc
							(start -0.1778 -0.2794)
							(mid -0.249642 -0.249642)
							(end -0.2794 -0.1778)
						)
						(arc
							(start -0.2794 0.1778)
							(mid -0.249642 0.249642)
							(end -0.1778 0.2794)
						)
						(arc
							(start 0.1778 0.2794)
							(mid 0.249642 0.249642)
							(end 0.2794 0.1778)
						)
						(arc
							(start 0.2794 -0.1778)
							(mid 0.249642 -0.249642)
							(end 0.1778 -0.2794)
						)
					)
					(width 0)
					(fill yes)
				)
			)
		)
		(pad "2" smd custom
			(at 0 0.4445 180)
			(size 0.1397 0.1397)
			(layers "F.Cu" "F.Mask" "F.Paste")
			(net "PCIE_MATED#")
			(options
				(clearance outline)
				(anchor circle)
			)
			(primitives
				(gr_poly
					(pts
						(arc
							(start -0.1778 -0.2794)
							(mid -0.249642 -0.249642)
							(end -0.2794 -0.1778)
						)
						(arc
							(start -0.2794 0.1778)
							(mid -0.249642 0.249642)
							(end -0.1778 0.2794)
						)
						(arc
							(start 0.1778 0.2794)
							(mid 0.249642 0.249642)
							(end 0.2794 0.1778)
						)
						(arc
							(start 0.2794 -0.1778)
							(mid 0.249642 -0.249642)
							(end 0.1778 -0.2794)
						)
					)
					(width 0)
					(fill yes)
				)
			)
		)
	)
	(footprint ""
		(layer "F.Cu")
		(at 215.265 -220.599 90)
		(property "Reference" "C83"
			(at 0 0 90)
			(layer "F.SilkS")
			(hide yes)
			(effects
				(font
					(size 1.27 1.27)
				)
			)
		)
		(property "Value" "SCD1U16V2KX-3GP"
			(at 1.1811 -2.7051 90)
			(unlocked yes)
			(layer "F.Fab")
			(hide yes)
			(effects
				(font
					(size 1.016 1.016)
					(thickness 0.1524)
				)
			)
		)
		(property "Device Type" "C402H22"
			(at 1.1811 -4.2291 90)
			(unlocked yes)
			(layer "F.Fab")
			(hide yes)
			(effects
				(font
					(size 1.016 1.016)
					(thickness 0.1524)
				)
			)
		)
		(duplicate_pad_numbers_are_jumpers no)
		(fp_rect
			(start -0.4318 0.9525)
			(end 0.4318 -0.9525)
			(stroke
				(width 0)
				(type default)
			)
			(fill no)
			(layer "F.CrtYd")
		)
		(fp_rect
			(start -0.4318 0.9525)
			(end 0.4318 -0.9525)
			(stroke
				(width 0)
				(type default)
			)
			(fill no)
			(layer "F.Fab")
		)
		(pad "1" smd custom
			(at 0 -0.4445 90)
			(size 0.1524 0.1524)
			(layers "F.Cu" "F.Mask" "F.Paste")
			(net "P3V3_STBY")
			(options
				(clearance outline)
				(anchor circle)
			)
			(primitives
				(gr_poly
					(pts
						(arc
							(start 0.3048 -0.2032)
							(mid 0.275042 -0.275042)
							(end 0.2032 -0.3048)
						)
						(arc
							(start -0.2032 -0.3048)
							(mid -0.275042 -0.275042)
							(end -0.3048 -0.2032)
						)
						(arc
							(start -0.3048 0.2032)
							(mid -0.275042 0.275042)
							(end -0.2032 0.3048)
						)
						(arc
							(start 0.2032 0.3048)
							(mid 0.275042 0.275042)
							(end 0.3048 0.2032)
						)
					)
					(width 0)
					(fill yes)
				)
			)
		)
		(pad "2" smd custom
			(at 0 0.4445 90)
			(size 0.1524 0.1524)
			(layers "F.Cu" "F.Mask" "F.Paste")
			(net "GND")
			(options
				(clearance outline)
				(anchor circle)
			)
			(primitives
				(gr_poly
					(pts
						(arc
							(start 0.3048 -0.2032)
							(mid 0.275042 -0.275042)
							(end 0.2032 -0.3048)
						)
						(arc
							(start -0.2032 -0.3048)
							(mid -0.275042 -0.275042)
							(end -0.3048 -0.2032)
						)
						(arc
							(start -0.3048 0.2032)
							(mid -0.275042 0.275042)
							(end -0.2032 0.3048)
						)
						(arc
							(start 0.2032 0.3048)
							(mid 0.275042 0.275042)
							(end 0.3048 0.2032)
						)
					)
					(width 0)
					(fill yes)
				)
			)
		)
	)
	(footprint ""
		(layer "F.Cu")
		(at 99.949 -221.488 180)
		(property "Reference" "R643"
			(at 0 0 180)
			(layer "F.SilkS")
			(hide yes)
			(effects
				(font
					(size 1.27 1.27)
				)
			)
		)
		(property "Value" "4K7R2F-GP"
			(at 0.064008 -3.993896 180)
			(unlocked yes)
			(layer "F.Fab")
			(hide yes)
			(effects
				(font
					(size 1.016 1.016)
					(thickness 0.1524)
				)
			)
		)
		(property "Device Type" "R402H16"
			(at 0.064008 -5.517896 180)
			(unlocked yes)
			(layer "F.Fab")
			(hide yes)
			(effects
				(font
					(size 1.016 1.016)
					(thickness 0.1524)
				)
			)
		)
		(duplicate_pad_numbers_are_jumpers no)
		(fp_line
			(start 0.508 -0.9398)
			(end -0.508 -0.9398)
			(stroke
				(width 0.1524)
				(type default)
			)
			(layer "F.SilkS")
		)
		(fp_line
			(start -0.508 -0.9398)
			(end -0.508 0.9398)
			(stroke
				(width 0.1524)
				(type default)
			)
			(layer "F.SilkS")
		)
		(fp_rect
			(start -0.508 0.9398)
			(end 0.508 -0.9398)
			(stroke
				(width 0)
				(type default)
			)
			(fill no)
			(layer "F.CrtYd")
		)
		(fp_rect
			(start -0.508 0.9398)
			(end 0.508 -0.9398)
			(stroke
				(width 0)
				(type default)
			)
			(fill no)
			(layer "F.Fab")
		)
		(pad "1" smd custom
			(at 0 -0.4445 180)
			(size 0.1397 0.1397)
			(layers "F.Cu" "F.Mask" "F.Paste")
			(net "P3V3_STBY")
			(options
				(clearance outline)
				(anchor circle)
			)
			(primitives
				(gr_poly
					(pts
						(arc
							(start -0.1778 -0.2794)
							(mid -0.249642 -0.249642)
							(end -0.2794 -0.1778)
						)
						(arc
							(start -0.2794 0.1778)
							(mid -0.249642 0.249642)
							(end -0.1778 0.2794)
						)
						(arc
							(start 0.1778 0.2794)
							(mid 0.249642 0.249642)
							(end 0.2794 0.1778)
						)
						(arc
							(start 0.2794 -0.1778)
							(mid 0.249642 -0.249642)
							(end 0.1778 -0.2794)
						)
					)
					(width 0)
					(fill yes)
				)
			)
		)
		(pad "2" smd custom
			(at 0 0.4445 180)
			(size 0.1397 0.1397)
			(layers "F.Cu" "F.Mask" "F.Paste")
			(net "IO_EXP_HDD_FAULT_A1")
			(options
				(clearance outline)
				(anchor circle)
			)
			(primitives
				(gr_poly
					(pts
						(arc
							(start -0.1778 -0.2794)
							(mid -0.249642 -0.249642)
							(end -0.2794 -0.1778)
						)
						(arc
							(start -0.2794 0.1778)
							(mid -0.249642 0.249642)
							(end -0.1778 0.2794)
						)
						(arc
							(start 0.1778 0.2794)
							(mid 0.249642 0.249642)
							(end 0.2794 0.1778)
						)
						(arc
							(start 0.2794 -0.1778)
							(mid 0.249642 -0.249642)
							(end 0.1778 -0.2794)
						)
					)
					(width 0)
					(fill yes)
				)
			)
		)
	)
	(footprint ""
		(layer "F.Cu")
		(at 106.788966 -63.8556)
		(property "Reference" "SR688"
			(at 0 0 0)
			(layer "F.SilkS")
			(hide yes)
			(effects
				(font
					(size 1.27 1.27)
				)
			)
		)
		(property "Value" "4K7R2F-GP"
			(at 0.064008 -3.993896 0)
			(unlocked yes)
			(layer "F.Fab")
			(hide yes)
			(effects
				(font
					(size 1.016 1.016)
					(thickness 0.1524)
				)
			)
		)
		(property "Device Type" "R402H16"
			(at 0.064008 -5.517896 0)
			(unlocked yes)
			(layer "F.Fab")
			(hide yes)
			(effects
				(font
					(size 1.016 1.016)
					(thickness 0.1524)
				)
			)
		)
		(duplicate_pad_numbers_are_jumpers no)
		(fp_line
			(start -0.508 -0.9398)
			(end -0.508 0.9398)
			(stroke
				(width 0.1524)
				(type default)
			)
			(layer "F.SilkS")
		)
		(fp_line
			(start 0.508 -0.9398)
			(end -0.508 -0.9398)
			(stroke
				(width 0.1524)
				(type default)
			)
			(layer "F.SilkS")
		)
		(fp_rect
			(start -0.508 0.9398)
			(end 0.508 -0.9398)
			(stroke
				(width 0)
				(type default)
			)
			(fill no)
			(layer "F.CrtYd")
		)
		(fp_rect
			(start -0.508 0.9398)
			(end 0.508 -0.9398)
			(stroke
				(width 0)
				(type default)
			)
			(fill no)
			(layer "F.Fab")
		)
		(pad "1" smd custom
			(at 0 -0.4445)
			(size 0.1397 0.1397)
			(layers "F.Cu" "F.Mask" "F.Paste")
			(net "IOC_TRST_N")
			(options
				(clearance outline)
				(anchor circle)
			)
			(primitives
				(gr_poly
					(pts
						(arc
							(start -0.1778 -0.2794)
							(mid -0.249642 -0.249642)
							(end -0.2794 -0.1778)
						)
						(arc
							(start -0.2794 0.1778)
							(mid -0.249642 0.249642)
							(end -0.1778 0.2794)
						)
						(arc
							(start 0.1778 0.2794)
							(mid 0.249642 0.249642)
							(end 0.2794 0.1778)
						)
						(arc
							(start 0.2794 -0.1778)
							(mid 0.249642 -0.249642)
							(end 0.1778 -0.2794)
						)
					)
					(width 0)
					(fill yes)
				)
			)
		)
		(pad "2" smd custom
			(at 0 0.4445)
			(size 0.1397 0.1397)
			(layers "F.Cu" "F.Mask" "F.Paste")
			(net "GND")
			(options
				(clearance outline)
				(anchor circle)
			)
			(primitives
				(gr_poly
					(pts
						(arc
							(start -0.1778 -0.2794)
							(mid -0.249642 -0.249642)
							(end -0.2794 -0.1778)
						)
						(arc
							(start -0.2794 0.1778)
							(mid -0.249642 0.249642)
							(end -0.1778 0.2794)
						)
						(arc
							(start 0.1778 0.2794)
							(mid 0.249642 0.249642)
							(end 0.2794 0.1778)
						)
						(arc
							(start 0.2794 -0.1778)
							(mid 0.249642 -0.249642)
							(end 0.1778 -0.2794)
						)
					)
					(width 0)
					(fill yes)
				)
			)
		)
	)
	(footprint ""
		(layer "F.Cu")
		(at 324.866 -144.526 90)
		(property "Reference" "R1848"
			(at 0 0 90)
			(layer "F.SilkS")
			(hide yes)
			(effects
				(font
					(size 1.27 1.27)
				)
			)
		)
		(property "Value" "10MR3F-GP"
			(at -0.0254 -2.5146 90)
			(unlocked yes)
			(layer "F.Fab")
			(hide yes)
			(effects
				(font
					(size 1.016 1.016)
					(thickness 0.1524)
				)
			)
		)
		(property "Device Type" "R603H22"
			(at -0.0254 -4.0386 90)
			(unlocked yes)
			(layer "F.Fab")
			(hide yes)
			(effects
				(font
					(size 1.016 1.016)
					(thickness 0.1524)
				)
			)
		)
		(duplicate_pad_numbers_are_jumpers no)
		(fp_line
			(start 0.2032 0)
			(end 0.4826 0)
			(stroke
				(width 0.2032)
				(type default)
			)
			(layer "F.SilkS")
		)
		(fp_line
			(start -0.4826 0)
			(end -0.2032 0)
			(stroke
				(width 0.2032)
				(type default)
			)
			(layer "F.SilkS")
		)
		(fp_rect
			(start -0.5842 1.3335)
			(end 0.5842 -1.3335)
			(stroke
				(width 0)
				(type default)
			)
			(fill no)
			(layer "F.CrtYd")
		)
		(fp_rect
			(start -0.5842 1.3335)
			(end 0.5842 -1.3335)
			(stroke
				(width 0)
				(type default)
			)
			(fill no)
			(layer "F.Fab")
		)
		(pad "1" smd custom
			(at 0 -0.762 90)
			(size 0.2159 0.2159)
			(layers "F.Cu" "F.Mask" "F.Paste")
			(net "RTC_OSCI")
			(options
				(clearance outline)
				(anchor circle)
			)
			(primitives
				(gr_poly
					(pts
						(arc
							(start -0.3302 -0.4318)
							(mid -0.402042 -0.402042)
							(end -0.4318 -0.3302)
						)
						(arc
							(start -0.4318 0.3302)
							(mid -0.402042 0.402042)
							(end -0.3302 0.4318)
						)
						(arc
							(start 0.3302 0.4318)
							(mid 0.402042 0.402042)
							(end 0.4318 0.3302)
						)
						(arc
							(start 0.4318 -0.3302)
							(mid 0.402042 -0.402042)
							(end 0.3302 -0.4318)
						)
					)
					(width 0)
					(fill yes)
				)
			)
		)
		(pad "2" smd custom
			(at 0 0.762 90)
			(size 0.2159 0.2159)
			(layers "F.Cu" "F.Mask" "F.Paste")
			(net "RTC_OSCO")
			(options
				(clearance outline)
				(anchor circle)
			)
			(primitives
				(gr_poly
					(pts
						(arc
							(start -0.3302 -0.4318)
							(mid -0.402042 -0.402042)
							(end -0.4318 -0.3302)
						)
						(arc
							(start -0.4318 0.3302)
							(mid -0.402042 0.402042)
							(end -0.3302 0.4318)
						)
						(arc
							(start 0.3302 0.4318)
							(mid 0.402042 0.402042)
							(end 0.4318 0.3302)
						)
						(arc
							(start 0.4318 -0.3302)
							(mid 0.402042 -0.402042)
							(end 0.3302 -0.4318)
						)
					)
					(width 0)
					(fill yes)
				)
			)
		)
	)
	(footprint ""
		(layer "F.Cu")
		(at 289.56 -210.058 90)
		(property "Reference" "R231"
			(at 0 0 90)
			(layer "F.SilkS")
			(hide yes)
			(effects
				(font
					(size 1.27 1.27)
				)
			)
		)
		(property "Value" "1KR2F-3-GP"
			(at 0.064008 -3.993896 90)
			(unlocked yes)
			(layer "F.Fab")
			(hide yes)
			(effects
				(font
					(size 1.016 1.016)
					(thickness 0.1524)
				)
			)
		)
		(property "Device Type" "R402H16"
			(at 0.064008 -5.517896 90)
			(unlocked yes)
			(layer "F.Fab")
			(hide yes)
			(effects
				(font
					(size 1.016 1.016)
					(thickness 0.1524)
				)
			)
		)
		(duplicate_pad_numbers_are_jumpers no)
		(fp_line
			(start 0.508 -0.9398)
			(end -0.508 -0.9398)
			(stroke
				(width 0.1524)
				(type default)
			)
			(layer "F.SilkS")
		)
		(fp_line
			(start -0.508 -0.9398)
			(end -0.508 0.9398)
			(stroke
				(width 0.1524)
				(type default)
			)
			(layer "F.SilkS")
		)
		(fp_rect
			(start -0.508 0.9398)
			(end 0.508 -0.9398)
			(stroke
				(width 0)
				(type default)
			)
			(fill no)
			(layer "F.CrtYd")
		)
		(fp_rect
			(start -0.508 0.9398)
			(end 0.508 -0.9398)
			(stroke
				(width 0)
				(type default)
			)
			(fill no)
			(layer "F.Fab")
		)
		(pad "1" smd custom
			(at 0 -0.4445 90)
			(size 0.1397 0.1397)
			(layers "F.Cu" "F.Mask" "F.Paste")
			(net "P1V53_STBY")
			(options
				(clearance outline)
				(anchor circle)
			)
			(primitives
				(gr_poly
					(pts
						(arc
							(start -0.1778 -0.2794)
							(mid -0.249642 -0.249642)
							(end -0.2794 -0.1778)
						)
						(arc
							(start -0.2794 0.1778)
							(mid -0.249642 0.249642)
							(end -0.1778 0.2794)
						)
						(arc
							(start 0.1778 0.2794)
							(mid 0.249642 0.249642)
							(end 0.2794 0.1778)
						)
						(arc
							(start 0.2794 -0.1778)
							(mid 0.249642 -0.249642)
							(end 0.1778 -0.2794)
						)
					)
					(width 0)
					(fill yes)
				)
			)
		)
		(pad "2" smd custom
			(at 0 0.4445 90)
			(size 0.1397 0.1397)
			(layers "F.Cu" "F.Mask" "F.Paste")
			(net "DDR_VREF")
			(options
				(clearance outline)
				(anchor circle)
			)
			(primitives
				(gr_poly
					(pts
						(arc
							(start -0.1778 -0.2794)
							(mid -0.249642 -0.249642)
							(end -0.2794 -0.1778)
						)
						(arc
							(start -0.2794 0.1778)
							(mid -0.249642 0.249642)
							(end -0.1778 0.2794)
						)
						(arc
							(start 0.1778 0.2794)
							(mid 0.249642 0.249642)
							(end 0.2794 0.1778)
						)
						(arc
							(start 0.2794 -0.1778)
							(mid 0.249642 -0.249642)
							(end 0.1778 -0.2794)
						)
					)
					(width 0)
					(fill yes)
				)
			)
		)
	)
	(footprint ""
		(layer "F.Cu")
		(at 184.404 -228.346 90)
		(property "Reference" "R1580"
			(at 0 0 90)
			(layer "F.SilkS")
			(hide yes)
			(effects
				(font
					(size 1.27 1.27)
				)
			)
		)
		(property "Value" "33R2F-3-GP"
			(at 0.064008 -3.993896 90)
			(unlocked yes)
			(layer "F.Fab")
			(hide yes)
			(effects
				(font
					(size 1.016 1.016)
					(thickness 0.1524)
				)
			)
		)
		(property "Device Type" "R402H16"
			(at 0.064008 -5.517896 90)
			(unlocked yes)
			(layer "F.Fab")
			(hide yes)
			(effects
				(font
					(size 1.016 1.016)
					(thickness 0.1524)
				)
			)
		)
		(duplicate_pad_numbers_are_jumpers no)
		(fp_line
			(start 0.508 -0.9398)
			(end -0.508 -0.9398)
			(stroke
				(width 0.1524)
				(type default)
			)
			(layer "F.SilkS")
		)
		(fp_line
			(start -0.508 -0.9398)
			(end -0.508 0.9398)
			(stroke
				(width 0.1524)
				(type default)
			)
			(layer "F.SilkS")
		)
		(fp_rect
			(start -0.508 0.9398)
			(end 0.508 -0.9398)
			(stroke
				(width 0)
				(type default)
			)
			(fill no)
			(layer "F.CrtYd")
		)
		(fp_rect
			(start -0.508 0.9398)
			(end 0.508 -0.9398)
			(stroke
				(width 0)
				(type default)
			)
			(fill no)
			(layer "F.Fab")
		)
		(pad "1" smd custom
			(at 0 -0.4445 90)
			(size 0.1397 0.1397)
			(layers "F.Cu" "F.Mask" "F.Paste")
			(net "FP_PWR_BTN_N")
			(options
				(clearance outline)
				(anchor circle)
			)
			(primitives
				(gr_poly
					(pts
						(arc
							(start -0.1778 -0.2794)
							(mid -0.249642 -0.249642)
							(end -0.2794 -0.1778)
						)
						(arc
							(start -0.2794 0.1778)
							(mid -0.249642 0.249642)
							(end -0.1778 0.2794)
						)
						(arc
							(start 0.1778 0.2794)
							(mid 0.249642 0.249642)
							(end 0.2794 0.1778)
						)
						(arc
							(start 0.2794 -0.1778)
							(mid 0.249642 -0.249642)
							(end 0.1778 -0.2794)
						)
					)
					(width 0)
					(fill yes)
				)
			)
		)
		(pad "2" smd custom
			(at 0 0.4445 90)
			(size 0.1397 0.1397)
			(layers "F.Cu" "F.Mask" "F.Paste")
			(net "FP_PWRBTN_RC_N")
			(options
				(clearance outline)
				(anchor circle)
			)
			(primitives
				(gr_poly
					(pts
						(arc
							(start -0.1778 -0.2794)
							(mid -0.249642 -0.249642)
							(end -0.2794 -0.1778)
						)
						(arc
							(start -0.2794 0.1778)
							(mid -0.249642 0.249642)
							(end -0.1778 0.2794)
						)
						(arc
							(start 0.1778 0.2794)
							(mid 0.249642 0.249642)
							(end 0.2794 0.1778)
						)
						(arc
							(start 0.2794 -0.1778)
							(mid 0.249642 -0.249642)
							(end 0.1778 -0.2794)
						)
					)
					(width 0)
					(fill yes)
				)
			)
		)
	)
	(footprint ""
		(layer "F.Cu")
		(at 107.931966 -63.8556)
		(property "Reference" "SR681"
			(at 0 0 0)
			(layer "F.SilkS")
			(hide yes)
			(effects
				(font
					(size 1.27 1.27)
				)
			)
		)
		(property "Value" "10KR2F-2-GP"
			(at 0.064008 -3.993896 0)
			(unlocked yes)
			(layer "F.Fab")
			(hide yes)
			(effects
				(font
					(size 1.016 1.016)
					(thickness 0.1524)
				)
			)
		)
		(property "Device Type" "R402H16"
			(at 0.064008 -5.517896 0)
			(unlocked yes)
			(layer "F.Fab")
			(hide yes)
			(effects
				(font
					(size 1.016 1.016)
					(thickness 0.1524)
				)
			)
		)
		(duplicate_pad_numbers_are_jumpers no)
		(fp_line
			(start -0.508 -0.9398)
			(end -0.508 0.9398)
			(stroke
				(width 0.1524)
				(type default)
			)
			(layer "F.SilkS")
		)
		(fp_line
			(start 0.508 -0.9398)
			(end -0.508 -0.9398)
			(stroke
				(width 0.1524)
				(type default)
			)
			(layer "F.SilkS")
		)
		(fp_rect
			(start -0.508 0.9398)
			(end 0.508 -0.9398)
			(stroke
				(width 0)
				(type default)
			)
			(fill no)
			(layer "F.CrtYd")
		)
		(fp_rect
			(start -0.508 0.9398)
			(end 0.508 -0.9398)
			(stroke
				(width 0)
				(type default)
			)
			(fill no)
			(layer "F.Fab")
		)
		(pad "1" smd custom
			(at 0 -0.4445)
			(size 0.1397 0.1397)
			(layers "F.Cu" "F.Mask" "F.Paste")
			(net "LSI_SCAN_EN")
			(options
				(clearance outline)
				(anchor circle)
			)
			(primitives
				(gr_poly
					(pts
						(arc
							(start -0.1778 -0.2794)
							(mid -0.249642 -0.249642)
							(end -0.2794 -0.1778)
						)
						(arc
							(start -0.2794 0.1778)
							(mid -0.249642 0.249642)
							(end -0.1778 0.2794)
						)
						(arc
							(start 0.1778 0.2794)
							(mid 0.249642 0.249642)
							(end 0.2794 0.1778)
						)
						(arc
							(start 0.2794 -0.1778)
							(mid 0.249642 -0.249642)
							(end 0.1778 -0.2794)
						)
					)
					(width 0)
					(fill yes)
				)
			)
		)
		(pad "2" smd custom
			(at 0 0.4445)
			(size 0.1397 0.1397)
			(layers "F.Cu" "F.Mask" "F.Paste")
			(net "GND")
			(options
				(clearance outline)
				(anchor circle)
			)
			(primitives
				(gr_poly
					(pts
						(arc
							(start -0.1778 -0.2794)
							(mid -0.249642 -0.249642)
							(end -0.2794 -0.1778)
						)
						(arc
							(start -0.2794 0.1778)
							(mid -0.249642 0.249642)
							(end -0.1778 0.2794)
						)
						(arc
							(start 0.1778 0.2794)
							(mid 0.249642 0.249642)
							(end 0.2794 0.1778)
						)
						(arc
							(start 0.2794 -0.1778)
							(mid 0.249642 -0.249642)
							(end 0.1778 -0.2794)
						)
					)
					(width 0)
					(fill yes)
				)
			)
		)
	)
	(footprint ""
		(layer "F.Cu")
		(at 329.556872 -214.702136 180)
		(property "Reference" "R182"
			(at 0 0 180)
			(layer "F.SilkS")
			(hide yes)
			(effects
				(font
					(size 1.27 1.27)
				)
			)
		)
		(property "Value" "0R2J-2-GP"
			(at 0.064008 -3.993896 180)
			(unlocked yes)
			(layer "F.Fab")
			(hide yes)
			(effects
				(font
					(size 1.016 1.016)
					(thickness 0.1524)
				)
			)
		)
		(property "Device Type" "R402H16"
			(at 0.064008 -5.517896 180)
			(unlocked yes)
			(layer "F.Fab")
			(hide yes)
			(effects
				(font
					(size 1.016 1.016)
					(thickness 0.1524)
				)
			)
		)
		(duplicate_pad_numbers_are_jumpers no)
		(fp_line
			(start 0.508 -0.9398)
			(end -0.508 -0.9398)
			(stroke
				(width 0.1524)
				(type default)
			)
			(layer "F.SilkS")
		)
		(fp_line
			(start -0.508 -0.9398)
			(end -0.508 0.9398)
			(stroke
				(width 0.1524)
				(type default)
			)
			(layer "F.SilkS")
		)
		(fp_rect
			(start -0.508 0.9398)
			(end 0.508 -0.9398)
			(stroke
				(width 0)
				(type default)
			)
			(fill no)
			(layer "F.CrtYd")
		)
		(fp_rect
			(start -0.508 0.9398)
			(end 0.508 -0.9398)
			(stroke
				(width 0)
				(type default)
			)
			(fill no)
			(layer "F.Fab")
		)
		(pad "1" smd custom
			(at 0 -0.4445 180)
			(size 0.1397 0.1397)
			(layers "F.Cu" "F.Mask" "F.Paste")
			(net "ADC_P1V8_STBY")
			(options
				(clearance outline)
				(anchor circle)
			)
			(primitives
				(gr_poly
					(pts
						(arc
							(start -0.1778 -0.2794)
							(mid -0.249642 -0.249642)
							(end -0.2794 -0.1778)
						)
						(arc
							(start -0.2794 0.1778)
							(mid -0.249642 0.249642)
							(end -0.1778 0.2794)
						)
						(arc
							(start 0.1778 0.2794)
							(mid 0.249642 0.249642)
							(end 0.2794 0.1778)
						)
						(arc
							(start 0.2794 -0.1778)
							(mid 0.249642 -0.249642)
							(end 0.1778 -0.2794)
						)
					)
					(width 0)
					(fill yes)
				)
			)
		)
		(pad "2" smd custom
			(at 0 0.4445 180)
			(size 0.1397 0.1397)
			(layers "F.Cu" "F.Mask" "F.Paste")
			(net "1V8_STBY_SENSE")
			(options
				(clearance outline)
				(anchor circle)
			)
			(primitives
				(gr_poly
					(pts
						(arc
							(start -0.1778 -0.2794)
							(mid -0.249642 -0.249642)
							(end -0.2794 -0.1778)
						)
						(arc
							(start -0.2794 0.1778)
							(mid -0.249642 0.249642)
							(end -0.1778 0.2794)
						)
						(arc
							(start 0.1778 0.2794)
							(mid 0.249642 0.249642)
							(end 0.2794 0.1778)
						)
						(arc
							(start 0.2794 -0.1778)
							(mid 0.249642 -0.249642)
							(end 0.1778 -0.2794)
						)
					)
					(width 0)
					(fill yes)
				)
			)
		)
	)
	(footprint ""
		(layer "F.Cu")
		(at 317.627 -176.276)
		(property "Reference" "C191"
			(at 0 0 0)
			(layer "F.SilkS")
			(hide yes)
			(effects
				(font
					(size 1.27 1.27)
				)
			)
		)
		(property "Value" "SCD1U16V2KX-3GP"
			(at 1.1811 -2.7051 0)
			(unlocked yes)
			(layer "F.Fab")
			(hide yes)
			(effects
				(font
					(size 1.016 1.016)
					(thickness 0.1524)
				)
			)
		)
		(property "Device Type" "C402H22"
			(at 1.1811 -4.2291 0)
			(unlocked yes)
			(layer "F.Fab")
			(hide yes)
			(effects
				(font
					(size 1.016 1.016)
					(thickness 0.1524)
				)
			)
		)
		(duplicate_pad_numbers_are_jumpers no)
		(fp_rect
			(start -0.4318 0.9525)
			(end 0.4318 -0.9525)
			(stroke
				(width 0)
				(type default)
			)
			(fill no)
			(layer "F.CrtYd")
		)
		(fp_rect
			(start -0.4318 0.9525)
			(end 0.4318 -0.9525)
			(stroke
				(width 0)
				(type default)
			)
			(fill no)
			(layer "F.Fab")
		)
		(pad "1" smd custom
			(at 0 -0.4445)
			(size 0.1524 0.1524)
			(layers "F.Cu" "F.Mask" "F.Paste")
			(net "ADCVREFFN")
			(options
				(clearance outline)
				(anchor circle)
			)
			(primitives
				(gr_poly
					(pts
						(arc
							(start 0.3048 -0.2032)
							(mid 0.275042 -0.275042)
							(end 0.2032 -0.3048)
						)
						(arc
							(start -0.2032 -0.3048)
							(mid -0.275042 -0.275042)
							(end -0.3048 -0.2032)
						)
						(arc
							(start -0.3048 0.2032)
							(mid -0.275042 0.275042)
							(end -0.2032 0.3048)
						)
						(arc
							(start 0.2032 0.3048)
							(mid 0.275042 0.275042)
							(end 0.3048 0.2032)
						)
					)
					(width 0)
					(fill yes)
				)
			)
		)
		(pad "2" smd custom
			(at 0 0.4445)
			(size 0.1524 0.1524)
			(layers "F.Cu" "F.Mask" "F.Paste")
			(net "ADCVREFFP")
			(options
				(clearance outline)
				(anchor circle)
			)
			(primitives
				(gr_poly
					(pts
						(arc
							(start 0.3048 -0.2032)
							(mid 0.275042 -0.275042)
							(end 0.2032 -0.3048)
						)
						(arc
							(start -0.2032 -0.3048)
							(mid -0.275042 -0.275042)
							(end -0.3048 -0.2032)
						)
						(arc
							(start -0.3048 0.2032)
							(mid -0.275042 0.275042)
							(end -0.2032 0.3048)
						)
						(arc
							(start 0.2032 0.3048)
							(mid 0.275042 0.275042)
							(end 0.3048 0.2032)
						)
					)
					(width 0)
					(fill yes)
				)
			)
		)
	)
	(footprint ""
		(layer "F.Cu")
		(at 302.387 -222.377 -90)
		(property "Reference" "R638"
			(at 0 0 270)
			(layer "F.SilkS")
			(hide yes)
			(effects
				(font
					(size 1.27 1.27)
				)
			)
		)
		(property "Value" "4K7R2F-GP"
			(at 0.064008 -3.993896 270)
			(unlocked yes)
			(layer "F.Fab")
			(hide yes)
			(effects
				(font
					(size 1.016 1.016)
					(thickness 0.1524)
				)
			)
		)
		(property "Device Type" "R402H16"
			(at 0.064008 -5.517896 270)
			(unlocked yes)
			(layer "F.Fab")
			(hide yes)
			(effects
				(font
					(size 1.016 1.016)
					(thickness 0.1524)
				)
			)
		)
		(duplicate_pad_numbers_are_jumpers no)
		(fp_line
			(start -0.508 -0.9398)
			(end -0.508 0.9398)
			(stroke
				(width 0.1524)
				(type default)
			)
			(layer "F.SilkS")
		)
		(fp_line
			(start 0.508 -0.9398)
			(end -0.508 -0.9398)
			(stroke
				(width 0.1524)
				(type default)
			)
			(layer "F.SilkS")
		)
		(fp_rect
			(start -0.508 0.9398)
			(end 0.508 -0.9398)
			(stroke
				(width 0)
				(type default)
			)
			(fill no)
			(layer "F.CrtYd")
		)
		(fp_rect
			(start -0.508 0.9398)
			(end 0.508 -0.9398)
			(stroke
				(width 0)
				(type default)
			)
			(fill no)
			(layer "F.Fab")
		)
		(pad "1" smd custom
			(at 0 -0.4445 270)
			(size 0.1397 0.1397)
			(layers "F.Cu" "F.Mask" "F.Paste")
			(net "P3V3_STBY")
			(options
				(clearance outline)
				(anchor circle)
			)
			(primitives
				(gr_poly
					(pts
						(arc
							(start -0.1778 -0.2794)
							(mid -0.249642 -0.249642)
							(end -0.2794 -0.1778)
						)
						(arc
							(start -0.2794 0.1778)
							(mid -0.249642 0.249642)
							(end -0.1778 0.2794)
						)
						(arc
							(start 0.1778 0.2794)
							(mid 0.249642 0.249642)
							(end 0.2794 0.1778)
						)
						(arc
							(start 0.2794 -0.1778)
							(mid 0.249642 -0.249642)
							(end 0.1778 -0.2794)
						)
					)
					(width 0)
					(fill yes)
				)
			)
		)
		(pad "2" smd custom
			(at 0 0.4445 270)
			(size 0.1397 0.1397)
			(layers "F.Cu" "F.Mask" "F.Paste")
			(net "DEBUG_OE_1_N")
			(options
				(clearance outline)
				(anchor circle)
			)
			(primitives
				(gr_poly
					(pts
						(arc
							(start -0.1778 -0.2794)
							(mid -0.249642 -0.249642)
							(end -0.2794 -0.1778)
						)
						(arc
							(start -0.2794 0.1778)
							(mid -0.249642 0.249642)
							(end -0.1778 0.2794)
						)
						(arc
							(start 0.1778 0.2794)
							(mid 0.249642 0.249642)
							(end 0.2794 0.1778)
						)
						(arc
							(start 0.2794 -0.1778)
							(mid 0.249642 -0.249642)
							(end 0.1778 -0.2794)
						)
					)
					(width 0)
					(fill yes)
				)
			)
		)
	)
	(footprint ""
		(layer "F.Cu")
		(at 316.611 -115.824 90)
		(property "Reference" "PR32"
			(at 0 0 90)
			(layer "F.SilkS")
			(hide yes)
			(effects
				(font
					(size 1.27 1.27)
				)
			)
		)
		(property "Value" "866KR2F-GP"
			(at 0.064008 -3.993896 90)
			(unlocked yes)
			(layer "F.Fab")
			(hide yes)
			(effects
				(font
					(size 1.016 1.016)
					(thickness 0.1524)
				)
			)
		)
		(property "Device Type" "R402H16"
			(at 0.064008 -5.517896 90)
			(unlocked yes)
			(layer "F.Fab")
			(hide yes)
			(effects
				(font
					(size 1.016 1.016)
					(thickness 0.1524)
				)
			)
		)
		(duplicate_pad_numbers_are_jumpers no)
		(fp_line
			(start 0.508 -0.9398)
			(end -0.508 -0.9398)
			(stroke
				(width 0.1524)
				(type default)
			)
			(layer "F.SilkS")
		)
		(fp_line
			(start -0.508 -0.9398)
			(end -0.508 0.9398)
			(stroke
				(width 0.1524)
				(type default)
			)
			(layer "F.SilkS")
		)
		(fp_rect
			(start -0.508 0.9398)
			(end 0.508 -0.9398)
			(stroke
				(width 0)
				(type default)
			)
			(fill no)
			(layer "F.CrtYd")
		)
		(fp_rect
			(start -0.508 0.9398)
			(end 0.508 -0.9398)
			(stroke
				(width 0)
				(type default)
			)
			(fill no)
			(layer "F.Fab")
		)
		(pad "1" smd custom
			(at 0 -0.4445 90)
			(size 0.1397 0.1397)
			(layers "F.Cu" "F.Mask" "F.Paste")
			(net "P3V3_STBY_VREG")
			(options
				(clearance outline)
				(anchor circle)
			)
			(primitives
				(gr_poly
					(pts
						(arc
							(start -0.1778 -0.2794)
							(mid -0.249642 -0.249642)
							(end -0.2794 -0.1778)
						)
						(arc
							(start -0.2794 0.1778)
							(mid -0.249642 0.249642)
							(end -0.1778 0.2794)
						)
						(arc
							(start 0.1778 0.2794)
							(mid 0.249642 0.249642)
							(end 0.2794 0.1778)
						)
						(arc
							(start 0.2794 -0.1778)
							(mid 0.249642 -0.249642)
							(end 0.1778 -0.2794)
						)
					)
					(width 0)
					(fill yes)
				)
			)
		)
		(pad "2" smd custom
			(at 0 0.4445 90)
			(size 0.1397 0.1397)
			(layers "F.Cu" "F.Mask" "F.Paste")
			(net "P3V3_STBY_RF")
			(options
				(clearance outline)
				(anchor circle)
			)
			(primitives
				(gr_poly
					(pts
						(arc
							(start -0.1778 -0.2794)
							(mid -0.249642 -0.249642)
							(end -0.2794 -0.1778)
						)
						(arc
							(start -0.2794 0.1778)
							(mid -0.249642 0.249642)
							(end -0.1778 0.2794)
						)
						(arc
							(start 0.1778 0.2794)
							(mid 0.249642 0.249642)
							(end 0.2794 0.1778)
						)
						(arc
							(start 0.2794 -0.1778)
							(mid 0.249642 -0.249642)
							(end 0.1778 -0.2794)
						)
					)
					(width 0)
					(fill yes)
				)
			)
		)
	)
	(footprint ""
		(layer "F.Cu")
		(at 173.473872 -196.083936 180)
		(property "Reference" "R431"
			(at 0 0 180)
			(layer "F.SilkS")
			(hide yes)
			(effects
				(font
					(size 1.27 1.27)
				)
			)
		)
		(property "Value" "0R2J-2-GP"
			(at 0.064008 -3.993896 180)
			(unlocked yes)
			(layer "F.Fab")
			(hide yes)
			(effects
				(font
					(size 1.016 1.016)
					(thickness 0.1524)
				)
			)
		)
		(property "Device Type" "R402H16"
			(at 0.064008 -5.517896 180)
			(unlocked yes)
			(layer "F.Fab")
			(hide yes)
			(effects
				(font
					(size 1.016 1.016)
					(thickness 0.1524)
				)
			)
		)
		(duplicate_pad_numbers_are_jumpers no)
		(fp_line
			(start 0.508 -0.9398)
			(end -0.508 -0.9398)
			(stroke
				(width 0.1524)
				(type default)
			)
			(layer "F.SilkS")
		)
		(fp_line
			(start -0.508 -0.9398)
			(end -0.508 0.9398)
			(stroke
				(width 0.1524)
				(type default)
			)
			(layer "F.SilkS")
		)
		(fp_rect
			(start -0.508 0.9398)
			(end 0.508 -0.9398)
			(stroke
				(width 0)
				(type default)
			)
			(fill no)
			(layer "F.CrtYd")
		)
		(fp_rect
			(start -0.508 0.9398)
			(end 0.508 -0.9398)
			(stroke
				(width 0)
				(type default)
			)
			(fill no)
			(layer "F.Fab")
		)
		(pad "1" smd custom
			(at 0 -0.4445 180)
			(size 0.1397 0.1397)
			(layers "F.Cu" "F.Mask" "F.Paste")
			(net "SAS_I2C_C_BUF_SCL")
			(options
				(clearance outline)
				(anchor circle)
			)
			(primitives
				(gr_poly
					(pts
						(arc
							(start -0.1778 -0.2794)
							(mid -0.249642 -0.249642)
							(end -0.2794 -0.1778)
						)
						(arc
							(start -0.2794 0.1778)
							(mid -0.249642 0.249642)
							(end -0.1778 0.2794)
						)
						(arc
							(start 0.1778 0.2794)
							(mid 0.249642 0.249642)
							(end 0.2794 0.1778)
						)
						(arc
							(start 0.2794 -0.1778)
							(mid 0.249642 -0.249642)
							(end 0.1778 -0.2794)
						)
					)
					(width 0)
					(fill yes)
				)
			)
		)
		(pad "2" smd custom
			(at 0 0.4445 180)
			(size 0.1397 0.1397)
			(layers "F.Cu" "F.Mask" "F.Paste")
			(net "BMC_I2C_C_SCL")
			(options
				(clearance outline)
				(anchor circle)
			)
			(primitives
				(gr_poly
					(pts
						(arc
							(start -0.1778 -0.2794)
							(mid -0.249642 -0.249642)
							(end -0.2794 -0.1778)
						)
						(arc
							(start -0.2794 0.1778)
							(mid -0.249642 0.249642)
							(end -0.1778 0.2794)
						)
						(arc
							(start 0.1778 0.2794)
							(mid 0.249642 0.249642)
							(end 0.2794 0.1778)
						)
						(arc
							(start 0.2794 -0.1778)
							(mid 0.249642 -0.249642)
							(end 0.1778 -0.2794)
						)
					)
					(width 0)
					(fill yes)
				)
			)
		)
	)
	(footprint ""
		(layer "F.Cu")
		(at 308.102 -180.975)
		(property "Reference" "TP100"
			(at 0 0 0)
			(layer "F.SilkS")
			(hide yes)
			(effects
				(font
					(size 1.27 1.27)
				)
			)
		)
		(property "Value" "TPAD28"
			(at 0.0127 -1.8034 0)
			(unlocked yes)
			(layer "F.Fab")
			(hide yes)
			(effects
				(font
					(size 1.016 1.016)
					(thickness 0.1524)
				)
			)
		)
		(property "Device Type" "TPAD28"
			(at 0.0127 -3.3274 0)
			(unlocked yes)
			(layer "F.Fab")
			(hide yes)
			(effects
				(font
					(size 1.016 1.016)
					(thickness 0.1524)
				)
			)
		)
		(duplicate_pad_numbers_are_jumpers no)
		(fp_poly
			(pts
				(arc
					(start 0.3556 0)
					(mid -0.3556 0)
					(end 0.3556 0)
				)
			)
			(stroke
				(width 0)
				(type default)
			)
			(fill no)
			(layer "F.CrtYd")
		)
		(fp_poly
			(pts
				(arc
					(start 0.6096 0)
					(mid -0.6096 0)
					(end 0.6096 0)
				)
			)
			(stroke
				(width 0)
				(type default)
			)
			(fill no)
			(layer "F.Fab")
		)
		(pad "1" smd circle
			(at 0 0)
			(size 0.7112 0.7112)
			(layers "F.Cu" "F.Mask" "F.Paste")
			(net "TP_BMC_GPIOL3")
		)
	)
	(footprint ""
		(layer "F.Cu")
		(at 165.598856 -112.404652)
		(property "Reference" "PC187"
			(at 0 0 0)
			(layer "F.SilkS")
			(hide yes)
			(effects
				(font
					(size 1.27 1.27)
				)
			)
		)
		(property "Value" "SC1U10V2KX-1GP"
			(at 1.1811 -2.7051 0)
			(unlocked yes)
			(layer "F.Fab")
			(hide yes)
			(effects
				(font
					(size 1.016 1.016)
					(thickness 0.1524)
				)
			)
		)
		(property "Device Type" "C402H22"
			(at 1.1811 -4.2291 0)
			(unlocked yes)
			(layer "F.Fab")
			(hide yes)
			(effects
				(font
					(size 1.016 1.016)
					(thickness 0.1524)
				)
			)
		)
		(duplicate_pad_numbers_are_jumpers no)
		(fp_rect
			(start -0.4318 0.9525)
			(end 0.4318 -0.9525)
			(stroke
				(width 0)
				(type default)
			)
			(fill no)
			(layer "F.CrtYd")
		)
		(fp_rect
			(start -0.4318 0.9525)
			(end 0.4318 -0.9525)
			(stroke
				(width 0)
				(type default)
			)
			(fill no)
			(layer "F.Fab")
		)
		(pad "1" smd custom
			(at 0 -0.4445)
			(size 0.1524 0.1524)
			(layers "F.Cu" "F.Mask" "F.Paste")
			(net "GND")
			(options
				(clearance outline)
				(anchor circle)
			)
			(primitives
				(gr_poly
					(pts
						(arc
							(start 0.3048 -0.2032)
							(mid 0.275042 -0.275042)
							(end 0.2032 -0.3048)
						)
						(arc
							(start -0.2032 -0.3048)
							(mid -0.275042 -0.275042)
							(end -0.3048 -0.2032)
						)
						(arc
							(start -0.3048 0.2032)
							(mid -0.275042 0.275042)
							(end -0.2032 0.3048)
						)
						(arc
							(start 0.2032 0.3048)
							(mid 0.275042 0.275042)
							(end 0.3048 0.2032)
						)
					)
					(width 0)
					(fill yes)
				)
			)
		)
		(pad "2" smd custom
			(at 0 0.4445)
			(size 0.1524 0.1524)
			(layers "F.Cu" "F.Mask" "F.Paste")
			(net "P0V9_E_EN")
			(options
				(clearance outline)
				(anchor circle)
			)
			(primitives
				(gr_poly
					(pts
						(arc
							(start 0.3048 -0.2032)
							(mid 0.275042 -0.275042)
							(end 0.2032 -0.3048)
						)
						(arc
							(start -0.2032 -0.3048)
							(mid -0.275042 -0.275042)
							(end -0.3048 -0.2032)
						)
						(arc
							(start -0.3048 0.2032)
							(mid -0.275042 0.275042)
							(end -0.2032 0.3048)
						)
						(arc
							(start 0.2032 0.3048)
							(mid 0.275042 0.275042)
							(end 0.3048 0.2032)
						)
					)
					(width 0)
					(fill yes)
				)
			)
		)
	)
	(footprint ""
		(layer "F.Cu")
		(at 308.791864 -205.096872)
		(property "Reference" "R168"
			(at 0 0 0)
			(layer "F.SilkS")
			(hide yes)
			(effects
				(font
					(size 1.27 1.27)
				)
			)
		)
		(property "Value" "0R2J-2-GP"
			(at 0.064008 -3.993896 0)
			(unlocked yes)
			(layer "F.Fab")
			(hide yes)
			(effects
				(font
					(size 1.016 1.016)
					(thickness 0.1524)
				)
			)
		)
		(property "Device Type" "R402H16"
			(at 0.064008 -5.517896 0)
			(unlocked yes)
			(layer "F.Fab")
			(hide yes)
			(effects
				(font
					(size 1.016 1.016)
					(thickness 0.1524)
				)
			)
		)
		(duplicate_pad_numbers_are_jumpers no)
		(fp_line
			(start -0.508 -0.9398)
			(end -0.508 0.9398)
			(stroke
				(width 0.1524)
				(type default)
			)
			(layer "F.SilkS")
		)
		(fp_line
			(start 0.508 -0.9398)
			(end -0.508 -0.9398)
			(stroke
				(width 0.1524)
				(type default)
			)
			(layer "F.SilkS")
		)
		(fp_rect
			(start -0.508 0.9398)
			(end 0.508 -0.9398)
			(stroke
				(width 0)
				(type default)
			)
			(fill no)
			(layer "F.CrtYd")
		)
		(fp_rect
			(start -0.508 0.9398)
			(end 0.508 -0.9398)
			(stroke
				(width 0)
				(type default)
			)
			(fill no)
			(layer "F.Fab")
		)
		(pad "1" smd custom
			(at 0 -0.4445)
			(size 0.1397 0.1397)
			(layers "F.Cu" "F.Mask" "F.Paste")
			(net "BMC_I2C_A_SCL")
			(options
				(clearance outline)
				(anchor circle)
			)
			(primitives
				(gr_poly
					(pts
						(arc
							(start -0.1778 -0.2794)
							(mid -0.249642 -0.249642)
							(end -0.2794 -0.1778)
						)
						(arc
							(start -0.2794 0.1778)
							(mid -0.249642 0.249642)
							(end -0.1778 0.2794)
						)
						(arc
							(start 0.1778 0.2794)
							(mid 0.249642 0.249642)
							(end 0.2794 0.1778)
						)
						(arc
							(start 0.2794 -0.1778)
							(mid 0.249642 -0.249642)
							(end 0.1778 -0.2794)
						)
					)
					(width 0)
					(fill yes)
				)
			)
		)
		(pad "2" smd custom
			(at 0 0.4445)
			(size 0.1397 0.1397)
			(layers "F.Cu" "F.Mask" "F.Paste")
			(net "LED_DR_I2C_SCL")
			(options
				(clearance outline)
				(anchor circle)
			)
			(primitives
				(gr_poly
					(pts
						(arc
							(start -0.1778 -0.2794)
							(mid -0.249642 -0.249642)
							(end -0.2794 -0.1778)
						)
						(arc
							(start -0.2794 0.1778)
							(mid -0.249642 0.249642)
							(end -0.1778 0.2794)
						)
						(arc
							(start 0.1778 0.2794)
							(mid 0.249642 0.249642)
							(end 0.2794 0.1778)
						)
						(arc
							(start 0.2794 -0.1778)
							(mid 0.249642 -0.249642)
							(end 0.1778 -0.2794)
						)
					)
					(width 0)
					(fill yes)
				)
			)
		)
	)
	(footprint ""
		(layer "F.Cu")
		(at 279.772872 -215.591136 180)
		(property "Reference" "R456"
			(at 0 0 180)
			(layer "F.SilkS")
			(hide yes)
			(effects
				(font
					(size 1.27 1.27)
				)
			)
		)
		(property "Value" "4K75R2F-1-GP"
			(at 0.064008 -3.993896 180)
			(unlocked yes)
			(layer "F.Fab")
			(hide yes)
			(effects
				(font
					(size 1.016 1.016)
					(thickness 0.1524)
				)
			)
		)
		(property "Device Type" "R402H16"
			(at 0.064008 -5.517896 180)
			(unlocked yes)
			(layer "F.Fab")
			(hide yes)
			(effects
				(font
					(size 1.016 1.016)
					(thickness 0.1524)
				)
			)
		)
		(duplicate_pad_numbers_are_jumpers no)
		(fp_line
			(start 0.508 -0.9398)
			(end -0.508 -0.9398)
			(stroke
				(width 0.1524)
				(type default)
			)
			(layer "F.SilkS")
		)
		(fp_line
			(start -0.508 -0.9398)
			(end -0.508 0.9398)
			(stroke
				(width 0.1524)
				(type default)
			)
			(layer "F.SilkS")
		)
		(fp_rect
			(start -0.508 0.9398)
			(end 0.508 -0.9398)
			(stroke
				(width 0)
				(type default)
			)
			(fill no)
			(layer "F.CrtYd")
		)
		(fp_rect
			(start -0.508 0.9398)
			(end 0.508 -0.9398)
			(stroke
				(width 0)
				(type default)
			)
			(fill no)
			(layer "F.Fab")
		)
		(pad "1" smd custom
			(at 0 -0.4445 180)
			(size 0.1397 0.1397)
			(layers "F.Cu" "F.Mask" "F.Paste")
			(net "P3V3_STBY")
			(options
				(clearance outline)
				(anchor circle)
			)
			(primitives
				(gr_poly
					(pts
						(arc
							(start -0.1778 -0.2794)
							(mid -0.249642 -0.249642)
							(end -0.2794 -0.1778)
						)
						(arc
							(start -0.2794 0.1778)
							(mid -0.249642 0.249642)
							(end -0.1778 0.2794)
						)
						(arc
							(start 0.1778 0.2794)
							(mid 0.249642 0.249642)
							(end 0.2794 0.1778)
						)
						(arc
							(start 0.2794 -0.1778)
							(mid 0.249642 -0.249642)
							(end 0.1778 -0.2794)
						)
					)
					(width 0)
					(fill yes)
				)
			)
		)
		(pad "2" smd custom
			(at 0 0.4445 180)
			(size 0.1397 0.1397)
			(layers "F.Cu" "F.Mask" "F.Paste")
			(net "TPS74801_1V53_STBY_EN")
			(options
				(clearance outline)
				(anchor circle)
			)
			(primitives
				(gr_poly
					(pts
						(arc
							(start -0.1778 -0.2794)
							(mid -0.249642 -0.249642)
							(end -0.2794 -0.1778)
						)
						(arc
							(start -0.2794 0.1778)
							(mid -0.249642 0.249642)
							(end -0.1778 0.2794)
						)
						(arc
							(start 0.1778 0.2794)
							(mid 0.249642 0.249642)
							(end 0.2794 0.1778)
						)
						(arc
							(start 0.2794 -0.1778)
							(mid 0.249642 -0.249642)
							(end 0.1778 -0.2794)
						)
					)
					(width 0)
					(fill yes)
				)
			)
		)
	)
	(footprint ""
		(layer "F.Cu")
		(at 76.816966 -84.328 -90)
		(property "Reference" "SC1226"
			(at 0 0 270)
			(layer "F.SilkS")
			(hide yes)
			(effects
				(font
					(size 1.27 1.27)
				)
			)
		)
		(property "Value" "SCD1U6D3V1KX-GP"
			(at -2.8321 -1.7399 270)
			(unlocked yes)
			(layer "F.Fab")
			(hide yes)
			(effects
				(font
					(size 1.016 1.016)
					(thickness 0.1524)
				)
			)
		)
		(property "Device Type" "C0201H13"
			(at -2.8321 -3.2639 270)
			(unlocked yes)
			(layer "F.Fab")
			(hide yes)
			(effects
				(font
					(size 1.016 1.016)
					(thickness 0.1524)
				)
			)
		)
		(duplicate_pad_numbers_are_jumpers no)
		(fp_rect
			(start -0.2794 0.6477)
			(end 0.2794 -0.6477)
			(stroke
				(width 0)
				(type default)
			)
			(fill no)
			(layer "F.CrtYd")
		)
		(fp_rect
			(start -0.2794 0.6477)
			(end 0.2794 -0.6477)
			(stroke
				(width 0)
				(type default)
			)
			(fill no)
			(layer "F.Fab")
		)
		(pad "1" smd custom
			(at 0 -0.2794 270)
			(size 0.0762 0.0762)
			(layers "F.Cu" "F.Mask" "F.Paste")
			(net "P1V8_E")
			(options
				(clearance outline)
				(anchor circle)
			)
			(primitives
				(gr_poly
					(pts
						(arc
							(start 0.1524 -0.127)
							(mid 0.137521 -0.162921)
							(end 0.1016 -0.1778)
						)
						(arc
							(start -0.1016 -0.1778)
							(mid -0.137521 -0.162921)
							(end -0.1524 -0.127)
						)
						(arc
							(start -0.1524 0.127)
							(mid -0.137521 0.162921)
							(end -0.1016 0.1778)
						)
						(arc
							(start 0.1016 0.1778)
							(mid 0.137521 0.162921)
							(end 0.1524 0.127)
						)
					)
					(width 0)
					(fill yes)
				)
			)
		)
		(pad "2" smd custom
			(at 0 0.2794 270)
			(size 0.0762 0.0762)
			(layers "F.Cu" "F.Mask" "F.Paste")
			(net "GND")
			(options
				(clearance outline)
				(anchor circle)
			)
			(primitives
				(gr_poly
					(pts
						(arc
							(start 0.1524 -0.127)
							(mid 0.137521 -0.162921)
							(end 0.1016 -0.1778)
						)
						(arc
							(start -0.1016 -0.1778)
							(mid -0.137521 -0.162921)
							(end -0.1524 -0.127)
						)
						(arc
							(start -0.1524 0.127)
							(mid -0.137521 0.162921)
							(end -0.1016 0.1778)
						)
						(arc
							(start 0.1016 0.1778)
							(mid 0.137521 0.162921)
							(end 0.1524 0.127)
						)
					)
					(width 0)
					(fill yes)
				)
			)
		)
	)
	(footprint ""
		(layer "F.Cu")
		(at 223.393 -22.733)
		(property "Reference" "R7892"
			(at 0 0 0)
			(layer "F.SilkS")
			(hide yes)
			(effects
				(font
					(size 1.27 1.27)
				)
			)
		)
		(property "Value" "0R2J-2-GP"
			(at 0.064008 -3.993896 0)
			(unlocked yes)
			(layer "F.Fab")
			(hide yes)
			(effects
				(font
					(size 1.016 1.016)
					(thickness 0.1524)
				)
			)
		)
		(property "Device Type" "R402H16"
			(at 0.064008 -5.517896 0)
			(unlocked yes)
			(layer "F.Fab")
			(hide yes)
			(effects
				(font
					(size 1.016 1.016)
					(thickness 0.1524)
				)
			)
		)
		(duplicate_pad_numbers_are_jumpers no)
		(fp_line
			(start -0.508 -0.9398)
			(end -0.508 0.9398)
			(stroke
				(width 0.1524)
				(type default)
			)
			(layer "F.SilkS")
		)
		(fp_line
			(start 0.508 -0.9398)
			(end -0.508 -0.9398)
			(stroke
				(width 0.1524)
				(type default)
			)
			(layer "F.SilkS")
		)
		(fp_rect
			(start -0.508 0.9398)
			(end 0.508 -0.9398)
			(stroke
				(width 0)
				(type default)
			)
			(fill no)
			(layer "F.CrtYd")
		)
		(fp_rect
			(start -0.508 0.9398)
			(end 0.508 -0.9398)
			(stroke
				(width 0)
				(type default)
			)
			(fill no)
			(layer "F.Fab")
		)
		(pad "1" smd custom
			(at 0 -0.4445)
			(size 0.1397 0.1397)
			(layers "F.Cu" "F.Mask" "F.Paste")
			(net "LED_DR_LED1")
			(options
				(clearance outline)
				(anchor circle)
			)
			(primitives
				(gr_poly
					(pts
						(arc
							(start -0.1778 -0.2794)
							(mid -0.249642 -0.249642)
							(end -0.2794 -0.1778)
						)
						(arc
							(start -0.2794 0.1778)
							(mid -0.249642 0.249642)
							(end -0.1778 0.2794)
						)
						(arc
							(start 0.1778 0.2794)
							(mid 0.249642 0.249642)
							(end 0.2794 0.1778)
						)
						(arc
							(start 0.2794 -0.1778)
							(mid 0.249642 -0.249642)
							(end 0.1778 -0.2794)
						)
					)
					(width 0)
					(fill yes)
				)
			)
		)
		(pad "2" smd custom
			(at 0 0.4445)
			(size 0.1397 0.1397)
			(layers "F.Cu" "F.Mask" "F.Paste")
			(net "LED_PWR_N_ON")
			(options
				(clearance outline)
				(anchor circle)
			)
			(primitives
				(gr_poly
					(pts
						(arc
							(start -0.1778 -0.2794)
							(mid -0.249642 -0.249642)
							(end -0.2794 -0.1778)
						)
						(arc
							(start -0.2794 0.1778)
							(mid -0.249642 0.249642)
							(end -0.1778 0.2794)
						)
						(arc
							(start 0.1778 0.2794)
							(mid 0.249642 0.249642)
							(end 0.2794 0.1778)
						)
						(arc
							(start 0.2794 -0.1778)
							(mid 0.249642 -0.249642)
							(end 0.1778 -0.2794)
						)
					)
					(width 0)
					(fill yes)
				)
			)
		)
	)
	(footprint ""
		(layer "F.Cu")
		(at 160.02 -149.479 -90)
		(property "Reference" "SR725"
			(at 0 0 270)
			(layer "F.SilkS")
			(hide yes)
			(effects
				(font
					(size 1.27 1.27)
				)
			)
		)
		(property "Value" "4K7R2F-GP"
			(at 0.064008 -3.993896 270)
			(unlocked yes)
			(layer "F.Fab")
			(hide yes)
			(effects
				(font
					(size 1.016 1.016)
					(thickness 0.1524)
				)
			)
		)
		(property "Device Type" "R402H16"
			(at 0.064008 -5.517896 270)
			(unlocked yes)
			(layer "F.Fab")
			(hide yes)
			(effects
				(font
					(size 1.016 1.016)
					(thickness 0.1524)
				)
			)
		)
		(duplicate_pad_numbers_are_jumpers no)
		(fp_line
			(start -0.508 -0.9398)
			(end -0.508 0.9398)
			(stroke
				(width 0.1524)
				(type default)
			)
			(layer "F.SilkS")
		)
		(fp_line
			(start 0.508 -0.9398)
			(end -0.508 -0.9398)
			(stroke
				(width 0.1524)
				(type default)
			)
			(layer "F.SilkS")
		)
		(fp_rect
			(start -0.508 0.9398)
			(end 0.508 -0.9398)
			(stroke
				(width 0)
				(type default)
			)
			(fill no)
			(layer "F.CrtYd")
		)
		(fp_rect
			(start -0.508 0.9398)
			(end 0.508 -0.9398)
			(stroke
				(width 0)
				(type default)
			)
			(fill no)
			(layer "F.Fab")
		)
		(pad "1" smd custom
			(at 0 -0.4445 270)
			(size 0.1397 0.1397)
			(layers "F.Cu" "F.Mask" "F.Paste")
			(net "IOC_P3V3_SDA_14")
			(options
				(clearance outline)
				(anchor circle)
			)
			(primitives
				(gr_poly
					(pts
						(arc
							(start -0.1778 -0.2794)
							(mid -0.249642 -0.249642)
							(end -0.2794 -0.1778)
						)
						(arc
							(start -0.2794 0.1778)
							(mid -0.249642 0.249642)
							(end -0.1778 0.2794)
						)
						(arc
							(start 0.1778 0.2794)
							(mid 0.249642 0.249642)
							(end 0.2794 0.1778)
						)
						(arc
							(start 0.2794 -0.1778)
							(mid 0.249642 -0.249642)
							(end 0.1778 -0.2794)
						)
					)
					(width 0)
					(fill yes)
				)
			)
		)
		(pad "2" smd custom
			(at 0 0.4445 270)
			(size 0.1397 0.1397)
			(layers "F.Cu" "F.Mask" "F.Paste")
			(net "P3V3")
			(options
				(clearance outline)
				(anchor circle)
			)
			(primitives
				(gr_poly
					(pts
						(arc
							(start -0.1778 -0.2794)
							(mid -0.249642 -0.249642)
							(end -0.2794 -0.1778)
						)
						(arc
							(start -0.2794 0.1778)
							(mid -0.249642 0.249642)
							(end -0.1778 0.2794)
						)
						(arc
							(start 0.1778 0.2794)
							(mid 0.249642 0.249642)
							(end 0.2794 0.1778)
						)
						(arc
							(start 0.2794 -0.1778)
							(mid 0.249642 -0.249642)
							(end 0.1778 -0.2794)
						)
					)
					(width 0)
					(fill yes)
				)
			)
		)
	)
	(footprint ""
		(layer "F.Cu")
		(at 215.080596 -102.000812 180)
		(property "Reference" "PU10"
			(at 0 0 180)
			(layer "F.SilkS")
			(hide yes)
			(effects
				(font
					(size 1.27 1.27)
				)
			)
		)
		(property "Value" "TPS74801RGW-GP"
			(at -4.7244 -6.223 180)
			(unlocked yes)
			(layer "F.Fab")
			(hide yes)
			(effects
				(font
					(size 1.016 1.016)
					(thickness 0.1524)
				)
			)
		)
		(property "Device Type" "QFN20-1G3D15H40"
			(at -4.7244 -7.747 180)
			(unlocked yes)
			(layer "F.Fab")
			(hide yes)
			(effects
				(font
					(size 1.016 1.016)
					(thickness 0.1524)
				)
			)
		)
		(duplicate_pad_numbers_are_jumpers no)
		(fp_line
			(start 3.5179 3.5179)
			(end 3.5179 2.2479)
			(stroke
				(width 0.1524)
				(type default)
			)
			(layer "F.SilkS")
		)
		(fp_line
			(start 3.160522 -1.299972)
			(end 3.922522 -1.299972)
			(stroke
				(width 0.1524)
				(type default)
			)
			(layer "F.SilkS")
		)
		(fp_line
			(start 2.2479 3.5179)
			(end 3.5179 3.5179)
			(stroke
				(width 0.1524)
				(type default)
			)
			(layer "F.SilkS")
		)
		(fp_line
			(start 1.299972 3.160522)
			(end 1.299972 3.668522)
			(stroke
				(width 0.1524)
				(type default)
			)
			(layer "F.SilkS")
		)
		(fp_line
			(start -1.299972 -3.160522)
			(end -1.299972 -3.668522)
			(stroke
				(width 0.1524)
				(type default)
			)
			(layer "F.SilkS")
		)
		(fp_line
			(start -2.2479 -3.5179)
			(end -3.5179 -3.5179)
			(stroke
				(width 0.1524)
				(type default)
			)
			(layer "F.SilkS")
		)
		(fp_line
			(start -3.160522 1.299972)
			(end -3.922522 1.299972)
			(stroke
				(width 0.1524)
				(type default)
			)
			(layer "F.SilkS")
		)
		(fp_line
			(start -3.5179 3.5179)
			(end -2.2479 3.5179)
			(stroke
				(width 0.1524)
				(type default)
			)
			(layer "F.SilkS")
		)
		(fp_line
			(start -3.5179 2.2479)
			(end -3.5179 3.5179)
			(stroke
				(width 0.1524)
				(type default)
			)
			(layer "F.SilkS")
		)
		(fp_line
			(start -3.5179 -3.5179)
			(end -3.5179 -2.2479)
			(stroke
				(width 0.1524)
				(type default)
			)
			(layer "F.SilkS")
		)
		(fp_poly
			(pts
				(xy 3.5179 -3.5179) (xy 2.2479 -3.5179) (xy 3.5179 -2.2479)
			)
			(stroke
				(width 0)
				(type default)
			)
			(fill yes)
			(layer "F.SilkS")
		)
		(fp_rect
			(start -2.5019 2.5019)
			(end 2.5019 -2.5019)
			(stroke
				(width 0)
				(type default)
			)
			(fill no)
			(layer "F.CrtYd")
		)
		(fp_poly
			(pts
				(xy -3.5179 3.5179) (xy -3.5179 -3.5179) (xy 3.5179 -3.5179) (xy 3.5179 -2.5019) (xy -2.5019 -2.5019)
				(xy -2.5019 2.5019) (xy 2.5019 2.5019) (xy 2.5019 -2.49682) (xy 3.5179 -2.49682) (xy 3.5179 3.5179)
			)
			(stroke
				(width 0)
				(type default)
			)
			(fill no)
			(layer "F.CrtYd")
		)
		(fp_rect
			(start -3.5179 3.5179)
			(end 3.5179 -3.5179)
			(stroke
				(width 0)
				(type default)
			)
			(fill no)
			(layer "F.Fab")
		)
		(pad "1" smd rect
			(at 1.299972 -2.474722 180)
			(size 0.3556 1.0668)
			(layers "F.Cu" "F.Mask" "F.Paste")
			(net "P1V5_C")
		)
		(pad "2" smd rect
			(at 0.649986 -2.474722 180)
			(size 0.3556 1.0668)
			(layers "F.Cu" "F.Mask" "F.Paste")
			(net "GND")
		)
		(pad "3" smd rect
			(at 0 -2.474722 180)
			(size 0.3556 1.0668)
			(layers "F.Cu" "F.Mask" "F.Paste")
			(net "GND")
		)
		(pad "4" smd rect
			(at -0.649986 -2.474722 180)
			(size 0.3556 1.0668)
			(layers "F.Cu" "F.Mask" "F.Paste")
			(net "GND")
		)
		(pad "5" smd rect
			(at -1.299972 -2.474722 180)
			(size 0.3556 1.0668)
			(layers "F.Cu" "F.Mask" "F.Paste")
			(net "TPS74801_P1V5_C_IN")
		)
		(pad "6" smd rect
			(at -2.474722 -1.299972 180)
			(size 1.0668 0.3556)
			(layers "F.Cu" "F.Mask" "F.Paste")
			(net "TPS74801_P1V5_C_IN")
		)
		(pad "7" smd rect
			(at -2.474722 -0.649986 180)
			(size 1.0668 0.3556)
			(layers "F.Cu" "F.Mask" "F.Paste")
			(net "TPS74801_P1V5_C_IN")
		)
		(pad "8" smd rect
			(at -2.474722 0 180)
			(size 1.0668 0.3556)
			(layers "F.Cu" "F.Mask" "F.Paste")
			(net "TPS74801_P1V5_C_IN")
		)
		(pad "9" smd rect
			(at -2.474722 0.649986 180)
			(size 1.0668 0.3556)
			(layers "F.Cu" "F.Mask" "F.Paste")
			(net "PWRGD_P1V5_C_PG")
		)
		(pad "10" smd rect
			(at -2.474722 1.299972 180)
			(size 1.0668 0.3556)
			(layers "F.Cu" "F.Mask" "F.Paste")
			(net "TPS74801_1V5_C_BIAS")
		)
		(pad "11" smd rect
			(at -1.299972 2.474722 180)
			(size 0.3556 1.0668)
			(layers "F.Cu" "F.Mask" "F.Paste")
			(net "TPS74801_1V5_C_EN")
		)
		(pad "12" smd rect
			(at -0.649986 2.474722 180)
			(size 0.3556 1.0668)
			(layers "F.Cu" "F.Mask" "F.Paste")
			(net "GND")
		)
		(pad "13" smd rect
			(at 0 2.474722 180)
			(size 0.3556 1.0668)
			(layers "F.Cu" "F.Mask" "F.Paste")
			(net "GND")
		)
		(pad "14" smd rect
			(at 0.649986 2.474722 180)
			(size 0.3556 1.0668)
			(layers "F.Cu" "F.Mask" "F.Paste")
			(net "GND")
		)
		(pad "15" smd rect
			(at 1.299972 2.474722 180)
			(size 0.3556 1.0668)
			(layers "F.Cu" "F.Mask" "F.Paste")
			(net "TPS74801_1V5_C_SS")
		)
		(pad "16" smd rect
			(at 2.474722 1.299972 180)
			(size 1.0668 0.3556)
			(layers "F.Cu" "F.Mask" "F.Paste")
			(net "TPS74801_1V5_C_FB")
		)
		(pad "17" smd rect
			(at 2.474722 0.649986 180)
			(size 1.0668 0.3556)
			(layers "F.Cu" "F.Mask" "F.Paste")
			(net "GND")
		)
		(pad "18" smd rect
			(at 2.474722 0 180)
			(size 1.0668 0.3556)
			(layers "F.Cu" "F.Mask" "F.Paste")
			(net "P1V5_C")
		)
		(pad "19" smd rect
			(at 2.474722 -0.649986 180)
			(size 1.0668 0.3556)
			(layers "F.Cu" "F.Mask" "F.Paste")
			(net "P1V5_C")
		)
		(pad "20" smd rect
			(at 2.474722 -1.299972 180)
			(size 1.0668 0.3556)
			(layers "F.Cu" "F.Mask" "F.Paste")
			(net "P1V5_C")
		)
		(pad "21" smd rect
			(at 0 0 180)
			(size 3.2512 3.2512)
			(layers "F.Cu" "F.Mask" "F.Paste")
			(net "GND")
		)
	)
	(footprint ""
		(layer "F.Cu")
		(at 308.991 -185.674 -90)
		(property "Reference" "SR849"
			(at 0 0 270)
			(layer "F.SilkS")
			(hide yes)
			(effects
				(font
					(size 1.27 1.27)
				)
			)
		)
		(property "Value" "4K75R2F-1-GP"
			(at 0.064008 -3.993896 270)
			(unlocked yes)
			(layer "F.Fab")
			(hide yes)
			(effects
				(font
					(size 1.016 1.016)
					(thickness 0.1524)
				)
			)
		)
		(property "Device Type" "R402H16"
			(at 0.064008 -5.517896 270)
			(unlocked yes)
			(layer "F.Fab")
			(hide yes)
			(effects
				(font
					(size 1.016 1.016)
					(thickness 0.1524)
				)
			)
		)
		(duplicate_pad_numbers_are_jumpers no)
		(fp_line
			(start -0.508 -0.9398)
			(end -0.508 0.9398)
			(stroke
				(width 0.1524)
				(type default)
			)
			(layer "F.SilkS")
		)
		(fp_line
			(start 0.508 -0.9398)
			(end -0.508 -0.9398)
			(stroke
				(width 0.1524)
				(type default)
			)
			(layer "F.SilkS")
		)
		(fp_rect
			(start -0.508 0.9398)
			(end 0.508 -0.9398)
			(stroke
				(width 0)
				(type default)
			)
			(fill no)
			(layer "F.CrtYd")
		)
		(fp_rect
			(start -0.508 0.9398)
			(end 0.508 -0.9398)
			(stroke
				(width 0)
				(type default)
			)
			(fill no)
			(layer "F.Fab")
		)
		(pad "1" smd custom
			(at 0 -0.4445 270)
			(size 0.1397 0.1397)
			(layers "F.Cu" "F.Mask" "F.Paste")
			(net "BMC_FW_DET_BOARD_VER_1")
			(options
				(clearance outline)
				(anchor circle)
			)
			(primitives
				(gr_poly
					(pts
						(arc
							(start -0.1778 -0.2794)
							(mid -0.249642 -0.249642)
							(end -0.2794 -0.1778)
						)
						(arc
							(start -0.2794 0.1778)
							(mid -0.249642 0.249642)
							(end -0.1778 0.2794)
						)
						(arc
							(start 0.1778 0.2794)
							(mid 0.249642 0.249642)
							(end 0.2794 0.1778)
						)
						(arc
							(start 0.2794 -0.1778)
							(mid 0.249642 -0.249642)
							(end 0.1778 -0.2794)
						)
					)
					(width 0)
					(fill yes)
				)
			)
		)
		(pad "2" smd custom
			(at 0 0.4445 270)
			(size 0.1397 0.1397)
			(layers "F.Cu" "F.Mask" "F.Paste")
			(net "GND")
			(options
				(clearance outline)
				(anchor circle)
			)
			(primitives
				(gr_poly
					(pts
						(arc
							(start -0.1778 -0.2794)
							(mid -0.249642 -0.249642)
							(end -0.2794 -0.1778)
						)
						(arc
							(start -0.2794 0.1778)
							(mid -0.249642 0.249642)
							(end -0.1778 0.2794)
						)
						(arc
							(start 0.1778 0.2794)
							(mid 0.249642 0.249642)
							(end 0.2794 0.1778)
						)
						(arc
							(start 0.2794 -0.1778)
							(mid 0.249642 -0.249642)
							(end 0.1778 -0.2794)
						)
					)
					(width 0)
					(fill yes)
				)
			)
		)
	)
	(footprint ""
		(layer "F.Cu")
		(at 113.938558 -74.93 -90)
		(property "Reference" "SQ5"
			(at 0 0 270)
			(layer "F.SilkS")
			(hide yes)
			(effects
				(font
					(size 1.27 1.27)
				)
			)
		)
		(property "Value" "AO3400A-GP"
			(at 0.0254 -12.3444 270)
			(unlocked yes)
			(layer "F.Fab")
			(hide yes)
			(effects
				(font
					(size 1.016 1.016)
					(thickness 0.1524)
				)
			)
		)
		(property "Device Type" "SOT23DGS2D8H50"
			(at 0.0254 -14.2494 270)
			(unlocked yes)
			(layer "F.Fab")
			(hide yes)
			(effects
				(font
					(size 1.016 1.016)
					(thickness 0.1524)
				)
			)
		)
		(duplicate_pad_numbers_are_jumpers no)
		(fp_line
			(start -1.7018 0.254)
			(end -1.7018 -0.254)
			(stroke
				(width 0.1524)
				(type default)
			)
			(layer "F.SilkS")
		)
		(fp_line
			(start 1.7018 0.254)
			(end -1.7018 0.254)
			(stroke
				(width 0.1524)
				(type default)
			)
			(layer "F.SilkS")
		)
		(fp_line
			(start -1.7018 -0.254)
			(end 1.7018 -0.254)
			(stroke
				(width 0.1524)
				(type default)
			)
			(layer "F.SilkS")
		)
		(fp_line
			(start 1.7018 -0.254)
			(end 1.7018 0.254)
			(stroke
				(width 0.1524)
				(type default)
			)
			(layer "F.SilkS")
		)
		(fp_rect
			(start -1.778 1.9812)
			(end 1.778 -1.9812)
			(stroke
				(width 0)
				(type default)
			)
			(fill no)
			(layer "F.CrtYd")
		)
		(fp_poly
			(pts
				(xy -1.778 -1.9812) (xy 1.778 -1.9812) (xy 1.778 1.9812) (xy -1.778 1.9812)
			)
			(stroke
				(width 0)
				(type default)
			)
			(fill no)
			(layer "F.Fab")
		)
		(pad "D" smd custom
			(at 0 -1.1176 270)
			(size 0.254 0.254)
			(layers "F.Cu" "F.Mask" "F.Paste")
			(net "EXP_HW_LED_D")
			(options
				(clearance outline)
				(anchor circle)
			)
			(primitives
				(gr_poly
					(pts
						(arc
							(start -0.508 -0.4064)
							(mid -0.448484 -0.550084)
							(end -0.3048 -0.6096)
						)
						(arc
							(start 0.3048 -0.6096)
							(mid 0.448484 -0.550084)
							(end 0.508 -0.4064)
						)
						(arc
							(start 0.508 0.4064)
							(mid 0.448484 0.550084)
							(end 0.3048 0.6096)
						)
						(arc
							(start -0.3048 0.6096)
							(mid -0.448484 0.550084)
							(end -0.508 0.4064)
						)
					)
					(width 0)
					(fill yes)
				)
			)
		)
		(pad "G" smd custom
			(at -1.016 1.1176 270)
			(size 0.254 0.254)
			(layers "F.Cu" "F.Mask" "F.Paste")
			(net "EXP_BLINK_OUT")
			(options
				(clearance outline)
				(anchor circle)
			)
			(primitives
				(gr_poly
					(pts
						(arc
							(start -0.508 -0.4064)
							(mid -0.448484 -0.550084)
							(end -0.3048 -0.6096)
						)
						(arc
							(start 0.3048 -0.6096)
							(mid 0.448484 -0.550084)
							(end 0.508 -0.4064)
						)
						(arc
							(start 0.508 0.4064)
							(mid 0.448484 0.550084)
							(end 0.3048 0.6096)
						)
						(arc
							(start -0.3048 0.6096)
							(mid -0.448484 0.550084)
							(end -0.508 0.4064)
						)
					)
					(width 0)
					(fill yes)
				)
			)
		)
		(pad "S" smd custom
			(at 1.016 1.1176 270)
			(size 0.254 0.254)
			(layers "F.Cu" "F.Mask" "F.Paste")
			(net "GND")
			(options
				(clearance outline)
				(anchor circle)
			)
			(primitives
				(gr_poly
					(pts
						(arc
							(start -0.508 -0.4064)
							(mid -0.448484 -0.550084)
							(end -0.3048 -0.6096)
						)
						(arc
							(start 0.3048 -0.6096)
							(mid 0.448484 -0.550084)
							(end 0.508 -0.4064)
						)
						(arc
							(start 0.508 0.4064)
							(mid 0.448484 0.550084)
							(end 0.3048 0.6096)
						)
						(arc
							(start -0.3048 0.6096)
							(mid -0.448484 0.550084)
							(end -0.508 0.4064)
						)
					)
					(width 0)
					(fill yes)
				)
			)
		)
	)
	(footprint ""
		(layer "F.Cu")
		(at 202.819 -119.634 -90)
		(property "Reference" "R9014"
			(at 0 0 270)
			(layer "F.SilkS")
			(hide yes)
			(effects
				(font
					(size 1.27 1.27)
				)
			)
		)
		(property "Value" "9K53R2F-GP"
			(at 0.064008 -3.993896 270)
			(unlocked yes)
			(layer "F.Fab")
			(hide yes)
			(effects
				(font
					(size 1.016 1.016)
					(thickness 0.1524)
				)
			)
		)
		(property "Device Type" "R402H16"
			(at 0.064008 -5.517896 270)
			(unlocked yes)
			(layer "F.Fab")
			(hide yes)
			(effects
				(font
					(size 1.016 1.016)
					(thickness 0.1524)
				)
			)
		)
		(duplicate_pad_numbers_are_jumpers no)
		(fp_line
			(start -0.508 -0.9398)
			(end -0.508 0.9398)
			(stroke
				(width 0.1524)
				(type default)
			)
			(layer "F.SilkS")
		)
		(fp_line
			(start 0.508 -0.9398)
			(end -0.508 -0.9398)
			(stroke
				(width 0.1524)
				(type default)
			)
			(layer "F.SilkS")
		)
		(fp_rect
			(start -0.508 0.9398)
			(end 0.508 -0.9398)
			(stroke
				(width 0)
				(type default)
			)
			(fill no)
			(layer "F.CrtYd")
		)
		(fp_rect
			(start -0.508 0.9398)
			(end 0.508 -0.9398)
			(stroke
				(width 0)
				(type default)
			)
			(fill no)
			(layer "F.Fab")
		)
		(pad "1" smd custom
			(at 0 -0.4445 270)
			(size 0.1397 0.1397)
			(layers "F.Cu" "F.Mask" "F.Paste")
			(net "P1V5_E_CC_R")
			(options
				(clearance outline)
				(anchor circle)
			)
			(primitives
				(gr_poly
					(pts
						(arc
							(start -0.1778 -0.2794)
							(mid -0.249642 -0.249642)
							(end -0.2794 -0.1778)
						)
						(arc
							(start -0.2794 0.1778)
							(mid -0.249642 0.249642)
							(end -0.1778 0.2794)
						)
						(arc
							(start 0.1778 0.2794)
							(mid 0.249642 0.249642)
							(end 0.2794 0.1778)
						)
						(arc
							(start 0.2794 -0.1778)
							(mid 0.249642 -0.249642)
							(end 0.1778 -0.2794)
						)
					)
					(width 0)
					(fill yes)
				)
			)
		)
		(pad "2" smd custom
			(at 0 0.4445 270)
			(size 0.1397 0.1397)
			(layers "F.Cu" "F.Mask" "F.Paste")
			(net "P1V5_E_VFB")
			(options
				(clearance outline)
				(anchor circle)
			)
			(primitives
				(gr_poly
					(pts
						(arc
							(start -0.1778 -0.2794)
							(mid -0.249642 -0.249642)
							(end -0.2794 -0.1778)
						)
						(arc
							(start -0.2794 0.1778)
							(mid -0.249642 0.249642)
							(end -0.1778 0.2794)
						)
						(arc
							(start 0.1778 0.2794)
							(mid 0.249642 0.249642)
							(end 0.2794 0.1778)
						)
						(arc
							(start 0.2794 -0.1778)
							(mid 0.249642 -0.249642)
							(end 0.1778 -0.2794)
						)
					)
					(width 0)
					(fill yes)
				)
			)
		)
	)
	(footprint ""
		(layer "F.Cu")
		(at 165.1 -113.919 -90)
		(property "Reference" "PR165"
			(at 0 0 270)
			(layer "F.SilkS")
			(hide yes)
			(effects
				(font
					(size 1.27 1.27)
				)
			)
		)
		(property "Value" "10KR2F-2-GP"
			(at 0.064008 -3.993896 270)
			(unlocked yes)
			(layer "F.Fab")
			(hide yes)
			(effects
				(font
					(size 1.016 1.016)
					(thickness 0.1524)
				)
			)
		)
		(property "Device Type" "R402H16"
			(at 0.064008 -5.517896 270)
			(unlocked yes)
			(layer "F.Fab")
			(hide yes)
			(effects
				(font
					(size 1.016 1.016)
					(thickness 0.1524)
				)
			)
		)
		(duplicate_pad_numbers_are_jumpers no)
		(fp_line
			(start -0.508 -0.9398)
			(end -0.508 0.9398)
			(stroke
				(width 0.1524)
				(type default)
			)
			(layer "F.SilkS")
		)
		(fp_line
			(start 0.508 -0.9398)
			(end -0.508 -0.9398)
			(stroke
				(width 0.1524)
				(type default)
			)
			(layer "F.SilkS")
		)
		(fp_rect
			(start -0.508 0.9398)
			(end 0.508 -0.9398)
			(stroke
				(width 0)
				(type default)
			)
			(fill no)
			(layer "F.CrtYd")
		)
		(fp_rect
			(start -0.508 0.9398)
			(end 0.508 -0.9398)
			(stroke
				(width 0)
				(type default)
			)
			(fill no)
			(layer "F.Fab")
		)
		(pad "1" smd custom
			(at 0 -0.4445 270)
			(size 0.1397 0.1397)
			(layers "F.Cu" "F.Mask" "F.Paste")
			(net "P0V9_E_VFB")
			(options
				(clearance outline)
				(anchor circle)
			)
			(primitives
				(gr_poly
					(pts
						(arc
							(start -0.1778 -0.2794)
							(mid -0.249642 -0.249642)
							(end -0.2794 -0.1778)
						)
						(arc
							(start -0.2794 0.1778)
							(mid -0.249642 0.249642)
							(end -0.1778 0.2794)
						)
						(arc
							(start 0.1778 0.2794)
							(mid 0.249642 0.249642)
							(end 0.2794 0.1778)
						)
						(arc
							(start 0.2794 -0.1778)
							(mid 0.249642 -0.249642)
							(end 0.1778 -0.2794)
						)
					)
					(width 0)
					(fill yes)
				)
			)
		)
		(pad "2" smd custom
			(at 0 0.4445 270)
			(size 0.1397 0.1397)
			(layers "F.Cu" "F.Mask" "F.Paste")
			(net "AGND_P0V9_E")
			(options
				(clearance outline)
				(anchor circle)
			)
			(primitives
				(gr_poly
					(pts
						(arc
							(start -0.1778 -0.2794)
							(mid -0.249642 -0.249642)
							(end -0.2794 -0.1778)
						)
						(arc
							(start -0.2794 0.1778)
							(mid -0.249642 0.249642)
							(end -0.1778 0.2794)
						)
						(arc
							(start 0.1778 0.2794)
							(mid 0.249642 0.249642)
							(end 0.2794 0.1778)
						)
						(arc
							(start 0.2794 -0.1778)
							(mid 0.249642 -0.249642)
							(end 0.1778 -0.2794)
						)
					)
					(width 0)
					(fill yes)
				)
			)
		)
	)
	(footprint ""
		(layer "F.Cu")
		(at 102.350062 -44.99991)
		(property "Reference" "SU2"
			(at 0 0 0)
			(layer "F.SilkS")
			(hide yes)
			(effects
				(font
					(size 1.27 1.27)
				)
			)
		)
		(property "Value" "SAS3008C0-1-DB-500020657-1-GP"
			(at -20.374102 -5.0292 0)
			(unlocked yes)
			(layer "F.Fab")
			(hide yes)
			(effects
				(font
					(size 1.016 1.016)
					(thickness 0.1524)
				)
			)
		)
		(property "Device Type" "BGA896D25H78"
			(at -20.374102 -6.5532 0)
			(unlocked yes)
			(layer "F.Fab")
			(hide yes)
			(effects
				(font
					(size 1.016 1.016)
					(thickness 0.1524)
				)
			)
		)
		(duplicate_pad_numbers_are_jumpers no)
		(fp_line
			(start -12.500102 -12.030202)
			(end -12.500102 -10.86993)
			(stroke
				(width 0.1524)
				(type default)
			)
			(layer "F.SilkS")
		)
		(fp_line
			(start -12.500102 -9.93013)
			(end -12.500102 9.93013)
			(stroke
				(width 0.1524)
				(type default)
			)
			(layer "F.SilkS")
		)
		(fp_line
			(start -12.500102 12.030202)
			(end -12.500102 10.86993)
			(stroke
				(width 0.1524)
				(type default)
			)
			(layer "F.SilkS")
		)
		(fp_line
			(start -12.030202 -12.500102)
			(end -10.86993 -12.500102)
			(stroke
				(width 0.1524)
				(type default)
			)
			(layer "F.SilkS")
		)
		(fp_line
			(start -12.030202 12.500102)
			(end -10.86993 12.500102)
			(stroke
				(width 0.1524)
				(type default)
			)
			(layer "F.SilkS")
		)
		(fp_line
			(start 9.93013 -12.500102)
			(end -9.93013 -12.500102)
			(stroke
				(width 0.1524)
				(type default)
			)
			(layer "F.SilkS")
		)
		(fp_line
			(start 9.93013 12.500102)
			(end -9.93013 12.500102)
			(stroke
				(width 0.1524)
				(type default)
			)
			(layer "F.SilkS")
		)
		(fp_line
			(start 12.030202 -12.500102)
			(end 10.86993 -12.500102)
			(stroke
				(width 0.1524)
				(type default)
			)
			(layer "F.SilkS")
		)
		(fp_line
			(start 12.030202 12.500102)
			(end 10.86993 12.500102)
			(stroke
				(width 0.1524)
				(type default)
			)
			(layer "F.SilkS")
		)
		(fp_line
			(start 12.500102 -12.030202)
			(end 12.500102 -10.86993)
			(stroke
				(width 0.1524)
				(type default)
			)
			(layer "F.SilkS")
		)
		(fp_line
			(start 12.500102 -9.93013)
			(end 12.500102 9.93013)
			(stroke
				(width 0.1524)
				(type default)
			)
			(layer "F.SilkS")
		)
		(fp_line
			(start 12.500102 12.030202)
			(end 12.500102 10.86993)
			(stroke
				(width 0.1524)
				(type default)
			)
			(layer "F.SilkS")
		)
		(fp_circle
			(center -12.500102 -12.500102)
			(end -12.030202 -12.500102)
			(stroke
				(width 0.1524)
				(type default)
			)
			(fill no)
			(layer "F.SilkS")
		)
		(fp_circle
			(center -12.500102 -10.40003)
			(end -12.030202 -10.40003)
			(stroke
				(width 0.1524)
				(type default)
			)
			(fill no)
			(layer "F.SilkS")
		)
		(fp_circle
			(center -12.500102 10.40003)
			(end -12.030202 10.40003)
			(stroke
				(width 0.1524)
				(type default)
			)
			(fill no)
			(layer "F.SilkS")
		)
		(fp_circle
			(center -12.500102 12.500102)
			(end -12.030202 12.500102)
			(stroke
				(width 0.1524)
				(type default)
			)
			(fill no)
			(layer "F.SilkS")
		)
		(fp_circle
			(center -10.40003 -12.500102)
			(end -9.93013 -12.500102)
			(stroke
				(width 0.1524)
				(type default)
			)
			(fill no)
			(layer "F.SilkS")
		)
		(fp_circle
			(center -10.40003 12.500102)
			(end -9.93013 12.500102)
			(stroke
				(width 0.1524)
				(type default)
			)
			(fill no)
			(layer "F.SilkS")
		)
		(fp_circle
			(center 10.40003 -12.500102)
			(end 10.86993 -12.500102)
			(stroke
				(width 0.1524)
				(type default)
			)
			(fill no)
			(layer "F.SilkS")
		)
		(fp_circle
			(center 10.40003 12.500102)
			(end 10.86993 12.500102)
			(stroke
				(width 0.1524)
				(type default)
			)
			(fill no)
			(layer "F.SilkS")
		)
		(fp_circle
			(center 12.500102 -12.500102)
			(end 12.970002 -12.500102)
			(stroke
				(width 0.1524)
				(type default)
			)
			(fill no)
			(layer "F.SilkS")
		)
		(fp_circle
			(center 12.500102 -10.40003)
			(end 12.970002 -10.40003)
			(stroke
				(width 0.1524)
				(type default)
			)
			(fill no)
			(layer "F.SilkS")
		)
		(fp_circle
			(center 12.500102 10.40003)
			(end 12.970002 10.40003)
			(stroke
				(width 0.1524)
				(type default)
			)
			(fill no)
			(layer "F.SilkS")
		)
		(fp_circle
			(center 12.500102 12.500102)
			(end 12.970002 12.500102)
			(stroke
				(width 0.1524)
				(type default)
			)
			(fill no)
			(layer "F.SilkS")
		)
		(fp_poly
			(pts
				(xy -12.931902 -12.931902) (xy -12.931902 -14.455902) (xy -14.455902 -12.931902)
			)
			(stroke
				(width 0)
				(type default)
			)
			(fill yes)
			(layer "F.SilkS")
		)
		(fp_rect
			(start -12.500102 12.500102)
			(end 12.500102 -12.500102)
			(stroke
				(width 0)
				(type default)
			)
			(fill no)
			(layer "F.CrtYd")
		)
		(fp_poly
			(pts
				(xy 13.5001 -12.500102) (xy -12.500102 -12.500102) (xy -12.500102 12.500102) (xy 12.500102 12.500102)
				(xy 12.500102 -12.487402) (xy 13.5001 -12.487402) (xy 13.5001 13.5001) (xy -13.5001 13.5001) (xy -13.5001 -13.5001)
				(xy 13.5001 -13.5001)
			)
			(stroke
				(width 0)
				(type default)
			)
			(fill no)
			(layer "F.CrtYd")
		)
		(fp_rect
			(start -14.500098 14.500098)
			(end 14.500098 -14.500098)
			(stroke
				(width 0)
				(type default)
			)
			(fill no)
			(layer "F.Fab")
		)
		(pad "A2" smd circle
			(at -10.80008 -11.599926)
			(size 0.4064 0.4064)
			(layers "F.Cu" "F.Mask" "F.Paste")
			(net "Net_1034")
		)
		(pad "A3" smd circle
			(at -9.99998 -11.599926)
			(size 0.4064 0.4064)
			(layers "F.Cu" "F.Mask" "F.Paste")
			(net "Net_1035")
		)
		(pad "A4" smd circle
			(at -9.19988 -11.599926)
			(size 0.3556 0.3556)
			(layers "F.Cu" "F.Mask" "F.Paste")
			(net "GND")
		)
		(pad "A5" smd circle
			(at -8.400034 -11.599926)
			(size 0.3556 0.3556)
			(layers "F.Cu" "F.Mask" "F.Paste")
			(net "Net_1036")
		)
		(pad "A6" smd circle
			(at -7.599934 -11.599926)
			(size 0.3556 0.3556)
			(layers "F.Cu" "F.Mask" "F.Paste")
			(net "ICE1_TMS")
		)
		(pad "A7" smd circle
			(at -6.800088 -11.599926)
			(size 0.3556 0.3556)
			(layers "F.Cu" "F.Mask" "F.Paste")
			(net "Net_1037")
		)
		(pad "A8" smd circle
			(at -5.999988 -11.599926)
			(size 0.3556 0.3556)
			(layers "F.Cu" "F.Mask" "F.Paste")
			(net "ICE0_TRST#")
		)
		(pad "A9" smd circle
			(at -5.199888 -11.599926)
			(size 0.3556 0.3556)
			(layers "F.Cu" "F.Mask" "F.Paste")
			(net "ICE0_TCK")
		)
		(pad "A10" smd circle
			(at -4.400042 -11.599926)
			(size 0.3556 0.3556)
			(layers "F.Cu" "F.Mask" "F.Paste")
			(net "ICE1_TDO")
		)
		(pad "A11" smd circle
			(at -3.599942 -11.599926)
			(size 0.3556 0.3556)
			(layers "F.Cu" "F.Mask" "F.Paste")
			(net "GND")
		)
		(pad "A12" smd circle
			(at -2.800096 -11.599926)
			(size 0.3556 0.3556)
			(layers "F.Cu" "F.Mask" "F.Paste")
			(net "Net_1027")
		)
		(pad "A13" smd circle
			(at -1.999996 -11.599926)
			(size 0.3556 0.3556)
			(layers "F.Cu" "F.Mask" "F.Paste")
			(net "PWRGD_P0V955_C")
		)
		(pad "A14" smd circle
			(at -1.199896 -11.599926)
			(size 0.3556 0.3556)
			(layers "F.Cu" "F.Mask" "F.Paste")
			(net "HM40ADC_VDDA")
		)
		(pad "A15" smd circle
			(at -0.40005 -11.599926)
			(size 0.3556 0.3556)
			(layers "F.Cu" "F.Mask" "F.Paste")
			(net "GND")
		)
		(pad "A16" smd circle
			(at 0.40005 -11.599926)
			(size 0.3556 0.3556)
			(layers "F.Cu" "F.Mask" "F.Paste")
			(net "IOC_TRST_N")
		)
		(pad "A17" smd circle
			(at 1.199896 -11.599926)
			(size 0.3556 0.3556)
			(layers "F.Cu" "F.Mask" "F.Paste")
			(net "JTAG_IOC_TDI")
		)
		(pad "A18" smd circle
			(at 1.999996 -11.599926)
			(size 0.3556 0.3556)
			(layers "F.Cu" "F.Mask" "F.Paste")
			(net "LSI_IDDT")
		)
		(pad "A19" smd circle
			(at 2.800096 -11.599926)
			(size 0.3556 0.3556)
			(layers "F.Cu" "F.Mask" "F.Paste")
			(net "Net_1028")
		)
		(pad "A20" smd circle
			(at 3.599942 -11.599926)
			(size 0.3556 0.3556)
			(layers "F.Cu" "F.Mask" "F.Paste")
			(net "Net_1029")
		)
		(pad "A21" smd circle
			(at 4.400042 -11.599926)
			(size 0.3556 0.3556)
			(layers "F.Cu" "F.Mask" "F.Paste")
			(net "XM_NOR_CS_N")
		)
		(pad "A22" smd circle
			(at 5.199888 -11.599926)
			(size 0.3556 0.3556)
			(layers "F.Cu" "F.Mask" "F.Paste")
			(net "XM_RB")
		)
		(pad "A23" smd circle
			(at 5.999988 -11.599926)
			(size 0.3556 0.3556)
			(layers "F.Cu" "F.Mask" "F.Paste")
			(net "Net_1023")
		)
		(pad "A24" smd circle
			(at 6.800088 -11.599926)
			(size 0.3556 0.3556)
			(layers "F.Cu" "F.Mask" "F.Paste")
			(net "XM_WE_N")
		)
		(pad "A25" smd circle
			(at 7.599934 -11.599926)
			(size 0.3556 0.3556)
			(layers "F.Cu" "F.Mask" "F.Paste")
			(net "XM_WP")
		)
		(pad "A26" smd circle
			(at 8.400034 -11.599926)
			(size 0.3556 0.3556)
			(layers "F.Cu" "F.Mask" "F.Paste")
			(net "XM_ADDR_3")
		)
		(pad "A27" smd circle
			(at 9.19988 -11.599926)
			(size 0.3556 0.3556)
			(layers "F.Cu" "F.Mask" "F.Paste")
			(net "Net_1024")
		)
		(pad "A28" smd circle
			(at 9.99998 -11.599926)
			(size 0.4064 0.4064)
			(layers "F.Cu" "F.Mask" "F.Paste")
			(net "XM_ADDR_4")
		)
		(pad "A29" smd circle
			(at 10.80008 -11.599926)
			(size 0.4064 0.4064)
			(layers "F.Cu" "F.Mask" "F.Paste")
			(net "XM_DATA_11")
		)
		(pad "AA1" smd circle
			(at -11.599926 4.400042)
			(size 0.3556 0.3556)
			(layers "F.Cu" "F.Mask" "F.Paste")
			(net "SAS3008_RAID_TX_C_P6")
		)
		(pad "AA2" smd circle
			(at -10.80008 4.400042)
			(size 0.3556 0.3556)
			(layers "F.Cu" "F.Mask" "F.Paste")
			(net "SAS3008_RAID_TX_C_N6")
		)
		(pad "AA3" smd circle
			(at -9.99998 4.400042)
			(size 0.3556 0.3556)
			(layers "F.Cu" "F.Mask" "F.Paste")
			(net "GND")
		)
		(pad "AA4" smd circle
			(at -9.19988 4.400042)
			(size 0.3556 0.3556)
			(layers "F.Cu" "F.Mask" "F.Paste")
			(net "IOC_SAS_RX_P6")
		)
		(pad "AA5" smd circle
			(at -8.400034 4.400042)
			(size 0.3556 0.3556)
			(layers "F.Cu" "F.Mask" "F.Paste")
			(net "IOC_SAS_RX_N6")
		)
		(pad "AA6" smd circle
			(at -7.599934 4.400042)
			(size 0.3556 0.3556)
			(layers "F.Cu" "F.Mask" "F.Paste")
			(net "GND")
		)
		(pad "AA7" smd circle
			(at -6.800088 4.400042)
			(size 0.3556 0.3556)
			(layers "F.Cu" "F.Mask" "F.Paste")
			(net "GND")
		)
		(pad "AA8" smd circle
			(at -5.999988 4.400042)
			(size 0.3556 0.3556)
			(layers "F.Cu" "F.Mask" "F.Paste")
			(net "GND")
		)
		(pad "AA9" smd circle
			(at -5.199888 4.400042)
			(size 0.3556 0.3556)
			(layers "F.Cu" "F.Mask" "F.Paste")
			(net "GND")
		)
		(pad "AA10" smd circle
			(at -4.400042 4.400042)
			(size 0.3556 0.3556)
			(layers "F.Cu" "F.Mask" "F.Paste")
			(net "GND")
		)
		(pad "AA11" smd circle
			(at -3.599942 4.400042)
			(size 0.3556 0.3556)
			(layers "F.Cu" "F.Mask" "F.Paste")
			(net "GND")
		)
		(pad "AA12" smd circle
			(at -2.800096 4.400042)
			(size 0.3556 0.3556)
			(layers "F.Cu" "F.Mask" "F.Paste")
			(net "GND")
		)
		(pad "AA13" smd circle
			(at -1.999996 4.400042)
			(size 0.3556 0.3556)
			(layers "F.Cu" "F.Mask" "F.Paste")
			(net "GND")
		)
		(pad "AA14" smd circle
			(at -1.199896 4.400042)
			(size 0.3556 0.3556)
			(layers "F.Cu" "F.Mask" "F.Paste")
			(net "GND")
		)
		(pad "AA15" smd circle
			(at -0.40005 4.400042)
			(size 0.3556 0.3556)
			(layers "F.Cu" "F.Mask" "F.Paste")
			(net "GND")
		)
		(pad "AA16" smd circle
			(at 0.40005 4.400042)
			(size 0.3556 0.3556)
			(layers "F.Cu" "F.Mask" "F.Paste")
			(net "GND")
		)
		(pad "AA17" smd circle
			(at 1.199896 4.400042)
			(size 0.3556 0.3556)
			(layers "F.Cu" "F.Mask" "F.Paste")
			(net "GND")
		)
		(pad "AA18" smd circle
			(at 1.999996 4.400042)
			(size 0.3556 0.3556)
			(layers "F.Cu" "F.Mask" "F.Paste")
			(net "GND")
		)
		(pad "AA19" smd circle
			(at 2.800096 4.400042)
			(size 0.3556 0.3556)
			(layers "F.Cu" "F.Mask" "F.Paste")
			(net "GND")
		)
		(pad "AA20" smd circle
			(at 3.599942 4.400042)
			(size 0.3556 0.3556)
			(layers "F.Cu" "F.Mask" "F.Paste")
			(net "GND")
		)
		(pad "AA21" smd circle
			(at 4.400042 4.400042)
			(size 0.3556 0.3556)
			(layers "F.Cu" "F.Mask" "F.Paste")
			(net "GND")
		)
		(pad "AA22" smd circle
			(at 5.199888 4.400042)
			(size 0.3556 0.3556)
			(layers "F.Cu" "F.Mask" "F.Paste")
			(net "GND")
		)
		(pad "AA23" smd circle
			(at 5.999988 4.400042)
			(size 0.3556 0.3556)
			(layers "F.Cu" "F.Mask" "F.Paste")
			(net "PLL_VDD")
		)
		(pad "AA24" smd circle
			(at 6.800088 4.400042)
			(size 0.3556 0.3556)
			(layers "F.Cu" "F.Mask" "F.Paste")
			(net "GND")
		)
		(pad "AA25" smd circle
			(at 7.599934 4.400042)
			(size 0.3556 0.3556)
			(layers "F.Cu" "F.Mask" "F.Paste")
			(net "GND")
		)
		(pad "AA26" smd circle
			(at 8.400034 4.400042)
			(size 0.3556 0.3556)
			(layers "F.Cu" "F.Mask" "F.Paste")
			(net "GND")
		)
		(pad "AA27" smd circle
			(at 9.19988 4.400042)
			(size 0.3556 0.3556)
			(layers "F.Cu" "F.Mask" "F.Paste")
			(net "P1V8_C")
		)
		(pad "AA28" smd circle
			(at 9.99998 4.400042)
			(size 0.3556 0.3556)
			(layers "F.Cu" "F.Mask" "F.Paste")
			(net "IOC_GPIO_36")
		)
		(pad "AA29" smd circle
			(at 10.80008 4.400042)
			(size 0.3556 0.3556)
			(layers "F.Cu" "F.Mask" "F.Paste")
			(net "IOC_GPIO_33")
		)
		(pad "AA30" smd circle
			(at 11.599926 4.400042)
			(size 0.3556 0.3556)
			(layers "F.Cu" "F.Mask" "F.Paste")
			(net "IOC_GPIO_37")
		)
		(pad "AB1" smd circle
			(at -11.599926 5.199888)
			(size 0.3556 0.3556)
			(layers "F.Cu" "F.Mask" "F.Paste")
			(net "SAS3008_RAID_TX_C_P7")
		)
		(pad "AB2" smd circle
			(at -10.80008 5.199888)
			(size 0.3556 0.3556)
			(layers "F.Cu" "F.Mask" "F.Paste")
			(net "SAS3008_RAID_TX_C_N7")
		)
		(pad "AB3" smd circle
			(at -9.99998 5.199888)
			(size 0.3556 0.3556)
			(layers "F.Cu" "F.Mask" "F.Paste")
			(net "GND")
		)
		(pad "AB4" smd circle
			(at -9.19988 5.199888)
			(size 0.3556 0.3556)
			(layers "F.Cu" "F.Mask" "F.Paste")
			(net "IOC_SAS_RX_P7")
		)
		(pad "AB5" smd circle
			(at -8.400034 5.199888)
			(size 0.3556 0.3556)
			(layers "F.Cu" "F.Mask" "F.Paste")
			(net "IOC_SAS_RX_N7")
		)
		(pad "AB6" smd circle
			(at -7.599934 5.199888)
			(size 0.3556 0.3556)
			(layers "F.Cu" "F.Mask" "F.Paste")
			(net "GND")
		)
		(pad "AB7" smd circle
			(at -6.800088 5.199888)
			(size 0.3556 0.3556)
			(layers "F.Cu" "F.Mask" "F.Paste")
			(net "SAS0_AVDD")
		)
		(pad "AB8" smd circle
			(at -5.999988 5.199888)
			(size 0.3556 0.3556)
			(layers "F.Cu" "F.Mask" "F.Paste")
			(net "GND")
		)
		(pad "AB9" smd circle
			(at -5.199888 5.199888)
			(size 0.3556 0.3556)
			(layers "F.Cu" "F.Mask" "F.Paste")
			(net "GND")
		)
		(pad "AB10" smd circle
			(at -4.400042 5.199888)
			(size 0.3556 0.3556)
			(layers "F.Cu" "F.Mask" "F.Paste")
			(net "GND")
		)
		(pad "AB11" smd circle
			(at -3.599942 5.199888)
			(size 0.3556 0.3556)
			(layers "F.Cu" "F.Mask" "F.Paste")
			(net "GND")
		)
		(pad "AB12" smd circle
			(at -2.800096 5.199888)
			(size 0.3556 0.3556)
			(layers "F.Cu" "F.Mask" "F.Paste")
			(net "GND")
		)
		(pad "AB13" smd circle
			(at -1.999996 5.199888)
			(size 0.3556 0.3556)
			(layers "F.Cu" "F.Mask" "F.Paste")
			(net "GND")
		)
		(pad "AB14" smd circle
			(at -1.199896 5.199888)
			(size 0.3556 0.3556)
			(layers "F.Cu" "F.Mask" "F.Paste")
			(net "GND")
		)
		(pad "AB15" smd circle
			(at -0.40005 5.199888)
			(size 0.3556 0.3556)
			(layers "F.Cu" "F.Mask" "F.Paste")
			(net "GND")
		)
		(pad "AB16" smd circle
			(at 0.40005 5.199888)
			(size 0.3556 0.3556)
			(layers "F.Cu" "F.Mask" "F.Paste")
			(net "GND")
		)
		(pad "AB17" smd circle
			(at 1.199896 5.199888)
			(size 0.3556 0.3556)
			(layers "F.Cu" "F.Mask" "F.Paste")
			(net "GND")
		)
		(pad "AB18" smd circle
			(at 1.999996 5.199888)
			(size 0.3556 0.3556)
			(layers "F.Cu" "F.Mask" "F.Paste")
			(net "GND")
		)
		(pad "AB19" smd circle
			(at 2.800096 5.199888)
			(size 0.3556 0.3556)
			(layers "F.Cu" "F.Mask" "F.Paste")
			(net "GND")
		)
		(pad "AB20" smd circle
			(at 3.599942 5.199888)
			(size 0.3556 0.3556)
			(layers "F.Cu" "F.Mask" "F.Paste")
			(net "GND")
		)
		(pad "AB21" smd circle
			(at 4.400042 5.199888)
			(size 0.3556 0.3556)
			(layers "F.Cu" "F.Mask" "F.Paste")
			(net "GND")
		)
		(pad "AB22" smd circle
			(at 5.199888 5.199888)
			(size 0.3556 0.3556)
			(layers "F.Cu" "F.Mask" "F.Paste")
			(net "GND")
		)
		(pad "AB23" smd circle
			(at 5.999988 5.199888)
			(size 0.3556 0.3556)
			(layers "F.Cu" "F.Mask" "F.Paste")
			(net "GND")
		)
		(pad "AB24" smd circle
			(at 6.800088 5.199888)
			(size 0.3556 0.3556)
			(layers "F.Cu" "F.Mask" "F.Paste")
			(net "GND")
		)
		(pad "AB25" smd circle
			(at 7.599934 5.199888)
			(size 0.3556 0.3556)
			(layers "F.Cu" "F.Mask" "F.Paste")
			(net "GND")
		)
		(pad "AB26" smd circle
			(at 8.400034 5.199888)
			(size 0.3556 0.3556)
			(layers "F.Cu" "F.Mask" "F.Paste")
			(net "P1V8_C")
		)
		(pad "AB27" smd circle
			(at 9.19988 5.199888)
			(size 0.3556 0.3556)
			(layers "F.Cu" "F.Mask" "F.Paste")
			(net "GND")
		)
		(pad "AB28" smd circle
			(at 9.99998 5.199888)
			(size 0.3556 0.3556)
			(layers "F.Cu" "F.Mask" "F.Paste")
			(net "IOC_GPIO_34")
		)
		(pad "AB29" smd circle
			(at 10.80008 5.199888)
			(size 0.3556 0.3556)
			(layers "F.Cu" "F.Mask" "F.Paste")
			(net "IOC_GPIO_23")
		)
		(pad "AB30" smd circle
			(at 11.599926 5.199888)
			(size 0.3556 0.3556)
			(layers "F.Cu" "F.Mask" "F.Paste")
			(net "IOC_GPIO_35")
		)
		(pad "AC1" smd circle
			(at -11.599926 5.999988)
			(size 0.3556 0.3556)
			(layers "F.Cu" "F.Mask" "F.Paste")
			(net "SAS0_VDDH")
		)
		(pad "AC2" smd circle
			(at -10.80008 5.999988)
			(size 0.3556 0.3556)
			(layers "F.Cu" "F.Mask" "F.Paste")
			(net "GND")
		)
		(pad "AC3" smd circle
			(at -9.99998 5.999988)
			(size 0.3556 0.3556)
			(layers "F.Cu" "F.Mask" "F.Paste")
			(net "GND")
		)
		(pad "AC4" smd circle
			(at -9.19988 5.999988)
			(size 0.3556 0.3556)
			(layers "F.Cu" "F.Mask" "F.Paste")
			(net "SAS0_AVDD")
		)
		(pad "AC5" smd circle
			(at -8.400034 5.999988)
			(size 0.3556 0.3556)
			(layers "F.Cu" "F.Mask" "F.Paste")
			(net "GND")
		)
		(pad "AC6" smd circle
			(at -7.599934 5.999988)
			(size 0.3556 0.3556)
			(layers "F.Cu" "F.Mask" "F.Paste")
			(net "SAS0_VDDH")
		)
		(pad "AC7" smd circle
			(at -6.800088 5.999988)
			(size 0.3556 0.3556)
			(layers "F.Cu" "F.Mask" "F.Paste")
			(net "GND")
		)
		(pad "AC8" smd circle
			(at -5.999988 5.999988)
			(size 0.3556 0.3556)
			(layers "F.Cu" "F.Mask" "F.Paste")
			(net "GND")
		)
		(pad "AC9" smd circle
			(at -5.199888 5.999988)
			(size 0.3556 0.3556)
			(layers "F.Cu" "F.Mask" "F.Paste")
			(net "GND")
		)
		(pad "AC10" smd circle
			(at -4.400042 5.999988)
			(size 0.3556 0.3556)
			(layers "F.Cu" "F.Mask" "F.Paste")
			(net "GND")
		)
		(pad "AC11" smd circle
			(at -3.599942 5.999988)
			(size 0.3556 0.3556)
			(layers "F.Cu" "F.Mask" "F.Paste")
			(net "PCE_AVDD")
		)
		(pad "AC12" smd circle
			(at -2.800096 5.999988)
			(size 0.3556 0.3556)
			(layers "F.Cu" "F.Mask" "F.Paste")
			(net "GND")
		)
		(pad "AC13" smd circle
			(at -1.999996 5.999988)
			(size 0.3556 0.3556)
			(layers "F.Cu" "F.Mask" "F.Paste")
			(net "GND")
		)
		(pad "AC14" smd circle
			(at -1.199896 5.999988)
			(size 0.3556 0.3556)
			(layers "F.Cu" "F.Mask" "F.Paste")
			(net "GND")
		)
		(pad "AC15" smd circle
			(at -0.40005 5.999988)
			(size 0.3556 0.3556)
			(layers "F.Cu" "F.Mask" "F.Paste")
			(net "GND")
		)
		(pad "AC16" smd circle
			(at 0.40005 5.999988)
			(size 0.3556 0.3556)
			(layers "F.Cu" "F.Mask" "F.Paste")
			(net "GND")
		)
		(pad "AC17" smd circle
			(at 1.199896 5.999988)
			(size 0.3556 0.3556)
			(layers "F.Cu" "F.Mask" "F.Paste")
			(net "GND")
		)
		(pad "AC18" smd circle
			(at 1.999996 5.999988)
			(size 0.3556 0.3556)
			(layers "F.Cu" "F.Mask" "F.Paste")
			(net "GND")
		)
		(pad "AC19" smd circle
			(at 2.800096 5.999988)
			(size 0.3556 0.3556)
			(layers "F.Cu" "F.Mask" "F.Paste")
			(net "GND")
		)
		(pad "AC20" smd circle
			(at 3.599942 5.999988)
			(size 0.3556 0.3556)
			(layers "F.Cu" "F.Mask" "F.Paste")
			(net "GND")
		)
		(pad "AC21" smd circle
			(at 4.400042 5.999988)
			(size 0.3556 0.3556)
			(layers "F.Cu" "F.Mask" "F.Paste")
			(net "GND")
		)
		(pad "AC22" smd circle
			(at 5.199888 5.999988)
			(size 0.3556 0.3556)
			(layers "F.Cu" "F.Mask" "F.Paste")
			(net "GND")
		)
		(pad "AC23" smd circle
			(at 5.999988 5.999988)
			(size 0.3556 0.3556)
			(layers "F.Cu" "F.Mask" "F.Paste")
			(net "GND")
		)
		(pad "AC24" smd circle
			(at 6.800088 5.999988)
			(size 0.3556 0.3556)
			(layers "F.Cu" "F.Mask" "F.Paste")
			(net "GND")
		)
		(pad "AC25" smd circle
			(at 7.599934 5.999988)
			(size 0.3556 0.3556)
			(layers "F.Cu" "F.Mask" "F.Paste")
			(net "GND")
		)
		(pad "AC26" smd circle
			(at 8.400034 5.999988)
			(size 0.3556 0.3556)
			(layers "F.Cu" "F.Mask" "F.Paste")
			(net "GND")
		)
		(pad "AC27" smd circle
			(at 9.19988 5.999988)
			(size 0.3556 0.3556)
			(layers "F.Cu" "F.Mask" "F.Paste")
			(net "P1V8_C")
		)
		(pad "AC28" smd circle
			(at 9.99998 5.999988)
			(size 0.3556 0.3556)
			(layers "F.Cu" "F.Mask" "F.Paste")
			(net "IOC_GPIO_28")
		)
		(pad "AC29" smd circle
			(at 10.80008 5.999988)
			(size 0.3556 0.3556)
			(layers "F.Cu" "F.Mask" "F.Paste")
			(net "IOC_GPIO_30")
		)
		(pad "AC30" smd circle
			(at 11.599926 5.999988)
			(size 0.3556 0.3556)
			(layers "F.Cu" "F.Mask" "F.Paste")
			(net "IOC_GPIO_8")
		)
		(pad "AD1" smd circle
			(at -11.599926 6.800088)
			(size 0.3556 0.3556)
			(layers "F.Cu" "F.Mask" "F.Paste")
			(net "SAS3008_RAID_TX_C_P3")
		)
		(pad "AD2" smd circle
			(at -10.80008 6.800088)
			(size 0.3556 0.3556)
			(layers "F.Cu" "F.Mask" "F.Paste")
			(net "SAS3008_RAID_TX_C_N3")
		)
		(pad "AD3" smd circle
			(at -9.99998 6.800088)
			(size 0.3556 0.3556)
			(layers "F.Cu" "F.Mask" "F.Paste")
			(net "GND")
		)
		(pad "AD4" smd circle
			(at -9.19988 6.800088)
			(size 0.3556 0.3556)
			(layers "F.Cu" "F.Mask" "F.Paste")
			(net "3008_SAS_RX_P3")
		)
		(pad "AD5" smd circle
			(at -8.400034 6.800088)
			(size 0.3556 0.3556)
			(layers "F.Cu" "F.Mask" "F.Paste")
			(net "3008_SAS_RX_N3")
		)
		(pad "AD6" smd circle
			(at -7.599934 6.800088)
			(size 0.3556 0.3556)
			(layers "F.Cu" "F.Mask" "F.Paste")
			(net "GND")
		)
		(pad "AD7" smd circle
			(at -6.800088 6.800088)
			(size 0.3556 0.3556)
			(layers "F.Cu" "F.Mask" "F.Paste")
			(net "SAS0_AVDD")
		)
		(pad "AD8" smd circle
			(at -5.999988 6.800088)
			(size 0.3556 0.3556)
			(layers "F.Cu" "F.Mask" "F.Paste")
			(net "GND")
		)
		(pad "AD9" smd circle
			(at -5.199888 6.800088)
			(size 0.3556 0.3556)
			(layers "F.Cu" "F.Mask" "F.Paste")
			(net "PCE_AVDD")
		)
		(pad "AD10" smd circle
			(at -4.400042 6.800088)
			(size 0.3556 0.3556)
			(layers "F.Cu" "F.Mask" "F.Paste")
			(net "GND")
		)
		(pad "AD11" smd circle
			(at -3.599942 6.800088)
			(size 0.3556 0.3556)
			(layers "F.Cu" "F.Mask" "F.Paste")
			(net "PCE_AVDD")
		)
		(pad "AD12" smd circle
			(at -2.800096 6.800088)
			(size 0.3556 0.3556)
			(layers "F.Cu" "F.Mask" "F.Paste")
			(net "GND")
		)
		(pad "AD13" smd circle
			(at -1.999996 6.800088)
			(size 0.3556 0.3556)
			(layers "F.Cu" "F.Mask" "F.Paste")
			(net "PCE_AVDD")
		)
		(pad "AD14" smd circle
			(at -1.199896 6.800088)
			(size 0.3556 0.3556)
			(layers "F.Cu" "F.Mask" "F.Paste")
			(net "GND")
		)
		(pad "AD15" smd circle
			(at -0.40005 6.800088)
			(size 0.3556 0.3556)
			(layers "F.Cu" "F.Mask" "F.Paste")
			(net "PCE_AVDD")
		)
		(pad "AD16" smd circle
			(at 0.40005 6.800088)
			(size 0.3556 0.3556)
			(layers "F.Cu" "F.Mask" "F.Paste")
			(net "GND")
		)
		(pad "AD17" smd circle
			(at 1.199896 6.800088)
			(size 0.3556 0.3556)
			(layers "F.Cu" "F.Mask" "F.Paste")
			(net "GND")
		)
		(pad "AD18" smd circle
			(at 1.999996 6.800088)
			(size 0.3556 0.3556)
			(layers "F.Cu" "F.Mask" "F.Paste")
			(net "GND")
		)
		(pad "AD19" smd circle
			(at 2.800096 6.800088)
			(size 0.3556 0.3556)
			(layers "F.Cu" "F.Mask" "F.Paste")
			(net "GND")
		)
		(pad "AD20" smd circle
			(at 3.599942 6.800088)
			(size 0.3556 0.3556)
			(layers "F.Cu" "F.Mask" "F.Paste")
			(net "GND")
		)
		(pad "AD21" smd circle
			(at 4.400042 6.800088)
			(size 0.3556 0.3556)
			(layers "F.Cu" "F.Mask" "F.Paste")
			(net "GND")
		)
		(pad "AD22" smd circle
			(at 5.199888 6.800088)
			(size 0.3556 0.3556)
			(layers "F.Cu" "F.Mask" "F.Paste")
			(net "GND")
		)
		(pad "AD23" smd circle
			(at 5.999988 6.800088)
			(size 0.3556 0.3556)
			(layers "F.Cu" "F.Mask" "F.Paste")
			(net "GND")
		)
		(pad "AD24" smd circle
			(at 6.800088 6.800088)
			(size 0.3556 0.3556)
			(layers "F.Cu" "F.Mask" "F.Paste")
			(net "GND")
		)
		(pad "AD25" smd circle
			(at 7.599934 6.800088)
			(size 0.3556 0.3556)
			(layers "F.Cu" "F.Mask" "F.Paste")
			(net "GND")
		)
		(pad "AD26" smd circle
			(at 8.400034 6.800088)
			(size 0.3556 0.3556)
			(layers "F.Cu" "F.Mask" "F.Paste")
			(net "P1V8_C")
		)
		(pad "AD27" smd circle
			(at 9.19988 6.800088)
			(size 0.3556 0.3556)
			(layers "F.Cu" "F.Mask" "F.Paste")
			(net "GND")
		)
		(pad "AD28" smd circle
			(at 9.99998 6.800088)
			(size 0.3556 0.3556)
			(layers "F.Cu" "F.Mask" "F.Paste")
			(net "IOC_GPIO_29")
		)
		(pad "AD29" smd circle
			(at 10.80008 6.800088)
			(size 0.3556 0.3556)
			(layers "F.Cu" "F.Mask" "F.Paste")
			(net "IOC_GPIO_27")
		)
		(pad "AD30" smd circle
			(at 11.599926 6.800088)
			(size 0.3556 0.3556)
			(layers "F.Cu" "F.Mask" "F.Paste")
			(net "IOC_GPIO_17")
		)
		(pad "AE1" smd circle
			(at -11.599926 7.599934)
			(size 0.3556 0.3556)
			(layers "F.Cu" "F.Mask" "F.Paste")
			(net "SAS3008_RAID_TX_C_P2")
		)
		(pad "AE2" smd circle
			(at -10.80008 7.599934)
			(size 0.3556 0.3556)
			(layers "F.Cu" "F.Mask" "F.Paste")
			(net "SAS3008_RAID_TX_C_N2")
		)
		(pad "AE3" smd circle
			(at -9.99998 7.599934)
			(size 0.3556 0.3556)
			(layers "F.Cu" "F.Mask" "F.Paste")
			(net "GND")
		)
		(pad "AE4" smd circle
			(at -9.19988 7.599934)
			(size 0.3556 0.3556)
			(layers "F.Cu" "F.Mask" "F.Paste")
			(net "3008_SAS_RX_P2")
		)
		(pad "AE5" smd circle
			(at -8.400034 7.599934)
			(size 0.3556 0.3556)
			(layers "F.Cu" "F.Mask" "F.Paste")
			(net "3008_SAS_RX_N2")
		)
		(pad "AE6" smd circle
			(at -7.599934 7.599934)
			(size 0.3556 0.3556)
			(layers "F.Cu" "F.Mask" "F.Paste")
			(net "GND")
		)
		(pad "AE7" smd circle
			(at -6.800088 7.599934)
			(size 0.3556 0.3556)
			(layers "F.Cu" "F.Mask" "F.Paste")
			(net "GND")
		)
		(pad "AE8" smd circle
			(at -5.999988 7.599934)
			(size 0.3556 0.3556)
			(layers "F.Cu" "F.Mask" "F.Paste")
			(net "P1V5_C")
		)
		(pad "AE9" smd circle
			(at -5.199888 7.599934)
			(size 0.3556 0.3556)
			(layers "F.Cu" "F.Mask" "F.Paste")
			(net "GND")
		)
		(pad "AE10" smd circle
			(at -4.400042 7.599934)
			(size 0.3556 0.3556)
			(layers "F.Cu" "F.Mask" "F.Paste")
			(net "P1V5_C")
		)
		(pad "AE11" smd circle
			(at -3.599942 7.599934)
			(size 0.3556 0.3556)
			(layers "F.Cu" "F.Mask" "F.Paste")
			(net "GND")
		)
		(pad "AE12" smd circle
			(at -2.800096 7.599934)
			(size 0.3556 0.3556)
			(layers "F.Cu" "F.Mask" "F.Paste")
			(net "P1V5_C")
		)
		(pad "AE13" smd circle
			(at -1.999996 7.599934)
			(size 0.3556 0.3556)
			(layers "F.Cu" "F.Mask" "F.Paste")
			(net "GND")
		)
		(pad "AE14" smd circle
			(at -1.199896 7.599934)
			(size 0.3556 0.3556)
			(layers "F.Cu" "F.Mask" "F.Paste")
			(net "P1V5_C")
		)
		(pad "AE15" smd circle
			(at -0.40005 7.599934)
			(size 0.3556 0.3556)
			(layers "F.Cu" "F.Mask" "F.Paste")
			(net "GND")
		)
		(pad "AE16" smd circle
			(at 0.40005 7.599934)
			(size 0.3556 0.3556)
			(layers "F.Cu" "F.Mask" "F.Paste")
			(net "P1V5_C")
		)
		(pad "AE17" smd circle
			(at 1.199896 7.599934)
			(size 0.3556 0.3556)
			(layers "F.Cu" "F.Mask" "F.Paste")
			(net "GND")
		)
		(pad "AE18" smd circle
			(at 1.999996 7.599934)
			(size 0.3556 0.3556)
			(layers "F.Cu" "F.Mask" "F.Paste")
			(net "GND")
		)
		(pad "AE19" smd circle
			(at 2.800096 7.599934)
			(size 0.3556 0.3556)
			(layers "F.Cu" "F.Mask" "F.Paste")
			(net "SPARE5")
		)
		(pad "AE20" smd circle
			(at 3.599942 7.599934)
			(size 0.3556 0.3556)
			(layers "F.Cu" "F.Mask" "F.Paste")
			(net "SPARE3")
		)
		(pad "AE21" smd circle
			(at 4.400042 7.599934)
			(size 0.3556 0.3556)
			(layers "F.Cu" "F.Mask" "F.Paste")
			(net "IOC_GPIO_7")
		)
		(pad "AE22" smd circle
			(at 5.199888 7.599934)
			(size 0.3556 0.3556)
			(layers "F.Cu" "F.Mask" "F.Paste")
			(net "SYS_DBMODE0")
		)
		(pad "AE23" smd circle
			(at 5.999988 7.599934)
			(size 0.3556 0.3556)
			(layers "F.Cu" "F.Mask" "F.Paste")
			(net "SYS_RST_N_1")
		)
		(pad "AE24" smd circle
			(at 6.800088 7.599934)
			(size 0.3556 0.3556)
			(layers "F.Cu" "F.Mask" "F.Paste")
			(net "GND")
		)
		(pad "AE25" smd circle
			(at 7.599934 7.599934)
			(size 0.3556 0.3556)
			(layers "F.Cu" "F.Mask" "F.Paste")
			(net "GND")
		)
		(pad "AE26" smd circle
			(at 8.400034 7.599934)
			(size 0.3556 0.3556)
			(layers "F.Cu" "F.Mask" "F.Paste")
			(net "GND")
		)
		(pad "AE27" smd circle
			(at 9.19988 7.599934)
			(size 0.3556 0.3556)
			(layers "F.Cu" "F.Mask" "F.Paste")
			(net "P1V8_C")
		)
		(pad "AE28" smd circle
			(at 9.99998 7.599934)
			(size 0.3556 0.3556)
			(layers "F.Cu" "F.Mask" "F.Paste")
			(net "UART_SERCLK")
		)
		(pad "AE29" smd circle
			(at 10.80008 7.599934)
			(size 0.3556 0.3556)
			(layers "F.Cu" "F.Mask" "F.Paste")
			(net "IOC_GPIO_39")
		)
		(pad "AE30" smd circle
			(at 11.599926 7.599934)
			(size 0.3556 0.3556)
			(layers "F.Cu" "F.Mask" "F.Paste")
			(net "IOC_GPIO_31")
		)
		(pad "AF1" smd circle
			(at -11.599926 8.400034)
			(size 0.3556 0.3556)
			(layers "F.Cu" "F.Mask" "F.Paste")
			(net "SAS0_VDDH")
		)
		(pad "AF2" smd circle
			(at -10.80008 8.400034)
			(size 0.3556 0.3556)
			(layers "F.Cu" "F.Mask" "F.Paste")
			(net "GND")
		)
		(pad "AF3" smd circle
			(at -9.99998 8.400034)
			(size 0.3556 0.3556)
			(layers "F.Cu" "F.Mask" "F.Paste")
			(net "GND")
		)
		(pad "AF4" smd circle
			(at -9.19988 8.400034)
			(size 0.3556 0.3556)
			(layers "F.Cu" "F.Mask" "F.Paste")
			(net "SAS0_AVDD")
		)
		(pad "AF5" smd circle
			(at -8.400034 8.400034)
			(size 0.3556 0.3556)
			(layers "F.Cu" "F.Mask" "F.Paste")
			(net "GND")
		)
		(pad "AF6" smd circle
			(at -7.599934 8.400034)
			(size 0.3556 0.3556)
			(layers "F.Cu" "F.Mask" "F.Paste")
			(net "GND")
		)
		(pad "AF7" smd circle
			(at -6.800088 8.400034)
			(size 0.3556 0.3556)
			(layers "F.Cu" "F.Mask" "F.Paste")
			(net "PCIE_SAS_C_CPU_RX_N0")
		)
		(pad "AF8" smd circle
			(at -5.999988 8.400034)
			(size 0.3556 0.3556)
			(layers "F.Cu" "F.Mask" "F.Paste")
			(net "PCIE_SAS_C_CPU_RX_N1")
		)
		(pad "AF9" smd circle
			(at -5.199888 8.400034)
			(size 0.3556 0.3556)
			(layers "F.Cu" "F.Mask" "F.Paste")
			(net "GND")
		)
		(pad "AF10" smd circle
			(at -4.400042 8.400034)
			(size 0.3556 0.3556)
			(layers "F.Cu" "F.Mask" "F.Paste")
			(net "PCIE_SAS_C_CPU_RX_N2")
		)
		(pad "AF11" smd circle
			(at -3.599942 8.400034)
			(size 0.3556 0.3556)
			(layers "F.Cu" "F.Mask" "F.Paste")
			(net "PCIE_SAS_C_CPU_RX_N3")
		)
		(pad "AF12" smd circle
			(at -2.800096 8.400034)
			(size 0.3556 0.3556)
			(layers "F.Cu" "F.Mask" "F.Paste")
			(net "GND")
		)
		(pad "AF13" smd circle
			(at -1.999996 8.400034)
			(size 0.3556 0.3556)
			(layers "F.Cu" "F.Mask" "F.Paste")
			(net "PCIE_SAS_C_CPU_RX_N4")
		)
		(pad "AF14" smd circle
			(at -1.199896 8.400034)
			(size 0.3556 0.3556)
			(layers "F.Cu" "F.Mask" "F.Paste")
			(net "PCIE_SAS_C_CPU_RX_N5")
		)
		(pad "AF15" smd circle
			(at -0.40005 8.400034)
			(size 0.3556 0.3556)
			(layers "F.Cu" "F.Mask" "F.Paste")
			(net "GND")
		)
		(pad "AF16" smd circle
			(at 0.40005 8.400034)
			(size 0.3556 0.3556)
			(layers "F.Cu" "F.Mask" "F.Paste")
			(net "PCIE_SAS_C_CPU_RX_N6")
		)
		(pad "AF17" smd circle
			(at 1.199896 8.400034)
			(size 0.3556 0.3556)
			(layers "F.Cu" "F.Mask" "F.Paste")
			(net "PCIE_SAS_C_CPU_RX_N7")
		)
		(pad "AF18" smd circle
			(at 1.999996 8.400034)
			(size 0.3556 0.3556)
			(layers "F.Cu" "F.Mask" "F.Paste")
			(net "GND")
		)
		(pad "AF19" smd circle
			(at 2.800096 8.400034)
			(size 0.3556 0.3556)
			(layers "F.Cu" "F.Mask" "F.Paste")
			(net "GND")
		)
		(pad "AF20" smd circle
			(at 3.599942 8.400034)
			(size 0.3556 0.3556)
			(layers "F.Cu" "F.Mask" "F.Paste")
			(net "P1V8_C")
		)
		(pad "AF21" smd circle
			(at 4.400042 8.400034)
			(size 0.3556 0.3556)
			(layers "F.Cu" "F.Mask" "F.Paste")
			(net "GND")
		)
		(pad "AF22" smd circle
			(at 5.199888 8.400034)
			(size 0.3556 0.3556)
			(layers "F.Cu" "F.Mask" "F.Paste")
			(net "P1V8_C")
		)
		(pad "AF23" smd circle
			(at 5.999988 8.400034)
			(size 0.3556 0.3556)
			(layers "F.Cu" "F.Mask" "F.Paste")
			(net "GND")
		)
		(pad "AF24" smd circle
			(at 6.800088 8.400034)
			(size 0.3556 0.3556)
			(layers "F.Cu" "F.Mask" "F.Paste")
			(net "P1V8_C")
		)
		(pad "AF25" smd circle
			(at 7.599934 8.400034)
			(size 0.3556 0.3556)
			(layers "F.Cu" "F.Mask" "F.Paste")
			(net "GND")
		)
		(pad "AF26" smd circle
			(at 8.400034 8.400034)
			(size 0.3556 0.3556)
			(layers "F.Cu" "F.Mask" "F.Paste")
			(net "P1V8_C")
		)
		(pad "AF27" smd circle
			(at 9.19988 8.400034)
			(size 0.3556 0.3556)
			(layers "F.Cu" "F.Mask" "F.Paste")
			(net "GND")
		)
		(pad "AF28" smd circle
			(at 9.99998 8.400034)
			(size 0.3556 0.3556)
			(layers "F.Cu" "F.Mask" "F.Paste")
			(net "IOC_GPIO_26")
		)
		(pad "AF29" smd circle
			(at 10.80008 8.400034)
			(size 0.3556 0.3556)
			(layers "F.Cu" "F.Mask" "F.Paste")
			(net "IOC_GPIO_0")
		)
		(pad "AF30" smd circle
			(at 11.599926 8.400034)
			(size 0.3556 0.3556)
			(layers "F.Cu" "F.Mask" "F.Paste")
			(net "IOC_GPIO_16")
		)
		(pad "AG1" smd circle
			(at -11.599926 9.19988)
			(size 0.3556 0.3556)
			(layers "F.Cu" "F.Mask" "F.Paste")
			(net "SAS3008_RAID_TX_C_P1")
		)
		(pad "AG2" smd circle
			(at -10.80008 9.19988)
			(size 0.3556 0.3556)
			(layers "F.Cu" "F.Mask" "F.Paste")
			(net "SAS3008_RAID_TX_C_N1")
		)
		(pad "AG3" smd circle
			(at -9.99998 9.19988)
			(size 0.3556 0.3556)
			(layers "F.Cu" "F.Mask" "F.Paste")
			(net "GND")
		)
		(pad "AG4" smd circle
			(at -9.19988 9.19988)
			(size 0.3556 0.3556)
			(layers "F.Cu" "F.Mask" "F.Paste")
			(net "3008_SAS_RX_P1")
		)
		(pad "AG5" smd circle
			(at -8.400034 9.19988)
			(size 0.3556 0.3556)
			(layers "F.Cu" "F.Mask" "F.Paste")
			(net "3008_SAS_RX_N1")
		)
		(pad "AG6" smd circle
			(at -7.599934 9.19988)
			(size 0.3556 0.3556)
			(layers "F.Cu" "F.Mask" "F.Paste")
			(net "GND")
		)
		(pad "AG7" smd circle
			(at -6.800088 9.19988)
			(size 0.3556 0.3556)
			(layers "F.Cu" "F.Mask" "F.Paste")
			(net "PCIE_SAS_C_CPU_RX_P0")
		)
		(pad "AG8" smd circle
			(at -5.999988 9.19988)
			(size 0.3556 0.3556)
			(layers "F.Cu" "F.Mask" "F.Paste")
			(net "PCIE_SAS_C_CPU_RX_P1")
		)
		(pad "AG9" smd circle
			(at -5.199888 9.19988)
			(size 0.3556 0.3556)
			(layers "F.Cu" "F.Mask" "F.Paste")
			(net "P1V5_C")
		)
		(pad "AG10" smd circle
			(at -4.400042 9.19988)
			(size 0.3556 0.3556)
			(layers "F.Cu" "F.Mask" "F.Paste")
			(net "PCIE_SAS_C_CPU_RX_P2")
		)
		(pad "AG11" smd circle
			(at -3.599942 9.19988)
			(size 0.3556 0.3556)
			(layers "F.Cu" "F.Mask" "F.Paste")
			(net "PCIE_SAS_C_CPU_RX_P3")
		)
		(pad "AG12" smd circle
			(at -2.800096 9.19988)
			(size 0.3556 0.3556)
			(layers "F.Cu" "F.Mask" "F.Paste")
			(net "P1V5_C")
		)
		(pad "AG13" smd circle
			(at -1.999996 9.19988)
			(size 0.3556 0.3556)
			(layers "F.Cu" "F.Mask" "F.Paste")
			(net "PCIE_SAS_C_CPU_RX_P4")
		)
		(pad "AG14" smd circle
			(at -1.199896 9.19988)
			(size 0.3556 0.3556)
			(layers "F.Cu" "F.Mask" "F.Paste")
			(net "PCIE_SAS_C_CPU_RX_P5")
		)
		(pad "AG15" smd circle
			(at -0.40005 9.19988)
			(size 0.3556 0.3556)
			(layers "F.Cu" "F.Mask" "F.Paste")
			(net "GND")
		)
		(pad "AG16" smd circle
			(at 0.40005 9.19988)
			(size 0.3556 0.3556)
			(layers "F.Cu" "F.Mask" "F.Paste")
			(net "PCIE_SAS_C_CPU_RX_P6")
		)
		(pad "AG17" smd circle
			(at 1.199896 9.19988)
			(size 0.3556 0.3556)
			(layers "F.Cu" "F.Mask" "F.Paste")
			(net "PCIE_SAS_C_CPU_RX_P7")
		)
		(pad "AG18" smd circle
			(at 1.999996 9.19988)
			(size 0.3556 0.3556)
			(layers "F.Cu" "F.Mask" "F.Paste")
			(net "P1V5_C")
		)
		(pad "AG19" smd circle
			(at 2.800096 9.19988)
			(size 0.3556 0.3556)
			(layers "F.Cu" "F.Mask" "F.Paste")
			(net "P1V8_C")
		)
		(pad "AG20" smd circle
			(at 3.599942 9.19988)
			(size 0.3556 0.3556)
			(layers "F.Cu" "F.Mask" "F.Paste")
			(net "GND")
		)
		(pad "AG21" smd circle
			(at 4.400042 9.19988)
			(size 0.3556 0.3556)
			(layers "F.Cu" "F.Mask" "F.Paste")
			(net "P1V8_C")
		)
		(pad "AG22" smd circle
			(at 5.199888 9.19988)
			(size 0.3556 0.3556)
			(layers "F.Cu" "F.Mask" "F.Paste")
			(net "GND")
		)
		(pad "AG23" smd circle
			(at 5.999988 9.19988)
			(size 0.3556 0.3556)
			(layers "F.Cu" "F.Mask" "F.Paste")
			(net "P1V8_C")
		)
		(pad "AG24" smd circle
			(at 6.800088 9.19988)
			(size 0.3556 0.3556)
			(layers "F.Cu" "F.Mask" "F.Paste")
			(net "GND")
		)
		(pad "AG25" smd circle
			(at 7.599934 9.19988)
			(size 0.3556 0.3556)
			(layers "F.Cu" "F.Mask" "F.Paste")
			(net "P1V8_C")
		)
		(pad "AG26" smd circle
			(at 8.400034 9.19988)
			(size 0.3556 0.3556)
			(layers "F.Cu" "F.Mask" "F.Paste")
			(net "GND")
		)
		(pad "AG27" smd circle
			(at 9.19988 9.19988)
			(size 0.3556 0.3556)
			(layers "F.Cu" "F.Mask" "F.Paste")
			(net "P1V8_C")
		)
		(pad "AG28" smd circle
			(at 9.99998 9.19988)
			(size 0.3556 0.3556)
			(layers "F.Cu" "F.Mask" "F.Paste")
			(net "IOC_GPIO_25")
		)
		(pad "AG29" smd circle
			(at 10.80008 9.19988)
			(size 0.3556 0.3556)
			(layers "F.Cu" "F.Mask" "F.Paste")
			(net "IOC_GPIO_18")
		)
		(pad "AG30" smd circle
			(at 11.599926 9.19988)
			(size 0.3556 0.3556)
			(layers "F.Cu" "F.Mask" "F.Paste")
			(net "IOC_GPIO_21")
		)
		(pad "AH1" smd circle
			(at -11.599926 9.99998)
			(size 0.4064 0.4064)
			(layers "F.Cu" "F.Mask" "F.Paste")
			(net "SAS3008_RAID_TX_C_P0")
		)
		(pad "AH2" smd circle
			(at -10.80008 9.99998)
			(size 0.4064 0.4064)
			(layers "F.Cu" "F.Mask" "F.Paste")
			(net "SAS3008_RAID_TX_C_N0")
		)
		(pad "AH3" smd circle
			(at -9.99998 9.99998)
			(size 0.4064 0.4064)
			(layers "F.Cu" "F.Mask" "F.Paste")
			(net "GND")
		)
		(pad "AH4" smd circle
			(at -9.19988 9.99998)
			(size 0.3556 0.3556)
			(layers "F.Cu" "F.Mask" "F.Paste")
			(net "3008_SAS_RX_P0")
		)
		(pad "AH5" smd circle
			(at -8.400034 9.99998)
			(size 0.3556 0.3556)
			(layers "F.Cu" "F.Mask" "F.Paste")
			(net "3008_SAS_RX_N0")
		)
		(pad "AH6" smd circle
			(at -7.599934 9.99998)
			(size 0.3556 0.3556)
			(layers "F.Cu" "F.Mask" "F.Paste")
			(net "GND")
		)
		(pad "AH7" smd circle
			(at -6.800088 9.99998)
			(size 0.3556 0.3556)
			(layers "F.Cu" "F.Mask" "F.Paste")
			(net "GND")
		)
		(pad "AH8" smd circle
			(at -5.999988 9.99998)
			(size 0.3556 0.3556)
			(layers "F.Cu" "F.Mask" "F.Paste")
			(net "GND")
		)
		(pad "AH9" smd circle
			(at -5.199888 9.99998)
			(size 0.3556 0.3556)
			(layers "F.Cu" "F.Mask" "F.Paste")
			(net "GND")
		)
		(pad "AH10" smd circle
			(at -4.400042 9.99998)
			(size 0.3556 0.3556)
			(layers "F.Cu" "F.Mask" "F.Paste")
			(net "GND")
		)
		(pad "AH11" smd circle
			(at -3.599942 9.99998)
			(size 0.3556 0.3556)
			(layers "F.Cu" "F.Mask" "F.Paste")
			(net "GND")
		)
		(pad "AH12" smd circle
			(at -2.800096 9.99998)
			(size 0.3556 0.3556)
			(layers "F.Cu" "F.Mask" "F.Paste")
			(net "GND")
		)
		(pad "AH13" smd circle
			(at -1.999996 9.99998)
			(size 0.3556 0.3556)
			(layers "F.Cu" "F.Mask" "F.Paste")
			(net "GND")
		)
		(pad "AH14" smd circle
			(at -1.199896 9.99998)
			(size 0.3556 0.3556)
			(layers "F.Cu" "F.Mask" "F.Paste")
			(net "GND")
		)
		(pad "AH15" smd circle
			(at -0.40005 9.99998)
			(size 0.3556 0.3556)
			(layers "F.Cu" "F.Mask" "F.Paste")
			(net "P1V5_C")
		)
		(pad "AH16" smd circle
			(at 0.40005 9.99998)
			(size 0.3556 0.3556)
			(layers "F.Cu" "F.Mask" "F.Paste")
			(net "GND")
		)
		(pad "AH17" smd circle
			(at 1.199896 9.99998)
			(size 0.3556 0.3556)
			(layers "F.Cu" "F.Mask" "F.Paste")
			(net "GND")
		)
		(pad "AH18" smd circle
			(at 1.999996 9.99998)
			(size 0.3556 0.3556)
			(layers "F.Cu" "F.Mask" "F.Paste")
			(net "GND")
		)
		(pad "AH19" smd circle
			(at 2.800096 9.99998)
			(size 0.3556 0.3556)
			(layers "F.Cu" "F.Mask" "F.Paste")
			(net "Net_1031")
		)
		(pad "AH20" smd circle
			(at 3.599942 9.99998)
			(size 0.3556 0.3556)
			(layers "F.Cu" "F.Mask" "F.Paste")
			(net "SYS_RST_N_0")
		)
		(pad "AH21" smd circle
			(at 4.400042 9.99998)
			(size 0.3556 0.3556)
			(layers "F.Cu" "F.Mask" "F.Paste")
			(net "IOC_UART_1_TX")
		)
		(pad "AH22" smd circle
			(at 5.199888 9.99998)
			(size 0.3556 0.3556)
			(layers "F.Cu" "F.Mask" "F.Paste")
			(net "IOC_GPIO_2")
		)
		(pad "AH23" smd circle
			(at 5.999988 9.99998)
			(size 0.3556 0.3556)
			(layers "F.Cu" "F.Mask" "F.Paste")
			(net "IOC_GPIO_3")
		)
		(pad "AH24" smd circle
			(at 6.800088 9.99998)
			(size 0.3556 0.3556)
			(layers "F.Cu" "F.Mask" "F.Paste")
			(net "IOC_GPIO_5")
		)
		(pad "AH25" smd circle
			(at 7.599934 9.99998)
			(size 0.3556 0.3556)
			(layers "F.Cu" "F.Mask" "F.Paste")
			(net "IOC_GPIO_6")
		)
		(pad "AH26" smd circle
			(at 8.400034 9.99998)
			(size 0.3556 0.3556)
			(layers "F.Cu" "F.Mask" "F.Paste")
			(net "IOC_UART_1_RX")
		)
		(pad "AH27" smd circle
			(at 9.19988 9.99998)
			(size 0.3556 0.3556)
			(layers "F.Cu" "F.Mask" "F.Paste")
			(net "SPARE0")
		)
		(pad "AH28" smd circle
			(at 9.99998 9.99998)
			(size 0.4064 0.4064)
			(layers "F.Cu" "F.Mask" "F.Paste")
			(net "IOC_GPIO_10")
		)
		(pad "AH29" smd circle
			(at 10.80008 9.99998)
			(size 0.4064 0.4064)
			(layers "F.Cu" "F.Mask" "F.Paste")
			(net "IOC_GPIO_22")
		)
		(pad "AH30" smd circle
			(at 11.599926 9.99998)
			(size 0.4064 0.4064)
			(layers "F.Cu" "F.Mask" "F.Paste")
			(net "IOC_GPIO_11")
		)
		(pad "AJ1" smd circle
			(at -11.599926 10.80008)
			(size 0.4064 0.4064)
			(layers "F.Cu" "F.Mask" "F.Paste")
			(net "SAS0_VDDH")
		)
		(pad "AJ2" smd circle
			(at -10.80008 10.80008)
			(size 0.4064 0.4064)
			(layers "F.Cu" "F.Mask" "F.Paste")
			(net "GND")
		)
		(pad "AJ3" smd circle
			(at -9.99998 10.80008)
			(size 0.4064 0.4064)
			(layers "F.Cu" "F.Mask" "F.Paste")
			(net "SAS0_AVDD")
		)
		(pad "AJ4" smd circle
			(at -9.19988 10.80008)
			(size 0.3556 0.3556)
			(layers "F.Cu" "F.Mask" "F.Paste")
			(net "GND")
		)
		(pad "AJ5" smd circle
			(at -8.400034 10.80008)
			(size 0.3556 0.3556)
			(layers "F.Cu" "F.Mask" "F.Paste")
			(net "GND")
		)
		(pad "AJ6" smd circle
			(at -7.599934 10.80008)
			(size 0.3556 0.3556)
			(layers "F.Cu" "F.Mask" "F.Paste")
			(net "GND")
		)
		(pad "AJ7" smd circle
			(at -6.800088 10.80008)
			(size 0.3556 0.3556)
			(layers "F.Cu" "F.Mask" "F.Paste")
			(net "PCIE_SAS_CPU_TX_N0")
		)
		(pad "AJ8" smd circle
			(at -5.999988 10.80008)
			(size 0.3556 0.3556)
			(layers "F.Cu" "F.Mask" "F.Paste")
			(net "PCIE_SAS_CPU_TX_N1")
		)
		(pad "AJ9" smd circle
			(at -5.199888 10.80008)
			(size 0.3556 0.3556)
			(layers "F.Cu" "F.Mask" "F.Paste")
			(net "GND")
		)
		(pad "AJ10" smd circle
			(at -4.400042 10.80008)
			(size 0.3556 0.3556)
			(layers "F.Cu" "F.Mask" "F.Paste")
			(net "PCIE_SAS_CPU_TX_N2")
		)
		(pad "AJ11" smd circle
			(at -3.599942 10.80008)
			(size 0.3556 0.3556)
			(layers "F.Cu" "F.Mask" "F.Paste")
			(net "PCIE_SAS_CPU_TX_N3")
		)
		(pad "AJ12" smd circle
			(at -2.800096 10.80008)
			(size 0.3556 0.3556)
			(layers "F.Cu" "F.Mask" "F.Paste")
			(net "GND")
		)
		(pad "AJ13" smd circle
			(at -1.999996 10.80008)
			(size 0.3556 0.3556)
			(layers "F.Cu" "F.Mask" "F.Paste")
			(net "PCIE_SAS_CPU_TX_N4")
		)
		(pad "AJ14" smd circle
			(at -1.199896 10.80008)
			(size 0.3556 0.3556)
			(layers "F.Cu" "F.Mask" "F.Paste")
			(net "PCIE_SAS_CPU_TX_N5")
		)
		(pad "AJ15" smd circle
			(at -0.40005 10.80008)
			(size 0.3556 0.3556)
			(layers "F.Cu" "F.Mask" "F.Paste")
			(net "GND")
		)
		(pad "AJ16" smd circle
			(at 0.40005 10.80008)
			(size 0.3556 0.3556)
			(layers "F.Cu" "F.Mask" "F.Paste")
			(net "PCIE_SAS_CPU_TX_N6")
		)
		(pad "AJ17" smd circle
			(at 1.199896 10.80008)
			(size 0.3556 0.3556)
			(layers "F.Cu" "F.Mask" "F.Paste")
			(net "PCIE_SAS_CPU_TX_N7")
		)
		(pad "AJ18" smd circle
			(at 1.999996 10.80008)
			(size 0.3556 0.3556)
			(layers "F.Cu" "F.Mask" "F.Paste")
			(net "GND")
		)
		(pad "AJ19" smd circle
			(at 2.800096 10.80008)
			(size 0.3556 0.3556)
			(layers "F.Cu" "F.Mask" "F.Paste")
			(net "Net_1032")
		)
		(pad "AJ20" smd circle
			(at 3.599942 10.80008)
			(size 0.3556 0.3556)
			(layers "F.Cu" "F.Mask" "F.Paste")
			(net "SYS_ERR_0")
		)
		(pad "AJ21" smd circle
			(at 4.400042 10.80008)
			(size 0.3556 0.3556)
			(layers "F.Cu" "F.Mask" "F.Paste")
			(net "IOC_RESET#")
		)
		(pad "AJ22" smd circle
			(at 5.199888 10.80008)
			(size 0.3556 0.3556)
			(layers "F.Cu" "F.Mask" "F.Paste")
			(net "SPARE2")
		)
		(pad "AJ23" smd circle
			(at 5.999988 10.80008)
			(size 0.3556 0.3556)
			(layers "F.Cu" "F.Mask" "F.Paste")
			(net "SYS_DBMODE3")
		)
		(pad "AJ24" smd circle
			(at 6.800088 10.80008)
			(size 0.3556 0.3556)
			(layers "F.Cu" "F.Mask" "F.Paste")
			(net "IOC_UART_0_RX")
		)
		(pad "AJ25" smd circle
			(at 7.599934 10.80008)
			(size 0.3556 0.3556)
			(layers "F.Cu" "F.Mask" "F.Paste")
			(net "IOC_GPIO_13")
		)
		(pad "AJ26" smd circle
			(at 8.400034 10.80008)
			(size 0.3556 0.3556)
			(layers "F.Cu" "F.Mask" "F.Paste")
			(net "IOC_GPIO_1")
		)
		(pad "AJ27" smd circle
			(at 9.19988 10.80008)
			(size 0.3556 0.3556)
			(layers "F.Cu" "F.Mask" "F.Paste")
			(net "IOC_GPIO_14")
		)
		(pad "AJ28" smd circle
			(at 9.99998 10.80008)
			(size 0.4064 0.4064)
			(layers "F.Cu" "F.Mask" "F.Paste")
			(net "IOC_GPIO_20")
		)
		(pad "AJ29" smd circle
			(at 10.80008 10.80008)
			(size 0.4064 0.4064)
			(layers "F.Cu" "F.Mask" "F.Paste")
			(net "IOC_GPIO_12")
		)
		(pad "AJ30" smd circle
			(at 11.599926 10.80008)
			(size 0.4064 0.4064)
			(layers "F.Cu" "F.Mask" "F.Paste")
			(net "IOC_GPIO_4")
		)
		(pad "AK2" smd circle
			(at -10.80008 11.599926)
			(size 0.4064 0.4064)
			(layers "F.Cu" "F.Mask" "F.Paste")
			(net "GND")
		)
		(pad "AK3" smd circle
			(at -9.99998 11.599926)
			(size 0.4064 0.4064)
			(layers "F.Cu" "F.Mask" "F.Paste")
			(net "GND")
		)
		(pad "AK4" smd circle
			(at -9.19988 11.599926)
			(size 0.3556 0.3556)
			(layers "F.Cu" "F.Mask" "F.Paste")
			(net "CLK_100M_PCIE_P")
		)
		(pad "AK5" smd circle
			(at -8.400034 11.599926)
			(size 0.3556 0.3556)
			(layers "F.Cu" "F.Mask" "F.Paste")
			(net "CLK_100M_PCIE_N")
		)
		(pad "AK6" smd circle
			(at -7.599934 11.599926)
			(size 0.3556 0.3556)
			(layers "F.Cu" "F.Mask" "F.Paste")
			(net "PCE_AVDD")
		)
		(pad "AK7" smd circle
			(at -6.800088 11.599926)
			(size 0.3556 0.3556)
			(layers "F.Cu" "F.Mask" "F.Paste")
			(net "PCIE_SAS_CPU_TX_P0")
		)
		(pad "AK8" smd circle
			(at -5.999988 11.599926)
			(size 0.3556 0.3556)
			(layers "F.Cu" "F.Mask" "F.Paste")
			(net "PCIE_SAS_CPU_TX_P1")
		)
		(pad "AK9" smd circle
			(at -5.199888 11.599926)
			(size 0.3556 0.3556)
			(layers "F.Cu" "F.Mask" "F.Paste")
			(net "PCE_AVDD")
		)
		(pad "AK10" smd circle
			(at -4.400042 11.599926)
			(size 0.3556 0.3556)
			(layers "F.Cu" "F.Mask" "F.Paste")
			(net "PCIE_SAS_CPU_TX_P2")
		)
		(pad "AK11" smd circle
			(at -3.599942 11.599926)
			(size 0.3556 0.3556)
			(layers "F.Cu" "F.Mask" "F.Paste")
			(net "PCIE_SAS_CPU_TX_P3")
		)
		(pad "AK12" smd circle
			(at -2.800096 11.599926)
			(size 0.3556 0.3556)
			(layers "F.Cu" "F.Mask" "F.Paste")
			(net "PCE_AVDD")
		)
		(pad "AK13" smd circle
			(at -1.999996 11.599926)
			(size 0.3556 0.3556)
			(layers "F.Cu" "F.Mask" "F.Paste")
			(net "PCIE_SAS_CPU_TX_P4")
		)
		(pad "AK14" smd circle
			(at -1.199896 11.599926)
			(size 0.3556 0.3556)
			(layers "F.Cu" "F.Mask" "F.Paste")
			(net "PCIE_SAS_CPU_TX_P5")
		)
		(pad "AK15" smd circle
			(at -0.40005 11.599926)
			(size 0.3556 0.3556)
			(layers "F.Cu" "F.Mask" "F.Paste")
			(net "PCE_AVDD")
		)
		(pad "AK16" smd circle
			(at 0.40005 11.599926)
			(size 0.3556 0.3556)
			(layers "F.Cu" "F.Mask" "F.Paste")
			(net "PCIE_SAS_CPU_TX_P6")
		)
		(pad "AK17" smd circle
			(at 1.199896 11.599926)
			(size 0.3556 0.3556)
			(layers "F.Cu" "F.Mask" "F.Paste")
			(net "PCIE_SAS_CPU_TX_P7")
		)
		(pad "AK18" smd circle
			(at 1.999996 11.599926)
			(size 0.3556 0.3556)
			(layers "F.Cu" "F.Mask" "F.Paste")
			(net "PCE_AVDD")
		)
		(pad "AK19" smd circle
			(at 2.800096 11.599926)
			(size 0.3556 0.3556)
			(layers "F.Cu" "F.Mask" "F.Paste")
			(net "Net_1033")
		)
		(pad "AK20" smd circle
			(at 3.599942 11.599926)
			(size 0.3556 0.3556)
			(layers "F.Cu" "F.Mask" "F.Paste")
			(net "SYS_DBMODE1")
		)
		(pad "AK21" smd circle
			(at 4.400042 11.599926)
			(size 0.3556 0.3556)
			(layers "F.Cu" "F.Mask" "F.Paste")
			(net "SYS_DBMODE4")
		)
		(pad "AK22" smd circle
			(at 5.199888 11.599926)
			(size 0.3556 0.3556)
			(layers "F.Cu" "F.Mask" "F.Paste")
			(net "SYS_ERROR1")
		)
		(pad "AK23" smd circle
			(at 5.999988 11.599926)
			(size 0.3556 0.3556)
			(layers "F.Cu" "F.Mask" "F.Paste")
			(net "SYS_HALT0#")
		)
		(pad "AK24" smd circle
			(at 6.800088 11.599926)
			(size 0.3556 0.3556)
			(layers "F.Cu" "F.Mask" "F.Paste")
			(net "SYS_DBMODE2")
		)
		(pad "AK25" smd circle
			(at 7.599934 11.599926)
			(size 0.3556 0.3556)
			(layers "F.Cu" "F.Mask" "F.Paste")
			(net "SPARE1")
		)
		(pad "AK26" smd circle
			(at 8.400034 11.599926)
			(size 0.3556 0.3556)
			(layers "F.Cu" "F.Mask" "F.Paste")
			(net "SYS_HALT1#")
		)
		(pad "AK27" smd circle
			(at 9.19988 11.599926)
			(size 0.3556 0.3556)
			(layers "F.Cu" "F.Mask" "F.Paste")
			(net "IOC_UART_0_TX")
		)
		(pad "AK28" smd circle
			(at 9.99998 11.599926)
			(size 0.4064 0.4064)
			(layers "F.Cu" "F.Mask" "F.Paste")
			(net "IOC_GPIO_19")
		)
		(pad "AK29" smd circle
			(at 10.80008 11.599926)
			(size 0.4064 0.4064)
			(layers "F.Cu" "F.Mask" "F.Paste")
			(net "IOC_GPIO_9")
		)
		(pad "B1" smd circle
			(at -11.599926 -10.80008)
			(size 0.4064 0.4064)
			(layers "F.Cu" "F.Mask" "F.Paste")
			(net "Net_1072")
		)
		(pad "B2" smd circle
			(at -10.80008 -10.80008)
			(size 0.4064 0.4064)
			(layers "F.Cu" "F.Mask" "F.Paste")
			(net "GND")
		)
		(pad "B3" smd circle
			(at -9.99998 -10.80008)
			(size 0.4064 0.4064)
			(layers "F.Cu" "F.Mask" "F.Paste")
			(net "Net_1038")
		)
		(pad "B4" smd circle
			(at -9.19988 -10.80008)
			(size 0.3556 0.3556)
			(layers "F.Cu" "F.Mask" "F.Paste")
			(net "Net_1039")
		)
		(pad "B5" smd circle
			(at -8.400034 -10.80008)
			(size 0.3556 0.3556)
			(layers "F.Cu" "F.Mask" "F.Paste")
			(net "Net_1040")
		)
		(pad "B6" smd circle
			(at -7.599934 -10.80008)
			(size 0.3556 0.3556)
			(layers "F.Cu" "F.Mask" "F.Paste")
			(net "GND")
		)
		(pad "B7" smd circle
			(at -6.800088 -10.80008)
			(size 0.3556 0.3556)
			(layers "F.Cu" "F.Mask" "F.Paste")
			(net "ICE1_TCK")
		)
		(pad "B8" smd circle
			(at -5.999988 -10.80008)
			(size 0.3556 0.3556)
			(layers "F.Cu" "F.Mask" "F.Paste")
			(net "ICE0_TDI")
		)
		(pad "B9" smd circle
			(at -5.199888 -10.80008)
			(size 0.3556 0.3556)
			(layers "F.Cu" "F.Mask" "F.Paste")
			(net "IOC_VREF_SET")
		)
		(pad "B10" smd circle
			(at -4.400042 -10.80008)
			(size 0.3556 0.3556)
			(layers "F.Cu" "F.Mask" "F.Paste")
			(net "Net_1041")
		)
		(pad "B11" smd circle
			(at -3.599942 -10.80008)
			(size 0.3556 0.3556)
			(layers "F.Cu" "F.Mask" "F.Paste")
			(net "GND")
		)
		(pad "B12" smd circle
			(at -2.800096 -10.80008)
			(size 0.3556 0.3556)
			(layers "F.Cu" "F.Mask" "F.Paste")
			(net "AVSO_IDDTN18")
		)
		(pad "B13" smd circle
			(at -1.999996 -10.80008)
			(size 0.3556 0.3556)
			(layers "F.Cu" "F.Mask" "F.Paste")
			(net "AVSO_VREF")
		)
		(pad "B14" smd circle
			(at -1.199896 -10.80008)
			(size 0.3556 0.3556)
			(layers "F.Cu" "F.Mask" "F.Paste")
			(net "GND")
		)
		(pad "B15" smd circle
			(at -0.40005 -10.80008)
			(size 0.3556 0.3556)
			(layers "F.Cu" "F.Mask" "F.Paste")
			(net "GND")
		)
		(pad "B16" smd circle
			(at 0.40005 -10.80008)
			(size 0.3556 0.3556)
			(layers "F.Cu" "F.Mask" "F.Paste")
			(net "LSI_JTAG_EN_N")
		)
		(pad "B17" smd circle
			(at 1.199896 -10.80008)
			(size 0.3556 0.3556)
			(layers "F.Cu" "F.Mask" "F.Paste")
			(net "LSI_SCAN_EN")
		)
		(pad "B18" smd circle
			(at 1.999996 -10.80008)
			(size 0.3556 0.3556)
			(layers "F.Cu" "F.Mask" "F.Paste")
			(net "JTAG_IOC_TMS")
		)
		(pad "B19" smd circle
			(at 2.800096 -10.80008)
			(size 0.3556 0.3556)
			(layers "F.Cu" "F.Mask" "F.Paste")
			(net "XM_CS0_N")
		)
		(pad "B20" smd circle
			(at 3.599942 -10.80008)
			(size 0.3556 0.3556)
			(layers "F.Cu" "F.Mask" "F.Paste")
			(net "XM_F_RST_N")
		)
		(pad "B21" smd circle
			(at 4.400042 -10.80008)
			(size 0.3556 0.3556)
			(layers "F.Cu" "F.Mask" "F.Paste")
			(net "XM_NAND_CS_N")
		)
		(pad "B22" smd circle
			(at 5.199888 -10.80008)
			(size 0.3556 0.3556)
			(layers "F.Cu" "F.Mask" "F.Paste")
			(net "XM_OE_N")
		)
		(pad "B23" smd circle
			(at 5.999988 -10.80008)
			(size 0.3556 0.3556)
			(layers "F.Cu" "F.Mask" "F.Paste")
			(net "Net_1025")
		)
		(pad "B24" smd circle
			(at 6.800088 -10.80008)
			(size 0.3556 0.3556)
			(layers "F.Cu" "F.Mask" "F.Paste")
			(net "Net_1026")
		)
		(pad "B25" smd circle
			(at 7.599934 -10.80008)
			(size 0.3556 0.3556)
			(layers "F.Cu" "F.Mask" "F.Paste")
			(net "XM_ADDR_0")
		)
		(pad "B26" smd circle
			(at 8.400034 -10.80008)
			(size 0.3556 0.3556)
			(layers "F.Cu" "F.Mask" "F.Paste")
			(net "XM_ALE")
		)
		(pad "B27" smd circle
			(at 9.19988 -10.80008)
			(size 0.3556 0.3556)
			(layers "F.Cu" "F.Mask" "F.Paste")
			(net "XM_ADDR_1")
		)
		(pad "B28" smd circle
			(at 9.99998 -10.80008)
			(size 0.4064 0.4064)
			(layers "F.Cu" "F.Mask" "F.Paste")
			(net "XM_ADDR_6")
		)
		(pad "B29" smd circle
			(at 10.80008 -10.80008)
			(size 0.4064 0.4064)
			(layers "F.Cu" "F.Mask" "F.Paste")
			(net "XM_ADDR_8")
		)
		(pad "B30" smd circle
			(at 11.599926 -10.80008)
			(size 0.4064 0.4064)
			(layers "F.Cu" "F.Mask" "F.Paste")
			(net "XM_ADDR_7")
		)
		(pad "C1" smd circle
			(at -11.599926 -9.99998)
			(size 0.4064 0.4064)
			(layers "F.Cu" "F.Mask" "F.Paste")
			(net "GND")
		)
		(pad "C2" smd circle
			(at -10.80008 -9.99998)
			(size 0.4064 0.4064)
			(layers "F.Cu" "F.Mask" "F.Paste")
			(net "Net_1042")
		)
		(pad "C3" smd circle
			(at -9.99998 -9.99998)
			(size 0.4064 0.4064)
			(layers "F.Cu" "F.Mask" "F.Paste")
			(net "Net_1043")
		)
		(pad "C4" smd circle
			(at -9.19988 -9.99998)
			(size 0.3556 0.3556)
			(layers "F.Cu" "F.Mask" "F.Paste")
			(net "Net_1044")
		)
		(pad "C5" smd circle
			(at -8.400034 -9.99998)
			(size 0.3556 0.3556)
			(layers "F.Cu" "F.Mask" "F.Paste")
			(net "GND")
		)
		(pad "C6" smd circle
			(at -7.599934 -9.99998)
			(size 0.3556 0.3556)
			(layers "F.Cu" "F.Mask" "F.Paste")
			(net "ICE1_TRST#")
		)
		(pad "C7" smd circle
			(at -6.800088 -9.99998)
			(size 0.3556 0.3556)
			(layers "F.Cu" "F.Mask" "F.Paste")
			(net "ICE0_TMS")
		)
		(pad "C8" smd circle
			(at -5.999988 -9.99998)
			(size 0.3556 0.3556)
			(layers "F.Cu" "F.Mask" "F.Paste")
			(net "ICE0_TDO")
		)
		(pad "C9" smd circle
			(at -5.199888 -9.99998)
			(size 0.3556 0.3556)
			(layers "F.Cu" "F.Mask" "F.Paste")
			(net "Net_1045")
		)
		(pad "C10" smd circle
			(at -4.400042 -9.99998)
			(size 0.3556 0.3556)
			(layers "F.Cu" "F.Mask" "F.Paste")
			(net "Net_1046")
		)
		(pad "C11" smd circle
			(at -3.599942 -9.99998)
			(size 0.3556 0.3556)
			(layers "F.Cu" "F.Mask" "F.Paste")
			(net "GND")
		)
		(pad "C12" smd circle
			(at -2.800096 -9.99998)
			(size 0.3556 0.3556)
			(layers "F.Cu" "F.Mask" "F.Paste")
			(net "P1V8_C_PG")
		)
		(pad "C13" smd circle
			(at -1.999996 -9.99998)
			(size 0.3556 0.3556)
			(layers "F.Cu" "F.Mask" "F.Paste")
			(net "Net_1030")
		)
		(pad "C14" smd circle
			(at -1.199896 -9.99998)
			(size 0.3556 0.3556)
			(layers "F.Cu" "F.Mask" "F.Paste")
			(net "GND")
		)
		(pad "C15" smd circle
			(at -0.40005 -9.99998)
			(size 0.3556 0.3556)
			(layers "F.Cu" "F.Mask" "F.Paste")
			(net "GND")
		)
		(pad "C16" smd circle
			(at 0.40005 -9.99998)
			(size 0.3556 0.3556)
			(layers "F.Cu" "F.Mask" "F.Paste")
			(net "LSI_TN")
		)
		(pad "C17" smd circle
			(at 1.199896 -9.99998)
			(size 0.3556 0.3556)
			(layers "F.Cu" "F.Mask" "F.Paste")
			(net "JTAG_IOC_TCK")
		)
		(pad "C18" smd circle
			(at 1.999996 -9.99998)
			(size 0.3556 0.3556)
			(layers "F.Cu" "F.Mask" "F.Paste")
			(net "IOC_TDO")
		)
		(pad "C19" smd circle
			(at 2.800096 -9.99998)
			(size 0.3556 0.3556)
			(layers "F.Cu" "F.Mask" "F.Paste")
			(net "XM_DATA_15")
		)
		(pad "C20" smd circle
			(at 3.599942 -9.99998)
			(size 0.3556 0.3556)
			(layers "F.Cu" "F.Mask" "F.Paste")
			(net "XM_DATA_6")
		)
		(pad "C21" smd circle
			(at 4.400042 -9.99998)
			(size 0.3556 0.3556)
			(layers "F.Cu" "F.Mask" "F.Paste")
			(net "XM_DATA_8")
		)
		(pad "C22" smd circle
			(at 5.199888 -9.99998)
			(size 0.3556 0.3556)
			(layers "F.Cu" "F.Mask" "F.Paste")
			(net "XM_DATA_5")
		)
		(pad "C23" smd circle
			(at 5.999988 -9.99998)
			(size 0.3556 0.3556)
			(layers "F.Cu" "F.Mask" "F.Paste")
			(net "XM_CLE")
		)
		(pad "C24" smd circle
			(at 6.800088 -9.99998)
			(size 0.3556 0.3556)
			(layers "F.Cu" "F.Mask" "F.Paste")
			(net "XM_DATA_7")
		)
		(pad "C25" smd circle
			(at 7.599934 -9.99998)
			(size 0.3556 0.3556)
			(layers "F.Cu" "F.Mask" "F.Paste")
			(net "XM_DATA_10")
		)
		(pad "C26" smd circle
			(at 8.400034 -9.99998)
			(size 0.3556 0.3556)
			(layers "F.Cu" "F.Mask" "F.Paste")
			(net "XM_DATA_9")
		)
		(pad "C27" smd circle
			(at 9.19988 -9.99998)
			(size 0.3556 0.3556)
			(layers "F.Cu" "F.Mask" "F.Paste")
			(net "XM_ADDR_2")
		)
		(pad "C28" smd circle
			(at 9.99998 -9.99998)
			(size 0.4064 0.4064)
			(layers "F.Cu" "F.Mask" "F.Paste")
			(net "XM_ADDR_5")
		)
		(pad "C29" smd circle
			(at 10.80008 -9.99998)
			(size 0.4064 0.4064)
			(layers "F.Cu" "F.Mask" "F.Paste")
			(net "XM_ADDR_11")
		)
		(pad "C30" smd circle
			(at 11.599926 -9.99998)
			(size 0.4064 0.4064)
			(layers "F.Cu" "F.Mask" "F.Paste")
			(net "XM_ADDR_13")
		)
		(pad "D1" smd circle
			(at -11.599926 -9.19988)
			(size 0.3556 0.3556)
			(layers "F.Cu" "F.Mask" "F.Paste")
			(net "Net_1073")
		)
		(pad "D2" smd circle
			(at -10.80008 -9.19988)
			(size 0.3556 0.3556)
			(layers "F.Cu" "F.Mask" "F.Paste")
			(net "Net_1047")
		)
		(pad "D3" smd circle
			(at -9.99998 -9.19988)
			(size 0.3556 0.3556)
			(layers "F.Cu" "F.Mask" "F.Paste")
			(net "Net_1048")
		)
		(pad "D4" smd circle
			(at -9.19988 -9.19988)
			(size 0.3556 0.3556)
			(layers "F.Cu" "F.Mask" "F.Paste")
			(net "P1V8_C")
		)
		(pad "D5" smd circle
			(at -8.400034 -9.19988)
			(size 0.3556 0.3556)
			(layers "F.Cu" "F.Mask" "F.Paste")
			(net "GND")
		)
		(pad "D6" smd circle
			(at -7.599934 -9.19988)
			(size 0.3556 0.3556)
			(layers "F.Cu" "F.Mask" "F.Paste")
			(net "P1V8_C")
		)
		(pad "D7" smd circle
			(at -6.800088 -9.19988)
			(size 0.3556 0.3556)
			(layers "F.Cu" "F.Mask" "F.Paste")
			(net "GND")
		)
		(pad "D8" smd circle
			(at -5.999988 -9.19988)
			(size 0.3556 0.3556)
			(layers "F.Cu" "F.Mask" "F.Paste")
			(net "P1V8_C")
		)
		(pad "D9" smd circle
			(at -5.199888 -9.19988)
			(size 0.3556 0.3556)
			(layers "F.Cu" "F.Mask" "F.Paste")
			(net "GND")
		)
		(pad "D10" smd circle
			(at -4.400042 -9.19988)
			(size 0.3556 0.3556)
			(layers "F.Cu" "F.Mask" "F.Paste")
			(net "P1V8_C")
		)
		(pad "D11" smd circle
			(at -3.599942 -9.19988)
			(size 0.3556 0.3556)
			(layers "F.Cu" "F.Mask" "F.Paste")
			(net "GND")
		)
		(pad "D12" smd circle
			(at -2.800096 -9.19988)
			(size 0.3556 0.3556)
			(layers "F.Cu" "F.Mask" "F.Paste")
			(net "GND")
		)
		(pad "D13" smd circle
			(at -1.999996 -9.19988)
			(size 0.3556 0.3556)
			(layers "F.Cu" "F.Mask" "F.Paste")
			(net "GND")
		)
		(pad "D14" smd circle
			(at -1.199896 -9.19988)
			(size 0.3556 0.3556)
			(layers "F.Cu" "F.Mask" "F.Paste")
			(net "GND")
		)
		(pad "D15" smd circle
			(at -0.40005 -9.19988)
			(size 0.3556 0.3556)
			(layers "F.Cu" "F.Mask" "F.Paste")
			(net "GND")
		)
		(pad "D16" smd circle
			(at 0.40005 -9.19988)
			(size 0.3556 0.3556)
			(layers "F.Cu" "F.Mask" "F.Paste")
			(net "P1V8_C")
		)
		(pad "D17" smd circle
			(at 1.199896 -9.19988)
			(size 0.3556 0.3556)
			(layers "F.Cu" "F.Mask" "F.Paste")
			(net "GND")
		)
		(pad "D18" smd circle
			(at 1.999996 -9.19988)
			(size 0.3556 0.3556)
			(layers "F.Cu" "F.Mask" "F.Paste")
			(net "P1V8_C")
		)
		(pad "D19" smd circle
			(at 2.800096 -9.19988)
			(size 0.3556 0.3556)
			(layers "F.Cu" "F.Mask" "F.Paste")
			(net "GND")
		)
		(pad "D20" smd circle
			(at 3.599942 -9.19988)
			(size 0.3556 0.3556)
			(layers "F.Cu" "F.Mask" "F.Paste")
			(net "P1V8_C")
		)
		(pad "D21" smd circle
			(at 4.400042 -9.19988)
			(size 0.3556 0.3556)
			(layers "F.Cu" "F.Mask" "F.Paste")
			(net "GND")
		)
		(pad "D22" smd circle
			(at 5.199888 -9.19988)
			(size 0.3556 0.3556)
			(layers "F.Cu" "F.Mask" "F.Paste")
			(net "P1V8_C")
		)
		(pad "D23" smd circle
			(at 5.999988 -9.19988)
			(size 0.3556 0.3556)
			(layers "F.Cu" "F.Mask" "F.Paste")
			(net "GND")
		)
		(pad "D24" smd circle
			(at 6.800088 -9.19988)
			(size 0.3556 0.3556)
			(layers "F.Cu" "F.Mask" "F.Paste")
			(net "P1V8_C")
		)
		(pad "D25" smd circle
			(at 7.599934 -9.19988)
			(size 0.3556 0.3556)
			(layers "F.Cu" "F.Mask" "F.Paste")
			(net "GND")
		)
		(pad "D26" smd circle
			(at 8.400034 -9.19988)
			(size 0.3556 0.3556)
			(layers "F.Cu" "F.Mask" "F.Paste")
			(net "P1V8_C")
		)
		(pad "D27" smd circle
			(at 9.19988 -9.19988)
			(size 0.3556 0.3556)
			(layers "F.Cu" "F.Mask" "F.Paste")
			(net "GND")
		)
		(pad "D28" smd circle
			(at 9.99998 -9.19988)
			(size 0.3556 0.3556)
			(layers "F.Cu" "F.Mask" "F.Paste")
			(net "XM_ADDR_9")
		)
		(pad "D29" smd circle
			(at 10.80008 -9.19988)
			(size 0.3556 0.3556)
			(layers "F.Cu" "F.Mask" "F.Paste")
			(net "XM_ADDR_10")
		)
		(pad "D30" smd circle
			(at 11.599926 -9.19988)
			(size 0.3556 0.3556)
			(layers "F.Cu" "F.Mask" "F.Paste")
			(net "XM_ADDR_17")
		)
		(pad "E1" smd circle
			(at -11.599926 -8.400034)
			(size 0.3556 0.3556)
			(layers "F.Cu" "F.Mask" "F.Paste")
			(net "Net_1074")
		)
		(pad "E2" smd circle
			(at -10.80008 -8.400034)
			(size 0.3556 0.3556)
			(layers "F.Cu" "F.Mask" "F.Paste")
			(net "Net_1049")
		)
		(pad "E3" smd circle
			(at -9.99998 -8.400034)
			(size 0.3556 0.3556)
			(layers "F.Cu" "F.Mask" "F.Paste")
			(net "GND")
		)
		(pad "E4" smd circle
			(at -9.19988 -8.400034)
			(size 0.3556 0.3556)
			(layers "F.Cu" "F.Mask" "F.Paste")
			(net "GND")
		)
		(pad "E5" smd circle
			(at -8.400034 -8.400034)
			(size 0.3556 0.3556)
			(layers "F.Cu" "F.Mask" "F.Paste")
			(net "P1V8_C")
		)
		(pad "E6" smd circle
			(at -7.599934 -8.400034)
			(size 0.3556 0.3556)
			(layers "F.Cu" "F.Mask" "F.Paste")
			(net "GND")
		)
		(pad "E7" smd circle
			(at -6.800088 -8.400034)
			(size 0.3556 0.3556)
			(layers "F.Cu" "F.Mask" "F.Paste")
			(net "P1V8_C")
		)
		(pad "E8" smd circle
			(at -5.999988 -8.400034)
			(size 0.3556 0.3556)
			(layers "F.Cu" "F.Mask" "F.Paste")
			(net "GND")
		)
		(pad "E9" smd circle
			(at -5.199888 -8.400034)
			(size 0.3556 0.3556)
			(layers "F.Cu" "F.Mask" "F.Paste")
			(net "P1V8_C")
		)
		(pad "E10" smd circle
			(at -4.400042 -8.400034)
			(size 0.3556 0.3556)
			(layers "F.Cu" "F.Mask" "F.Paste")
			(net "GND")
		)
		(pad "E11" smd circle
			(at -3.599942 -8.400034)
			(size 0.3556 0.3556)
			(layers "F.Cu" "F.Mask" "F.Paste")
			(net "GND")
		)
		(pad "E12" smd circle
			(at -2.800096 -8.400034)
			(size 0.3556 0.3556)
			(layers "F.Cu" "F.Mask" "F.Paste")
			(net "GND")
		)
		(pad "E13" smd circle
			(at -1.999996 -8.400034)
			(size 0.3556 0.3556)
			(layers "F.Cu" "F.Mask" "F.Paste")
			(net "GND")
		)
		(pad "E14" smd circle
			(at -1.199896 -8.400034)
			(size 0.3556 0.3556)
			(layers "F.Cu" "F.Mask" "F.Paste")
			(net "GND")
		)
		(pad "E15" smd circle
			(at -0.40005 -8.400034)
			(size 0.3556 0.3556)
			(layers "F.Cu" "F.Mask" "F.Paste")
			(net "P1V8_C")
		)
		(pad "E16" smd circle
			(at 0.40005 -8.400034)
			(size 0.3556 0.3556)
			(layers "F.Cu" "F.Mask" "F.Paste")
			(net "GND")
		)
		(pad "E17" smd circle
			(at 1.199896 -8.400034)
			(size 0.3556 0.3556)
			(layers "F.Cu" "F.Mask" "F.Paste")
			(net "P1V8_C")
		)
		(pad "E18" smd circle
			(at 1.999996 -8.400034)
			(size 0.3556 0.3556)
			(layers "F.Cu" "F.Mask" "F.Paste")
			(net "GND")
		)
		(pad "E19" smd circle
			(at 2.800096 -8.400034)
			(size 0.3556 0.3556)
			(layers "F.Cu" "F.Mask" "F.Paste")
			(net "P1V8_C")
		)
		(pad "E20" smd circle
			(at 3.599942 -8.400034)
			(size 0.3556 0.3556)
			(layers "F.Cu" "F.Mask" "F.Paste")
			(net "GND")
		)
		(pad "E21" smd circle
			(at 4.400042 -8.400034)
			(size 0.3556 0.3556)
			(layers "F.Cu" "F.Mask" "F.Paste")
			(net "P1V8_C")
		)
		(pad "E22" smd circle
			(at 5.199888 -8.400034)
			(size 0.3556 0.3556)
			(layers "F.Cu" "F.Mask" "F.Paste")
			(net "GND")
		)
		(pad "E23" smd circle
			(at 5.999988 -8.400034)
			(size 0.3556 0.3556)
			(layers "F.Cu" "F.Mask" "F.Paste")
			(net "P1V8_C")
		)
		(pad "E24" smd circle
			(at 6.800088 -8.400034)
			(size 0.3556 0.3556)
			(layers "F.Cu" "F.Mask" "F.Paste")
			(net "GND")
		)
		(pad "E25" smd circle
			(at 7.599934 -8.400034)
			(size 0.3556 0.3556)
			(layers "F.Cu" "F.Mask" "F.Paste")
			(net "P1V8_C")
		)
		(pad "E26" smd circle
			(at 8.400034 -8.400034)
			(size 0.3556 0.3556)
			(layers "F.Cu" "F.Mask" "F.Paste")
			(net "GND")
		)
		(pad "E27" smd circle
			(at 9.19988 -8.400034)
			(size 0.3556 0.3556)
			(layers "F.Cu" "F.Mask" "F.Paste")
			(net "P1V8_C")
		)
		(pad "E28" smd circle
			(at 9.99998 -8.400034)
			(size 0.3556 0.3556)
			(layers "F.Cu" "F.Mask" "F.Paste")
			(net "XM_ADDR_12")
		)
		(pad "E29" smd circle
			(at 10.80008 -8.400034)
			(size 0.3556 0.3556)
			(layers "F.Cu" "F.Mask" "F.Paste")
			(net "XM_DATA_14")
		)
		(pad "E30" smd circle
			(at 11.599926 -8.400034)
			(size 0.3556 0.3556)
			(layers "F.Cu" "F.Mask" "F.Paste")
			(net "XM_ADDR_14")
		)
		(pad "F1" smd circle
			(at -11.599926 -7.599934)
			(size 0.3556 0.3556)
			(layers "F.Cu" "F.Mask" "F.Paste")
			(net "Net_1075")
		)
		(pad "F2" smd circle
			(at -10.80008 -7.599934)
			(size 0.3556 0.3556)
			(layers "F.Cu" "F.Mask" "F.Paste")
			(net "Net_1050")
		)
		(pad "F3" smd circle
			(at -9.99998 -7.599934)
			(size 0.3556 0.3556)
			(layers "F.Cu" "F.Mask" "F.Paste")
			(net "Net_1051")
		)
		(pad "F4" smd circle
			(at -9.19988 -7.599934)
			(size 0.3556 0.3556)
			(layers "F.Cu" "F.Mask" "F.Paste")
			(net "P1V8_C")
		)
		(pad "F5" smd circle
			(at -8.400034 -7.599934)
			(size 0.3556 0.3556)
			(layers "F.Cu" "F.Mask" "F.Paste")
			(net "GND")
		)
		(pad "F6" smd circle
			(at -7.599934 -7.599934)
			(size 0.3556 0.3556)
			(layers "F.Cu" "F.Mask" "F.Paste")
			(net "Net_1052")
		)
		(pad "F7" smd circle
			(at -6.800088 -7.599934)
			(size 0.3556 0.3556)
			(layers "F.Cu" "F.Mask" "F.Paste")
			(net "Net_1053")
		)
		(pad "F8" smd circle
			(at -5.999988 -7.599934)
			(size 0.3556 0.3556)
			(layers "F.Cu" "F.Mask" "F.Paste")
			(net "Net_1054")
		)
		(pad "F9" smd circle
			(at -5.199888 -7.599934)
			(size 0.3556 0.3556)
			(layers "F.Cu" "F.Mask" "F.Paste")
			(net "Net_1055")
		)
		(pad "F10" smd circle
			(at -4.400042 -7.599934)
			(size 0.3556 0.3556)
			(layers "F.Cu" "F.Mask" "F.Paste")
			(net "Net_1056")
		)
		(pad "F11" smd circle
			(at -3.599942 -7.599934)
			(size 0.3556 0.3556)
			(layers "F.Cu" "F.Mask" "F.Paste")
			(net "GND")
		)
		(pad "F12" smd circle
			(at -2.800096 -7.599934)
			(size 0.3556 0.3556)
			(layers "F.Cu" "F.Mask" "F.Paste")
			(net "GND")
		)
		(pad "F13" smd circle
			(at -1.999996 -7.599934)
			(size 0.3556 0.3556)
			(layers "F.Cu" "F.Mask" "F.Paste")
			(net "GND")
		)
		(pad "F14" smd circle
			(at -1.199896 -7.599934)
			(size 0.3556 0.3556)
			(layers "F.Cu" "F.Mask" "F.Paste")
			(net "GND")
		)
		(pad "F15" smd circle
			(at -0.40005 -7.599934)
			(size 0.3556 0.3556)
			(layers "F.Cu" "F.Mask" "F.Paste")
			(net "GND")
		)
		(pad "F16" smd circle
			(at 0.40005 -7.599934)
			(size 0.3556 0.3556)
			(layers "F.Cu" "F.Mask" "F.Paste")
			(net "GND")
		)
		(pad "F17" smd circle
			(at 1.199896 -7.599934)
			(size 0.3556 0.3556)
			(layers "F.Cu" "F.Mask" "F.Paste")
			(net "GND")
		)
		(pad "F18" smd circle
			(at 1.999996 -7.599934)
			(size 0.3556 0.3556)
			(layers "F.Cu" "F.Mask" "F.Paste")
			(net "GND")
		)
		(pad "F19" smd circle
			(at 2.800096 -7.599934)
			(size 0.3556 0.3556)
			(layers "F.Cu" "F.Mask" "F.Paste")
			(net "GND")
		)
		(pad "F20" smd circle
			(at 3.599942 -7.599934)
			(size 0.3556 0.3556)
			(layers "F.Cu" "F.Mask" "F.Paste")
			(net "GND")
		)
		(pad "F21" smd circle
			(at 4.400042 -7.599934)
			(size 0.3556 0.3556)
			(layers "F.Cu" "F.Mask" "F.Paste")
			(net "GND")
		)
		(pad "F22" smd circle
			(at 5.199888 -7.599934)
			(size 0.3556 0.3556)
			(layers "F.Cu" "F.Mask" "F.Paste")
			(net "GND")
		)
		(pad "F23" smd circle
			(at 5.999988 -7.599934)
			(size 0.3556 0.3556)
			(layers "F.Cu" "F.Mask" "F.Paste")
			(net "GND")
		)
		(pad "F24" smd circle
			(at 6.800088 -7.599934)
			(size 0.3556 0.3556)
			(layers "F.Cu" "F.Mask" "F.Paste")
			(net "GND")
		)
		(pad "F25" smd circle
			(at 7.599934 -7.599934)
			(size 0.3556 0.3556)
			(layers "F.Cu" "F.Mask" "F.Paste")
			(net "GND")
		)
		(pad "F26" smd circle
			(at 8.400034 -7.599934)
			(size 0.3556 0.3556)
			(layers "F.Cu" "F.Mask" "F.Paste")
			(net "P1V8_C")
		)
		(pad "F27" smd circle
			(at 9.19988 -7.599934)
			(size 0.3556 0.3556)
			(layers "F.Cu" "F.Mask" "F.Paste")
			(net "GND")
		)
		(pad "F28" smd circle
			(at 9.99998 -7.599934)
			(size 0.3556 0.3556)
			(layers "F.Cu" "F.Mask" "F.Paste")
			(net "XM_ADDR_19")
		)
		(pad "F29" smd circle
			(at 10.80008 -7.599934)
			(size 0.3556 0.3556)
			(layers "F.Cu" "F.Mask" "F.Paste")
			(net "XM_ADDR_16")
		)
		(pad "F30" smd circle
			(at 11.599926 -7.599934)
			(size 0.3556 0.3556)
			(layers "F.Cu" "F.Mask" "F.Paste")
			(net "XM_ADDR_20")
		)
		(pad "G1" smd circle
			(at -11.599926 -6.800088)
			(size 0.3556 0.3556)
			(layers "F.Cu" "F.Mask" "F.Paste")
			(net "Net_1076")
		)
		(pad "G2" smd circle
			(at -10.80008 -6.800088)
			(size 0.3556 0.3556)
			(layers "F.Cu" "F.Mask" "F.Paste")
			(net "Net_1057")
		)
		(pad "G3" smd circle
			(at -9.99998 -6.800088)
			(size 0.3556 0.3556)
			(layers "F.Cu" "F.Mask" "F.Paste")
			(net "Net_1058")
		)
		(pad "G4" smd circle
			(at -9.19988 -6.800088)
			(size 0.3556 0.3556)
			(layers "F.Cu" "F.Mask" "F.Paste")
			(net "GND")
		)
		(pad "G5" smd circle
			(at -8.400034 -6.800088)
			(size 0.3556 0.3556)
			(layers "F.Cu" "F.Mask" "F.Paste")
			(net "P1V8_C")
		)
		(pad "G6" smd circle
			(at -7.599934 -6.800088)
			(size 0.3556 0.3556)
			(layers "F.Cu" "F.Mask" "F.Paste")
			(net "Net_1059")
		)
		(pad "G7" smd circle
			(at -6.800088 -6.800088)
			(size 0.3556 0.3556)
			(layers "F.Cu" "F.Mask" "F.Paste")
			(net "GND")
		)
		(pad "G8" smd circle
			(at -5.999988 -6.800088)
			(size 0.3556 0.3556)
			(layers "F.Cu" "F.Mask" "F.Paste")
			(net "GND")
		)
		(pad "G9" smd circle
			(at -5.199888 -6.800088)
			(size 0.3556 0.3556)
			(layers "F.Cu" "F.Mask" "F.Paste")
			(net "GND")
		)
		(pad "G10" smd circle
			(at -4.400042 -6.800088)
			(size 0.3556 0.3556)
			(layers "F.Cu" "F.Mask" "F.Paste")
			(net "GND")
		)
		(pad "G11" smd circle
			(at -3.599942 -6.800088)
			(size 0.3556 0.3556)
			(layers "F.Cu" "F.Mask" "F.Paste")
			(net "GND")
		)
		(pad "G12" smd circle
			(at -2.800096 -6.800088)
			(size 0.3556 0.3556)
			(layers "F.Cu" "F.Mask" "F.Paste")
			(net "GND")
		)
		(pad "G13" smd circle
			(at -1.999996 -6.800088)
			(size 0.3556 0.3556)
			(layers "F.Cu" "F.Mask" "F.Paste")
			(net "GND")
		)
		(pad "G14" smd circle
			(at -1.199896 -6.800088)
			(size 0.3556 0.3556)
			(layers "F.Cu" "F.Mask" "F.Paste")
			(net "GND")
		)
		(pad "G15" smd circle
			(at -0.40005 -6.800088)
			(size 0.3556 0.3556)
			(layers "F.Cu" "F.Mask" "F.Paste")
			(net "GND")
		)
		(pad "G16" smd circle
			(at 0.40005 -6.800088)
			(size 0.3556 0.3556)
			(layers "F.Cu" "F.Mask" "F.Paste")
			(net "GND")
		)
		(pad "G17" smd circle
			(at 1.199896 -6.800088)
			(size 0.3556 0.3556)
			(layers "F.Cu" "F.Mask" "F.Paste")
			(net "GND")
		)
		(pad "G18" smd circle
			(at 1.999996 -6.800088)
			(size 0.3556 0.3556)
			(layers "F.Cu" "F.Mask" "F.Paste")
			(net "GND")
		)
		(pad "G19" smd circle
			(at 2.800096 -6.800088)
			(size 0.3556 0.3556)
			(layers "F.Cu" "F.Mask" "F.Paste")
			(net "GND")
		)
		(pad "G20" smd circle
			(at 3.599942 -6.800088)
			(size 0.3556 0.3556)
			(layers "F.Cu" "F.Mask" "F.Paste")
			(net "GND")
		)
		(pad "G21" smd circle
			(at 4.400042 -6.800088)
			(size 0.3556 0.3556)
			(layers "F.Cu" "F.Mask" "F.Paste")
			(net "GND")
		)
		(pad "G22" smd circle
			(at 5.199888 -6.800088)
			(size 0.3556 0.3556)
			(layers "F.Cu" "F.Mask" "F.Paste")
			(net "GND")
		)
		(pad "G23" smd circle
			(at 5.999988 -6.800088)
			(size 0.3556 0.3556)
			(layers "F.Cu" "F.Mask" "F.Paste")
			(net "GND")
		)
		(pad "G24" smd circle
			(at 6.800088 -6.800088)
			(size 0.3556 0.3556)
			(layers "F.Cu" "F.Mask" "F.Paste")
			(net "GND")
		)
		(pad "G25" smd circle
			(at 7.599934 -6.800088)
			(size 0.3556 0.3556)
			(layers "F.Cu" "F.Mask" "F.Paste")
			(net "GND")
		)
		(pad "G26" smd circle
			(at 8.400034 -6.800088)
			(size 0.3556 0.3556)
			(layers "F.Cu" "F.Mask" "F.Paste")
			(net "GND")
		)
		(pad "G27" smd circle
			(at 9.19988 -6.800088)
			(size 0.3556 0.3556)
			(layers "F.Cu" "F.Mask" "F.Paste")
			(net "P1V8_C")
		)
		(pad "G28" smd circle
			(at 9.99998 -6.800088)
			(size 0.3556 0.3556)
			(layers "F.Cu" "F.Mask" "F.Paste")
			(net "XM_ADDR_15")
		)
		(pad "G29" smd circle
			(at 10.80008 -6.800088)
			(size 0.3556 0.3556)
			(layers "F.Cu" "F.Mask" "F.Paste")
			(net "XM_ADDR_21")
		)
		(pad "G30" smd circle
			(at 11.599926 -6.800088)
			(size 0.3556 0.3556)
			(layers "F.Cu" "F.Mask" "F.Paste")
			(net "XM_DATA_13")
		)
		(pad "H1" smd circle
			(at -11.599926 -5.999988)
			(size 0.3556 0.3556)
			(layers "F.Cu" "F.Mask" "F.Paste")
			(net "GND")
		)
		(pad "H2" smd circle
			(at -10.80008 -5.999988)
			(size 0.3556 0.3556)
			(layers "F.Cu" "F.Mask" "F.Paste")
			(net "Net_1060")
		)
		(pad "H3" smd circle
			(at -9.99998 -5.999988)
			(size 0.3556 0.3556)
			(layers "F.Cu" "F.Mask" "F.Paste")
			(net "Net_1061")
		)
		(pad "H4" smd circle
			(at -9.19988 -5.999988)
			(size 0.3556 0.3556)
			(layers "F.Cu" "F.Mask" "F.Paste")
			(net "P1V8_C")
		)
		(pad "H5" smd circle
			(at -8.400034 -5.999988)
			(size 0.3556 0.3556)
			(layers "F.Cu" "F.Mask" "F.Paste")
			(net "GND")
		)
		(pad "H6" smd circle
			(at -7.599934 -5.999988)
			(size 0.3556 0.3556)
			(layers "F.Cu" "F.Mask" "F.Paste")
			(net "Net_1062")
		)
		(pad "H7" smd circle
			(at -6.800088 -5.999988)
			(size 0.3556 0.3556)
			(layers "F.Cu" "F.Mask" "F.Paste")
			(net "GND")
		)
		(pad "H8" smd circle
			(at -5.999988 -5.999988)
			(size 0.3556 0.3556)
			(layers "F.Cu" "F.Mask" "F.Paste")
			(net "GND")
		)
		(pad "H9" smd circle
			(at -5.199888 -5.999988)
			(size 0.3556 0.3556)
			(layers "F.Cu" "F.Mask" "F.Paste")
			(net "GND")
		)
		(pad "H10" smd circle
			(at -4.400042 -5.999988)
			(size 0.3556 0.3556)
			(layers "F.Cu" "F.Mask" "F.Paste")
			(net "GND")
		)
		(pad "H11" smd circle
			(at -3.599942 -5.999988)
			(size 0.3556 0.3556)
			(layers "F.Cu" "F.Mask" "F.Paste")
			(net "GND")
		)
		(pad "H12" smd circle
			(at -2.800096 -5.999988)
			(size 0.3556 0.3556)
			(layers "F.Cu" "F.Mask" "F.Paste")
			(net "GND")
		)
		(pad "H13" smd circle
			(at -1.999996 -5.999988)
			(size 0.3556 0.3556)
			(layers "F.Cu" "F.Mask" "F.Paste")
			(net "GND")
		)
		(pad "H14" smd circle
			(at -1.199896 -5.999988)
			(size 0.3556 0.3556)
			(layers "F.Cu" "F.Mask" "F.Paste")
			(net "GND")
		)
		(pad "H15" smd circle
			(at -0.40005 -5.999988)
			(size 0.3556 0.3556)
			(layers "F.Cu" "F.Mask" "F.Paste")
			(net "GND")
		)
		(pad "H16" smd circle
			(at 0.40005 -5.999988)
			(size 0.3556 0.3556)
			(layers "F.Cu" "F.Mask" "F.Paste")
			(net "GND")
		)
		(pad "H17" smd circle
			(at 1.199896 -5.999988)
			(size 0.3556 0.3556)
			(layers "F.Cu" "F.Mask" "F.Paste")
			(net "GND")
		)
		(pad "H18" smd circle
			(at 1.999996 -5.999988)
			(size 0.3556 0.3556)
			(layers "F.Cu" "F.Mask" "F.Paste")
			(net "GND")
		)
		(pad "H19" smd circle
			(at 2.800096 -5.999988)
			(size 0.3556 0.3556)
			(layers "F.Cu" "F.Mask" "F.Paste")
			(net "GND")
		)
		(pad "H20" smd circle
			(at 3.599942 -5.999988)
			(size 0.3556 0.3556)
			(layers "F.Cu" "F.Mask" "F.Paste")
			(net "GND")
		)
		(pad "H21" smd circle
			(at 4.400042 -5.999988)
			(size 0.3556 0.3556)
			(layers "F.Cu" "F.Mask" "F.Paste")
			(net "GND")
		)
		(pad "H22" smd circle
			(at 5.199888 -5.999988)
			(size 0.3556 0.3556)
			(layers "F.Cu" "F.Mask" "F.Paste")
			(net "GND")
		)
		(pad "H23" smd circle
			(at 5.999988 -5.999988)
			(size 0.3556 0.3556)
			(layers "F.Cu" "F.Mask" "F.Paste")
			(net "GND")
		)
		(pad "H24" smd circle
			(at 6.800088 -5.999988)
			(size 0.3556 0.3556)
			(layers "F.Cu" "F.Mask" "F.Paste")
			(net "GND")
		)
		(pad "H25" smd circle
			(at 7.599934 -5.999988)
			(size 0.3556 0.3556)
			(layers "F.Cu" "F.Mask" "F.Paste")
			(net "GND")
		)
		(pad "H26" smd circle
			(at 8.400034 -5.999988)
			(size 0.3556 0.3556)
			(layers "F.Cu" "F.Mask" "F.Paste")
			(net "P1V8_C")
		)
		(pad "H27" smd circle
			(at 9.19988 -5.999988)
			(size 0.3556 0.3556)
			(layers "F.Cu" "F.Mask" "F.Paste")
			(net "GND")
		)
		(pad "H28" smd circle
			(at 9.99998 -5.999988)
			(size 0.3556 0.3556)
			(layers "F.Cu" "F.Mask" "F.Paste")
			(net "XM_DATA_0")
		)
		(pad "H29" smd circle
			(at 10.80008 -5.999988)
			(size 0.3556 0.3556)
			(layers "F.Cu" "F.Mask" "F.Paste")
			(net "XM_ADDR_25")
		)
		(pad "H30" smd circle
			(at 11.599926 -5.999988)
			(size 0.3556 0.3556)
			(layers "F.Cu" "F.Mask" "F.Paste")
			(net "XM_ADDR_18")
		)
		(pad "J1" smd circle
			(at -11.599926 -5.199888)
			(size 0.3556 0.3556)
			(layers "F.Cu" "F.Mask" "F.Paste")
			(net "Net_1077")
		)
		(pad "J2" smd circle
			(at -10.80008 -5.199888)
			(size 0.3556 0.3556)
			(layers "F.Cu" "F.Mask" "F.Paste")
			(net "Net_1063")
		)
		(pad "J3" smd circle
			(at -9.99998 -5.199888)
			(size 0.3556 0.3556)
			(layers "F.Cu" "F.Mask" "F.Paste")
			(net "Net_1064")
		)
		(pad "J4" smd circle
			(at -9.19988 -5.199888)
			(size 0.3556 0.3556)
			(layers "F.Cu" "F.Mask" "F.Paste")
			(net "GND")
		)
		(pad "J5" smd circle
			(at -8.400034 -5.199888)
			(size 0.3556 0.3556)
			(layers "F.Cu" "F.Mask" "F.Paste")
			(net "P1V8_C")
		)
		(pad "J6" smd circle
			(at -7.599934 -5.199888)
			(size 0.3556 0.3556)
			(layers "F.Cu" "F.Mask" "F.Paste")
			(net "Net_1065")
		)
		(pad "J7" smd circle
			(at -6.800088 -5.199888)
			(size 0.3556 0.3556)
			(layers "F.Cu" "F.Mask" "F.Paste")
			(net "GND")
		)
		(pad "J8" smd circle
			(at -5.999988 -5.199888)
			(size 0.3556 0.3556)
			(layers "F.Cu" "F.Mask" "F.Paste")
			(net "GND")
		)
		(pad "J9" smd circle
			(at -5.199888 -5.199888)
			(size 0.3556 0.3556)
			(layers "F.Cu" "F.Mask" "F.Paste")
			(net "GND")
		)
		(pad "J10" smd circle
			(at -4.400042 -5.199888)
			(size 0.3556 0.3556)
			(layers "F.Cu" "F.Mask" "F.Paste")
			(net "GND")
		)
		(pad "J11" smd circle
			(at -3.599942 -5.199888)
			(size 0.3556 0.3556)
			(layers "F.Cu" "F.Mask" "F.Paste")
			(net "GND")
		)
		(pad "J12" smd circle
			(at -2.800096 -5.199888)
			(size 0.3556 0.3556)
			(layers "F.Cu" "F.Mask" "F.Paste")
			(net "P0V955_C")
		)
		(pad "J13" smd circle
			(at -1.999996 -5.199888)
			(size 0.3556 0.3556)
			(layers "F.Cu" "F.Mask" "F.Paste")
			(net "GND")
		)
		(pad "J14" smd circle
			(at -1.199896 -5.199888)
			(size 0.3556 0.3556)
			(layers "F.Cu" "F.Mask" "F.Paste")
			(net "GND")
		)
		(pad "J15" smd circle
			(at -0.40005 -5.199888)
			(size 0.3556 0.3556)
			(layers "F.Cu" "F.Mask" "F.Paste")
			(net "GND")
		)
		(pad "J16" smd circle
			(at 0.40005 -5.199888)
			(size 0.3556 0.3556)
			(layers "F.Cu" "F.Mask" "F.Paste")
			(net "GND")
		)
		(pad "J17" smd circle
			(at 1.199896 -5.199888)
			(size 0.3556 0.3556)
			(layers "F.Cu" "F.Mask" "F.Paste")
			(net "GND")
		)
		(pad "J18" smd circle
			(at 1.999996 -5.199888)
			(size 0.3556 0.3556)
			(layers "F.Cu" "F.Mask" "F.Paste")
			(net "GND")
		)
		(pad "J19" smd circle
			(at 2.800096 -5.199888)
			(size 0.3556 0.3556)
			(layers "F.Cu" "F.Mask" "F.Paste")
			(net "GND")
		)
		(pad "J20" smd circle
			(at 3.599942 -5.199888)
			(size 0.3556 0.3556)
			(layers "F.Cu" "F.Mask" "F.Paste")
			(net "GND")
		)
		(pad "J21" smd circle
			(at 4.400042 -5.199888)
			(size 0.3556 0.3556)
			(layers "F.Cu" "F.Mask" "F.Paste")
			(net "GND")
		)
		(pad "J22" smd circle
			(at 5.199888 -5.199888)
			(size 0.3556 0.3556)
			(layers "F.Cu" "F.Mask" "F.Paste")
			(net "GND")
		)
		(pad "J23" smd circle
			(at 5.999988 -5.199888)
			(size 0.3556 0.3556)
			(layers "F.Cu" "F.Mask" "F.Paste")
			(net "GND")
		)
		(pad "J24" smd circle
			(at 6.800088 -5.199888)
			(size 0.3556 0.3556)
			(layers "F.Cu" "F.Mask" "F.Paste")
			(net "GND")
		)
		(pad "J25" smd circle
			(at 7.599934 -5.199888)
			(size 0.3556 0.3556)
			(layers "F.Cu" "F.Mask" "F.Paste")
			(net "GND")
		)
		(pad "J26" smd circle
			(at 8.400034 -5.199888)
			(size 0.3556 0.3556)
			(layers "F.Cu" "F.Mask" "F.Paste")
			(net "GND")
		)
		(pad "J27" smd circle
			(at 9.19988 -5.199888)
			(size 0.3556 0.3556)
			(layers "F.Cu" "F.Mask" "F.Paste")
			(net "P1V8_C")
		)
		(pad "J28" smd circle
			(at 9.99998 -5.199888)
			(size 0.3556 0.3556)
			(layers "F.Cu" "F.Mask" "F.Paste")
			(net "XM_DATA_12")
		)
		(pad "J29" smd circle
			(at 10.80008 -5.199888)
			(size 0.3556 0.3556)
			(layers "F.Cu" "F.Mask" "F.Paste")
			(net "XM_ADDR_22")
		)
		(pad "J30" smd circle
			(at 11.599926 -5.199888)
			(size 0.3556 0.3556)
			(layers "F.Cu" "F.Mask" "F.Paste")
			(net "XM_ADDR_24")
		)
		(pad "K1" smd circle
			(at -11.599926 -4.400042)
			(size 0.3556 0.3556)
			(layers "F.Cu" "F.Mask" "F.Paste")
			(net "SIO_LOAD_1")
		)
		(pad "K2" smd circle
			(at -10.80008 -4.400042)
			(size 0.3556 0.3556)
			(layers "F.Cu" "F.Mask" "F.Paste")
			(net "SIO_DOUT_0")
		)
		(pad "K3" smd circle
			(at -9.99998 -4.400042)
			(size 0.3556 0.3556)
			(layers "F.Cu" "F.Mask" "F.Paste")
			(net "GND")
		)
		(pad "K4" smd circle
			(at -9.19988 -4.400042)
			(size 0.3556 0.3556)
			(layers "F.Cu" "F.Mask" "F.Paste")
			(net "P1V8_C")
		)
		(pad "K5" smd circle
			(at -8.400034 -4.400042)
			(size 0.3556 0.3556)
			(layers "F.Cu" "F.Mask" "F.Paste")
			(net "GND")
		)
		(pad "K6" smd circle
			(at -7.599934 -4.400042)
			(size 0.3556 0.3556)
			(layers "F.Cu" "F.Mask" "F.Paste")
			(net "Net_1066")
		)
		(pad "K7" smd circle
			(at -6.800088 -4.400042)
			(size 0.3556 0.3556)
			(layers "F.Cu" "F.Mask" "F.Paste")
			(net "GND")
		)
		(pad "K8" smd circle
			(at -5.999988 -4.400042)
			(size 0.3556 0.3556)
			(layers "F.Cu" "F.Mask" "F.Paste")
			(net "GND")
		)
		(pad "K9" smd circle
			(at -5.199888 -4.400042)
			(size 0.3556 0.3556)
			(layers "F.Cu" "F.Mask" "F.Paste")
			(net "GND")
		)
		(pad "K10" smd circle
			(at -4.400042 -4.400042)
			(size 0.3556 0.3556)
			(layers "F.Cu" "F.Mask" "F.Paste")
			(net "GND")
		)
		(pad "K11" smd circle
			(at -3.599942 -4.400042)
			(size 0.3556 0.3556)
			(layers "F.Cu" "F.Mask" "F.Paste")
			(net "GND")
		)
		(pad "K12" smd circle
			(at -2.800096 -4.400042)
			(size 0.3556 0.3556)
			(layers "F.Cu" "F.Mask" "F.Paste")
			(net "GND")
		)
		(pad "K13" smd circle
			(at -1.999996 -4.400042)
			(size 0.3556 0.3556)
			(layers "F.Cu" "F.Mask" "F.Paste")
			(net "P0V955_C")
		)
		(pad "K14" smd circle
			(at -1.199896 -4.400042)
			(size 0.3556 0.3556)
			(layers "F.Cu" "F.Mask" "F.Paste")
			(net "GND")
		)
		(pad "K15" smd circle
			(at -0.40005 -4.400042)
			(size 0.3556 0.3556)
			(layers "F.Cu" "F.Mask" "F.Paste")
			(net "GND")
		)
		(pad "K16" smd circle
			(at 0.40005 -4.400042)
			(size 0.3556 0.3556)
			(layers "F.Cu" "F.Mask" "F.Paste")
			(net "GND")
		)
		(pad "K17" smd circle
			(at 1.199896 -4.400042)
			(size 0.3556 0.3556)
			(layers "F.Cu" "F.Mask" "F.Paste")
			(net "GND")
		)
		(pad "K18" smd circle
			(at 1.999996 -4.400042)
			(size 0.3556 0.3556)
			(layers "F.Cu" "F.Mask" "F.Paste")
			(net "GND")
		)
		(pad "K19" smd circle
			(at 2.800096 -4.400042)
			(size 0.3556 0.3556)
			(layers "F.Cu" "F.Mask" "F.Paste")
			(net "GND")
		)
		(pad "K20" smd circle
			(at 3.599942 -4.400042)
			(size 0.3556 0.3556)
			(layers "F.Cu" "F.Mask" "F.Paste")
			(net "GND")
		)
		(pad "K21" smd circle
			(at 4.400042 -4.400042)
			(size 0.3556 0.3556)
			(layers "F.Cu" "F.Mask" "F.Paste")
			(net "P0V955_C")
		)
		(pad "K22" smd circle
			(at 5.199888 -4.400042)
			(size 0.3556 0.3556)
			(layers "F.Cu" "F.Mask" "F.Paste")
			(net "GND")
		)
		(pad "K23" smd circle
			(at 5.999988 -4.400042)
			(size 0.3556 0.3556)
			(layers "F.Cu" "F.Mask" "F.Paste")
			(net "GND")
		)
		(pad "K24" smd circle
			(at 6.800088 -4.400042)
			(size 0.3556 0.3556)
			(layers "F.Cu" "F.Mask" "F.Paste")
			(net "GND")
		)
		(pad "K25" smd circle
			(at 7.599934 -4.400042)
			(size 0.3556 0.3556)
			(layers "F.Cu" "F.Mask" "F.Paste")
			(net "GND")
		)
		(pad "K26" smd circle
			(at 8.400034 -4.400042)
			(size 0.3556 0.3556)
			(layers "F.Cu" "F.Mask" "F.Paste")
			(net "P1V8_C")
		)
		(pad "K27" smd circle
			(at 9.19988 -4.400042)
			(size 0.3556 0.3556)
			(layers "F.Cu" "F.Mask" "F.Paste")
			(net "GND")
		)
		(pad "K28" smd circle
			(at 9.99998 -4.400042)
			(size 0.3556 0.3556)
			(layers "F.Cu" "F.Mask" "F.Paste")
			(net "XM_DATA_2")
		)
		(pad "K29" smd circle
			(at 10.80008 -4.400042)
			(size 0.3556 0.3556)
			(layers "F.Cu" "F.Mask" "F.Paste")
			(net "XM_ADDR_23")
		)
		(pad "K30" smd circle
			(at 11.599926 -4.400042)
			(size 0.3556 0.3556)
			(layers "F.Cu" "F.Mask" "F.Paste")
			(net "XM_DATA_1")
		)
		(pad "L1" smd circle
			(at -11.599926 -3.599942)
			(size 0.3556 0.3556)
			(layers "F.Cu" "F.Mask" "F.Paste")
			(net "SIO_CLK_1")
		)
		(pad "L2" smd circle
			(at -10.80008 -3.599942)
			(size 0.3556 0.3556)
			(layers "F.Cu" "F.Mask" "F.Paste")
			(net "SIO_DIN_1")
		)
		(pad "L3" smd circle
			(at -9.99998 -3.599942)
			(size 0.3556 0.3556)
			(layers "F.Cu" "F.Mask" "F.Paste")
			(net "Net_1067")
		)
		(pad "L4" smd circle
			(at -9.19988 -3.599942)
			(size 0.3556 0.3556)
			(layers "F.Cu" "F.Mask" "F.Paste")
			(net "GND")
		)
		(pad "L5" smd circle
			(at -8.400034 -3.599942)
			(size 0.3556 0.3556)
			(layers "F.Cu" "F.Mask" "F.Paste")
			(net "P1V8_C")
		)
		(pad "L6" smd circle
			(at -7.599934 -3.599942)
			(size 0.3556 0.3556)
			(layers "F.Cu" "F.Mask" "F.Paste")
			(net "ICE1_TDI")
		)
		(pad "L7" smd circle
			(at -6.800088 -3.599942)
			(size 0.3556 0.3556)
			(layers "F.Cu" "F.Mask" "F.Paste")
			(net "GND")
		)
		(pad "L8" smd circle
			(at -5.999988 -3.599942)
			(size 0.3556 0.3556)
			(layers "F.Cu" "F.Mask" "F.Paste")
			(net "GND")
		)
		(pad "L9" smd circle
			(at -5.199888 -3.599942)
			(size 0.3556 0.3556)
			(layers "F.Cu" "F.Mask" "F.Paste")
			(net "GND")
		)
		(pad "L10" smd circle
			(at -4.400042 -3.599942)
			(size 0.3556 0.3556)
			(layers "F.Cu" "F.Mask" "F.Paste")
			(net "GND")
		)
		(pad "L11" smd circle
			(at -3.599942 -3.599942)
			(size 0.3556 0.3556)
			(layers "F.Cu" "F.Mask" "F.Paste")
			(net "GND")
		)
		(pad "L12" smd circle
			(at -2.800096 -3.599942)
			(size 0.3556 0.3556)
			(layers "F.Cu" "F.Mask" "F.Paste")
			(net "GND")
		)
		(pad "L13" smd circle
			(at -1.999996 -3.599942)
			(size 0.3556 0.3556)
			(layers "F.Cu" "F.Mask" "F.Paste")
			(net "GND")
		)
		(pad "L14" smd circle
			(at -1.199896 -3.599942)
			(size 0.3556 0.3556)
			(layers "F.Cu" "F.Mask" "F.Paste")
			(net "P0V955_C")
		)
		(pad "L15" smd circle
			(at -0.40005 -3.599942)
			(size 0.3556 0.3556)
			(layers "F.Cu" "F.Mask" "F.Paste")
			(net "GND")
		)
		(pad "L16" smd circle
			(at 0.40005 -3.599942)
			(size 0.3556 0.3556)
			(layers "F.Cu" "F.Mask" "F.Paste")
			(net "P0V955_C")
		)
		(pad "L17" smd circle
			(at 1.199896 -3.599942)
			(size 0.3556 0.3556)
			(layers "F.Cu" "F.Mask" "F.Paste")
			(net "GND")
		)
		(pad "L18" smd circle
			(at 1.999996 -3.599942)
			(size 0.3556 0.3556)
			(layers "F.Cu" "F.Mask" "F.Paste")
			(net "P0V955_C")
		)
		(pad "L19" smd circle
			(at 2.800096 -3.599942)
			(size 0.3556 0.3556)
			(layers "F.Cu" "F.Mask" "F.Paste")
			(net "GND")
		)
		(pad "L20" smd circle
			(at 3.599942 -3.599942)
			(size 0.3556 0.3556)
			(layers "F.Cu" "F.Mask" "F.Paste")
			(net "P0V955_C")
		)
		(pad "L21" smd circle
			(at 4.400042 -3.599942)
			(size 0.3556 0.3556)
			(layers "F.Cu" "F.Mask" "F.Paste")
			(net "GND")
		)
		(pad "L22" smd circle
			(at 5.199888 -3.599942)
			(size 0.3556 0.3556)
			(layers "F.Cu" "F.Mask" "F.Paste")
			(net "VDDIO_15")
		)
		(pad "L23" smd circle
			(at 5.999988 -3.599942)
			(size 0.3556 0.3556)
			(layers "F.Cu" "F.Mask" "F.Paste")
			(net "GND")
		)
		(pad "L24" smd circle
			(at 6.800088 -3.599942)
			(size 0.3556 0.3556)
			(layers "F.Cu" "F.Mask" "F.Paste")
			(net "GND")
		)
		(pad "L25" smd circle
			(at 7.599934 -3.599942)
			(size 0.3556 0.3556)
			(layers "F.Cu" "F.Mask" "F.Paste")
			(net "GND")
		)
		(pad "L26" smd circle
			(at 8.400034 -3.599942)
			(size 0.3556 0.3556)
			(layers "F.Cu" "F.Mask" "F.Paste")
			(net "GND")
		)
		(pad "L27" smd circle
			(at 9.19988 -3.599942)
			(size 0.3556 0.3556)
			(layers "F.Cu" "F.Mask" "F.Paste")
			(net "P1V8_C")
		)
		(pad "L28" smd circle
			(at 9.99998 -3.599942)
			(size 0.3556 0.3556)
			(layers "F.Cu" "F.Mask" "F.Paste")
			(net "GND")
		)
		(pad "L29" smd circle
			(at 10.80008 -3.599942)
			(size 0.3556 0.3556)
			(layers "F.Cu" "F.Mask" "F.Paste")
			(net "XM_DATA_4")
		)
		(pad "L30" smd circle
			(at 11.599926 -3.599942)
			(size 0.3556 0.3556)
			(layers "F.Cu" "F.Mask" "F.Paste")
			(net "XM_DATA_3")
		)
		(pad "M1" smd circle
			(at -11.599926 -2.800096)
			(size 0.3556 0.3556)
			(layers "F.Cu" "F.Mask" "F.Paste")
			(net "SIO_CLK_0")
		)
		(pad "M2" smd circle
			(at -10.80008 -2.800096)
			(size 0.3556 0.3556)
			(layers "F.Cu" "F.Mask" "F.Paste")
			(net "SIO_DOUT_1")
		)
		(pad "M3" smd circle
			(at -9.99998 -2.800096)
			(size 0.3556 0.3556)
			(layers "F.Cu" "F.Mask" "F.Paste")
			(net "SIO_LOAD_0")
		)
		(pad "M4" smd circle
			(at -9.19988 -2.800096)
			(size 0.3556 0.3556)
			(layers "F.Cu" "F.Mask" "F.Paste")
			(net "P1V8_C")
		)
		(pad "M5" smd circle
			(at -8.400034 -2.800096)
			(size 0.3556 0.3556)
			(layers "F.Cu" "F.Mask" "F.Paste")
			(net "GND")
		)
		(pad "M6" smd circle
			(at -7.599934 -2.800096)
			(size 0.3556 0.3556)
			(layers "F.Cu" "F.Mask" "F.Paste")
			(net "ICE_SEL")
		)
		(pad "M7" smd circle
			(at -6.800088 -2.800096)
			(size 0.3556 0.3556)
			(layers "F.Cu" "F.Mask" "F.Paste")
			(net "GND")
		)
		(pad "M8" smd circle
			(at -5.999988 -2.800096)
			(size 0.3556 0.3556)
			(layers "F.Cu" "F.Mask" "F.Paste")
			(net "GND")
		)
		(pad "M9" smd circle
			(at -5.199888 -2.800096)
			(size 0.3556 0.3556)
			(layers "F.Cu" "F.Mask" "F.Paste")
			(net "P1V8_C")
		)
		(pad "M10" smd circle
			(at -4.400042 -2.800096)
			(size 0.3556 0.3556)
			(layers "F.Cu" "F.Mask" "F.Paste")
			(net "GND")
		)
		(pad "M11" smd circle
			(at -3.599942 -2.800096)
			(size 0.3556 0.3556)
			(layers "F.Cu" "F.Mask" "F.Paste")
			(net "P0V955_C")
		)
		(pad "M12" smd circle
			(at -2.800096 -2.800096)
			(size 0.3556 0.3556)
			(layers "F.Cu" "F.Mask" "F.Paste")
			(net "GND")
		)
		(pad "M13" smd circle
			(at -1.999996 -2.800096)
			(size 0.3556 0.3556)
			(layers "F.Cu" "F.Mask" "F.Paste")
			(net "P0V955_C")
		)
		(pad "M14" smd circle
			(at -1.199896 -2.800096)
			(size 0.3556 0.3556)
			(layers "F.Cu" "F.Mask" "F.Paste")
			(net "GND")
		)
		(pad "M15" smd circle
			(at -0.40005 -2.800096)
			(size 0.3556 0.3556)
			(layers "F.Cu" "F.Mask" "F.Paste")
			(net "P0V955_C")
		)
		(pad "M16" smd circle
			(at 0.40005 -2.800096)
			(size 0.3556 0.3556)
			(layers "F.Cu" "F.Mask" "F.Paste")
			(net "GND")
		)
		(pad "M17" smd circle
			(at 1.199896 -2.800096)
			(size 0.3556 0.3556)
			(layers "F.Cu" "F.Mask" "F.Paste")
			(net "P0V955_C")
		)
		(pad "M18" smd circle
			(at 1.999996 -2.800096)
			(size 0.3556 0.3556)
			(layers "F.Cu" "F.Mask" "F.Paste")
			(net "GND")
		)
		(pad "M19" smd circle
			(at 2.800096 -2.800096)
			(size 0.3556 0.3556)
			(layers "F.Cu" "F.Mask" "F.Paste")
			(net "P0V955_C")
		)
		(pad "M20" smd circle
			(at 3.599942 -2.800096)
			(size 0.3556 0.3556)
			(layers "F.Cu" "F.Mask" "F.Paste")
			(net "GND")
		)
		(pad "M21" smd circle
			(at 4.400042 -2.800096)
			(size 0.3556 0.3556)
			(layers "F.Cu" "F.Mask" "F.Paste")
			(net "P0V955_C")
		)
		(pad "M22" smd circle
			(at 5.199888 -2.800096)
			(size 0.3556 0.3556)
			(layers "F.Cu" "F.Mask" "F.Paste")
			(net "GND")
		)
		(pad "M23" smd circle
			(at 5.999988 -2.800096)
			(size 0.3556 0.3556)
			(layers "F.Cu" "F.Mask" "F.Paste")
			(net "GND")
		)
		(pad "M24" smd circle
			(at 6.800088 -2.800096)
			(size 0.3556 0.3556)
			(layers "F.Cu" "F.Mask" "F.Paste")
			(net "GND")
		)
		(pad "M25" smd circle
			(at 7.599934 -2.800096)
			(size 0.3556 0.3556)
			(layers "F.Cu" "F.Mask" "F.Paste")
			(net "GND")
		)
		(pad "M26" smd circle
			(at 8.400034 -2.800096)
			(size 0.3556 0.3556)
			(layers "F.Cu" "F.Mask" "F.Paste")
			(net "GND")
		)
		(pad "M27" smd circle
			(at 9.19988 -2.800096)
			(size 0.3556 0.3556)
			(layers "F.Cu" "F.Mask" "F.Paste")
			(net "GND")
		)
		(pad "M28" smd circle
			(at 9.99998 -2.800096)
			(size 0.3556 0.3556)
			(layers "F.Cu" "F.Mask" "F.Paste")
			(net "GND")
		)
		(pad "M29" smd circle
			(at 10.80008 -2.800096)
			(size 0.3556 0.3556)
			(layers "F.Cu" "F.Mask" "F.Paste")
			(net "GND")
		)
		(pad "M30" smd circle
			(at 11.599926 -2.800096)
			(size 0.3556 0.3556)
			(layers "F.Cu" "F.Mask" "F.Paste")
			(net "GND")
		)
		(pad "N1" smd circle
			(at -11.599926 -1.999996)
			(size 0.3556 0.3556)
			(layers "F.Cu" "F.Mask" "F.Paste")
			(net "GND")
		)
		(pad "N2" smd circle
			(at -10.80008 -1.999996)
			(size 0.3556 0.3556)
			(layers "F.Cu" "F.Mask" "F.Paste")
			(net "GND")
		)
		(pad "N3" smd circle
			(at -9.99998 -1.999996)
			(size 0.3556 0.3556)
			(layers "F.Cu" "F.Mask" "F.Paste")
			(net "P1V8_C")
		)
		(pad "N4" smd circle
			(at -9.19988 -1.999996)
			(size 0.3556 0.3556)
			(layers "F.Cu" "F.Mask" "F.Paste")
			(net "GND")
		)
		(pad "N5" smd circle
			(at -8.400034 -1.999996)
			(size 0.3556 0.3556)
			(layers "F.Cu" "F.Mask" "F.Paste")
			(net "Net_1068")
		)
		(pad "N6" smd circle
			(at -7.599934 -1.999996)
			(size 0.3556 0.3556)
			(layers "F.Cu" "F.Mask" "F.Paste")
			(net "Net_1069")
		)
		(pad "N7" smd circle
			(at -6.800088 -1.999996)
			(size 0.3556 0.3556)
			(layers "F.Cu" "F.Mask" "F.Paste")
			(net "GND")
		)
		(pad "N8" smd circle
			(at -5.999988 -1.999996)
			(size 0.3556 0.3556)
			(layers "F.Cu" "F.Mask" "F.Paste")
			(net "GND")
		)
		(pad "N9" smd circle
			(at -5.199888 -1.999996)
			(size 0.3556 0.3556)
			(layers "F.Cu" "F.Mask" "F.Paste")
			(net "GND")
		)
		(pad "N10" smd circle
			(at -4.400042 -1.999996)
			(size 0.3556 0.3556)
			(layers "F.Cu" "F.Mask" "F.Paste")
			(net "GND")
		)
		(pad "N11" smd circle
			(at -3.599942 -1.999996)
			(size 0.3556 0.3556)
			(layers "F.Cu" "F.Mask" "F.Paste")
			(net "GND")
		)
		(pad "N12" smd circle
			(at -2.800096 -1.999996)
			(size 0.3556 0.3556)
			(layers "F.Cu" "F.Mask" "F.Paste")
			(net "P0V955_C")
		)
		(pad "N13" smd circle
			(at -1.999996 -1.999996)
			(size 0.3556 0.3556)
			(layers "F.Cu" "F.Mask" "F.Paste")
			(net "GND")
		)
		(pad "N14" smd circle
			(at -1.199896 -1.999996)
			(size 0.3556 0.3556)
			(layers "F.Cu" "F.Mask" "F.Paste")
			(net "P0V955_C")
		)
		(pad "N15" smd circle
			(at -0.40005 -1.999996)
			(size 0.3556 0.3556)
			(layers "F.Cu" "F.Mask" "F.Paste")
			(net "GND")
		)
		(pad "N16" smd circle
			(at 0.40005 -1.999996)
			(size 0.3556 0.3556)
			(layers "F.Cu" "F.Mask" "F.Paste")
			(net "P0V955_C")
		)
		(pad "N17" smd circle
			(at 1.199896 -1.999996)
			(size 0.3556 0.3556)
			(layers "F.Cu" "F.Mask" "F.Paste")
			(net "GND")
		)
		(pad "N18" smd circle
			(at 1.999996 -1.999996)
			(size 0.3556 0.3556)
			(layers "F.Cu" "F.Mask" "F.Paste")
			(net "P0V955_C")
		)
		(pad "N19" smd circle
			(at 2.800096 -1.999996)
			(size 0.3556 0.3556)
			(layers "F.Cu" "F.Mask" "F.Paste")
			(net "GND")
		)
		(pad "N20" smd circle
			(at 3.599942 -1.999996)
			(size 0.3556 0.3556)
			(layers "F.Cu" "F.Mask" "F.Paste")
			(net "P0V955_C")
		)
		(pad "N21" smd circle
			(at 4.400042 -1.999996)
			(size 0.3556 0.3556)
			(layers "F.Cu" "F.Mask" "F.Paste")
			(net "GND")
		)
		(pad "N22" smd circle
			(at 5.199888 -1.999996)
			(size 0.3556 0.3556)
			(layers "F.Cu" "F.Mask" "F.Paste")
			(net "GND")
		)
		(pad "N23" smd circle
			(at 5.999988 -1.999996)
			(size 0.3556 0.3556)
			(layers "F.Cu" "F.Mask" "F.Paste")
			(net "GND")
		)
		(pad "N24" smd circle
			(at 6.800088 -1.999996)
			(size 0.3556 0.3556)
			(layers "F.Cu" "F.Mask" "F.Paste")
			(net "GND")
		)
		(pad "N25" smd circle
			(at 7.599934 -1.999996)
			(size 0.3556 0.3556)
			(layers "F.Cu" "F.Mask" "F.Paste")
			(net "GND")
		)
		(pad "N26" smd circle
			(at 8.400034 -1.999996)
			(size 0.3556 0.3556)
			(layers "F.Cu" "F.Mask" "F.Paste")
			(net "GND")
		)
		(pad "N27" smd circle
			(at 9.19988 -1.999996)
			(size 0.3556 0.3556)
			(layers "F.Cu" "F.Mask" "F.Paste")
			(net "P1V8_C")
		)
		(pad "N28" smd circle
			(at 9.99998 -1.999996)
			(size 0.3556 0.3556)
			(layers "F.Cu" "F.Mask" "F.Paste")
			(net "IOC_GPIO_32")
		)
		(pad "N29" smd circle
			(at 10.80008 -1.999996)
			(size 0.3556 0.3556)
			(layers "F.Cu" "F.Mask" "F.Paste")
			(net "MEM_CLK_SEL")
		)
		(pad "N30" smd circle
			(at 11.599926 -1.999996)
			(size 0.3556 0.3556)
			(layers "F.Cu" "F.Mask" "F.Paste")
			(net "SBL_SDA")
		)
		(pad "P1" smd circle
			(at -11.599926 -1.199896)
			(size 0.3556 0.3556)
			(layers "F.Cu" "F.Mask" "F.Paste")
			(net "IOC_REF_CLK_P")
		)
		(pad "P2" smd circle
			(at -10.80008 -1.199896)
			(size 0.3556 0.3556)
			(layers "F.Cu" "F.Mask" "F.Paste")
			(net "IOC_REF_CLK_N")
		)
		(pad "P3" smd circle
			(at -9.99998 -1.199896)
			(size 0.3556 0.3556)
			(layers "F.Cu" "F.Mask" "F.Paste")
			(net "GND")
		)
		(pad "P4" smd circle
			(at -9.19988 -1.199896)
			(size 0.3556 0.3556)
			(layers "F.Cu" "F.Mask" "F.Paste")
			(net "P1V8_C")
		)
		(pad "P5" smd circle
			(at -8.400034 -1.199896)
			(size 0.3556 0.3556)
			(layers "F.Cu" "F.Mask" "F.Paste")
			(net "Net_1070")
		)
		(pad "P6" smd circle
			(at -7.599934 -1.199896)
			(size 0.3556 0.3556)
			(layers "F.Cu" "F.Mask" "F.Paste")
			(net "Net_1071")
		)
		(pad "P7" smd circle
			(at -6.800088 -1.199896)
			(size 0.3556 0.3556)
			(layers "F.Cu" "F.Mask" "F.Paste")
			(net "GND")
		)
		(pad "P8" smd circle
			(at -5.999988 -1.199896)
			(size 0.3556 0.3556)
			(layers "F.Cu" "F.Mask" "F.Paste")
			(net "GND")
		)
		(pad "P9" smd circle
			(at -5.199888 -1.199896)
			(size 0.3556 0.3556)
			(layers "F.Cu" "F.Mask" "F.Paste")
			(net "GND")
		)
		(pad "P10" smd circle
			(at -4.400042 -1.199896)
			(size 0.3556 0.3556)
			(layers "F.Cu" "F.Mask" "F.Paste")
			(net "GND")
		)
		(pad "P11" smd circle
			(at -3.599942 -1.199896)
			(size 0.3556 0.3556)
			(layers "F.Cu" "F.Mask" "F.Paste")
			(net "GND")
		)
		(pad "P12" smd circle
			(at -2.800096 -1.199896)
			(size 0.3556 0.3556)
			(layers "F.Cu" "F.Mask" "F.Paste")
			(net "GND")
		)
		(pad "P13" smd circle
			(at -1.999996 -1.199896)
			(size 0.3556 0.3556)
			(layers "F.Cu" "F.Mask" "F.Paste")
			(net "P0V955_C")
		)
		(pad "P14" smd circle
			(at -1.199896 -1.199896)
			(size 0.3556 0.3556)
			(layers "F.Cu" "F.Mask" "F.Paste")
			(net "GND")
		)
		(pad "P15" smd circle
			(at -0.40005 -1.199896)
			(size 0.3556 0.3556)
			(layers "F.Cu" "F.Mask" "F.Paste")
			(net "P0V955_C")
		)
		(pad "P16" smd circle
			(at 0.40005 -1.199896)
			(size 0.3556 0.3556)
			(layers "F.Cu" "F.Mask" "F.Paste")
			(net "GND")
		)
		(pad "P17" smd circle
			(at 1.199896 -1.199896)
			(size 0.3556 0.3556)
			(layers "F.Cu" "F.Mask" "F.Paste")
			(net "P0V955_C")
		)
		(pad "P18" smd circle
			(at 1.999996 -1.199896)
			(size 0.3556 0.3556)
			(layers "F.Cu" "F.Mask" "F.Paste")
			(net "GND")
		)
		(pad "P19" smd circle
			(at 2.800096 -1.199896)
			(size 0.3556 0.3556)
			(layers "F.Cu" "F.Mask" "F.Paste")
			(net "P0V955_C")
		)
		(pad "P20" smd circle
			(at 3.599942 -1.199896)
			(size 0.3556 0.3556)
			(layers "F.Cu" "F.Mask" "F.Paste")
			(net "GND")
		)
		(pad "P21" smd circle
			(at 4.400042 -1.199896)
			(size 0.3556 0.3556)
			(layers "F.Cu" "F.Mask" "F.Paste")
			(net "P0V955_C")
		)
		(pad "P22" smd circle
			(at 5.199888 -1.199896)
			(size 0.3556 0.3556)
			(layers "F.Cu" "F.Mask" "F.Paste")
			(net "GND")
		)
		(pad "P23" smd circle
			(at 5.999988 -1.199896)
			(size 0.3556 0.3556)
			(layers "F.Cu" "F.Mask" "F.Paste")
			(net "GND")
		)
		(pad "P24" smd circle
			(at 6.800088 -1.199896)
			(size 0.3556 0.3556)
			(layers "F.Cu" "F.Mask" "F.Paste")
			(net "GND")
		)
		(pad "P25" smd circle
			(at 7.599934 -1.199896)
			(size 0.3556 0.3556)
			(layers "F.Cu" "F.Mask" "F.Paste")
			(net "GND")
		)
		(pad "P26" smd circle
			(at 8.400034 -1.199896)
			(size 0.3556 0.3556)
			(layers "F.Cu" "F.Mask" "F.Paste")
			(net "P1V8_C")
		)
		(pad "P27" smd circle
			(at 9.19988 -1.199896)
			(size 0.3556 0.3556)
			(layers "F.Cu" "F.Mask" "F.Paste")
			(net "GND")
		)
		(pad "P28" smd circle
			(at 9.99998 -1.199896)
			(size 0.3556 0.3556)
			(layers "F.Cu" "F.Mask" "F.Paste")
			(net "IOC_SCL_3")
		)
		(pad "P29" smd circle
			(at 10.80008 -1.199896)
			(size 0.3556 0.3556)
			(layers "F.Cu" "F.Mask" "F.Paste")
			(net "IOC_CLK_SEL0")
		)
		(pad "P30" smd circle
			(at 11.599926 -1.199896)
			(size 0.3556 0.3556)
			(layers "F.Cu" "F.Mask" "F.Paste")
			(net "IOC_SCL_1")
		)
		(pad "R1" smd circle
			(at -11.599926 -0.40005)
			(size 0.3556 0.3556)
			(layers "F.Cu" "F.Mask" "F.Paste")
			(net "GND")
		)
		(pad "R2" smd circle
			(at -10.80008 -0.40005)
			(size 0.3556 0.3556)
			(layers "F.Cu" "F.Mask" "F.Paste")
			(net "GND")
		)
		(pad "R3" smd circle
			(at -9.99998 -0.40005)
			(size 0.3556 0.3556)
			(layers "F.Cu" "F.Mask" "F.Paste")
			(net "GND")
		)
		(pad "R4" smd circle
			(at -9.19988 -0.40005)
			(size 0.3556 0.3556)
			(layers "F.Cu" "F.Mask" "F.Paste")
			(net "GND")
		)
		(pad "R5" smd circle
			(at -8.400034 -0.40005)
			(size 0.3556 0.3556)
			(layers "F.Cu" "F.Mask" "F.Paste")
			(net "IOC_SIO_BLINK")
		)
		(pad "R6" smd circle
			(at -7.599934 -0.40005)
			(size 0.3556 0.3556)
			(layers "F.Cu" "F.Mask" "F.Paste")
			(net "POWERLOSS#")
		)
		(pad "R7" smd circle
			(at -6.800088 -0.40005)
			(size 0.3556 0.3556)
			(layers "F.Cu" "F.Mask" "F.Paste")
			(net "GND")
		)
		(pad "R8" smd circle
			(at -5.999988 -0.40005)
			(size 0.3556 0.3556)
			(layers "F.Cu" "F.Mask" "F.Paste")
			(net "GND")
		)
		(pad "R9" smd circle
			(at -5.199888 -0.40005)
			(size 0.3556 0.3556)
			(layers "F.Cu" "F.Mask" "F.Paste")
			(net "GND")
		)
		(pad "R10" smd circle
			(at -4.400042 -0.40005)
			(size 0.3556 0.3556)
			(layers "F.Cu" "F.Mask" "F.Paste")
			(net "GND")
		)
		(pad "R11" smd circle
			(at -3.599942 -0.40005)
			(size 0.3556 0.3556)
			(layers "F.Cu" "F.Mask" "F.Paste")
			(net "GND")
		)
		(pad "R12" smd circle
			(at -2.800096 -0.40005)
			(size 0.3556 0.3556)
			(layers "F.Cu" "F.Mask" "F.Paste")
			(net "P0V955_C")
		)
		(pad "R13" smd circle
			(at -1.999996 -0.40005)
			(size 0.3556 0.3556)
			(layers "F.Cu" "F.Mask" "F.Paste")
			(net "GND")
		)
		(pad "R14" smd circle
			(at -1.199896 -0.40005)
			(size 0.3556 0.3556)
			(layers "F.Cu" "F.Mask" "F.Paste")
			(net "P0V955_C")
		)
		(pad "R15" smd circle
			(at -0.40005 -0.40005)
			(size 0.3556 0.3556)
			(layers "F.Cu" "F.Mask" "F.Paste")
			(net "GND")
		)
		(pad "R16" smd circle
			(at 0.40005 -0.40005)
			(size 0.3556 0.3556)
			(layers "F.Cu" "F.Mask" "F.Paste")
			(net "P0V955_C")
		)
		(pad "R17" smd circle
			(at 1.199896 -0.40005)
			(size 0.3556 0.3556)
			(layers "F.Cu" "F.Mask" "F.Paste")
			(net "GND")
		)
		(pad "R18" smd circle
			(at 1.999996 -0.40005)
			(size 0.3556 0.3556)
			(layers "F.Cu" "F.Mask" "F.Paste")
			(net "P0V955_C")
		)
		(pad "R19" smd circle
			(at 2.800096 -0.40005)
			(size 0.3556 0.3556)
			(layers "F.Cu" "F.Mask" "F.Paste")
			(net "GND")
		)
		(pad "R20" smd circle
			(at 3.599942 -0.40005)
			(size 0.3556 0.3556)
			(layers "F.Cu" "F.Mask" "F.Paste")
			(net "P0V955_C")
		)
		(pad "R21" smd circle
			(at 4.400042 -0.40005)
			(size 0.3556 0.3556)
			(layers "F.Cu" "F.Mask" "F.Paste")
			(net "GND")
		)
		(pad "R22" smd circle
			(at 5.199888 -0.40005)
			(size 0.3556 0.3556)
			(layers "F.Cu" "F.Mask" "F.Paste")
			(net "GND")
		)
		(pad "R23" smd circle
			(at 5.999988 -0.40005)
			(size 0.3556 0.3556)
			(layers "F.Cu" "F.Mask" "F.Paste")
			(net "GND")
		)
		(pad "R24" smd circle
			(at 6.800088 -0.40005)
			(size 0.3556 0.3556)
			(layers "F.Cu" "F.Mask" "F.Paste")
			(net "GND")
		)
		(pad "R25" smd circle
			(at 7.599934 -0.40005)
			(size 0.3556 0.3556)
			(layers "F.Cu" "F.Mask" "F.Paste")
			(net "GND")
		)
		(pad "R26" smd circle
			(at 8.400034 -0.40005)
			(size 0.3556 0.3556)
			(layers "F.Cu" "F.Mask" "F.Paste")
			(net "GND")
		)
		(pad "R27" smd circle
			(at 9.19988 -0.40005)
			(size 0.3556 0.3556)
			(layers "F.Cu" "F.Mask" "F.Paste")
			(net "P1V8_C")
		)
		(pad "R28" smd circle
			(at 9.99998 -0.40005)
			(size 0.3556 0.3556)
			(layers "F.Cu" "F.Mask" "F.Paste")
			(net "IOC_SDA_4")
		)
		(pad "R29" smd circle
			(at 10.80008 -0.40005)
			(size 0.3556 0.3556)
			(layers "F.Cu" "F.Mask" "F.Paste")
			(net "IOC_SDA_0")
		)
		(pad "R30" smd circle
			(at 11.599926 -0.40005)
			(size 0.3556 0.3556)
			(layers "F.Cu" "F.Mask" "F.Paste")
			(net "SYS_CORE_TRI#")
		)
		(pad "T1" smd circle
			(at -11.599926 0.40005)
			(size 0.3556 0.3556)
			(layers "F.Cu" "F.Mask" "F.Paste")
			(net "RTRIM")
		)
		(pad "T2" smd circle
			(at -10.80008 0.40005)
			(size 0.3556 0.3556)
			(layers "F.Cu" "F.Mask" "F.Paste")
			(net "RTRIM#")
		)
		(pad "T3" smd circle
			(at -9.99998 0.40005)
			(size 0.3556 0.3556)
			(layers "F.Cu" "F.Mask" "F.Paste")
			(net "GND")
		)
		(pad "T4" smd circle
			(at -9.19988 0.40005)
			(size 0.3556 0.3556)
			(layers "F.Cu" "F.Mask" "F.Paste")
			(net "OSC_REF_CLK")
		)
		(pad "T5" smd circle
			(at -8.400034 0.40005)
			(size 0.3556 0.3556)
			(layers "F.Cu" "F.Mask" "F.Paste")
			(net "GND")
		)
		(pad "T6" smd circle
			(at -7.599934 0.40005)
			(size 0.3556 0.3556)
			(layers "F.Cu" "F.Mask" "F.Paste")
			(net "SIO_DIN_0")
		)
		(pad "T7" smd circle
			(at -6.800088 0.40005)
			(size 0.3556 0.3556)
			(layers "F.Cu" "F.Mask" "F.Paste")
			(net "GND")
		)
		(pad "T8" smd circle
			(at -5.999988 0.40005)
			(size 0.3556 0.3556)
			(layers "F.Cu" "F.Mask" "F.Paste")
			(net "GND")
		)
		(pad "T9" smd circle
			(at -5.199888 0.40005)
			(size 0.3556 0.3556)
			(layers "F.Cu" "F.Mask" "F.Paste")
			(net "SYS_PLL_VDD")
		)
		(pad "T10" smd circle
			(at -4.400042 0.40005)
			(size 0.3556 0.3556)
			(layers "F.Cu" "F.Mask" "F.Paste")
			(net "GND")
		)
		(pad "T11" smd circle
			(at -3.599942 0.40005)
			(size 0.3556 0.3556)
			(layers "F.Cu" "F.Mask" "F.Paste")
			(net "GND")
		)
		(pad "T12" smd circle
			(at -2.800096 0.40005)
			(size 0.3556 0.3556)
			(layers "F.Cu" "F.Mask" "F.Paste")
			(net "GND")
		)
		(pad "T13" smd circle
			(at -1.999996 0.40005)
			(size 0.3556 0.3556)
			(layers "F.Cu" "F.Mask" "F.Paste")
			(net "P0V955_C")
		)
		(pad "T14" smd circle
			(at -1.199896 0.40005)
			(size 0.3556 0.3556)
			(layers "F.Cu" "F.Mask" "F.Paste")
			(net "GND")
		)
		(pad "T15" smd circle
			(at -0.40005 0.40005)
			(size 0.3556 0.3556)
			(layers "F.Cu" "F.Mask" "F.Paste")
			(net "P0V955_C")
		)
		(pad "T16" smd circle
			(at 0.40005 0.40005)
			(size 0.3556 0.3556)
			(layers "F.Cu" "F.Mask" "F.Paste")
			(net "GND")
		)
		(pad "T17" smd circle
			(at 1.199896 0.40005)
			(size 0.3556 0.3556)
			(layers "F.Cu" "F.Mask" "F.Paste")
			(net "P0V955_C")
		)
		(pad "T18" smd circle
			(at 1.999996 0.40005)
			(size 0.3556 0.3556)
			(layers "F.Cu" "F.Mask" "F.Paste")
			(net "GND")
		)
		(pad "T19" smd circle
			(at 2.800096 0.40005)
			(size 0.3556 0.3556)
			(layers "F.Cu" "F.Mask" "F.Paste")
			(net "P0V955_C")
		)
		(pad "T20" smd circle
			(at 3.599942 0.40005)
			(size 0.3556 0.3556)
			(layers "F.Cu" "F.Mask" "F.Paste")
			(net "GND")
		)
		(pad "T21" smd circle
			(at 4.400042 0.40005)
			(size 0.3556 0.3556)
			(layers "F.Cu" "F.Mask" "F.Paste")
			(net "P0V955_C")
		)
		(pad "T22" smd circle
			(at 5.199888 0.40005)
			(size 0.3556 0.3556)
			(layers "F.Cu" "F.Mask" "F.Paste")
			(net "GND")
		)
		(pad "T23" smd circle
			(at 5.999988 0.40005)
			(size 0.3556 0.3556)
			(layers "F.Cu" "F.Mask" "F.Paste")
			(net "GND")
		)
		(pad "T24" smd circle
			(at 6.800088 0.40005)
			(size 0.3556 0.3556)
			(layers "F.Cu" "F.Mask" "F.Paste")
			(net "GND")
		)
		(pad "T25" smd circle
			(at 7.599934 0.40005)
			(size 0.3556 0.3556)
			(layers "F.Cu" "F.Mask" "F.Paste")
			(net "GND")
		)
		(pad "T26" smd circle
			(at 8.400034 0.40005)
			(size 0.3556 0.3556)
			(layers "F.Cu" "F.Mask" "F.Paste")
			(net "P1V8_C")
		)
		(pad "T27" smd circle
			(at 9.19988 0.40005)
			(size 0.3556 0.3556)
			(layers "F.Cu" "F.Mask" "F.Paste")
			(net "GND")
		)
		(pad "T28" smd circle
			(at 9.99998 0.40005)
			(size 0.3556 0.3556)
			(layers "F.Cu" "F.Mask" "F.Paste")
			(net "IOC_CLK_SEL1")
		)
		(pad "T29" smd circle
			(at 10.80008 0.40005)
			(size 0.3556 0.3556)
			(layers "F.Cu" "F.Mask" "F.Paste")
			(net "SYS_HB_LED")
		)
		(pad "T30" smd circle
			(at 11.599926 0.40005)
			(size 0.3556 0.3556)
			(layers "F.Cu" "F.Mask" "F.Paste")
			(net "SBL_SCL")
		)
		(pad "U1" smd circle
			(at -11.599926 1.199896)
			(size 0.3556 0.3556)
			(layers "F.Cu" "F.Mask" "F.Paste")
			(net "SAS0_VDDH")
		)
		(pad "U2" smd circle
			(at -10.80008 1.199896)
			(size 0.3556 0.3556)
			(layers "F.Cu" "F.Mask" "F.Paste")
			(net "GND")
		)
		(pad "U3" smd circle
			(at -9.99998 1.199896)
			(size 0.3556 0.3556)
			(layers "F.Cu" "F.Mask" "F.Paste")
			(net "GND")
		)
		(pad "U4" smd circle
			(at -9.19988 1.199896)
			(size 0.3556 0.3556)
			(layers "F.Cu" "F.Mask" "F.Paste")
			(net "GND")
		)
		(pad "U5" smd circle
			(at -8.400034 1.199896)
			(size 0.3556 0.3556)
			(layers "F.Cu" "F.Mask" "F.Paste")
			(net "GND")
		)
		(pad "U6" smd circle
			(at -7.599934 1.199896)
			(size 0.3556 0.3556)
			(layers "F.Cu" "F.Mask" "F.Paste")
			(net "GND")
		)
		(pad "U7" smd circle
			(at -6.800088 1.199896)
			(size 0.3556 0.3556)
			(layers "F.Cu" "F.Mask" "F.Paste")
			(net "GND")
		)
		(pad "U8" smd circle
			(at -5.999988 1.199896)
			(size 0.3556 0.3556)
			(layers "F.Cu" "F.Mask" "F.Paste")
			(net "GND")
		)
		(pad "U9" smd circle
			(at -5.199888 1.199896)
			(size 0.3556 0.3556)
			(layers "F.Cu" "F.Mask" "F.Paste")
			(net "GND")
		)
		(pad "U10" smd circle
			(at -4.400042 1.199896)
			(size 0.3556 0.3556)
			(layers "F.Cu" "F.Mask" "F.Paste")
			(net "SHELL_PLL_VDD")
		)
		(pad "U11" smd circle
			(at -3.599942 1.199896)
			(size 0.3556 0.3556)
			(layers "F.Cu" "F.Mask" "F.Paste")
			(net "GND")
		)
		(pad "U12" smd circle
			(at -2.800096 1.199896)
			(size 0.3556 0.3556)
			(layers "F.Cu" "F.Mask" "F.Paste")
			(net "P0V955_C")
		)
		(pad "U13" smd circle
			(at -1.999996 1.199896)
			(size 0.3556 0.3556)
			(layers "F.Cu" "F.Mask" "F.Paste")
			(net "GND")
		)
		(pad "U14" smd circle
			(at -1.199896 1.199896)
			(size 0.3556 0.3556)
			(layers "F.Cu" "F.Mask" "F.Paste")
			(net "P0V955_C")
		)
		(pad "U15" smd circle
			(at -0.40005 1.199896)
			(size 0.3556 0.3556)
			(layers "F.Cu" "F.Mask" "F.Paste")
			(net "GND")
		)
		(pad "U16" smd circle
			(at 0.40005 1.199896)
			(size 0.3556 0.3556)
			(layers "F.Cu" "F.Mask" "F.Paste")
			(net "P0V955_C")
		)
		(pad "U17" smd circle
			(at 1.199896 1.199896)
			(size 0.3556 0.3556)
			(layers "F.Cu" "F.Mask" "F.Paste")
			(net "GND")
		)
		(pad "U18" smd circle
			(at 1.999996 1.199896)
			(size 0.3556 0.3556)
			(layers "F.Cu" "F.Mask" "F.Paste")
			(net "P0V955_C")
		)
		(pad "U19" smd circle
			(at 2.800096 1.199896)
			(size 0.3556 0.3556)
			(layers "F.Cu" "F.Mask" "F.Paste")
			(net "GND")
		)
		(pad "U20" smd circle
			(at 3.599942 1.199896)
			(size 0.3556 0.3556)
			(layers "F.Cu" "F.Mask" "F.Paste")
			(net "P0V955_C")
		)
		(pad "U21" smd circle
			(at 4.400042 1.199896)
			(size 0.3556 0.3556)
			(layers "F.Cu" "F.Mask" "F.Paste")
			(net "GND")
		)
		(pad "U22" smd circle
			(at 5.199888 1.199896)
			(size 0.3556 0.3556)
			(layers "F.Cu" "F.Mask" "F.Paste")
			(net "GND")
		)
		(pad "U23" smd circle
			(at 5.999988 1.199896)
			(size 0.3556 0.3556)
			(layers "F.Cu" "F.Mask" "F.Paste")
			(net "GND")
		)
		(pad "U24" smd circle
			(at 6.800088 1.199896)
			(size 0.3556 0.3556)
			(layers "F.Cu" "F.Mask" "F.Paste")
			(net "GND")
		)
		(pad "U25" smd circle
			(at 7.599934 1.199896)
			(size 0.3556 0.3556)
			(layers "F.Cu" "F.Mask" "F.Paste")
			(net "GND")
		)
		(pad "U26" smd circle
			(at 8.400034 1.199896)
			(size 0.3556 0.3556)
			(layers "F.Cu" "F.Mask" "F.Paste")
			(net "GND")
		)
		(pad "U27" smd circle
			(at 9.19988 1.199896)
			(size 0.3556 0.3556)
			(layers "F.Cu" "F.Mask" "F.Paste")
			(net "P1V8_C")
		)
		(pad "U28" smd circle
			(at 9.99998 1.199896)
			(size 0.3556 0.3556)
			(layers "F.Cu" "F.Mask" "F.Paste")
			(net "IOC_RESET#")
		)
		(pad "U29" smd circle
			(at 10.80008 1.199896)
			(size 0.3556 0.3556)
			(layers "F.Cu" "F.Mask" "F.Paste")
			(net "IOC_SDA_3")
		)
		(pad "U30" smd circle
			(at 11.599926 1.199896)
			(size 0.3556 0.3556)
			(layers "F.Cu" "F.Mask" "F.Paste")
			(net "CP_DONE")
		)
		(pad "V1" smd circle
			(at -11.599926 1.999996)
			(size 0.3556 0.3556)
			(layers "F.Cu" "F.Mask" "F.Paste")
			(net "SAS3008_RAID_TX_C_P4")
		)
		(pad "V2" smd circle
			(at -10.80008 1.999996)
			(size 0.3556 0.3556)
			(layers "F.Cu" "F.Mask" "F.Paste")
			(net "SAS3008_RAID_TX_C_N4")
		)
		(pad "V3" smd circle
			(at -9.99998 1.999996)
			(size 0.3556 0.3556)
			(layers "F.Cu" "F.Mask" "F.Paste")
			(net "GND")
		)
		(pad "V4" smd circle
			(at -9.19988 1.999996)
			(size 0.3556 0.3556)
			(layers "F.Cu" "F.Mask" "F.Paste")
			(net "IOC_SAS_RX_P4")
		)
		(pad "V5" smd circle
			(at -8.400034 1.999996)
			(size 0.3556 0.3556)
			(layers "F.Cu" "F.Mask" "F.Paste")
			(net "IOC_SAS_RX_N4")
		)
		(pad "V6" smd circle
			(at -7.599934 1.999996)
			(size 0.3556 0.3556)
			(layers "F.Cu" "F.Mask" "F.Paste")
			(net "GND")
		)
		(pad "V7" smd circle
			(at -6.800088 1.999996)
			(size 0.3556 0.3556)
			(layers "F.Cu" "F.Mask" "F.Paste")
			(net "SAS0_AVDD")
		)
		(pad "V8" smd circle
			(at -5.999988 1.999996)
			(size 0.3556 0.3556)
			(layers "F.Cu" "F.Mask" "F.Paste")
			(net "GND")
		)
		(pad "V9" smd circle
			(at -5.199888 1.999996)
			(size 0.3556 0.3556)
			(layers "F.Cu" "F.Mask" "F.Paste")
			(net "SAS0_AVDD")
		)
		(pad "V10" smd circle
			(at -4.400042 1.999996)
			(size 0.3556 0.3556)
			(layers "F.Cu" "F.Mask" "F.Paste")
			(net "GND")
		)
		(pad "V11" smd circle
			(at -3.599942 1.999996)
			(size 0.3556 0.3556)
			(layers "F.Cu" "F.Mask" "F.Paste")
			(net "VDDA_SAS_REF_CLK")
		)
		(pad "V12" smd circle
			(at -2.800096 1.999996)
			(size 0.3556 0.3556)
			(layers "F.Cu" "F.Mask" "F.Paste")
			(net "GND")
		)
		(pad "V13" smd circle
			(at -1.999996 1.999996)
			(size 0.3556 0.3556)
			(layers "F.Cu" "F.Mask" "F.Paste")
			(net "P0V955_C")
		)
		(pad "V14" smd circle
			(at -1.199896 1.999996)
			(size 0.3556 0.3556)
			(layers "F.Cu" "F.Mask" "F.Paste")
			(net "GND")
		)
		(pad "V15" smd circle
			(at -0.40005 1.999996)
			(size 0.3556 0.3556)
			(layers "F.Cu" "F.Mask" "F.Paste")
			(net "P0V955_C")
		)
		(pad "V16" smd circle
			(at 0.40005 1.999996)
			(size 0.3556 0.3556)
			(layers "F.Cu" "F.Mask" "F.Paste")
			(net "GND")
		)
		(pad "V17" smd circle
			(at 1.199896 1.999996)
			(size 0.3556 0.3556)
			(layers "F.Cu" "F.Mask" "F.Paste")
			(net "P0V955_C")
		)
		(pad "V18" smd circle
			(at 1.999996 1.999996)
			(size 0.3556 0.3556)
			(layers "F.Cu" "F.Mask" "F.Paste")
			(net "GND")
		)
		(pad "V19" smd circle
			(at 2.800096 1.999996)
			(size 0.3556 0.3556)
			(layers "F.Cu" "F.Mask" "F.Paste")
			(net "P0V955_C")
		)
		(pad "V20" smd circle
			(at 3.599942 1.999996)
			(size 0.3556 0.3556)
			(layers "F.Cu" "F.Mask" "F.Paste")
			(net "GND")
		)
		(pad "V21" smd circle
			(at 4.400042 1.999996)
			(size 0.3556 0.3556)
			(layers "F.Cu" "F.Mask" "F.Paste")
			(net "P0V955_C")
		)
		(pad "V22" smd circle
			(at 5.199888 1.999996)
			(size 0.3556 0.3556)
			(layers "F.Cu" "F.Mask" "F.Paste")
			(net "GND")
		)
		(pad "V23" smd circle
			(at 5.999988 1.999996)
			(size 0.3556 0.3556)
			(layers "F.Cu" "F.Mask" "F.Paste")
			(net "GND")
		)
		(pad "V24" smd circle
			(at 6.800088 1.999996)
			(size 0.3556 0.3556)
			(layers "F.Cu" "F.Mask" "F.Paste")
			(net "GND")
		)
		(pad "V25" smd circle
			(at 7.599934 1.999996)
			(size 0.3556 0.3556)
			(layers "F.Cu" "F.Mask" "F.Paste")
			(net "GND")
		)
		(pad "V26" smd circle
			(at 8.400034 1.999996)
			(size 0.3556 0.3556)
			(layers "F.Cu" "F.Mask" "F.Paste")
			(net "P1V8_C")
		)
		(pad "V27" smd circle
			(at 9.19988 1.999996)
			(size 0.3556 0.3556)
			(layers "F.Cu" "F.Mask" "F.Paste")
			(net "GND")
		)
		(pad "V28" smd circle
			(at 9.99998 1.999996)
			(size 0.3556 0.3556)
			(layers "F.Cu" "F.Mask" "F.Paste")
			(net "IOC_SCL_2")
		)
		(pad "V29" smd circle
			(at 10.80008 1.999996)
			(size 0.3556 0.3556)
			(layers "F.Cu" "F.Mask" "F.Paste")
			(net "IOC_SCL_0")
		)
		(pad "V30" smd circle
			(at 11.599926 1.999996)
			(size 0.3556 0.3556)
			(layers "F.Cu" "F.Mask" "F.Paste")
			(net "IOC_SDA_1")
		)
		(pad "W1" smd circle
			(at -11.599926 2.800096)
			(size 0.3556 0.3556)
			(layers "F.Cu" "F.Mask" "F.Paste")
			(net "SAS3008_RAID_TX_C_P5")
		)
		(pad "W2" smd circle
			(at -10.80008 2.800096)
			(size 0.3556 0.3556)
			(layers "F.Cu" "F.Mask" "F.Paste")
			(net "SAS3008_RAID_TX_C_N5")
		)
		(pad "W3" smd circle
			(at -9.99998 2.800096)
			(size 0.3556 0.3556)
			(layers "F.Cu" "F.Mask" "F.Paste")
			(net "GND")
		)
		(pad "W4" smd circle
			(at -9.19988 2.800096)
			(size 0.3556 0.3556)
			(layers "F.Cu" "F.Mask" "F.Paste")
			(net "IOC_SAS_RX_P5")
		)
		(pad "W5" smd circle
			(at -8.400034 2.800096)
			(size 0.3556 0.3556)
			(layers "F.Cu" "F.Mask" "F.Paste")
			(net "IOC_SAS_RX_N5")
		)
		(pad "W6" smd circle
			(at -7.599934 2.800096)
			(size 0.3556 0.3556)
			(layers "F.Cu" "F.Mask" "F.Paste")
			(net "GND")
		)
		(pad "W7" smd circle
			(at -6.800088 2.800096)
			(size 0.3556 0.3556)
			(layers "F.Cu" "F.Mask" "F.Paste")
			(net "GND")
		)
		(pad "W8" smd circle
			(at -5.999988 2.800096)
			(size 0.3556 0.3556)
			(layers "F.Cu" "F.Mask" "F.Paste")
			(net "GND")
		)
		(pad "W9" smd circle
			(at -5.199888 2.800096)
			(size 0.3556 0.3556)
			(layers "F.Cu" "F.Mask" "F.Paste")
			(net "GND")
		)
		(pad "W10" smd circle
			(at -4.400042 2.800096)
			(size 0.3556 0.3556)
			(layers "F.Cu" "F.Mask" "F.Paste")
			(net "GND")
		)
		(pad "W11" smd circle
			(at -3.599942 2.800096)
			(size 0.3556 0.3556)
			(layers "F.Cu" "F.Mask" "F.Paste")
			(net "GND")
		)
		(pad "W12" smd circle
			(at -2.800096 2.800096)
			(size 0.3556 0.3556)
			(layers "F.Cu" "F.Mask" "F.Paste")
			(net "GND")
		)
		(pad "W13" smd circle
			(at -1.999996 2.800096)
			(size 0.3556 0.3556)
			(layers "F.Cu" "F.Mask" "F.Paste")
			(net "GND")
		)
		(pad "W14" smd circle
			(at -1.199896 2.800096)
			(size 0.3556 0.3556)
			(layers "F.Cu" "F.Mask" "F.Paste")
			(net "P0V955_C")
		)
		(pad "W15" smd circle
			(at -0.40005 2.800096)
			(size 0.3556 0.3556)
			(layers "F.Cu" "F.Mask" "F.Paste")
			(net "GND")
		)
		(pad "W16" smd circle
			(at 0.40005 2.800096)
			(size 0.3556 0.3556)
			(layers "F.Cu" "F.Mask" "F.Paste")
			(net "P0V955_C")
		)
		(pad "W17" smd circle
			(at 1.199896 2.800096)
			(size 0.3556 0.3556)
			(layers "F.Cu" "F.Mask" "F.Paste")
			(net "GND")
		)
		(pad "W18" smd circle
			(at 1.999996 2.800096)
			(size 0.3556 0.3556)
			(layers "F.Cu" "F.Mask" "F.Paste")
			(net "P0V955_C")
		)
		(pad "W19" smd circle
			(at 2.800096 2.800096)
			(size 0.3556 0.3556)
			(layers "F.Cu" "F.Mask" "F.Paste")
			(net "GND")
		)
		(pad "W20" smd circle
			(at 3.599942 2.800096)
			(size 0.3556 0.3556)
			(layers "F.Cu" "F.Mask" "F.Paste")
			(net "P0V955_C")
		)
		(pad "W21" smd circle
			(at 4.400042 2.800096)
			(size 0.3556 0.3556)
			(layers "F.Cu" "F.Mask" "F.Paste")
			(net "GND")
		)
		(pad "W22" smd circle
			(at 5.199888 2.800096)
			(size 0.3556 0.3556)
			(layers "F.Cu" "F.Mask" "F.Paste")
			(net "GND")
		)
		(pad "W23" smd circle
			(at 5.999988 2.800096)
			(size 0.3556 0.3556)
			(layers "F.Cu" "F.Mask" "F.Paste")
			(net "GND")
		)
		(pad "W24" smd circle
			(at 6.800088 2.800096)
			(size 0.3556 0.3556)
			(layers "F.Cu" "F.Mask" "F.Paste")
			(net "GND")
		)
		(pad "W25" smd circle
			(at 7.599934 2.800096)
			(size 0.3556 0.3556)
			(layers "F.Cu" "F.Mask" "F.Paste")
			(net "GND")
		)
		(pad "W26" smd circle
			(at 8.400034 2.800096)
			(size 0.3556 0.3556)
			(layers "F.Cu" "F.Mask" "F.Paste")
			(net "GND")
		)
		(pad "W27" smd circle
			(at 9.19988 2.800096)
			(size 0.3556 0.3556)
			(layers "F.Cu" "F.Mask" "F.Paste")
			(net "P1V8_C")
		)
		(pad "W28" smd circle
			(at 9.99998 2.800096)
			(size 0.3556 0.3556)
			(layers "F.Cu" "F.Mask" "F.Paste")
			(net "IOC_GPIO_38")
		)
		(pad "W29" smd circle
			(at 10.80008 2.800096)
			(size 0.3556 0.3556)
			(layers "F.Cu" "F.Mask" "F.Paste")
			(net "IOC_SCL_4")
		)
		(pad "W30" smd circle
			(at 11.599926 2.800096)
			(size 0.3556 0.3556)
			(layers "F.Cu" "F.Mask" "F.Paste")
			(net "IOC_GPIO_24")
		)
		(pad "Y1" smd circle
			(at -11.599926 3.599942)
			(size 0.3556 0.3556)
			(layers "F.Cu" "F.Mask" "F.Paste")
			(net "SAS0_VDDH")
		)
		(pad "Y2" smd circle
			(at -10.80008 3.599942)
			(size 0.3556 0.3556)
			(layers "F.Cu" "F.Mask" "F.Paste")
			(net "GND")
		)
		(pad "Y3" smd circle
			(at -9.99998 3.599942)
			(size 0.3556 0.3556)
			(layers "F.Cu" "F.Mask" "F.Paste")
			(net "GND")
		)
		(pad "Y4" smd circle
			(at -9.19988 3.599942)
			(size 0.3556 0.3556)
			(layers "F.Cu" "F.Mask" "F.Paste")
			(net "SAS0_AVDD")
		)
		(pad "Y5" smd circle
			(at -8.400034 3.599942)
			(size 0.3556 0.3556)
			(layers "F.Cu" "F.Mask" "F.Paste")
			(net "GND")
		)
		(pad "Y6" smd circle
			(at -7.599934 3.599942)
			(size 0.3556 0.3556)
			(layers "F.Cu" "F.Mask" "F.Paste")
			(net "SAS0_VDDH")
		)
		(pad "Y7" smd circle
			(at -6.800088 3.599942)
			(size 0.3556 0.3556)
			(layers "F.Cu" "F.Mask" "F.Paste")
			(net "SAS0_AVDD")
		)
		(pad "Y8" smd circle
			(at -5.999988 3.599942)
			(size 0.3556 0.3556)
			(layers "F.Cu" "F.Mask" "F.Paste")
			(net "GND")
		)
		(pad "Y9" smd circle
			(at -5.199888 3.599942)
			(size 0.3556 0.3556)
			(layers "F.Cu" "F.Mask" "F.Paste")
			(net "GND")
		)
		(pad "Y10" smd circle
			(at -4.400042 3.599942)
			(size 0.3556 0.3556)
			(layers "F.Cu" "F.Mask" "F.Paste")
			(net "GND")
		)
		(pad "Y11" smd circle
			(at -3.599942 3.599942)
			(size 0.3556 0.3556)
			(layers "F.Cu" "F.Mask" "F.Paste")
			(net "GND")
		)
		(pad "Y12" smd circle
			(at -2.800096 3.599942)
			(size 0.3556 0.3556)
			(layers "F.Cu" "F.Mask" "F.Paste")
			(net "GND")
		)
		(pad "Y13" smd circle
			(at -1.999996 3.599942)
			(size 0.3556 0.3556)
			(layers "F.Cu" "F.Mask" "F.Paste")
			(net "GND")
		)
		(pad "Y14" smd circle
			(at -1.199896 3.599942)
			(size 0.3556 0.3556)
			(layers "F.Cu" "F.Mask" "F.Paste")
			(net "GND")
		)
		(pad "Y15" smd circle
			(at -0.40005 3.599942)
			(size 0.3556 0.3556)
			(layers "F.Cu" "F.Mask" "F.Paste")
			(net "GND")
		)
		(pad "Y16" smd circle
			(at 0.40005 3.599942)
			(size 0.3556 0.3556)
			(layers "F.Cu" "F.Mask" "F.Paste")
			(net "GND")
		)
		(pad "Y17" smd circle
			(at 1.199896 3.599942)
			(size 0.3556 0.3556)
			(layers "F.Cu" "F.Mask" "F.Paste")
			(net "P0V955_C")
		)
		(pad "Y18" smd circle
			(at 1.999996 3.599942)
			(size 0.3556 0.3556)
			(layers "F.Cu" "F.Mask" "F.Paste")
			(net "GND")
		)
		(pad "Y19" smd circle
			(at 2.800096 3.599942)
			(size 0.3556 0.3556)
			(layers "F.Cu" "F.Mask" "F.Paste")
			(net "P0V955_C")
		)
		(pad "Y20" smd circle
			(at 3.599942 3.599942)
			(size 0.3556 0.3556)
			(layers "F.Cu" "F.Mask" "F.Paste")
			(net "GND")
		)
		(pad "Y21" smd circle
			(at 4.400042 3.599942)
			(size 0.3556 0.3556)
			(layers "F.Cu" "F.Mask" "F.Paste")
			(net "P0V955_C")
		)
		(pad "Y22" smd circle
			(at 5.199888 3.599942)
			(size 0.3556 0.3556)
			(layers "F.Cu" "F.Mask" "F.Paste")
			(net "GND")
		)
		(pad "Y23" smd circle
			(at 5.999988 3.599942)
			(size 0.3556 0.3556)
			(layers "F.Cu" "F.Mask" "F.Paste")
			(net "GND")
		)
		(pad "Y24" smd circle
			(at 6.800088 3.599942)
			(size 0.3556 0.3556)
			(layers "F.Cu" "F.Mask" "F.Paste")
			(net "GND")
		)
		(pad "Y25" smd circle
			(at 7.599934 3.599942)
			(size 0.3556 0.3556)
			(layers "F.Cu" "F.Mask" "F.Paste")
			(net "GND")
		)
		(pad "Y26" smd circle
			(at 8.400034 3.599942)
			(size 0.3556 0.3556)
			(layers "F.Cu" "F.Mask" "F.Paste")
			(net "P1V8_C")
		)
		(pad "Y27" smd circle
			(at 9.19988 3.599942)
			(size 0.3556 0.3556)
			(layers "F.Cu" "F.Mask" "F.Paste")
			(net "GND")
		)
		(pad "Y28" smd circle
			(at 9.99998 3.599942)
			(size 0.3556 0.3556)
			(layers "F.Cu" "F.Mask" "F.Paste")
			(net "IOC_SDA_2")
		)
		(pad "Y29" smd circle
			(at 10.80008 3.599942)
			(size 0.3556 0.3556)
			(layers "F.Cu" "F.Mask" "F.Paste")
			(net "SPARE4")
		)
		(pad "Y30" smd circle
			(at 11.599926 3.599942)
			(size 0.3556 0.3556)
			(layers "F.Cu" "F.Mask" "F.Paste")
			(net "IOC_GPIO_15")
		)
	)
	(footprint ""
		(layer "F.Cu")
		(at 326.898 -114.3)
		(property "Reference" "PC25"
			(at 0 0 0)
			(layer "F.SilkS")
			(hide yes)
			(effects
				(font
					(size 1.27 1.27)
				)
			)
		)
		(property "Value" "SCD1U25V3KX-GP"
			(at 0 -2.8194 0)
			(unlocked yes)
			(layer "F.Fab")
			(hide yes)
			(effects
				(font
					(size 1.016 1.016)
					(thickness 0.1524)
				)
			)
		)
		(property "Device Type" "C603H36"
			(at 0 -4.3434 0)
			(unlocked yes)
			(layer "F.Fab")
			(hide yes)
			(effects
				(font
					(size 1.016 1.016)
					(thickness 0.1524)
				)
			)
		)
		(duplicate_pad_numbers_are_jumpers no)
		(fp_line
			(start 0.508 0)
			(end -0.508 0)
			(stroke
				(width 0.2032)
				(type default)
			)
			(layer "F.SilkS")
		)
		(fp_rect
			(start -0.5842 1.3335)
			(end 0.5842 -1.3335)
			(stroke
				(width 0)
				(type default)
			)
			(fill no)
			(layer "F.CrtYd")
		)
		(fp_rect
			(start -0.5842 1.3335)
			(end 0.5842 -1.3335)
			(stroke
				(width 0)
				(type default)
			)
			(fill no)
			(layer "F.Fab")
		)
		(pad "1" smd custom
			(at 0 -0.762)
			(size 0.2159 0.2159)
			(layers "F.Cu" "F.Mask" "F.Paste")
			(net "P3V3_STBY_VIN")
			(options
				(clearance outline)
				(anchor circle)
			)
			(primitives
				(gr_poly
					(pts
						(arc
							(start -0.3302 -0.4318)
							(mid -0.402042 -0.402042)
							(end -0.4318 -0.3302)
						)
						(arc
							(start -0.4318 0.3302)
							(mid -0.402042 0.402042)
							(end -0.3302 0.4318)
						)
						(arc
							(start 0.3302 0.4318)
							(mid 0.402042 0.402042)
							(end 0.4318 0.3302)
						)
						(arc
							(start 0.4318 -0.3302)
							(mid 0.402042 -0.402042)
							(end 0.3302 -0.4318)
						)
					)
					(width 0)
					(fill yes)
				)
			)
		)
		(pad "2" smd custom
			(at 0 0.762)
			(size 0.2159 0.2159)
			(layers "F.Cu" "F.Mask" "F.Paste")
			(net "GND")
			(options
				(clearance outline)
				(anchor circle)
			)
			(primitives
				(gr_poly
					(pts
						(arc
							(start -0.3302 -0.4318)
							(mid -0.402042 -0.402042)
							(end -0.4318 -0.3302)
						)
						(arc
							(start -0.4318 0.3302)
							(mid -0.402042 0.402042)
							(end -0.3302 0.4318)
						)
						(arc
							(start 0.3302 0.4318)
							(mid 0.402042 0.402042)
							(end 0.4318 0.3302)
						)
						(arc
							(start 0.4318 -0.3302)
							(mid 0.402042 -0.402042)
							(end 0.3302 -0.4318)
						)
					)
					(width 0)
					(fill yes)
				)
			)
		)
	)
	(footprint ""
		(layer "F.Cu")
		(at 229.743 -20.066)
		(property "Reference" "SR807"
			(at 0 0 0)
			(layer "F.SilkS")
			(hide yes)
			(effects
				(font
					(size 1.27 1.27)
				)
			)
		)
		(property "Value" "0R3J-0-U-GP"
			(at -0.0254 -2.5146 0)
			(unlocked yes)
			(layer "F.Fab")
			(hide yes)
			(effects
				(font
					(size 1.016 1.016)
					(thickness 0.1524)
				)
			)
		)
		(property "Device Type" "R603H22"
			(at -0.0254 -4.0386 0)
			(unlocked yes)
			(layer "F.Fab")
			(hide yes)
			(effects
				(font
					(size 1.016 1.016)
					(thickness 0.1524)
				)
			)
		)
		(duplicate_pad_numbers_are_jumpers no)
		(fp_line
			(start -0.4826 0)
			(end -0.2032 0)
			(stroke
				(width 0.2032)
				(type default)
			)
			(layer "F.SilkS")
		)
		(fp_line
			(start 0.2032 0)
			(end 0.4826 0)
			(stroke
				(width 0.2032)
				(type default)
			)
			(layer "F.SilkS")
		)
		(fp_rect
			(start -0.5842 1.3335)
			(end 0.5842 -1.3335)
			(stroke
				(width 0)
				(type default)
			)
			(fill no)
			(layer "F.CrtYd")
		)
		(fp_rect
			(start -0.5842 1.3335)
			(end 0.5842 -1.3335)
			(stroke
				(width 0)
				(type default)
			)
			(fill no)
			(layer "F.Fab")
		)
		(pad "1" smd custom
			(at 0 -0.762)
			(size 0.2159 0.2159)
			(layers "F.Cu" "F.Mask" "F.Paste")
			(net "P1V8_E")
			(options
				(clearance outline)
				(anchor circle)
			)
			(primitives
				(gr_poly
					(pts
						(arc
							(start -0.3302 -0.4318)
							(mid -0.402042 -0.402042)
							(end -0.4318 -0.3302)
						)
						(arc
							(start -0.4318 0.3302)
							(mid -0.402042 0.402042)
							(end -0.3302 0.4318)
						)
						(arc
							(start 0.3302 0.4318)
							(mid 0.402042 0.402042)
							(end 0.4318 0.3302)
						)
						(arc
							(start 0.4318 -0.3302)
							(mid 0.402042 -0.402042)
							(end 0.3302 -0.4318)
						)
					)
					(width 0)
					(fill yes)
				)
			)
		)
		(pad "2" smd custom
			(at 0 0.762)
			(size 0.2159 0.2159)
			(layers "F.Cu" "F.Mask" "F.Paste")
			(net "3D3V_ICE")
			(options
				(clearance outline)
				(anchor circle)
			)
			(primitives
				(gr_poly
					(pts
						(arc
							(start -0.3302 -0.4318)
							(mid -0.402042 -0.402042)
							(end -0.4318 -0.3302)
						)
						(arc
							(start -0.4318 0.3302)
							(mid -0.402042 0.402042)
							(end -0.3302 0.4318)
						)
						(arc
							(start 0.3302 0.4318)
							(mid 0.402042 0.402042)
							(end 0.4318 0.3302)
						)
						(arc
							(start 0.4318 -0.3302)
							(mid 0.402042 -0.402042)
							(end 0.3302 -0.4318)
						)
					)
					(width 0)
					(fill yes)
				)
			)
		)
	)
	(footprint ""
		(layer "F.Cu")
		(at 261.562596 -53.232812 90)
		(property "Reference" "SR721"
			(at 0 0 90)
			(layer "F.SilkS")
			(hide yes)
			(effects
				(font
					(size 1.27 1.27)
				)
			)
		)
		(property "Value" "4K7R2F-GP"
			(at 0.064008 -3.993896 90)
			(unlocked yes)
			(layer "F.Fab")
			(hide yes)
			(effects
				(font
					(size 1.016 1.016)
					(thickness 0.1524)
				)
			)
		)
		(property "Device Type" "R402H16"
			(at 0.064008 -5.517896 90)
			(unlocked yes)
			(layer "F.Fab")
			(hide yes)
			(effects
				(font
					(size 1.016 1.016)
					(thickness 0.1524)
				)
			)
		)
		(duplicate_pad_numbers_are_jumpers no)
		(fp_line
			(start 0.508 -0.9398)
			(end -0.508 -0.9398)
			(stroke
				(width 0.1524)
				(type default)
			)
			(layer "F.SilkS")
		)
		(fp_line
			(start -0.508 -0.9398)
			(end -0.508 0.9398)
			(stroke
				(width 0.1524)
				(type default)
			)
			(layer "F.SilkS")
		)
		(fp_rect
			(start -0.508 0.9398)
			(end 0.508 -0.9398)
			(stroke
				(width 0)
				(type default)
			)
			(fill no)
			(layer "F.CrtYd")
		)
		(fp_rect
			(start -0.508 0.9398)
			(end 0.508 -0.9398)
			(stroke
				(width 0)
				(type default)
			)
			(fill no)
			(layer "F.Fab")
		)
		(pad "1" smd custom
			(at 0 -0.4445 90)
			(size 0.1397 0.1397)
			(layers "F.Cu" "F.Mask" "F.Paste")
			(net "IOC_EEPROM_A2")
			(options
				(clearance outline)
				(anchor circle)
			)
			(primitives
				(gr_poly
					(pts
						(arc
							(start -0.1778 -0.2794)
							(mid -0.249642 -0.249642)
							(end -0.2794 -0.1778)
						)
						(arc
							(start -0.2794 0.1778)
							(mid -0.249642 0.249642)
							(end -0.1778 0.2794)
						)
						(arc
							(start 0.1778 0.2794)
							(mid 0.249642 0.249642)
							(end 0.2794 0.1778)
						)
						(arc
							(start 0.2794 -0.1778)
							(mid 0.249642 -0.249642)
							(end 0.1778 -0.2794)
						)
					)
					(width 0)
					(fill yes)
				)
			)
		)
		(pad "2" smd custom
			(at 0 0.4445 90)
			(size 0.1397 0.1397)
			(layers "F.Cu" "F.Mask" "F.Paste")
			(net "GND")
			(options
				(clearance outline)
				(anchor circle)
			)
			(primitives
				(gr_poly
					(pts
						(arc
							(start -0.1778 -0.2794)
							(mid -0.249642 -0.249642)
							(end -0.2794 -0.1778)
						)
						(arc
							(start -0.2794 0.1778)
							(mid -0.249642 0.249642)
							(end -0.1778 0.2794)
						)
						(arc
							(start 0.1778 0.2794)
							(mid 0.249642 0.249642)
							(end 0.2794 0.1778)
						)
						(arc
							(start 0.2794 -0.1778)
							(mid 0.249642 -0.249642)
							(end 0.1778 -0.2794)
						)
					)
					(width 0)
					(fill yes)
				)
			)
		)
	)
	(footprint ""
		(layer "F.Cu")
		(at 330.699872 -110.435136 90)
		(property "Reference" "PR28"
			(at 0 0 90)
			(layer "F.SilkS")
			(hide yes)
			(effects
				(font
					(size 1.27 1.27)
				)
			)
		)
		(property "Value" "3D01R5F-GP"
			(at 0 -8.9535 90)
			(unlocked yes)
			(layer "F.Fab")
			(hide yes)
			(effects
				(font
					(size 1.27 1.016)
					(thickness 0.1524)
				)
			)
		)
		(property "Device Type" "R805H24"
			(at 0 -10.6299 90)
			(unlocked yes)
			(layer "F.Fab")
			(hide yes)
			(effects
				(font
					(size 1.27 1.016)
					(thickness 0.1524)
				)
			)
		)
		(duplicate_pad_numbers_are_jumpers no)
		(fp_line
			(start 0.889 -1.7018)
			(end -0.889 -1.7018)
			(stroke
				(width 0.1524)
				(type default)
			)
			(layer "F.SilkS")
		)
		(fp_line
			(start 0.889 -1.7018)
			(end 0.889 -0.381)
			(stroke
				(width 0.1524)
				(type default)
			)
			(layer "F.SilkS")
		)
		(fp_line
			(start -0.889 -1.7018)
			(end -0.889 0.2794)
			(stroke
				(width 0.1524)
				(type default)
			)
			(layer "F.SilkS")
		)
		(fp_line
			(start -0.889 0.0762)
			(end -0.889 1.7018)
			(stroke
				(width 0.1524)
				(type default)
			)
			(layer "F.SilkS")
		)
		(fp_line
			(start 0.889 1.7018)
			(end 0.889 -0.508)
			(stroke
				(width 0.1524)
				(type default)
			)
			(layer "F.SilkS")
		)
		(fp_line
			(start -0.889 1.7018)
			(end 0.889 1.7018)
			(stroke
				(width 0.1524)
				(type default)
			)
			(layer "F.SilkS")
		)
		(fp_poly
			(pts
				(xy 0.9652 -1.778) (xy 0.9652 1.778) (xy -0.9652 1.778) (xy -0.9652 -1.778)
			)
			(stroke
				(width 0)
				(type default)
			)
			(fill no)
			(layer "F.CrtYd")
		)
		(fp_rect
			(start -0.9652 1.778)
			(end 0.9652 -1.778)
			(stroke
				(width 0)
				(type default)
			)
			(fill no)
			(layer "F.Fab")
		)
		(pad "1" smd rect
			(at 0 -0.9652 90)
			(size 1.397 1.143)
			(layers "F.Cu" "F.Mask" "F.Paste")
			(net "P3V3_STBY_SNB")
		)
		(pad "2" smd rect
			(at 0 0.9652 90)
			(size 1.397 1.143)
			(layers "F.Cu" "F.Mask" "F.Paste")
			(net "GND")
		)
	)
	(footprint ""
		(layer "F.Cu")
		(at 308.102 -160.655)
		(property "Reference" "R470"
			(at 0 0 0)
			(layer "F.SilkS")
			(hide yes)
			(effects
				(font
					(size 1.27 1.27)
				)
			)
		)
		(property "Value" "0R2J-2-GP"
			(at 0.064008 -3.993896 0)
			(unlocked yes)
			(layer "F.Fab")
			(hide yes)
			(effects
				(font
					(size 1.016 1.016)
					(thickness 0.1524)
				)
			)
		)
		(property "Device Type" "R402H16"
			(at 0.064008 -5.517896 0)
			(unlocked yes)
			(layer "F.Fab")
			(hide yes)
			(effects
				(font
					(size 1.016 1.016)
					(thickness 0.1524)
				)
			)
		)
		(duplicate_pad_numbers_are_jumpers no)
		(fp_line
			(start -0.508 -0.9398)
			(end -0.508 0.9398)
			(stroke
				(width 0.1524)
				(type default)
			)
			(layer "F.SilkS")
		)
		(fp_line
			(start 0.508 -0.9398)
			(end -0.508 -0.9398)
			(stroke
				(width 0.1524)
				(type default)
			)
			(layer "F.SilkS")
		)
		(fp_rect
			(start -0.508 0.9398)
			(end 0.508 -0.9398)
			(stroke
				(width 0)
				(type default)
			)
			(fill no)
			(layer "F.CrtYd")
		)
		(fp_rect
			(start -0.508 0.9398)
			(end 0.508 -0.9398)
			(stroke
				(width 0)
				(type default)
			)
			(fill no)
			(layer "F.Fab")
		)
		(pad "1" smd custom
			(at 0 -0.4445)
			(size 0.1397 0.1397)
			(layers "F.Cu" "F.Mask" "F.Paste")
			(net "BMC0_SMB10_DAT")
			(options
				(clearance outline)
				(anchor circle)
			)
			(primitives
				(gr_poly
					(pts
						(arc
							(start -0.1778 -0.2794)
							(mid -0.249642 -0.249642)
							(end -0.2794 -0.1778)
						)
						(arc
							(start -0.2794 0.1778)
							(mid -0.249642 0.249642)
							(end -0.1778 0.2794)
						)
						(arc
							(start 0.1778 0.2794)
							(mid 0.249642 0.249642)
							(end 0.2794 0.1778)
						)
						(arc
							(start 0.2794 -0.1778)
							(mid 0.249642 -0.249642)
							(end 0.1778 -0.2794)
						)
					)
					(width 0)
					(fill yes)
				)
			)
		)
		(pad "2" smd custom
			(at 0 0.4445)
			(size 0.1397 0.1397)
			(layers "F.Cu" "F.Mask" "F.Paste")
			(net "BMC_I2C_SDA_10")
			(options
				(clearance outline)
				(anchor circle)
			)
			(primitives
				(gr_poly
					(pts
						(arc
							(start -0.1778 -0.2794)
							(mid -0.249642 -0.249642)
							(end -0.2794 -0.1778)
						)
						(arc
							(start -0.2794 0.1778)
							(mid -0.249642 0.249642)
							(end -0.1778 0.2794)
						)
						(arc
							(start 0.1778 0.2794)
							(mid 0.249642 0.249642)
							(end 0.2794 0.1778)
						)
						(arc
							(start 0.2794 -0.1778)
							(mid 0.249642 -0.249642)
							(end 0.1778 -0.2794)
						)
					)
					(width 0)
					(fill yes)
				)
			)
		)
	)
	(footprint ""
		(layer "F.Cu")
		(at 152.247092 -98.200464 -90)
		(property "Reference" "SL15"
			(at 0 0 270)
			(layer "F.SilkS")
			(hide yes)
			(effects
				(font
					(size 1.27 1.27)
				)
			)
		)
		(property "Value" "MPZ2012S300AT-GP"
			(at 0 -4.2418 270)
			(unlocked yes)
			(layer "F.Fab")
			(hide yes)
			(effects
				(font
					(size 1.016 1.016)
					(thickness 0.1524)
				)
			)
		)
		(property "Device Type" "L805H42"
			(at 0 -5.7912 270)
			(unlocked yes)
			(layer "F.Fab")
			(hide yes)
			(effects
				(font
					(size 1.016 1.016)
					(thickness 0.1524)
				)
			)
		)
		(duplicate_pad_numbers_are_jumpers no)
		(fp_line
			(start -0.889 1.7018)
			(end -0.889 -1.7018)
			(stroke
				(width 0.1524)
				(type default)
			)
			(layer "F.SilkS")
		)
		(fp_line
			(start 0.889 1.7018)
			(end -0.889 1.7018)
			(stroke
				(width 0.1524)
				(type default)
			)
			(layer "F.SilkS")
		)
		(fp_line
			(start -0.889 -1.7018)
			(end 0.889 -1.7018)
			(stroke
				(width 0.1524)
				(type default)
			)
			(layer "F.SilkS")
		)
		(fp_line
			(start 0.889 -1.7018)
			(end 0.889 1.7018)
			(stroke
				(width 0.1524)
				(type default)
			)
			(layer "F.SilkS")
		)
		(fp_rect
			(start -0.9652 1.778)
			(end 0.9652 -1.778)
			(stroke
				(width 0)
				(type default)
			)
			(fill no)
			(layer "F.CrtYd")
		)
		(fp_rect
			(start -0.9652 1.778)
			(end 0.9652 -1.778)
			(stroke
				(width 0)
				(type default)
			)
			(fill no)
			(layer "F.Fab")
		)
		(pad "1" smd rect
			(at 0 -0.9652 270)
			(size 1.397 1.143)
			(layers "F.Cu" "F.Mask" "F.Paste")
			(net "P0V9_E")
		)
		(pad "2" smd rect
			(at 0 0.9652 270)
			(size 1.397 1.143)
			(layers "F.Cu" "F.Mask" "F.Paste")
			(net "GB_VDDA")
		)
	)
	(footprint ""
		(layer "F.Cu")
		(at 225.933 -14.351 90)
		(property "Reference" "Q13"
			(at 0 0 90)
			(layer "F.SilkS")
			(hide yes)
			(effects
				(font
					(size 1.27 1.27)
				)
			)
		)
		(property "Value" "2N7002A-7-GP"
			(at 0.127 -8.9662 90)
			(unlocked yes)
			(layer "F.Fab")
			(hide yes)
			(effects
				(font
					(size 1.016 1.016)
					(thickness 0.1524)
				)
			)
		)
		(property "Device Type" "SOT23DGS2D4H48"
			(at 0.127 -10.4902 90)
			(unlocked yes)
			(layer "F.Fab")
			(hide yes)
			(effects
				(font
					(size 1.016 1.016)
					(thickness 0.1524)
				)
			)
		)
		(duplicate_pad_numbers_are_jumpers no)
		(fp_line
			(start 1.651 -1.778)
			(end -1.651 -1.778)
			(stroke
				(width 0.1524)
				(type default)
			)
			(layer "F.SilkS")
		)
		(fp_line
			(start -1.651 -1.778)
			(end -1.651 1.778)
			(stroke
				(width 0.1524)
				(type default)
			)
			(layer "F.SilkS")
		)
		(fp_line
			(start 1.651 1.778)
			(end 1.651 -1.778)
			(stroke
				(width 0.1524)
				(type default)
			)
			(layer "F.SilkS")
		)
		(fp_line
			(start -1.651 1.778)
			(end 1.651 1.778)
			(stroke
				(width 0.1524)
				(type default)
			)
			(layer "F.SilkS")
		)
		(fp_poly
			(pts
				(xy -1.778 1.8796) (xy -1.778 -1.8796) (xy 1.778 -1.8796) (xy 1.778 1.8796)
			)
			(stroke
				(width 0)
				(type default)
			)
			(fill no)
			(layer "F.CrtYd")
		)
		(fp_poly
			(pts
				(xy -1.778 1.8796) (xy -1.778 -1.8796) (xy 1.778 -1.8796) (xy 1.778 1.8796)
			)
			(stroke
				(width 0)
				(type default)
			)
			(fill no)
			(layer "F.Fab")
		)
		(pad "D" smd custom
			(at 0 -0.9525 90)
			(size 0.1905 0.1905)
			(layers "F.Cu" "F.Mask" "F.Paste")
			(net "ENCLO_LED_RED_D1")
			(options
				(clearance outline)
				(anchor circle)
			)
			(primitives
				(gr_poly
					(pts
						(arc
							(start -0.1778 0.5715)
							(mid -0.321484 0.511984)
							(end -0.381 0.3683)
						)
						(arc
							(start -0.381 -0.3683)
							(mid -0.321484 -0.511984)
							(end -0.1778 -0.5715)
						)
						(arc
							(start 0.1778 -0.5715)
							(mid 0.321484 -0.511984)
							(end 0.381 -0.3683)
						)
						(arc
							(start 0.381 0.3683)
							(mid 0.321484 0.511984)
							(end 0.1778 0.5715)
						)
					)
					(width 0)
					(fill yes)
				)
			)
		)
		(pad "G" smd custom
			(at -0.98425 0.9525 90)
			(size 0.1905 0.1905)
			(layers "F.Cu" "F.Mask" "F.Paste")
			(net "ENCLO_LED_RED_D")
			(options
				(clearance outline)
				(anchor circle)
			)
			(primitives
				(gr_poly
					(pts
						(arc
							(start -0.1778 0.5715)
							(mid -0.321484 0.511984)
							(end -0.381 0.3683)
						)
						(arc
							(start -0.381 -0.3683)
							(mid -0.321484 -0.511984)
							(end -0.1778 -0.5715)
						)
						(arc
							(start 0.1778 -0.5715)
							(mid 0.321484 -0.511984)
							(end 0.381 -0.3683)
						)
						(arc
							(start 0.381 0.3683)
							(mid 0.321484 0.511984)
							(end 0.1778 0.5715)
						)
					)
					(width 0)
					(fill yes)
				)
			)
		)
		(pad "S" smd custom
			(at 0.98425 0.9525 90)
			(size 0.1905 0.1905)
			(layers "F.Cu" "F.Mask" "F.Paste")
			(net "GND")
			(options
				(clearance outline)
				(anchor circle)
			)
			(primitives
				(gr_poly
					(pts
						(arc
							(start -0.1778 0.5715)
							(mid -0.321484 0.511984)
							(end -0.381 0.3683)
						)
						(arc
							(start -0.381 -0.3683)
							(mid -0.321484 -0.511984)
							(end -0.1778 -0.5715)
						)
						(arc
							(start 0.1778 -0.5715)
							(mid 0.321484 -0.511984)
							(end 0.381 -0.3683)
						)
						(arc
							(start 0.381 0.3683)
							(mid 0.321484 0.511984)
							(end 0.1778 0.5715)
						)
					)
					(width 0)
					(fill yes)
				)
			)
		)
	)
	(footprint ""
		(layer "F.Cu")
		(at 266.065 -178.054 90)
		(property "Reference" "R345"
			(at 0 0 90)
			(layer "F.SilkS")
			(hide yes)
			(effects
				(font
					(size 1.27 1.27)
				)
			)
		)
		(property "Value" "3K3R2F-2-GP"
			(at 0.064008 -3.993896 90)
			(unlocked yes)
			(layer "F.Fab")
			(hide yes)
			(effects
				(font
					(size 1.016 1.016)
					(thickness 0.1524)
				)
			)
		)
		(property "Device Type" "R402H16"
			(at 0.064008 -5.517896 90)
			(unlocked yes)
			(layer "F.Fab")
			(hide yes)
			(effects
				(font
					(size 1.016 1.016)
					(thickness 0.1524)
				)
			)
		)
		(duplicate_pad_numbers_are_jumpers no)
		(fp_line
			(start 0.508 -0.9398)
			(end -0.508 -0.9398)
			(stroke
				(width 0.1524)
				(type default)
			)
			(layer "F.SilkS")
		)
		(fp_line
			(start -0.508 -0.9398)
			(end -0.508 0.9398)
			(stroke
				(width 0.1524)
				(type default)
			)
			(layer "F.SilkS")
		)
		(fp_rect
			(start -0.508 0.9398)
			(end 0.508 -0.9398)
			(stroke
				(width 0)
				(type default)
			)
			(fill no)
			(layer "F.CrtYd")
		)
		(fp_rect
			(start -0.508 0.9398)
			(end 0.508 -0.9398)
			(stroke
				(width 0)
				(type default)
			)
			(fill no)
			(layer "F.Fab")
		)
		(pad "1" smd custom
			(at 0 -0.4445 90)
			(size 0.1397 0.1397)
			(layers "F.Cu" "F.Mask" "F.Paste")
			(net "P3V3_STBY")
			(options
				(clearance outline)
				(anchor circle)
			)
			(primitives
				(gr_poly
					(pts
						(arc
							(start -0.1778 -0.2794)
							(mid -0.249642 -0.249642)
							(end -0.2794 -0.1778)
						)
						(arc
							(start -0.2794 0.1778)
							(mid -0.249642 0.249642)
							(end -0.1778 0.2794)
						)
						(arc
							(start 0.1778 0.2794)
							(mid 0.249642 0.249642)
							(end 0.2794 0.1778)
						)
						(arc
							(start 0.2794 -0.1778)
							(mid 0.249642 -0.249642)
							(end 0.1778 -0.2794)
						)
					)
					(width 0)
					(fill yes)
				)
			)
		)
		(pad "2" smd custom
			(at 0 0.4445 90)
			(size 0.1397 0.1397)
			(layers "F.Cu" "F.Mask" "F.Paste")
			(net "ROMA17")
			(options
				(clearance outline)
				(anchor circle)
			)
			(primitives
				(gr_poly
					(pts
						(arc
							(start -0.1778 -0.2794)
							(mid -0.249642 -0.249642)
							(end -0.2794 -0.1778)
						)
						(arc
							(start -0.2794 0.1778)
							(mid -0.249642 0.249642)
							(end -0.1778 0.2794)
						)
						(arc
							(start 0.1778 0.2794)
							(mid 0.249642 0.249642)
							(end 0.2794 0.1778)
						)
						(arc
							(start 0.2794 -0.1778)
							(mid 0.249642 -0.249642)
							(end 0.1778 -0.2794)
						)
					)
					(width 0)
					(fill yes)
				)
			)
		)
	)
	(footprint ""
		(layer "F.Cu")
		(at 338.357718 -157.584648)
		(property "Reference" "R222"
			(at 0 0 0)
			(layer "F.SilkS")
			(hide yes)
			(effects
				(font
					(size 1.27 1.27)
				)
			)
		)
		(property "Value" "4K7R2F-GP"
			(at 0.064008 -3.993896 0)
			(unlocked yes)
			(layer "F.Fab")
			(hide yes)
			(effects
				(font
					(size 1.016 1.016)
					(thickness 0.1524)
				)
			)
		)
		(property "Device Type" "R402H16"
			(at 0.064008 -5.517896 0)
			(unlocked yes)
			(layer "F.Fab")
			(hide yes)
			(effects
				(font
					(size 1.016 1.016)
					(thickness 0.1524)
				)
			)
		)
		(duplicate_pad_numbers_are_jumpers no)
		(fp_line
			(start -0.508 -0.9398)
			(end -0.508 0.9398)
			(stroke
				(width 0.1524)
				(type default)
			)
			(layer "F.SilkS")
		)
		(fp_line
			(start 0.508 -0.9398)
			(end -0.508 -0.9398)
			(stroke
				(width 0.1524)
				(type default)
			)
			(layer "F.SilkS")
		)
		(fp_rect
			(start -0.508 0.9398)
			(end 0.508 -0.9398)
			(stroke
				(width 0)
				(type default)
			)
			(fill no)
			(layer "F.CrtYd")
		)
		(fp_rect
			(start -0.508 0.9398)
			(end 0.508 -0.9398)
			(stroke
				(width 0)
				(type default)
			)
			(fill no)
			(layer "F.Fab")
		)
		(pad "1" smd custom
			(at 0 -0.4445)
			(size 0.1397 0.1397)
			(layers "F.Cu" "F.Mask" "F.Paste")
			(net "P3V3_STBY")
			(options
				(clearance outline)
				(anchor circle)
			)
			(primitives
				(gr_poly
					(pts
						(arc
							(start -0.1778 -0.2794)
							(mid -0.249642 -0.249642)
							(end -0.2794 -0.1778)
						)
						(arc
							(start -0.2794 0.1778)
							(mid -0.249642 0.249642)
							(end -0.1778 0.2794)
						)
						(arc
							(start 0.1778 0.2794)
							(mid 0.249642 0.249642)
							(end 0.2794 0.1778)
						)
						(arc
							(start 0.2794 -0.1778)
							(mid 0.249642 -0.249642)
							(end 0.1778 -0.2794)
						)
					)
					(width 0)
					(fill yes)
				)
			)
		)
		(pad "2" smd custom
			(at 0 0.4445)
			(size 0.1397 0.1397)
			(layers "F.Cu" "F.Mask" "F.Paste")
			(net "USB_OCS_N2")
			(options
				(clearance outline)
				(anchor circle)
			)
			(primitives
				(gr_poly
					(pts
						(arc
							(start -0.1778 -0.2794)
							(mid -0.249642 -0.249642)
							(end -0.2794 -0.1778)
						)
						(arc
							(start -0.2794 0.1778)
							(mid -0.249642 0.249642)
							(end -0.1778 0.2794)
						)
						(arc
							(start 0.1778 0.2794)
							(mid 0.249642 0.249642)
							(end 0.2794 0.1778)
						)
						(arc
							(start 0.2794 -0.1778)
							(mid 0.249642 -0.249642)
							(end 0.1778 -0.2794)
						)
					)
					(width 0)
					(fill yes)
				)
			)
		)
	)
	(footprint ""
		(layer "F.Cu")
		(at 257.483864 -229.226872 90)
		(property "Reference" "R457"
			(at 0 0 90)
			(layer "F.SilkS")
			(hide yes)
			(effects
				(font
					(size 1.27 1.27)
				)
			)
		)
		(property "Value" "4K75R2F-1-GP"
			(at 0.064008 -3.993896 90)
			(unlocked yes)
			(layer "F.Fab")
			(hide yes)
			(effects
				(font
					(size 1.016 1.016)
					(thickness 0.1524)
				)
			)
		)
		(property "Device Type" "R402H16"
			(at 0.064008 -5.517896 90)
			(unlocked yes)
			(layer "F.Fab")
			(hide yes)
			(effects
				(font
					(size 1.016 1.016)
					(thickness 0.1524)
				)
			)
		)
		(duplicate_pad_numbers_are_jumpers no)
		(fp_line
			(start 0.508 -0.9398)
			(end -0.508 -0.9398)
			(stroke
				(width 0.1524)
				(type default)
			)
			(layer "F.SilkS")
		)
		(fp_line
			(start -0.508 -0.9398)
			(end -0.508 0.9398)
			(stroke
				(width 0.1524)
				(type default)
			)
			(layer "F.SilkS")
		)
		(fp_rect
			(start -0.508 0.9398)
			(end 0.508 -0.9398)
			(stroke
				(width 0)
				(type default)
			)
			(fill no)
			(layer "F.CrtYd")
		)
		(fp_rect
			(start -0.508 0.9398)
			(end 0.508 -0.9398)
			(stroke
				(width 0)
				(type default)
			)
			(fill no)
			(layer "F.Fab")
		)
		(pad "1" smd custom
			(at 0 -0.4445 90)
			(size 0.1397 0.1397)
			(layers "F.Cu" "F.Mask" "F.Paste")
			(net "P3V3_STBY")
			(options
				(clearance outline)
				(anchor circle)
			)
			(primitives
				(gr_poly
					(pts
						(arc
							(start -0.1778 -0.2794)
							(mid -0.249642 -0.249642)
							(end -0.2794 -0.1778)
						)
						(arc
							(start -0.2794 0.1778)
							(mid -0.249642 0.249642)
							(end -0.1778 0.2794)
						)
						(arc
							(start 0.1778 0.2794)
							(mid 0.249642 0.249642)
							(end 0.2794 0.1778)
						)
						(arc
							(start 0.2794 -0.1778)
							(mid 0.249642 -0.249642)
							(end 0.1778 -0.2794)
						)
					)
					(width 0)
					(fill yes)
				)
			)
		)
		(pad "2" smd custom
			(at 0 0.4445 90)
			(size 0.1397 0.1397)
			(layers "F.Cu" "F.Mask" "F.Paste")
			(net "TPS74801_1V26_STBY_EN")
			(options
				(clearance outline)
				(anchor circle)
			)
			(primitives
				(gr_poly
					(pts
						(arc
							(start -0.1778 -0.2794)
							(mid -0.249642 -0.249642)
							(end -0.2794 -0.1778)
						)
						(arc
							(start -0.2794 0.1778)
							(mid -0.249642 0.249642)
							(end -0.1778 0.2794)
						)
						(arc
							(start 0.1778 0.2794)
							(mid 0.249642 0.249642)
							(end 0.2794 0.1778)
						)
						(arc
							(start 0.2794 -0.1778)
							(mid 0.249642 -0.249642)
							(end 0.1778 -0.2794)
						)
					)
					(width 0)
					(fill yes)
				)
			)
		)
	)
	(footprint ""
		(layer "F.Cu")
		(at 323.85 -171.323 90)
		(property "Reference" "R412"
			(at 0 0 90)
			(layer "F.SilkS")
			(hide yes)
			(effects
				(font
					(size 1.27 1.27)
				)
			)
		)
		(property "Value" "0R2J-2-GP"
			(at 0.064008 -3.993896 90)
			(unlocked yes)
			(layer "F.Fab")
			(hide yes)
			(effects
				(font
					(size 1.016 1.016)
					(thickness 0.1524)
				)
			)
		)
		(property "Device Type" "R402H16"
			(at 0.064008 -5.517896 90)
			(unlocked yes)
			(layer "F.Fab")
			(hide yes)
			(effects
				(font
					(size 1.016 1.016)
					(thickness 0.1524)
				)
			)
		)
		(duplicate_pad_numbers_are_jumpers no)
		(fp_line
			(start 0.508 -0.9398)
			(end -0.508 -0.9398)
			(stroke
				(width 0.1524)
				(type default)
			)
			(layer "F.SilkS")
		)
		(fp_line
			(start -0.508 -0.9398)
			(end -0.508 0.9398)
			(stroke
				(width 0.1524)
				(type default)
			)
			(layer "F.SilkS")
		)
		(fp_rect
			(start -0.508 0.9398)
			(end 0.508 -0.9398)
			(stroke
				(width 0)
				(type default)
			)
			(fill no)
			(layer "F.CrtYd")
		)
		(fp_rect
			(start -0.508 0.9398)
			(end 0.508 -0.9398)
			(stroke
				(width 0)
				(type default)
			)
			(fill no)
			(layer "F.Fab")
		)
		(pad "1" smd custom
			(at 0 -0.4445 90)
			(size 0.1397 0.1397)
			(layers "F.Cu" "F.Mask" "F.Paste")
			(net "EXP_SMART_RX")
			(options
				(clearance outline)
				(anchor circle)
			)
			(primitives
				(gr_poly
					(pts
						(arc
							(start -0.1778 -0.2794)
							(mid -0.249642 -0.249642)
							(end -0.2794 -0.1778)
						)
						(arc
							(start -0.2794 0.1778)
							(mid -0.249642 0.249642)
							(end -0.1778 0.2794)
						)
						(arc
							(start 0.1778 0.2794)
							(mid 0.249642 0.249642)
							(end 0.2794 0.1778)
						)
						(arc
							(start 0.2794 -0.1778)
							(mid 0.249642 -0.249642)
							(end 0.1778 -0.2794)
						)
					)
					(width 0)
					(fill yes)
				)
			)
		)
		(pad "2" smd custom
			(at 0 0.4445 90)
			(size 0.1397 0.1397)
			(layers "F.Cu" "F.Mask" "F.Paste")
			(net "EXP_UART_RX_R")
			(options
				(clearance outline)
				(anchor circle)
			)
			(primitives
				(gr_poly
					(pts
						(arc
							(start -0.1778 -0.2794)
							(mid -0.249642 -0.249642)
							(end -0.2794 -0.1778)
						)
						(arc
							(start -0.2794 0.1778)
							(mid -0.249642 0.249642)
							(end -0.1778 0.2794)
						)
						(arc
							(start 0.1778 0.2794)
							(mid 0.249642 0.249642)
							(end 0.2794 0.1778)
						)
						(arc
							(start 0.2794 -0.1778)
							(mid 0.249642 -0.249642)
							(end 0.1778 -0.2794)
						)
					)
					(width 0)
					(fill yes)
				)
			)
		)
	)
	(footprint ""
		(layer "F.Cu")
		(at 326.600058 -1.800098)
		(property "Reference" "SW20"
			(at 0 0 0)
			(layer "F.SilkS")
			(hide yes)
			(effects
				(font
					(size 1.27 1.27)
				)
			)
		)
		(property "Value" "SW-SLIDE74-GP"
			(at -4.272534 -5.45465 0)
			(unlocked yes)
			(layer "F.Fab")
			(hide yes)
			(effects
				(font
					(size 1.016 1.016)
					(thickness 0.1524)
				)
			)
		)
		(property "Device Type" "LSSM12-P-V-TR"
			(at -4.272534 -6.97865 0)
			(unlocked yes)
			(layer "F.Fab")
			(hide yes)
			(effects
				(font
					(size 1.016 1.016)
					(thickness 0.1524)
				)
			)
		)
		(duplicate_pad_numbers_are_jumpers no)
		(fp_line
			(start -5.0038 -2.0066)
			(end -3.3528 -2.0066)
			(stroke
				(width 0.1524)
				(type default)
			)
			(layer "F.SilkS")
		)
		(fp_line
			(start -5.0038 2.2098)
			(end -5.0038 -2.0066)
			(stroke
				(width 0.1524)
				(type default)
			)
			(layer "F.SilkS")
		)
		(fp_line
			(start -3.3528 -4.2418)
			(end 3.3528 -4.2418)
			(stroke
				(width 0.1524)
				(type default)
			)
			(layer "F.SilkS")
		)
		(fp_line
			(start -3.3528 -2.0066)
			(end -3.3528 -4.2418)
			(stroke
				(width 0.1524)
				(type default)
			)
			(layer "F.SilkS")
		)
		(fp_line
			(start -2.2987 -4.3688)
			(end -2.6797 -4.3688)
			(stroke
				(width 0.3302)
				(type default)
			)
			(layer "F.SilkS")
		)
		(fp_line
			(start -2.0066 2.2098)
			(end -5.0038 2.2098)
			(stroke
				(width 0.1524)
				(type default)
			)
			(layer "F.SilkS")
		)
		(fp_line
			(start -2.0066 4.0132)
			(end -2.0066 2.2098)
			(stroke
				(width 0.1524)
				(type default)
			)
			(layer "F.SilkS")
		)
		(fp_line
			(start 2.0066 2.2098)
			(end 2.0066 4.0132)
			(stroke
				(width 0.1524)
				(type default)
			)
			(layer "F.SilkS")
		)
		(fp_line
			(start 2.0066 4.0132)
			(end -2.0066 4.0132)
			(stroke
				(width 0.1524)
				(type default)
			)
			(layer "F.SilkS")
		)
		(fp_line
			(start 3.3528 -4.2418)
			(end 3.3528 -2.0066)
			(stroke
				(width 0.1524)
				(type default)
			)
			(layer "F.SilkS")
		)
		(fp_line
			(start 3.3528 -2.0066)
			(end 5.0038 -2.0066)
			(stroke
				(width 0.1524)
				(type default)
			)
			(layer "F.SilkS")
		)
		(fp_line
			(start 5.0038 -2.0066)
			(end 5.0038 2.2098)
			(stroke
				(width 0.1524)
				(type default)
			)
			(layer "F.SilkS")
		)
		(fp_line
			(start 5.0038 2.2098)
			(end 2.0066 2.2098)
			(stroke
				(width 0.1524)
				(type default)
			)
			(layer "F.SilkS")
		)
		(fp_poly
			(pts
				(xy -2.500122 -4.318) (xy -3.008122 -4.826) (xy -1.992122 -4.826)
			)
			(stroke
				(width 0)
				(type default)
			)
			(fill yes)
			(layer "F.SilkS")
		)
		(fp_poly
			(pts
				(xy -1.7526 3.7592) (xy -1.7526 1.9558) (xy -4.7498 1.9558) (xy -4.7498 -1.7526) (xy -2.794 -1.7526)
				(xy -2.794 -3.7592) (xy 2.794 -3.7592) (xy 2.794 -1.7526) (xy 4.7498 -1.7526) (xy 4.7498 1.9558)
				(xy 1.7526 1.9558) (xy 1.7526 3.7592)
			)
			(stroke
				(width 0)
				(type default)
			)
			(fill no)
			(layer "F.CrtYd")
		)
		(fp_poly
			(pts
				(xy -2.2606 4.2672) (xy -2.2606 2.4638) (xy -5.2578 2.4638) (xy -5.2578 -0.1524) (xy -4.7498 -0.1524)
				(xy -4.7498 1.9558) (xy -1.7526 1.9558) (xy -1.7526 3.7592) (xy 1.7526 3.7592) (xy 1.7526 1.9558)
				(xy 4.7498 1.9558) (xy 4.7498 -1.7526) (xy 2.794 -1.7526) (xy 2.794 -3.7592) (xy -2.794 -3.7592)
				(xy -2.794 -1.7526) (xy -4.7498 -1.7526) (xy -4.7498 -0.15748) (xy -5.2578 -0.15748) (xy -5.2578 -2.2606)
				(xy -3.6068 -2.2606) (xy -3.6068 -4.4958) (xy 3.6068 -4.4958) (xy 3.6068 -2.2606) (xy 5.2578 -2.2606)
				(xy 5.2578 2.4638) (xy 2.2606 2.4638) (xy 2.2606 4.2672)
			)
			(stroke
				(width 0)
				(type default)
			)
			(fill no)
			(layer "F.CrtYd")
		)
		(fp_poly
			(pts
				(xy -2.2606 4.2672) (xy -2.2606 2.4638) (xy -5.2578 2.4638) (xy -5.2578 -2.2606) (xy -3.6068 -2.2606)
				(xy -3.6068 -4.4958) (xy 3.6068 -4.4958) (xy 3.6068 -2.2606) (xy 5.2578 -2.2606) (xy 5.2578 2.4638)
				(xy 2.2606 2.4638) (xy 2.2606 4.2672)
			)
			(stroke
				(width 0)
				(type default)
			)
			(fill no)
			(layer "F.Fab")
		)
		(pad "" np_thru_hole circle
			(at -3.400044 0)
			(size 0.254 0.254)
			(drill 0.9652)
			(layers "*.Cu" "*.Mask")
			(clearance 0.7112)
			(thermal_gap 0.7112)
		)
		(pad "" np_thru_hole circle
			(at 3.400044 0)
			(size 0.254 0.254)
			(drill 0.9652)
			(layers "*.Cu" "*.Mask")
			(clearance 0.7112)
			(thermal_gap 0.7112)
		)
		(pad "1" smd rect
			(at -2.500122 -2.750058)
			(size 1.1938 2.4892)
			(layers "F.Cu" "F.Mask" "F.Paste")
			(net "DEBUG_LED_SW_H")
		)
		(pad "2" smd rect
			(at 0 -2.750058)
			(size 1.1938 2.4892)
			(layers "F.Cu" "F.Mask" "F.Paste")
			(net "DEBUG_LED_SW")
		)
		(pad "3" smd rect
			(at 2.500122 -2.750058)
			(size 1.1938 2.4892)
			(layers "F.Cu" "F.Mask" "F.Paste")
			(net "DEBUG_PORT_GND")
		)
		(zone
			(layers "F.Cu" "B.Cu" "In1.Cu" "In2.Cu" "In3.Cu" "In4.Cu" "In5.Cu" "In6.Cu")
			(hatch none 0.5)
			(connect_pads
				(clearance 0)
			)
			(min_thickness 0.25)
			(keepout
				(tracks not_allowed)
				(vias allowed)
				(pads allowed)
				(copperpour not_allowed)
				(footprints allowed)
			)
			(placement
				(enabled no)
				(sheetname "")
			)
			(fill
				(thermal_gap 0.5)
				(thermal_bridge_width 0.5)
				(island_removal_mode 0)
			)
			(polygon
				(pts
					(arc
						(start 323.987414 -1.800098)
						(mid 322.412614 -1.800098)
						(end 323.987414 -1.800098)
					)
				)
			)
		)
		(zone
			(layers "F.Cu" "B.Cu" "In1.Cu" "In2.Cu" "In3.Cu" "In4.Cu" "In5.Cu" "In6.Cu")
			(hatch none 0.5)
			(connect_pads
				(clearance 0)
			)
			(min_thickness 0.25)
			(keepout
				(tracks not_allowed)
				(vias allowed)
				(pads allowed)
				(copperpour not_allowed)
				(footprints allowed)
			)
			(placement
				(enabled no)
				(sheetname "")
			)
			(fill
				(thermal_gap 0.5)
				(thermal_bridge_width 0.5)
				(island_removal_mode 0)
			)
			(polygon
				(pts
					(arc
						(start 330.787502 -1.800098)
						(mid 329.212702 -1.800098)
						(end 330.787502 -1.800098)
					)
				)
			)
		)
	)
	(footprint ""
		(layer "F.Cu")
		(at 78.867 -4.572 180)
		(property "Reference" "PL10"
			(at 0 0 180)
			(layer "F.SilkS")
			(hide yes)
			(effects
				(font
					(size 1.27 1.27)
				)
			)
		)
		(property "Value" "BLM41PG600-GP"
			(at -3.690874 -7.441184 180)
			(unlocked yes)
			(layer "F.Fab")
			(hide yes)
			(effects
				(font
					(size 1.016 1.016)
					(thickness 0.1524)
				)
			)
		)
		(property "Device Type" "L451616H71"
			(at -3.690874 -5.917184 180)
			(unlocked yes)
			(layer "F.Fab")
			(hide yes)
			(effects
				(font
					(size 1.016 1.016)
					(thickness 0.1524)
				)
			)
		)
		(duplicate_pad_numbers_are_jumpers no)
		(fp_line
			(start 2.8702 1.2954)
			(end 2.8702 -1.2954)
			(stroke
				(width 0.1524)
				(type default)
			)
			(layer "F.SilkS")
		)
		(fp_line
			(start 2.8702 1.2954)
			(end 2.8702 -1.2954)
			(stroke
				(width 0.1524)
				(type default)
			)
			(layer "F.SilkS")
		)
		(fp_line
			(start 2.8702 -1.2954)
			(end -2.8702 -1.2954)
			(stroke
				(width 0.1524)
				(type default)
			)
			(layer "F.SilkS")
		)
		(fp_line
			(start 2.8702 -1.2954)
			(end -2.8702 -1.2954)
			(stroke
				(width 0.1524)
				(type default)
			)
			(layer "F.SilkS")
		)
		(fp_line
			(start -2.8702 1.2954)
			(end 2.8702 1.2954)
			(stroke
				(width 0.1524)
				(type default)
			)
			(layer "F.SilkS")
		)
		(fp_line
			(start -2.8702 1.2954)
			(end 2.8702 1.2954)
			(stroke
				(width 0.1524)
				(type default)
			)
			(layer "F.SilkS")
		)
		(fp_line
			(start -2.8702 -1.2954)
			(end -2.8702 1.2954)
			(stroke
				(width 0.1524)
				(type default)
			)
			(layer "F.SilkS")
		)
		(fp_line
			(start -2.8702 -1.2954)
			(end -2.8702 1.2954)
			(stroke
				(width 0.1524)
				(type default)
			)
			(layer "F.SilkS")
		)
		(fp_poly
			(pts
				(xy -2.8702 1.2954) (xy 2.8702 1.2954) (xy 2.8702 -1.2954) (xy -2.8702 -1.2954)
			)
			(stroke
				(width 0)
				(type default)
			)
			(fill no)
			(layer "F.CrtYd")
		)
		(fp_poly
			(pts
				(xy -2.8702 1.2954) (xy 2.8702 1.2954) (xy 2.8702 -1.2954) (xy -2.8702 -1.2954)
			)
			(stroke
				(width 0)
				(type default)
			)
			(fill no)
			(layer "F.Fab")
		)
		(pad "1" smd rect
			(at -1.9685 0 180)
			(size 1.3716 1.8796)
			(layers "F.Cu" "F.Mask" "F.Paste")
			(net "P12V")
		)
		(pad "2" smd rect
			(at 1.9685 0 180)
			(size 1.3716 1.8796)
			(layers "F.Cu" "F.Mask" "F.Paste")
			(net "VT235_VDDH")
		)
	)
	(footprint ""
		(layer "F.Cu")
		(at 113.24717 -78.5368)
		(property "Reference" "STP70"
			(at 0 0 0)
			(layer "F.SilkS")
			(hide yes)
			(effects
				(font
					(size 1.27 1.27)
				)
			)
		)
		(property "Value" "TPAD28"
			(at 0.0127 -1.8034 0)
			(unlocked yes)
			(layer "F.Fab")
			(hide yes)
			(effects
				(font
					(size 1.016 1.016)
					(thickness 0.1524)
				)
			)
		)
		(property "Device Type" "TPAD28"
			(at 0.0127 -3.3274 0)
			(unlocked yes)
			(layer "F.Fab")
			(hide yes)
			(effects
				(font
					(size 1.016 1.016)
					(thickness 0.1524)
				)
			)
		)
		(duplicate_pad_numbers_are_jumpers no)
		(fp_poly
			(pts
				(arc
					(start 0.3556 0)
					(mid -0.3556 0)
					(end 0.3556 0)
				)
			)
			(stroke
				(width 0)
				(type default)
			)
			(fill no)
			(layer "F.CrtYd")
		)
		(fp_poly
			(pts
				(arc
					(start 0.6096 0)
					(mid -0.6096 0)
					(end 0.6096 0)
				)
			)
			(stroke
				(width 0)
				(type default)
			)
			(fill no)
			(layer "F.Fab")
		)
		(pad "1" smd circle
			(at 0 0)
			(size 0.7112 0.7112)
			(layers "F.Cu" "F.Mask" "F.Paste")
			(net "EXP_TEST_MUX32")
		)
	)
	(footprint ""
		(layer "F.Cu")
		(at 101.74097 -114.3 180)
		(property "Reference" "SC1089"
			(at 0 0 180)
			(layer "F.SilkS")
			(hide yes)
			(effects
				(font
					(size 1.27 1.27)
				)
			)
		)
		(property "Value" "SCD01U10V1KX-GP"
			(at -2.8321 -1.7399 180)
			(unlocked yes)
			(layer "F.Fab")
			(hide yes)
			(effects
				(font
					(size 1.016 1.016)
					(thickness 0.1524)
				)
			)
		)
		(property "Device Type" "C0201H13"
			(at -2.8321 -3.2639 180)
			(unlocked yes)
			(layer "F.Fab")
			(hide yes)
			(effects
				(font
					(size 1.016 1.016)
					(thickness 0.1524)
				)
			)
		)
		(duplicate_pad_numbers_are_jumpers no)
		(fp_rect
			(start -0.2794 0.6477)
			(end 0.2794 -0.6477)
			(stroke
				(width 0)
				(type default)
			)
			(fill no)
			(layer "F.CrtYd")
		)
		(fp_rect
			(start -0.2794 0.6477)
			(end 0.2794 -0.6477)
			(stroke
				(width 0)
				(type default)
			)
			(fill no)
			(layer "F.Fab")
		)
		(pad "1" smd custom
			(at 0 -0.2794 180)
			(size 0.0762 0.0762)
			(layers "F.Cu" "F.Mask" "F.Paste")
			(net "SAS_HDD_TX11_N")
			(options
				(clearance outline)
				(anchor circle)
			)
			(primitives
				(gr_poly
					(pts
						(arc
							(start 0.1524 -0.127)
							(mid 0.137521 -0.162921)
							(end 0.1016 -0.1778)
						)
						(arc
							(start -0.1016 -0.1778)
							(mid -0.137521 -0.162921)
							(end -0.1524 -0.127)
						)
						(arc
							(start -0.1524 0.127)
							(mid -0.137521 0.162921)
							(end -0.1016 0.1778)
						)
						(arc
							(start 0.1016 0.1778)
							(mid 0.137521 0.162921)
							(end 0.1524 0.127)
						)
					)
					(width 0)
					(fill yes)
				)
			)
		)
		(pad "2" smd custom
			(at 0 0.2794 180)
			(size 0.0762 0.0762)
			(layers "F.Cu" "F.Mask" "F.Paste")
			(net "SAS_EXP_GF_TX_DN15")
			(options
				(clearance outline)
				(anchor circle)
			)
			(primitives
				(gr_poly
					(pts
						(arc
							(start 0.1524 -0.127)
							(mid 0.137521 -0.162921)
							(end 0.1016 -0.1778)
						)
						(arc
							(start -0.1016 -0.1778)
							(mid -0.137521 -0.162921)
							(end -0.1524 -0.127)
						)
						(arc
							(start -0.1524 0.127)
							(mid -0.137521 0.162921)
							(end -0.1016 0.1778)
						)
						(arc
							(start 0.1016 0.1778)
							(mid 0.137521 0.162921)
							(end 0.1524 0.127)
						)
					)
					(width 0)
					(fill yes)
				)
			)
		)
	)
	(footprint ""
		(layer "F.Cu")
		(at 95.89897 -81.661 -90)
		(property "Reference" "SR789"
			(at 0 0 270)
			(layer "F.SilkS")
			(hide yes)
			(effects
				(font
					(size 1.27 1.27)
				)
			)
		)
		(property "Value" "4K75R2F-1-GP"
			(at 0.064008 -3.993896 270)
			(unlocked yes)
			(layer "F.Fab")
			(hide yes)
			(effects
				(font
					(size 1.016 1.016)
					(thickness 0.1524)
				)
			)
		)
		(property "Device Type" "R402H16"
			(at 0.064008 -5.517896 270)
			(unlocked yes)
			(layer "F.Fab")
			(hide yes)
			(effects
				(font
					(size 1.016 1.016)
					(thickness 0.1524)
				)
			)
		)
		(duplicate_pad_numbers_are_jumpers no)
		(fp_line
			(start -0.508 -0.9398)
			(end -0.508 0.9398)
			(stroke
				(width 0.1524)
				(type default)
			)
			(layer "F.SilkS")
		)
		(fp_line
			(start 0.508 -0.9398)
			(end -0.508 -0.9398)
			(stroke
				(width 0.1524)
				(type default)
			)
			(layer "F.SilkS")
		)
		(fp_rect
			(start -0.508 0.9398)
			(end 0.508 -0.9398)
			(stroke
				(width 0)
				(type default)
			)
			(fill no)
			(layer "F.CrtYd")
		)
		(fp_rect
			(start -0.508 0.9398)
			(end 0.508 -0.9398)
			(stroke
				(width 0)
				(type default)
			)
			(fill no)
			(layer "F.Fab")
		)
		(pad "1" smd custom
			(at 0 -0.4445 270)
			(size 0.1397 0.1397)
			(layers "F.Cu" "F.Mask" "F.Paste")
			(net "EXP_CPU_MODE_1")
			(options
				(clearance outline)
				(anchor circle)
			)
			(primitives
				(gr_poly
					(pts
						(arc
							(start -0.1778 -0.2794)
							(mid -0.249642 -0.249642)
							(end -0.2794 -0.1778)
						)
						(arc
							(start -0.2794 0.1778)
							(mid -0.249642 0.249642)
							(end -0.1778 0.2794)
						)
						(arc
							(start 0.1778 0.2794)
							(mid 0.249642 0.249642)
							(end 0.2794 0.1778)
						)
						(arc
							(start 0.2794 -0.1778)
							(mid 0.249642 -0.249642)
							(end 0.1778 -0.2794)
						)
					)
					(width 0)
					(fill yes)
				)
			)
		)
		(pad "2" smd custom
			(at 0 0.4445 270)
			(size 0.1397 0.1397)
			(layers "F.Cu" "F.Mask" "F.Paste")
			(net "GND")
			(options
				(clearance outline)
				(anchor circle)
			)
			(primitives
				(gr_poly
					(pts
						(arc
							(start -0.1778 -0.2794)
							(mid -0.249642 -0.249642)
							(end -0.2794 -0.1778)
						)
						(arc
							(start -0.2794 0.1778)
							(mid -0.249642 0.249642)
							(end -0.1778 0.2794)
						)
						(arc
							(start 0.1778 0.2794)
							(mid 0.249642 0.249642)
							(end 0.2794 0.1778)
						)
						(arc
							(start 0.2794 -0.1778)
							(mid 0.249642 -0.249642)
							(end 0.1778 -0.2794)
						)
					)
					(width 0)
					(fill yes)
				)
			)
		)
	)
	(footprint ""
		(layer "F.Cu")
		(at 14.428216 -211.00288 -90)
		(property "Reference" "SR589"
			(at 0 0 270)
			(layer "F.SilkS")
			(hide yes)
			(effects
				(font
					(size 1.27 1.27)
				)
			)
		)
		(property "Value" "4K7R2F-GP"
			(at 0.064008 -3.993896 270)
			(unlocked yes)
			(layer "F.Fab")
			(hide yes)
			(effects
				(font
					(size 1.016 1.016)
					(thickness 0.1524)
				)
			)
		)
		(property "Device Type" "R402H16"
			(at 0.064008 -5.517896 270)
			(unlocked yes)
			(layer "F.Fab")
			(hide yes)
			(effects
				(font
					(size 1.016 1.016)
					(thickness 0.1524)
				)
			)
		)
		(duplicate_pad_numbers_are_jumpers no)
		(fp_line
			(start -0.508 -0.9398)
			(end -0.508 0.9398)
			(stroke
				(width 0.1524)
				(type default)
			)
			(layer "F.SilkS")
		)
		(fp_line
			(start 0.508 -0.9398)
			(end -0.508 -0.9398)
			(stroke
				(width 0.1524)
				(type default)
			)
			(layer "F.SilkS")
		)
		(fp_rect
			(start -0.508 0.9398)
			(end 0.508 -0.9398)
			(stroke
				(width 0)
				(type default)
			)
			(fill no)
			(layer "F.CrtYd")
		)
		(fp_rect
			(start -0.508 0.9398)
			(end 0.508 -0.9398)
			(stroke
				(width 0)
				(type default)
			)
			(fill no)
			(layer "F.Fab")
		)
		(pad "1" smd custom
			(at 0 -0.4445 270)
			(size 0.1397 0.1397)
			(layers "F.Cu" "F.Mask" "F.Paste")
			(net "BMC_IOEXP_SDA_10")
			(options
				(clearance outline)
				(anchor circle)
			)
			(primitives
				(gr_poly
					(pts
						(arc
							(start -0.1778 -0.2794)
							(mid -0.249642 -0.249642)
							(end -0.2794 -0.1778)
						)
						(arc
							(start -0.2794 0.1778)
							(mid -0.249642 0.249642)
							(end -0.1778 0.2794)
						)
						(arc
							(start 0.1778 0.2794)
							(mid 0.249642 0.249642)
							(end 0.2794 0.1778)
						)
						(arc
							(start 0.2794 -0.1778)
							(mid 0.249642 -0.249642)
							(end 0.1778 -0.2794)
						)
					)
					(width 0)
					(fill yes)
				)
			)
		)
		(pad "2" smd custom
			(at 0 0.4445 270)
			(size 0.1397 0.1397)
			(layers "F.Cu" "F.Mask" "F.Paste")
			(net "P1V8_E")
			(options
				(clearance outline)
				(anchor circle)
			)
			(primitives
				(gr_poly
					(pts
						(arc
							(start -0.1778 -0.2794)
							(mid -0.249642 -0.249642)
							(end -0.2794 -0.1778)
						)
						(arc
							(start -0.2794 0.1778)
							(mid -0.249642 0.249642)
							(end -0.1778 0.2794)
						)
						(arc
							(start 0.1778 0.2794)
							(mid 0.249642 0.249642)
							(end 0.2794 0.1778)
						)
						(arc
							(start 0.2794 -0.1778)
							(mid 0.249642 -0.249642)
							(end 0.1778 -0.2794)
						)
					)
					(width 0)
					(fill yes)
				)
			)
		)
	)
	(footprint ""
		(layer "F.Cu")
		(at 299.72 -191.897)
		(property "Reference" "R583"
			(at 0 0 0)
			(layer "F.SilkS")
			(hide yes)
			(effects
				(font
					(size 1.27 1.27)
				)
			)
		)
		(property "Value" "0R2J-2-GP"
			(at 0.064008 -3.993896 0)
			(unlocked yes)
			(layer "F.Fab")
			(hide yes)
			(effects
				(font
					(size 1.016 1.016)
					(thickness 0.1524)
				)
			)
		)
		(property "Device Type" "R402H16"
			(at 0.064008 -5.517896 0)
			(unlocked yes)
			(layer "F.Fab")
			(hide yes)
			(effects
				(font
					(size 1.016 1.016)
					(thickness 0.1524)
				)
			)
		)
		(duplicate_pad_numbers_are_jumpers no)
		(fp_line
			(start -0.508 -0.9398)
			(end -0.508 0.9398)
			(stroke
				(width 0.1524)
				(type default)
			)
			(layer "F.SilkS")
		)
		(fp_line
			(start 0.508 -0.9398)
			(end -0.508 -0.9398)
			(stroke
				(width 0.1524)
				(type default)
			)
			(layer "F.SilkS")
		)
		(fp_rect
			(start -0.508 0.9398)
			(end 0.508 -0.9398)
			(stroke
				(width 0)
				(type default)
			)
			(fill no)
			(layer "F.CrtYd")
		)
		(fp_rect
			(start -0.508 0.9398)
			(end 0.508 -0.9398)
			(stroke
				(width 0)
				(type default)
			)
			(fill no)
			(layer "F.Fab")
		)
		(pad "1" smd custom
			(at 0 -0.4445)
			(size 0.1397 0.1397)
			(layers "F.Cu" "F.Mask" "F.Paste")
			(net "BMC_UART_SWITCH_2")
			(options
				(clearance outline)
				(anchor circle)
			)
			(primitives
				(gr_poly
					(pts
						(arc
							(start -0.1778 -0.2794)
							(mid -0.249642 -0.249642)
							(end -0.2794 -0.1778)
						)
						(arc
							(start -0.2794 0.1778)
							(mid -0.249642 0.249642)
							(end -0.1778 0.2794)
						)
						(arc
							(start 0.1778 0.2794)
							(mid 0.249642 0.249642)
							(end 0.2794 0.1778)
						)
						(arc
							(start 0.2794 -0.1778)
							(mid 0.249642 -0.249642)
							(end 0.1778 -0.2794)
						)
					)
					(width 0)
					(fill yes)
				)
			)
		)
		(pad "2" smd custom
			(at 0 0.4445)
			(size 0.1397 0.1397)
			(layers "F.Cu" "F.Mask" "F.Paste")
			(net "BMC0_TACH12")
			(options
				(clearance outline)
				(anchor circle)
			)
			(primitives
				(gr_poly
					(pts
						(arc
							(start -0.1778 -0.2794)
							(mid -0.249642 -0.249642)
							(end -0.2794 -0.1778)
						)
						(arc
							(start -0.2794 0.1778)
							(mid -0.249642 0.249642)
							(end -0.1778 0.2794)
						)
						(arc
							(start 0.1778 0.2794)
							(mid 0.249642 0.249642)
							(end 0.2794 0.1778)
						)
						(arc
							(start 0.2794 -0.1778)
							(mid 0.249642 -0.249642)
							(end 0.1778 -0.2794)
						)
					)
					(width 0)
					(fill yes)
				)
			)
		)
	)
	(footprint ""
		(layer "F.Cu")
		(at 183.8198 -53.086 90)
		(property "Reference" "R22"
			(at 0 0 90)
			(layer "F.SilkS")
			(hide yes)
			(effects
				(font
					(size 1.27 1.27)
				)
			)
		)
		(property "Value" "10KR2F-2-GP"
			(at 0.064008 -3.993896 90)
			(unlocked yes)
			(layer "F.Fab")
			(hide yes)
			(effects
				(font
					(size 1.016 1.016)
					(thickness 0.1524)
				)
			)
		)
		(property "Device Type" "R402H16"
			(at 0.064008 -5.517896 90)
			(unlocked yes)
			(layer "F.Fab")
			(hide yes)
			(effects
				(font
					(size 1.016 1.016)
					(thickness 0.1524)
				)
			)
		)
		(duplicate_pad_numbers_are_jumpers no)
		(fp_line
			(start 0.508 -0.9398)
			(end -0.508 -0.9398)
			(stroke
				(width 0.1524)
				(type default)
			)
			(layer "F.SilkS")
		)
		(fp_line
			(start -0.508 -0.9398)
			(end -0.508 0.9398)
			(stroke
				(width 0.1524)
				(type default)
			)
			(layer "F.SilkS")
		)
		(fp_rect
			(start -0.508 0.9398)
			(end 0.508 -0.9398)
			(stroke
				(width 0)
				(type default)
			)
			(fill no)
			(layer "F.CrtYd")
		)
		(fp_rect
			(start -0.508 0.9398)
			(end 0.508 -0.9398)
			(stroke
				(width 0)
				(type default)
			)
			(fill no)
			(layer "F.Fab")
		)
		(pad "1" smd custom
			(at 0 -0.4445 90)
			(size 0.1397 0.1397)
			(layers "F.Cu" "F.Mask" "F.Paste")
			(net "P0V9_E_PG")
			(options
				(clearance outline)
				(anchor circle)
			)
			(primitives
				(gr_poly
					(pts
						(arc
							(start -0.1778 -0.2794)
							(mid -0.249642 -0.249642)
							(end -0.2794 -0.1778)
						)
						(arc
							(start -0.2794 0.1778)
							(mid -0.249642 0.249642)
							(end -0.1778 0.2794)
						)
						(arc
							(start 0.1778 0.2794)
							(mid 0.249642 0.249642)
							(end 0.2794 0.1778)
						)
						(arc
							(start 0.2794 -0.1778)
							(mid 0.249642 -0.249642)
							(end 0.1778 -0.2794)
						)
					)
					(width 0)
					(fill yes)
				)
			)
		)
		(pad "2" smd custom
			(at 0 0.4445 90)
			(size 0.1397 0.1397)
			(layers "F.Cu" "F.Mask" "F.Paste")
			(net "MSB_PRSNT_AND_3")
			(options
				(clearance outline)
				(anchor circle)
			)
			(primitives
				(gr_poly
					(pts
						(arc
							(start -0.1778 -0.2794)
							(mid -0.249642 -0.249642)
							(end -0.2794 -0.1778)
						)
						(arc
							(start -0.2794 0.1778)
							(mid -0.249642 0.249642)
							(end -0.1778 0.2794)
						)
						(arc
							(start 0.1778 0.2794)
							(mid 0.249642 0.249642)
							(end 0.2794 0.1778)
						)
						(arc
							(start 0.2794 -0.1778)
							(mid 0.249642 -0.249642)
							(end 0.1778 -0.2794)
						)
					)
					(width 0)
					(fill yes)
				)
			)
		)
	)
	(footprint ""
		(layer "F.Cu")
		(at 253.746 -136.779)
		(property "Reference" "R7906"
			(at 0 0 0)
			(layer "F.SilkS")
			(hide yes)
			(effects
				(font
					(size 1.27 1.27)
				)
			)
		)
		(property "Value" "0R2J-2-GP"
			(at 0.064008 -3.993896 0)
			(unlocked yes)
			(layer "F.Fab")
			(hide yes)
			(effects
				(font
					(size 1.016 1.016)
					(thickness 0.1524)
				)
			)
		)
		(property "Device Type" "R402H16"
			(at 0.064008 -5.517896 0)
			(unlocked yes)
			(layer "F.Fab")
			(hide yes)
			(effects
				(font
					(size 1.016 1.016)
					(thickness 0.1524)
				)
			)
		)
		(duplicate_pad_numbers_are_jumpers no)
		(fp_line
			(start -0.508 -0.9398)
			(end -0.508 0.9398)
			(stroke
				(width 0.1524)
				(type default)
			)
			(layer "F.SilkS")
		)
		(fp_line
			(start 0.508 -0.9398)
			(end -0.508 -0.9398)
			(stroke
				(width 0.1524)
				(type default)
			)
			(layer "F.SilkS")
		)
		(fp_rect
			(start -0.508 0.9398)
			(end 0.508 -0.9398)
			(stroke
				(width 0)
				(type default)
			)
			(fill no)
			(layer "F.CrtYd")
		)
		(fp_rect
			(start -0.508 0.9398)
			(end 0.508 -0.9398)
			(stroke
				(width 0)
				(type default)
			)
			(fill no)
			(layer "F.Fab")
		)
		(pad "1" smd custom
			(at 0 -0.4445)
			(size 0.1397 0.1397)
			(layers "F.Cu" "F.Mask" "F.Paste")
			(net "CPU_BMC_UART_RX")
			(options
				(clearance outline)
				(anchor circle)
			)
			(primitives
				(gr_poly
					(pts
						(arc
							(start -0.1778 -0.2794)
							(mid -0.249642 -0.249642)
							(end -0.2794 -0.1778)
						)
						(arc
							(start -0.2794 0.1778)
							(mid -0.249642 0.249642)
							(end -0.1778 0.2794)
						)
						(arc
							(start 0.1778 0.2794)
							(mid 0.249642 0.249642)
							(end 0.2794 0.1778)
						)
						(arc
							(start 0.2794 -0.1778)
							(mid 0.249642 -0.249642)
							(end 0.1778 -0.2794)
						)
					)
					(width 0)
					(fill yes)
				)
			)
		)
		(pad "2" smd custom
			(at 0 0.4445)
			(size 0.1397 0.1397)
			(layers "F.Cu" "F.Mask" "F.Paste")
			(net "CPU_U193_PIN6_RX")
			(options
				(clearance outline)
				(anchor circle)
			)
			(primitives
				(gr_poly
					(pts
						(arc
							(start -0.1778 -0.2794)
							(mid -0.249642 -0.249642)
							(end -0.2794 -0.1778)
						)
						(arc
							(start -0.2794 0.1778)
							(mid -0.249642 0.249642)
							(end -0.1778 0.2794)
						)
						(arc
							(start 0.1778 0.2794)
							(mid 0.249642 0.249642)
							(end 0.2794 0.1778)
						)
						(arc
							(start 0.2794 -0.1778)
							(mid 0.249642 -0.249642)
							(end 0.1778 -0.2794)
						)
					)
					(width 0)
					(fill yes)
				)
			)
		)
	)
	(footprint ""
		(layer "F.Cu")
		(at 199.517 -220.472)
		(property "Reference" "U174"
			(at 0 0 0)
			(layer "F.SilkS")
			(hide yes)
			(effects
				(font
					(size 1.27 1.27)
				)
			)
		)
		(property "Value" "SNLVC1G126DCKR-GP"
			(at -2.3368 -8.6868 0)
			(unlocked yes)
			(layer "F.Fab")
			(hide yes)
			(effects
				(font
					(size 1.016 1.016)
					(thickness 0.1524)
				)
			)
		)
		(property "Device Type" "SC70-5H44"
			(at -2.3114 -10.414 0)
			(unlocked yes)
			(layer "F.Fab")
			(hide yes)
			(effects
				(font
					(size 1.016 1.016)
					(thickness 0.1524)
				)
			)
		)
		(duplicate_pad_numbers_are_jumpers no)
		(fp_line
			(start -1.27 -1.7018)
			(end 1.27 -1.7018)
			(stroke
				(width 0.1524)
				(type default)
			)
			(layer "F.SilkS")
		)
		(fp_line
			(start -1.27 1.7018)
			(end -1.27 -1.7018)
			(stroke
				(width 0.1524)
				(type default)
			)
			(layer "F.SilkS")
		)
		(fp_line
			(start 0.6604 -1.8034)
			(end 1.3843 -1.8034)
			(stroke
				(width 0.3302)
				(type default)
			)
			(layer "F.SilkS")
		)
		(fp_line
			(start 1.27 -1.7018)
			(end 1.27 1.7018)
			(stroke
				(width 0.1524)
				(type default)
			)
			(layer "F.SilkS")
		)
		(fp_line
			(start 1.27 1.7018)
			(end -1.27 1.7018)
			(stroke
				(width 0.1524)
				(type default)
			)
			(layer "F.SilkS")
		)
		(fp_line
			(start 1.3843 -1.8034)
			(end 1.3843 -1.1176)
			(stroke
				(width 0.3302)
				(type default)
			)
			(layer "F.SilkS")
		)
		(fp_rect
			(start -1.524 1.9558)
			(end 1.524 -1.9558)
			(stroke
				(width 0)
				(type default)
			)
			(fill no)
			(layer "F.CrtYd")
		)
		(fp_poly
			(pts
				(xy -1.524 -1.9558) (xy 1.524 -1.9558) (xy 1.524 1.9558) (xy -1.524 1.9558)
			)
			(stroke
				(width 0)
				(type default)
			)
			(fill no)
			(layer "F.Fab")
		)
		(pad "1" smd rect
			(at 0.65024 -0.8255)
			(size 0.4064 1.2192)
			(layers "F.Cu" "F.Mask" "F.Paste")
			(net "FM_BMC_READY_N")
		)
		(pad "2" smd rect
			(at 0 -0.8255)
			(size 0.4064 1.2192)
			(layers "F.Cu" "F.Mask" "F.Paste")
			(net "RSTBTN_FP_N")
		)
		(pad "3" smd rect
			(at -0.65024 -0.8255)
			(size 0.4064 1.2192)
			(layers "F.Cu" "F.Mask" "F.Paste")
			(net "GND")
		)
		(pad "4" smd rect
			(at -0.65024 0.8255)
			(size 0.4064 1.2192)
			(layers "F.Cu" "F.Mask" "F.Paste")
			(net "RSTBTN_OUT_N")
		)
		(pad "5" smd rect
			(at 0.65024 0.8255)
			(size 0.4064 1.2192)
			(layers "F.Cu" "F.Mask" "F.Paste")
			(net "P3V3_STBY")
		)
	)
	(footprint ""
		(layer "F.Cu")
		(at 84.582 -24.384 180)
		(property "Reference" "PR188"
			(at 0 0 180)
			(layer "F.SilkS")
			(hide yes)
			(effects
				(font
					(size 1.27 1.27)
				)
			)
		)
		(property "Value" "100KR2F-L1-GP"
			(at 0.064008 -3.993896 180)
			(unlocked yes)
			(layer "F.Fab")
			(hide yes)
			(effects
				(font
					(size 1.016 1.016)
					(thickness 0.1524)
				)
			)
		)
		(property "Device Type" "R402H16"
			(at 0.064008 -5.517896 180)
			(unlocked yes)
			(layer "F.Fab")
			(hide yes)
			(effects
				(font
					(size 1.016 1.016)
					(thickness 0.1524)
				)
			)
		)
		(duplicate_pad_numbers_are_jumpers no)
		(fp_line
			(start 0.508 -0.9398)
			(end -0.508 -0.9398)
			(stroke
				(width 0.1524)
				(type default)
			)
			(layer "F.SilkS")
		)
		(fp_line
			(start -0.508 -0.9398)
			(end -0.508 0.9398)
			(stroke
				(width 0.1524)
				(type default)
			)
			(layer "F.SilkS")
		)
		(fp_rect
			(start -0.508 0.9398)
			(end 0.508 -0.9398)
			(stroke
				(width 0)
				(type default)
			)
			(fill no)
			(layer "F.CrtYd")
		)
		(fp_rect
			(start -0.508 0.9398)
			(end 0.508 -0.9398)
			(stroke
				(width 0)
				(type default)
			)
			(fill no)
			(layer "F.Fab")
		)
		(pad "1" smd custom
			(at 0 -0.4445 180)
			(size 0.1397 0.1397)
			(layers "F.Cu" "F.Mask" "F.Paste")
			(net "VT235_VDES")
			(options
				(clearance outline)
				(anchor circle)
			)
			(primitives
				(gr_poly
					(pts
						(arc
							(start -0.1778 -0.2794)
							(mid -0.249642 -0.249642)
							(end -0.2794 -0.1778)
						)
						(arc
							(start -0.2794 0.1778)
							(mid -0.249642 0.249642)
							(end -0.1778 0.2794)
						)
						(arc
							(start 0.1778 0.2794)
							(mid 0.249642 0.249642)
							(end 0.2794 0.1778)
						)
						(arc
							(start 0.2794 -0.1778)
							(mid 0.249642 -0.249642)
							(end 0.1778 -0.2794)
						)
					)
					(width 0)
					(fill yes)
				)
			)
		)
		(pad "2" smd custom
			(at 0 0.4445 180)
			(size 0.1397 0.1397)
			(layers "F.Cu" "F.Mask" "F.Paste")
			(net "VT235_VREF")
			(options
				(clearance outline)
				(anchor circle)
			)
			(primitives
				(gr_poly
					(pts
						(arc
							(start -0.1778 -0.2794)
							(mid -0.249642 -0.249642)
							(end -0.2794 -0.1778)
						)
						(arc
							(start -0.2794 0.1778)
							(mid -0.249642 0.249642)
							(end -0.1778 0.2794)
						)
						(arc
							(start 0.1778 0.2794)
							(mid 0.249642 0.249642)
							(end 0.2794 0.1778)
						)
						(arc
							(start 0.2794 -0.1778)
							(mid 0.249642 -0.249642)
							(end 0.1778 -0.2794)
						)
					)
					(width 0)
					(fill yes)
				)
			)
		)
	)
	(footprint ""
		(layer "F.Cu")
		(at 86.49716 -37.973 -90)
		(property "Reference" "SC885"
			(at 0 0 270)
			(layer "F.SilkS")
			(hide yes)
			(effects
				(font
					(size 1.27 1.27)
				)
			)
		)
		(property "Value" "SCD01U10V1KX-GP"
			(at -2.8321 -1.7399 270)
			(unlocked yes)
			(layer "F.Fab")
			(hide yes)
			(effects
				(font
					(size 1.016 1.016)
					(thickness 0.1524)
				)
			)
		)
		(property "Device Type" "C0201H13"
			(at -2.8321 -3.2639 270)
			(unlocked yes)
			(layer "F.Fab")
			(hide yes)
			(effects
				(font
					(size 1.016 1.016)
					(thickness 0.1524)
				)
			)
		)
		(duplicate_pad_numbers_are_jumpers no)
		(fp_rect
			(start -0.2794 0.6477)
			(end 0.2794 -0.6477)
			(stroke
				(width 0)
				(type default)
			)
			(fill no)
			(layer "F.CrtYd")
		)
		(fp_rect
			(start -0.2794 0.6477)
			(end 0.2794 -0.6477)
			(stroke
				(width 0)
				(type default)
			)
			(fill no)
			(layer "F.Fab")
		)
		(pad "1" smd custom
			(at 0 -0.2794 270)
			(size 0.0762 0.0762)
			(layers "F.Cu" "F.Mask" "F.Paste")
			(net "SAS3008_RAID_TX_C_N3")
			(options
				(clearance outline)
				(anchor circle)
			)
			(primitives
				(gr_poly
					(pts
						(arc
							(start 0.1524 -0.127)
							(mid 0.137521 -0.162921)
							(end 0.1016 -0.1778)
						)
						(arc
							(start -0.1016 -0.1778)
							(mid -0.137521 -0.162921)
							(end -0.1524 -0.127)
						)
						(arc
							(start -0.1524 0.127)
							(mid -0.137521 0.162921)
							(end -0.1016 0.1778)
						)
						(arc
							(start 0.1016 0.1778)
							(mid 0.137521 0.162921)
							(end 0.1524 0.127)
						)
					)
					(width 0)
					(fill yes)
				)
			)
		)
		(pad "2" smd custom
			(at 0 0.2794 270)
			(size 0.0762 0.0762)
			(layers "F.Cu" "F.Mask" "F.Paste")
			(net "SAS3008_RAID_TX_N3")
			(options
				(clearance outline)
				(anchor circle)
			)
			(primitives
				(gr_poly
					(pts
						(arc
							(start 0.1524 -0.127)
							(mid 0.137521 -0.162921)
							(end 0.1016 -0.1778)
						)
						(arc
							(start -0.1016 -0.1778)
							(mid -0.137521 -0.162921)
							(end -0.1524 -0.127)
						)
						(arc
							(start -0.1524 0.127)
							(mid -0.137521 0.162921)
							(end -0.1016 0.1778)
						)
						(arc
							(start 0.1016 0.1778)
							(mid 0.137521 0.162921)
							(end 0.1524 0.127)
						)
					)
					(width 0)
					(fill yes)
				)
			)
		)
	)
	(footprint ""
		(layer "F.Cu")
		(at 219.72397 -69.088)
		(property "Reference" "R15"
			(at 0 0 0)
			(layer "F.SilkS")
			(hide yes)
			(effects
				(font
					(size 1.27 1.27)
				)
			)
		)
		(property "Value" "100R2F-L1-GP-U"
			(at 0.064008 -3.993896 0)
			(unlocked yes)
			(layer "F.Fab")
			(hide yes)
			(effects
				(font
					(size 1.016 1.016)
					(thickness 0.1524)
				)
			)
		)
		(property "Device Type" "R402H14"
			(at 0.064008 -5.517896 0)
			(unlocked yes)
			(layer "F.Fab")
			(hide yes)
			(effects
				(font
					(size 1.016 1.016)
					(thickness 0.1524)
				)
			)
		)
		(duplicate_pad_numbers_are_jumpers no)
		(fp_line
			(start -0.508 -0.9398)
			(end -0.508 0.9398)
			(stroke
				(width 0.1524)
				(type default)
			)
			(layer "F.SilkS")
		)
		(fp_line
			(start 0.508 -0.9398)
			(end -0.508 -0.9398)
			(stroke
				(width 0.1524)
				(type default)
			)
			(layer "F.SilkS")
		)
		(fp_rect
			(start -0.508 0.9398)
			(end 0.508 -0.9398)
			(stroke
				(width 0)
				(type default)
			)
			(fill no)
			(layer "F.CrtYd")
		)
		(fp_rect
			(start -0.508 0.9398)
			(end 0.508 -0.9398)
			(stroke
				(width 0)
				(type default)
			)
			(fill no)
			(layer "F.Fab")
		)
		(pad "1" smd custom
			(at 0 -0.4445)
			(size 0.1397 0.1397)
			(layers "F.Cu" "F.Mask" "F.Paste")
			(net "SVR_ID0")
			(options
				(clearance outline)
				(anchor circle)
			)
			(primitives
				(gr_poly
					(pts
						(arc
							(start -0.1778 -0.2794)
							(mid -0.249642 -0.249642)
							(end -0.2794 -0.1778)
						)
						(arc
							(start -0.2794 0.1778)
							(mid -0.249642 0.249642)
							(end -0.1778 0.2794)
						)
						(arc
							(start 0.1778 0.2794)
							(mid 0.249642 0.249642)
							(end 0.2794 0.1778)
						)
						(arc
							(start 0.2794 -0.1778)
							(mid 0.249642 -0.249642)
							(end 0.1778 -0.2794)
						)
					)
					(width 0)
					(fill yes)
				)
			)
		)
		(pad "2" smd custom
			(at 0 0.4445)
			(size 0.1397 0.1397)
			(layers "F.Cu" "F.Mask" "F.Paste")
			(net "GND")
			(options
				(clearance outline)
				(anchor circle)
			)
			(primitives
				(gr_poly
					(pts
						(arc
							(start -0.1778 -0.2794)
							(mid -0.249642 -0.249642)
							(end -0.2794 -0.1778)
						)
						(arc
							(start -0.2794 0.1778)
							(mid -0.249642 0.249642)
							(end -0.1778 0.2794)
						)
						(arc
							(start 0.1778 0.2794)
							(mid 0.249642 0.249642)
							(end 0.2794 0.1778)
						)
						(arc
							(start 0.2794 -0.1778)
							(mid 0.249642 -0.249642)
							(end 0.1778 -0.2794)
						)
					)
					(width 0)
					(fill yes)
				)
			)
		)
	)
	(footprint ""
		(layer "F.Cu")
		(at 317.754 -118.618 180)
		(property "Reference" "PR29"
			(at 0 0 180)
			(layer "F.SilkS")
			(hide yes)
			(effects
				(font
					(size 1.27 1.27)
				)
			)
		)
		(property "Value" "475KR2F-GP"
			(at 0.064008 -3.993896 180)
			(unlocked yes)
			(layer "F.Fab")
			(hide yes)
			(effects
				(font
					(size 1.016 1.016)
					(thickness 0.1524)
				)
			)
		)
		(property "Device Type" "R402H16"
			(at 0.064008 -5.517896 180)
			(unlocked yes)
			(layer "F.Fab")
			(hide yes)
			(effects
				(font
					(size 1.016 1.016)
					(thickness 0.1524)
				)
			)
		)
		(duplicate_pad_numbers_are_jumpers no)
		(fp_line
			(start 0.508 -0.9398)
			(end -0.508 -0.9398)
			(stroke
				(width 0.1524)
				(type default)
			)
			(layer "F.SilkS")
		)
		(fp_line
			(start -0.508 -0.9398)
			(end -0.508 0.9398)
			(stroke
				(width 0.1524)
				(type default)
			)
			(layer "F.SilkS")
		)
		(fp_rect
			(start -0.508 0.9398)
			(end 0.508 -0.9398)
			(stroke
				(width 0)
				(type default)
			)
			(fill no)
			(layer "F.CrtYd")
		)
		(fp_rect
			(start -0.508 0.9398)
			(end 0.508 -0.9398)
			(stroke
				(width 0)
				(type default)
			)
			(fill no)
			(layer "F.Fab")
		)
		(pad "1" smd custom
			(at 0 -0.4445 180)
			(size 0.1397 0.1397)
			(layers "F.Cu" "F.Mask" "F.Paste")
			(net "P3V3_STBY_MODE")
			(options
				(clearance outline)
				(anchor circle)
			)
			(primitives
				(gr_poly
					(pts
						(arc
							(start -0.1778 -0.2794)
							(mid -0.249642 -0.249642)
							(end -0.2794 -0.1778)
						)
						(arc
							(start -0.2794 0.1778)
							(mid -0.249642 0.249642)
							(end -0.1778 0.2794)
						)
						(arc
							(start 0.1778 0.2794)
							(mid 0.249642 0.249642)
							(end 0.2794 0.1778)
						)
						(arc
							(start 0.2794 -0.1778)
							(mid 0.249642 -0.249642)
							(end 0.1778 -0.2794)
						)
					)
					(width 0)
					(fill yes)
				)
			)
		)
		(pad "2" smd custom
			(at 0 0.4445 180)
			(size 0.1397 0.1397)
			(layers "F.Cu" "F.Mask" "F.Paste")
			(net "P3V3_STBY_PG")
			(options
				(clearance outline)
				(anchor circle)
			)
			(primitives
				(gr_poly
					(pts
						(arc
							(start -0.1778 -0.2794)
							(mid -0.249642 -0.249642)
							(end -0.2794 -0.1778)
						)
						(arc
							(start -0.2794 0.1778)
							(mid -0.249642 0.249642)
							(end -0.1778 0.2794)
						)
						(arc
							(start 0.1778 0.2794)
							(mid 0.249642 0.249642)
							(end 0.2794 0.1778)
						)
						(arc
							(start 0.2794 -0.1778)
							(mid 0.249642 -0.249642)
							(end 0.1778 -0.2794)
						)
					)
					(width 0)
					(fill yes)
				)
			)
		)
	)
	(footprint ""
		(layer "F.Cu")
		(at 158.369 -110.998 90)
		(property "Reference" "SC1207"
			(at 0 0 90)
			(layer "F.SilkS")
			(hide yes)
			(effects
				(font
					(size 1.27 1.27)
				)
			)
		)
		(property "Value" "SC10U6D3V5KX-4GP"
			(at -0.0762 -6.1214 90)
			(unlocked yes)
			(layer "F.Fab")
			(hide yes)
			(effects
				(font
					(size 1.016 1.016)
					(thickness 0.1524)
				)
			)
		)
		(property "Device Type" "C805H58"
			(at -0.0762 -8.1534 90)
			(unlocked yes)
			(layer "F.Fab")
			(hide yes)
			(effects
				(font
					(size 1.016 1.016)
					(thickness 0.1524)
				)
			)
		)
		(duplicate_pad_numbers_are_jumpers no)
		(fp_line
			(start 0.635 0)
			(end -0.635 0)
			(stroke
				(width 0.508)
				(type default)
			)
			(layer "F.SilkS")
		)
		(fp_rect
			(start -0.9652 1.778)
			(end 0.9652 -1.778)
			(stroke
				(width 0)
				(type default)
			)
			(fill no)
			(layer "F.CrtYd")
		)
		(fp_poly
			(pts
				(xy -0.9652 -1.778) (xy 0.9652 -1.778) (xy 0.9652 1.778) (xy -0.9652 1.778)
			)
			(stroke
				(width 0)
				(type default)
			)
			(fill no)
			(layer "F.Fab")
		)
		(pad "1" smd rect
			(at 0 -0.9652 90)
			(size 1.397 1.143)
			(layers "F.Cu" "F.Mask" "F.Paste")
			(net "P0V9_E")
		)
		(pad "2" smd rect
			(at 0 0.9652 90)
			(size 1.397 1.143)
			(layers "F.Cu" "F.Mask" "F.Paste")
			(net "GND")
		)
	)
	(footprint ""
		(layer "F.Cu")
		(at 33.50006 -68.460112)
		(property "Reference" "LED7"
			(at 0 0 0)
			(layer "F.SilkS")
			(hide yes)
			(effects
				(font
					(size 1.27 1.27)
				)
			)
		)
		(property "Value" "LED-RB-8-GP"
			(at -4.6736 3.8354 0)
			(unlocked yes)
			(layer "F.Fab")
			(hide yes)
			(effects
				(font
					(size 1.016 1.016)
					(thickness 0.1524)
				)
			)
		)
		(property "Device Type" "LED-100-3P-067106H325"
			(at -4.6736 2.3114 0)
			(unlocked yes)
			(layer "F.Fab")
			(hide yes)
			(effects
				(font
					(size 1.016 1.016)
					(thickness 0.1524)
				)
			)
		)
		(duplicate_pad_numbers_are_jumpers no)
		(fp_line
			(start -3.6068 -0.889)
			(end 3.6068 -0.889)
			(stroke
				(width 0.1524)
				(type default)
			)
			(layer "F.SilkS")
		)
		(fp_line
			(start -3.6068 6.6548)
			(end -3.6068 -0.889)
			(stroke
				(width 0.1524)
				(type default)
			)
			(layer "F.SilkS")
		)
		(fp_line
			(start -1.7526 6.6548)
			(end -3.6068 6.6548)
			(stroke
				(width 0.1524)
				(type default)
			)
			(layer "F.SilkS")
		)
		(fp_line
			(start -1.7526 10.414)
			(end -1.7526 6.6548)
			(stroke
				(width 0.1524)
				(type default)
			)
			(layer "F.SilkS")
		)
		(fp_line
			(start 1.7526 6.6548)
			(end 1.7526 10.414)
			(stroke
				(width 0.1524)
				(type default)
			)
			(layer "F.SilkS")
		)
		(fp_line
			(start 1.7526 10.414)
			(end -1.7526 10.414)
			(stroke
				(width 0.1524)
				(type default)
			)
			(layer "F.SilkS")
		)
		(fp_line
			(start 3.6068 -0.889)
			(end 3.6068 6.6548)
			(stroke
				(width 0.1524)
				(type default)
			)
			(layer "F.SilkS")
		)
		(fp_line
			(start 3.6068 6.6548)
			(end 1.7526 6.6548)
			(stroke
				(width 0.1524)
				(type default)
			)
			(layer "F.SilkS")
		)
		(fp_circle
			(center -2.54 0)
			(end -1.5494 0)
			(stroke
				(width 0.3048)
				(type default)
			)
			(fill no)
			(layer "F.SilkS")
		)
		(fp_circle
			(center 0 0)
			(end 0.9906 0)
			(stroke
				(width 0.3048)
				(type default)
			)
			(fill no)
			(layer "F.SilkS")
		)
		(fp_circle
			(center 2.54 0)
			(end 3.5306 0)
			(stroke
				(width 0.3048)
				(type default)
			)
			(fill no)
			(layer "F.SilkS")
		)
		(fp_poly
			(pts
				(xy -1.4986 10.1473) (xy -1.4986 6.4008) (xy -3.3528 6.4008) (xy -3.3528 -0.3937) (xy 3.3528 -0.3937)
				(xy 3.3528 6.4008) (xy 1.4986 6.4008) (xy 1.4986 10.1473)
			)
			(stroke
				(width 0)
				(type default)
			)
			(fill no)
			(layer "F.CrtYd")
		)
		(fp_poly
			(pts
				(xy -2.0066 10.668) (xy 2.0066 10.668) (xy 2.0066 6.9088) (xy 3.8608 6.9088) (xy 3.8608 2.2098)
				(xy 3.3528 2.2098) (xy 3.3528 6.4008) (xy 1.4986 6.4008) (xy 1.4986 10.1473) (xy -1.4986 10.1473)
				(xy -1.4986 6.4008) (xy -3.3528 6.4008) (xy -3.3528 -0.3937) (xy 3.3528 -0.3937) (xy 3.3528 2.1971)
				(xy 3.8608 2.1971) (xy 3.8608 -1.143) (xy -3.8608 -1.143) (xy -3.8608 6.9088) (xy -2.0066 6.9088)
			)
			(stroke
				(width 0)
				(type default)
			)
			(fill no)
			(layer "F.CrtYd")
		)
		(fp_poly
			(pts
				(xy -2.0066 10.668) (xy -2.0066 6.9088) (xy -3.8608 6.9088) (xy -3.8608 -1.143) (xy 3.8608 -1.143)
				(xy 3.8608 6.9088) (xy 2.0066 6.9088) (xy 2.0066 10.668)
			)
			(stroke
				(width 0)
				(type default)
			)
			(fill no)
			(layer "F.Fab")
		)
		(pad "1" thru_hole circle
			(at 2.54 0)
			(size 1.27 1.27)
			(drill 0.889)
			(layers "*.Cu" "*.Mask")
			(remove_unused_layers no)
			(net "INTA_LED_BLUE_C")
			(clearance 0.1651)
			(thermal_gap 0.1651)
		)
		(pad "2" thru_hole circle
			(at 0 0)
			(size 1.27 1.27)
			(drill 0.889)
			(layers "*.Cu" "*.Mask")
			(remove_unused_layers no)
			(net "INTA_LED_GND")
			(clearance 0.1651)
			(thermal_gap 0.1651)
		)
		(pad "3" thru_hole circle
			(at -2.54 0)
			(size 1.27 1.27)
			(drill 0.889)
			(layers "*.Cu" "*.Mask")
			(remove_unused_layers no)
			(net "INTA_LED_RED_C")
			(clearance 0.1651)
			(thermal_gap 0.1651)
		)
	)
	(footprint ""
		(layer "F.Cu")
		(at 315.341 -192.278)
		(property "Reference" "TP178"
			(at 0 0 0)
			(layer "F.SilkS")
			(hide yes)
			(effects
				(font
					(size 1.27 1.27)
				)
			)
		)
		(property "Value" "TPAD28"
			(at -0.0127 -1.6637 0)
			(unlocked yes)
			(layer "F.Fab")
			(hide yes)
			(effects
				(font
					(size 1.016 1.016)
					(thickness 0.1524)
				)
			)
		)
		(property "Device Type" "TPAD28"
			(at -0.0127 -3.1877 0)
			(unlocked yes)
			(layer "F.Fab")
			(hide yes)
			(effects
				(font
					(size 1.016 1.016)
					(thickness 0.1524)
				)
			)
		)
		(duplicate_pad_numbers_are_jumpers no)
		(fp_poly
			(pts
				(arc
					(start 0.3556 0)
					(mid -0.3556 0)
					(end 0.3556 0)
				)
			)
			(stroke
				(width 0)
				(type default)
			)
			(fill no)
			(layer "F.CrtYd")
		)
		(fp_poly
			(pts
				(arc
					(start 0.6096 0)
					(mid -0.6096 0)
					(end 0.6096 0)
				)
			)
			(stroke
				(width 0)
				(type default)
			)
			(fill no)
			(layer "F.Fab")
		)
		(pad "1" smd circle
			(at 0 0)
			(size 0.7112 0.7112)
			(layers "F.Cu" "F.Mask" "F.Paste")
			(net "JTAG_BMC_TCK")
		)
	)
	(footprint ""
		(layer "F.Cu")
		(at 169.789348 -122.545856 180)
		(property "Reference" "PR163"
			(at 0 0 180)
			(layer "F.SilkS")
			(hide yes)
			(effects
				(font
					(size 1.27 1.27)
				)
			)
		)
		(property "Value" "100KR2F-L1-GP"
			(at 0.064008 -3.993896 180)
			(unlocked yes)
			(layer "F.Fab")
			(hide yes)
			(effects
				(font
					(size 1.016 1.016)
					(thickness 0.1524)
				)
			)
		)
		(property "Device Type" "R402H16"
			(at 0.064008 -5.517896 180)
			(unlocked yes)
			(layer "F.Fab")
			(hide yes)
			(effects
				(font
					(size 1.016 1.016)
					(thickness 0.1524)
				)
			)
		)
		(duplicate_pad_numbers_are_jumpers no)
		(fp_line
			(start 0.508 -0.9398)
			(end -0.508 -0.9398)
			(stroke
				(width 0.1524)
				(type default)
			)
			(layer "F.SilkS")
		)
		(fp_line
			(start -0.508 -0.9398)
			(end -0.508 0.9398)
			(stroke
				(width 0.1524)
				(type default)
			)
			(layer "F.SilkS")
		)
		(fp_rect
			(start -0.508 0.9398)
			(end 0.508 -0.9398)
			(stroke
				(width 0)
				(type default)
			)
			(fill no)
			(layer "F.CrtYd")
		)
		(fp_rect
			(start -0.508 0.9398)
			(end 0.508 -0.9398)
			(stroke
				(width 0)
				(type default)
			)
			(fill no)
			(layer "F.Fab")
		)
		(pad "1" smd custom
			(at 0 -0.4445 180)
			(size 0.1397 0.1397)
			(layers "F.Cu" "F.Mask" "F.Paste")
			(net "P0V9_E_MODE")
			(options
				(clearance outline)
				(anchor circle)
			)
			(primitives
				(gr_poly
					(pts
						(arc
							(start -0.1778 -0.2794)
							(mid -0.249642 -0.249642)
							(end -0.2794 -0.1778)
						)
						(arc
							(start -0.2794 0.1778)
							(mid -0.249642 0.249642)
							(end -0.1778 0.2794)
						)
						(arc
							(start 0.1778 0.2794)
							(mid 0.249642 0.249642)
							(end 0.2794 0.1778)
						)
						(arc
							(start 0.2794 -0.1778)
							(mid 0.249642 -0.249642)
							(end 0.1778 -0.2794)
						)
					)
					(width 0)
					(fill yes)
				)
			)
		)
		(pad "2" smd custom
			(at 0 0.4445 180)
			(size 0.1397 0.1397)
			(layers "F.Cu" "F.Mask" "F.Paste")
			(net "AGND_P0V9_E")
			(options
				(clearance outline)
				(anchor circle)
			)
			(primitives
				(gr_poly
					(pts
						(arc
							(start -0.1778 -0.2794)
							(mid -0.249642 -0.249642)
							(end -0.2794 -0.1778)
						)
						(arc
							(start -0.2794 0.1778)
							(mid -0.249642 0.249642)
							(end -0.1778 0.2794)
						)
						(arc
							(start 0.1778 0.2794)
							(mid 0.249642 0.249642)
							(end 0.2794 0.1778)
						)
						(arc
							(start 0.2794 -0.1778)
							(mid 0.249642 -0.249642)
							(end 0.1778 -0.2794)
						)
					)
					(width 0)
					(fill yes)
				)
			)
		)
	)
	(footprint ""
		(layer "F.Cu")
		(at 117.964966 -43.815 -90)
		(property "Reference" "SR614"
			(at 0 0 270)
			(layer "F.SilkS")
			(hide yes)
			(effects
				(font
					(size 1.27 1.27)
				)
			)
		)
		(property "Value" "2K2R2F-GP"
			(at 0.064008 -3.993896 270)
			(unlocked yes)
			(layer "F.Fab")
			(hide yes)
			(effects
				(font
					(size 1.016 1.016)
					(thickness 0.1524)
				)
			)
		)
		(property "Device Type" "R402H16"
			(at 0.064008 -5.517896 270)
			(unlocked yes)
			(layer "F.Fab")
			(hide yes)
			(effects
				(font
					(size 1.016 1.016)
					(thickness 0.1524)
				)
			)
		)
		(duplicate_pad_numbers_are_jumpers no)
		(fp_line
			(start -0.508 -0.9398)
			(end -0.508 0.9398)
			(stroke
				(width 0.1524)
				(type default)
			)
			(layer "F.SilkS")
		)
		(fp_line
			(start 0.508 -0.9398)
			(end -0.508 -0.9398)
			(stroke
				(width 0.1524)
				(type default)
			)
			(layer "F.SilkS")
		)
		(fp_rect
			(start -0.508 0.9398)
			(end 0.508 -0.9398)
			(stroke
				(width 0)
				(type default)
			)
			(fill no)
			(layer "F.CrtYd")
		)
		(fp_rect
			(start -0.508 0.9398)
			(end 0.508 -0.9398)
			(stroke
				(width 0)
				(type default)
			)
			(fill no)
			(layer "F.Fab")
		)
		(pad "1" smd custom
			(at 0 -0.4445 270)
			(size 0.1397 0.1397)
			(layers "F.Cu" "F.Mask" "F.Paste")
			(net "P1V8_C")
			(options
				(clearance outline)
				(anchor circle)
			)
			(primitives
				(gr_poly
					(pts
						(arc
							(start -0.1778 -0.2794)
							(mid -0.249642 -0.249642)
							(end -0.2794 -0.1778)
						)
						(arc
							(start -0.2794 0.1778)
							(mid -0.249642 0.249642)
							(end -0.1778 0.2794)
						)
						(arc
							(start 0.1778 0.2794)
							(mid 0.249642 0.249642)
							(end 0.2794 0.1778)
						)
						(arc
							(start 0.2794 -0.1778)
							(mid 0.249642 -0.249642)
							(end 0.1778 -0.2794)
						)
					)
					(width 0)
					(fill yes)
				)
			)
		)
		(pad "2" smd custom
			(at 0 0.4445 270)
			(size 0.1397 0.1397)
			(layers "F.Cu" "F.Mask" "F.Paste")
			(net "SBL_SCL")
			(options
				(clearance outline)
				(anchor circle)
			)
			(primitives
				(gr_poly
					(pts
						(arc
							(start -0.1778 -0.2794)
							(mid -0.249642 -0.249642)
							(end -0.2794 -0.1778)
						)
						(arc
							(start -0.2794 0.1778)
							(mid -0.249642 0.249642)
							(end -0.1778 0.2794)
						)
						(arc
							(start 0.1778 0.2794)
							(mid 0.249642 0.249642)
							(end 0.2794 0.1778)
						)
						(arc
							(start 0.2794 -0.1778)
							(mid 0.249642 -0.249642)
							(end 0.1778 -0.2794)
						)
					)
					(width 0)
					(fill yes)
				)
			)
		)
	)
	(footprint ""
		(layer "F.Cu")
		(at 322.444872 -112.848136 180)
		(property "Reference" "PU2"
			(at 0 0 180)
			(layer "F.SilkS")
			(hide yes)
			(effects
				(font
					(size 1.27 1.27)
				)
			)
		)
		(property "Value" "TPS53318DQPR-GP"
			(at -5.022088 -6.851904 180)
			(unlocked yes)
			(layer "F.Fab")
			(hide yes)
			(effects
				(font
					(size 1.016 1.016)
					(thickness 0.1524)
				)
			)
		)
		(property "Device Type" "DFN22G6050-G6133H60"
			(at -5.022088 -8.375904 180)
			(unlocked yes)
			(layer "F.Fab")
			(hide yes)
			(effects
				(font
					(size 1.016 1.016)
					(thickness 0.1524)
				)
			)
		)
		(duplicate_pad_numbers_are_jumpers no)
		(fp_line
			(start 3.5052 3.5179)
			(end 3.5052 2.2479)
			(stroke
				(width 0.1524)
				(type default)
			)
			(layer "F.SilkS")
		)
		(fp_line
			(start 2.2352 3.5179)
			(end 3.5052 3.5179)
			(stroke
				(width 0.1524)
				(type default)
			)
			(layer "F.SilkS")
		)
		(fp_line
			(start 1.500124 3.262122)
			(end 1.500124 4.024122)
			(stroke
				(width 0.1524)
				(type default)
			)
			(layer "F.SilkS")
		)
		(fp_line
			(start 0.500126 -3.262122)
			(end 0.500126 -3.770122)
			(stroke
				(width 0.1524)
				(type default)
			)
			(layer "F.SilkS")
		)
		(fp_line
			(start -0.999998 3.262122)
			(end -0.999998 3.770122)
			(stroke
				(width 0.1524)
				(type default)
			)
			(layer "F.SilkS")
		)
		(fp_line
			(start -1.999996 -3.262122)
			(end -1.999996 -4.024122)
			(stroke
				(width 0.1524)
				(type default)
			)
			(layer "F.SilkS")
		)
		(fp_line
			(start -2.2352 -3.5179)
			(end -3.5052 -3.5179)
			(stroke
				(width 0.1524)
				(type default)
			)
			(layer "F.SilkS")
		)
		(fp_line
			(start -3.5052 3.5179)
			(end -2.2352 3.5179)
			(stroke
				(width 0.1524)
				(type default)
			)
			(layer "F.SilkS")
		)
		(fp_line
			(start -3.5052 2.2479)
			(end -3.5052 3.5179)
			(stroke
				(width 0.1524)
				(type default)
			)
			(layer "F.SilkS")
		)
		(fp_line
			(start -3.5052 -3.5179)
			(end -3.5052 -2.2479)
			(stroke
				(width 0.1524)
				(type default)
			)
			(layer "F.SilkS")
		)
		(fp_poly
			(pts
				(xy 3.5052 -3.5179) (xy 2.4765 -3.5179) (xy 3.5052 -2.4892)
			)
			(stroke
				(width 0)
				(type default)
			)
			(fill yes)
			(layer "F.SilkS")
		)
		(fp_rect
			(start -2.9972 2.5019)
			(end 2.9972 -2.5019)
			(stroke
				(width 0)
				(type default)
			)
			(fill no)
			(layer "F.CrtYd")
		)
		(fp_poly
			(pts
				(xy 3.556 -2.5019) (xy -2.9972 -2.5019) (xy -2.9972 2.5019) (xy 2.9972 2.5019) (xy 2.9972 -2.4892)
				(xy 3.556 -2.4892) (xy 3.556 3.5179) (xy -3.556 3.5179) (xy -3.556 -3.5179) (xy 3.556 -3.5179)
			)
			(stroke
				(width 0)
				(type default)
			)
			(fill no)
			(layer "F.CrtYd")
		)
		(fp_rect
			(start -3.556 3.5179)
			(end 3.556 -3.5179)
			(stroke
				(width 0)
				(type default)
			)
			(fill no)
			(layer "F.Fab")
		)
		(pad "1" smd rect
			(at 2.500122 -2.449322 180)
			(size 0.3048 1.1176)
			(layers "F.Cu" "F.Mask" "F.Paste")
			(net "P3V3_STBY_VFB")
		)
		(pad "2" smd rect
			(at 1.999996 -2.449322 180)
			(size 0.3048 1.1176)
			(layers "F.Cu" "F.Mask" "F.Paste")
			(net "P3V3_STBY_EN")
		)
		(pad "3" smd rect
			(at 1.500124 -2.449322 180)
			(size 0.3048 1.1176)
			(layers "F.Cu" "F.Mask" "F.Paste")
			(net "P3V3_STBY_PG")
		)
		(pad "4" smd rect
			(at 0.999998 -2.449322 180)
			(size 0.3048 1.1176)
			(layers "F.Cu" "F.Mask" "F.Paste")
			(net "P3V3_STBY_VBST")
		)
		(pad "5" smd rect
			(at 0.500126 -2.449322 180)
			(size 0.3048 1.1176)
			(layers "F.Cu" "F.Mask" "F.Paste")
			(net "P3V3_STBY_ROVP")
		)
		(pad "6" smd rect
			(at 0 -2.449322 180)
			(size 0.3048 1.1176)
			(layers "F.Cu" "F.Mask" "F.Paste")
			(net "P3V3_STBY_LL")
		)
		(pad "7" smd rect
			(at -0.500126 -2.449322 180)
			(size 0.3048 1.1176)
			(layers "F.Cu" "F.Mask" "F.Paste")
			(net "P3V3_STBY_LL")
		)
		(pad "8" smd rect
			(at -0.999998 -2.449322 180)
			(size 0.3048 1.1176)
			(layers "F.Cu" "F.Mask" "F.Paste")
			(net "P3V3_STBY_LL")
		)
		(pad "9" smd rect
			(at -1.500124 -2.449322 180)
			(size 0.3048 1.1176)
			(layers "F.Cu" "F.Mask" "F.Paste")
			(net "P3V3_STBY_LL")
		)
		(pad "10" smd rect
			(at -1.999996 -2.449322 180)
			(size 0.3048 1.1176)
			(layers "F.Cu" "F.Mask" "F.Paste")
			(net "P3V3_STBY_LL")
		)
		(pad "11" smd rect
			(at -2.500122 -2.449322 180)
			(size 0.3048 1.1176)
			(layers "F.Cu" "F.Mask" "F.Paste")
			(net "P3V3_STBY_LL")
		)
		(pad "12" smd rect
			(at -2.500122 2.449322 180)
			(size 0.3048 1.1176)
			(layers "F.Cu" "F.Mask" "F.Paste")
			(net "P3V3_STBY_VIN")
		)
		(pad "13" smd rect
			(at -1.999996 2.449322 180)
			(size 0.3048 1.1176)
			(layers "F.Cu" "F.Mask" "F.Paste")
			(net "P3V3_STBY_VIN")
		)
		(pad "14" smd rect
			(at -1.500124 2.449322 180)
			(size 0.3048 1.1176)
			(layers "F.Cu" "F.Mask" "F.Paste")
			(net "P3V3_STBY_VIN")
		)
		(pad "15" smd rect
			(at -0.999998 2.449322 180)
			(size 0.3048 1.1176)
			(layers "F.Cu" "F.Mask" "F.Paste")
			(net "P3V3_STBY_VIN")
		)
		(pad "16" smd rect
			(at -0.500126 2.449322 180)
			(size 0.3048 1.1176)
			(layers "F.Cu" "F.Mask" "F.Paste")
			(net "P3V3_STBY_VIN")
		)
		(pad "17" smd rect
			(at 0 2.449322 180)
			(size 0.3048 1.1176)
			(layers "F.Cu" "F.Mask" "F.Paste")
			(net "P3V3_STBY_VIN")
		)
		(pad "18" smd rect
			(at 0.500126 2.449322 180)
			(size 0.3048 1.1176)
			(layers "F.Cu" "F.Mask" "F.Paste")
			(net "P3V3_STBY_VREG")
		)
		(pad "19" smd rect
			(at 0.999998 2.449322 180)
			(size 0.3048 1.1176)
			(layers "F.Cu" "F.Mask" "F.Paste")
			(net "P3V3_STBY_VDD")
		)
		(pad "20" smd rect
			(at 1.500124 2.449322 180)
			(size 0.3048 1.1176)
			(layers "F.Cu" "F.Mask" "F.Paste")
			(net "P3V3_STBY_MODE")
		)
		(pad "21" smd rect
			(at 1.999996 2.449322 180)
			(size 0.3048 1.1176)
			(layers "F.Cu" "F.Mask" "F.Paste")
			(net "P3V3_STBY_TRIP")
		)
		(pad "22" smd rect
			(at 2.500122 2.449322 180)
			(size 0.3048 1.1176)
			(layers "F.Cu" "F.Mask" "F.Paste")
			(net "P3V3_STBY_RF")
		)
		(pad "23" smd custom
			(at 0 0 180)
			(size 0.83185 0.83185)
			(layers "F.Cu" "F.Mask" "F.Paste")
			(net "GND")
			(options
				(clearance outline)
				(anchor circle)
			)
			(primitives
				(gr_poly
					(pts
						(xy -2.7813 1.6637) (xy -2.7813 1.2954) (xy -3.048 1.2954) (xy -3.048 0.9525) (xy -2.7813 0.9525)
						(xy -2.7813 -0.9525) (xy -3.048 -0.9525) (xy -3.048 -1.2954) (xy -2.7813 -1.2954) (xy -2.7813 -1.6637)
						(xy 2.7813 -1.6637) (xy 2.7813 -1.2954) (xy 3.048 -1.2954) (xy 3.048 -0.9525) (xy 2.7813 -0.9525)
						(xy 2.7813 0.9525) (xy 3.048 0.9525) (xy 3.048 1.2954) (xy 2.7813 1.2954) (xy 2.7813 1.6637)
					)
					(width 0)
					(fill yes)
				)
			)
		)
	)
	(footprint ""
		(layer "F.Cu")
		(at 101.727 -67.4116 90)
		(property "Reference" "SR709"
			(at 0 0 90)
			(layer "F.SilkS")
			(hide yes)
			(effects
				(font
					(size 1.27 1.27)
				)
			)
		)
		(property "Value" "10R2F-L-GP"
			(at 0.064008 -3.993896 90)
			(unlocked yes)
			(layer "F.Fab")
			(hide yes)
			(effects
				(font
					(size 1.016 1.016)
					(thickness 0.1524)
				)
			)
		)
		(property "Device Type" "R402H14"
			(at 0.064008 -5.517896 90)
			(unlocked yes)
			(layer "F.Fab")
			(hide yes)
			(effects
				(font
					(size 1.016 1.016)
					(thickness 0.1524)
				)
			)
		)
		(duplicate_pad_numbers_are_jumpers no)
		(fp_line
			(start 0.508 -0.9398)
			(end -0.508 -0.9398)
			(stroke
				(width 0.1524)
				(type default)
			)
			(layer "F.SilkS")
		)
		(fp_line
			(start -0.508 -0.9398)
			(end -0.508 0.9398)
			(stroke
				(width 0.1524)
				(type default)
			)
			(layer "F.SilkS")
		)
		(fp_rect
			(start -0.508 0.9398)
			(end 0.508 -0.9398)
			(stroke
				(width 0)
				(type default)
			)
			(fill no)
			(layer "F.CrtYd")
		)
		(fp_rect
			(start -0.508 0.9398)
			(end 0.508 -0.9398)
			(stroke
				(width 0)
				(type default)
			)
			(fill no)
			(layer "F.Fab")
		)
		(pad "1" smd custom
			(at 0 -0.4445 90)
			(size 0.1397 0.1397)
			(layers "F.Cu" "F.Mask" "F.Paste")
			(net "P1V8_C")
			(options
				(clearance outline)
				(anchor circle)
			)
			(primitives
				(gr_poly
					(pts
						(arc
							(start -0.1778 -0.2794)
							(mid -0.249642 -0.249642)
							(end -0.2794 -0.1778)
						)
						(arc
							(start -0.2794 0.1778)
							(mid -0.249642 0.249642)
							(end -0.1778 0.2794)
						)
						(arc
							(start 0.1778 0.2794)
							(mid 0.249642 0.249642)
							(end 0.2794 0.1778)
						)
						(arc
							(start 0.2794 -0.1778)
							(mid 0.249642 -0.249642)
							(end 0.1778 -0.2794)
						)
					)
					(width 0)
					(fill yes)
				)
			)
		)
		(pad "2" smd custom
			(at 0 0.4445 90)
			(size 0.1397 0.1397)
			(layers "F.Cu" "F.Mask" "F.Paste")
			(net "HM40ADC_VDDA")
			(options
				(clearance outline)
				(anchor circle)
			)
			(primitives
				(gr_poly
					(pts
						(arc
							(start -0.1778 -0.2794)
							(mid -0.249642 -0.249642)
							(end -0.2794 -0.1778)
						)
						(arc
							(start -0.2794 0.1778)
							(mid -0.249642 0.249642)
							(end -0.1778 0.2794)
						)
						(arc
							(start 0.1778 0.2794)
							(mid 0.249642 0.249642)
							(end 0.2794 0.1778)
						)
						(arc
							(start 0.2794 -0.1778)
							(mid 0.249642 -0.249642)
							(end 0.1778 -0.2794)
						)
					)
					(width 0)
					(fill yes)
				)
			)
		)
	)
	(footprint ""
		(layer "F.Cu")
		(at 333.9338 -145.542 90)
		(property "Reference" "R7897"
			(at 0 0 90)
			(layer "F.SilkS")
			(hide yes)
			(effects
				(font
					(size 1.27 1.27)
				)
			)
		)
		(property "Value" "4K7R2F-GP"
			(at 0.064008 -3.993896 90)
			(unlocked yes)
			(layer "F.Fab")
			(hide yes)
			(effects
				(font
					(size 1.016 1.016)
					(thickness 0.1524)
				)
			)
		)
		(property "Device Type" "R402H16"
			(at 0.064008 -5.517896 90)
			(unlocked yes)
			(layer "F.Fab")
			(hide yes)
			(effects
				(font
					(size 1.016 1.016)
					(thickness 0.1524)
				)
			)
		)
		(duplicate_pad_numbers_are_jumpers no)
		(fp_line
			(start 0.508 -0.9398)
			(end -0.508 -0.9398)
			(stroke
				(width 0.1524)
				(type default)
			)
			(layer "F.SilkS")
		)
		(fp_line
			(start -0.508 -0.9398)
			(end -0.508 0.9398)
			(stroke
				(width 0.1524)
				(type default)
			)
			(layer "F.SilkS")
		)
		(fp_rect
			(start -0.508 0.9398)
			(end 0.508 -0.9398)
			(stroke
				(width 0)
				(type default)
			)
			(fill no)
			(layer "F.CrtYd")
		)
		(fp_rect
			(start -0.508 0.9398)
			(end 0.508 -0.9398)
			(stroke
				(width 0)
				(type default)
			)
			(fill no)
			(layer "F.Fab")
		)
		(pad "1" smd custom
			(at 0 -0.4445 90)
			(size 0.1397 0.1397)
			(layers "F.Cu" "F.Mask" "F.Paste")
			(net "P3V3_STBY")
			(options
				(clearance outline)
				(anchor circle)
			)
			(primitives
				(gr_poly
					(pts
						(arc
							(start -0.1778 -0.2794)
							(mid -0.249642 -0.249642)
							(end -0.2794 -0.1778)
						)
						(arc
							(start -0.2794 0.1778)
							(mid -0.249642 0.249642)
							(end -0.1778 0.2794)
						)
						(arc
							(start 0.1778 0.2794)
							(mid 0.249642 0.249642)
							(end 0.2794 0.1778)
						)
						(arc
							(start 0.2794 -0.1778)
							(mid 0.249642 -0.249642)
							(end 0.1778 -0.2794)
						)
					)
					(width 0)
					(fill yes)
				)
			)
		)
		(pad "2" smd custom
			(at 0 0.4445 90)
			(size 0.1397 0.1397)
			(layers "F.Cu" "F.Mask" "F.Paste")
			(net "USB_RESET_N")
			(options
				(clearance outline)
				(anchor circle)
			)
			(primitives
				(gr_poly
					(pts
						(arc
							(start -0.1778 -0.2794)
							(mid -0.249642 -0.249642)
							(end -0.2794 -0.1778)
						)
						(arc
							(start -0.2794 0.1778)
							(mid -0.249642 0.249642)
							(end -0.1778 0.2794)
						)
						(arc
							(start 0.1778 0.2794)
							(mid 0.249642 0.249642)
							(end 0.2794 0.1778)
						)
						(arc
							(start 0.2794 -0.1778)
							(mid 0.249642 -0.249642)
							(end 0.1778 -0.2794)
						)
					)
					(width 0)
					(fill yes)
				)
			)
		)
	)
	(footprint ""
		(layer "F.Cu")
		(at 23.564088 -181.865016)
		(property "Reference" "SR313"
			(at 0 0 0)
			(layer "F.SilkS")
			(hide yes)
			(effects
				(font
					(size 1.27 1.27)
				)
			)
		)
		(property "Value" "0R2J-2-GP"
			(at 0.064008 -3.993896 0)
			(unlocked yes)
			(layer "F.Fab")
			(hide yes)
			(effects
				(font
					(size 1.016 1.016)
					(thickness 0.1524)
				)
			)
		)
		(property "Device Type" "R402H16"
			(at 0.064008 -5.517896 0)
			(unlocked yes)
			(layer "F.Fab")
			(hide yes)
			(effects
				(font
					(size 1.016 1.016)
					(thickness 0.1524)
				)
			)
		)
		(duplicate_pad_numbers_are_jumpers no)
		(fp_line
			(start -0.508 -0.9398)
			(end -0.508 0.9398)
			(stroke
				(width 0.1524)
				(type default)
			)
			(layer "F.SilkS")
		)
		(fp_line
			(start 0.508 -0.9398)
			(end -0.508 -0.9398)
			(stroke
				(width 0.1524)
				(type default)
			)
			(layer "F.SilkS")
		)
		(fp_rect
			(start -0.508 0.9398)
			(end 0.508 -0.9398)
			(stroke
				(width 0)
				(type default)
			)
			(fill no)
			(layer "F.CrtYd")
		)
		(fp_rect
			(start -0.508 0.9398)
			(end 0.508 -0.9398)
			(stroke
				(width 0)
				(type default)
			)
			(fill no)
			(layer "F.Fab")
		)
		(pad "1" smd custom
			(at 0 -0.4445)
			(size 0.1397 0.1397)
			(layers "F.Cu" "F.Mask" "F.Paste")
			(net "PRE_SDA")
			(options
				(clearance outline)
				(anchor circle)
			)
			(primitives
				(gr_poly
					(pts
						(arc
							(start -0.1778 -0.2794)
							(mid -0.249642 -0.249642)
							(end -0.2794 -0.1778)
						)
						(arc
							(start -0.2794 0.1778)
							(mid -0.249642 0.249642)
							(end -0.1778 0.2794)
						)
						(arc
							(start 0.1778 0.2794)
							(mid 0.249642 0.249642)
							(end 0.2794 0.1778)
						)
						(arc
							(start 0.2794 -0.1778)
							(mid 0.249642 -0.249642)
							(end 0.1778 -0.2794)
						)
					)
					(width 0)
					(fill yes)
				)
			)
		)
		(pad "2" smd custom
			(at 0 0.4445)
			(size 0.1397 0.1397)
			(layers "F.Cu" "F.Mask" "F.Paste")
			(net "BMC_IOEXP_SDA_10")
			(options
				(clearance outline)
				(anchor circle)
			)
			(primitives
				(gr_poly
					(pts
						(arc
							(start -0.1778 -0.2794)
							(mid -0.249642 -0.249642)
							(end -0.2794 -0.1778)
						)
						(arc
							(start -0.2794 0.1778)
							(mid -0.249642 0.249642)
							(end -0.1778 0.2794)
						)
						(arc
							(start 0.1778 0.2794)
							(mid 0.249642 0.249642)
							(end 0.2794 0.1778)
						)
						(arc
							(start 0.2794 -0.1778)
							(mid 0.249642 -0.249642)
							(end 0.1778 -0.2794)
						)
					)
					(width 0)
					(fill yes)
				)
			)
		)
	)
	(footprint ""
		(layer "F.Cu")
		(at 90.18397 -139.954 180)
		(property "Reference" "R157"
			(at 0 0 180)
			(layer "F.SilkS")
			(hide yes)
			(effects
				(font
					(size 1.27 1.27)
				)
			)
		)
		(property "Value" "0R2J-2-GP"
			(at 0.064008 -3.993896 180)
			(unlocked yes)
			(layer "F.Fab")
			(hide yes)
			(effects
				(font
					(size 1.016 1.016)
					(thickness 0.1524)
				)
			)
		)
		(property "Device Type" "R402H16"
			(at 0.064008 -5.517896 180)
			(unlocked yes)
			(layer "F.Fab")
			(hide yes)
			(effects
				(font
					(size 1.016 1.016)
					(thickness 0.1524)
				)
			)
		)
		(duplicate_pad_numbers_are_jumpers no)
		(fp_line
			(start 0.508 -0.9398)
			(end -0.508 -0.9398)
			(stroke
				(width 0.1524)
				(type default)
			)
			(layer "F.SilkS")
		)
		(fp_line
			(start -0.508 -0.9398)
			(end -0.508 0.9398)
			(stroke
				(width 0.1524)
				(type default)
			)
			(layer "F.SilkS")
		)
		(fp_rect
			(start -0.508 0.9398)
			(end 0.508 -0.9398)
			(stroke
				(width 0)
				(type default)
			)
			(fill no)
			(layer "F.CrtYd")
		)
		(fp_rect
			(start -0.508 0.9398)
			(end 0.508 -0.9398)
			(stroke
				(width 0)
				(type default)
			)
			(fill no)
			(layer "F.Fab")
		)
		(pad "1" smd custom
			(at 0 -0.4445 180)
			(size 0.1397 0.1397)
			(layers "F.Cu" "F.Mask" "F.Paste")
			(net "EXP_SELF_TRAY")
			(options
				(clearance outline)
				(anchor circle)
			)
			(primitives
				(gr_poly
					(pts
						(arc
							(start -0.1778 -0.2794)
							(mid -0.249642 -0.249642)
							(end -0.2794 -0.1778)
						)
						(arc
							(start -0.2794 0.1778)
							(mid -0.249642 0.249642)
							(end -0.1778 0.2794)
						)
						(arc
							(start 0.1778 0.2794)
							(mid 0.249642 0.249642)
							(end 0.2794 0.1778)
						)
						(arc
							(start 0.2794 -0.1778)
							(mid 0.249642 -0.249642)
							(end 0.1778 -0.2794)
						)
					)
					(width 0)
					(fill yes)
				)
			)
		)
		(pad "2" smd custom
			(at 0 0.4445 180)
			(size 0.1397 0.1397)
			(layers "F.Cu" "F.Mask" "F.Paste")
			(net "SELF_TRAY")
			(options
				(clearance outline)
				(anchor circle)
			)
			(primitives
				(gr_poly
					(pts
						(arc
							(start -0.1778 -0.2794)
							(mid -0.249642 -0.249642)
							(end -0.2794 -0.1778)
						)
						(arc
							(start -0.2794 0.1778)
							(mid -0.249642 0.249642)
							(end -0.1778 0.2794)
						)
						(arc
							(start 0.1778 0.2794)
							(mid 0.249642 0.249642)
							(end 0.2794 0.1778)
						)
						(arc
							(start 0.2794 -0.1778)
							(mid 0.249642 -0.249642)
							(end 0.1778 -0.2794)
						)
					)
					(width 0)
					(fill yes)
				)
			)
		)
	)
	(footprint ""
		(layer "F.Cu")
		(at 96.66097 -118.3005 180)
		(property "Reference" "SR745"
			(at 0 0 180)
			(layer "F.SilkS")
			(hide yes)
			(effects
				(font
					(size 1.27 1.27)
				)
			)
		)
		(property "Value" "4K7R2F-GP"
			(at 0.064008 -3.993896 180)
			(unlocked yes)
			(layer "F.Fab")
			(hide yes)
			(effects
				(font
					(size 1.016 1.016)
					(thickness 0.1524)
				)
			)
		)
		(property "Device Type" "R402H16"
			(at 0.064008 -5.517896 180)
			(unlocked yes)
			(layer "F.Fab")
			(hide yes)
			(effects
				(font
					(size 1.016 1.016)
					(thickness 0.1524)
				)
			)
		)
		(duplicate_pad_numbers_are_jumpers no)
		(fp_line
			(start 0.508 -0.9398)
			(end -0.508 -0.9398)
			(stroke
				(width 0.1524)
				(type default)
			)
			(layer "F.SilkS")
		)
		(fp_line
			(start -0.508 -0.9398)
			(end -0.508 0.9398)
			(stroke
				(width 0.1524)
				(type default)
			)
			(layer "F.SilkS")
		)
		(fp_rect
			(start -0.508 0.9398)
			(end 0.508 -0.9398)
			(stroke
				(width 0)
				(type default)
			)
			(fill no)
			(layer "F.CrtYd")
		)
		(fp_rect
			(start -0.508 0.9398)
			(end 0.508 -0.9398)
			(stroke
				(width 0)
				(type default)
			)
			(fill no)
			(layer "F.Fab")
		)
		(pad "1" smd custom
			(at 0 -0.4445 180)
			(size 0.1397 0.1397)
			(layers "F.Cu" "F.Mask" "F.Paste")
			(net "EXP_SIO_CLK_IN")
			(options
				(clearance outline)
				(anchor circle)
			)
			(primitives
				(gr_poly
					(pts
						(arc
							(start -0.1778 -0.2794)
							(mid -0.249642 -0.249642)
							(end -0.2794 -0.1778)
						)
						(arc
							(start -0.2794 0.1778)
							(mid -0.249642 0.249642)
							(end -0.1778 0.2794)
						)
						(arc
							(start 0.1778 0.2794)
							(mid 0.249642 0.249642)
							(end 0.2794 0.1778)
						)
						(arc
							(start 0.2794 -0.1778)
							(mid 0.249642 -0.249642)
							(end 0.1778 -0.2794)
						)
					)
					(width 0)
					(fill yes)
				)
			)
		)
		(pad "2" smd custom
			(at 0 0.4445 180)
			(size 0.1397 0.1397)
			(layers "F.Cu" "F.Mask" "F.Paste")
			(net "P1V8_E")
			(options
				(clearance outline)
				(anchor circle)
			)
			(primitives
				(gr_poly
					(pts
						(arc
							(start -0.1778 -0.2794)
							(mid -0.249642 -0.249642)
							(end -0.2794 -0.1778)
						)
						(arc
							(start -0.2794 0.1778)
							(mid -0.249642 0.249642)
							(end -0.1778 0.2794)
						)
						(arc
							(start 0.1778 0.2794)
							(mid 0.249642 0.249642)
							(end 0.2794 0.1778)
						)
						(arc
							(start 0.2794 -0.1778)
							(mid 0.249642 -0.249642)
							(end 0.1778 -0.2794)
						)
					)
					(width 0)
					(fill yes)
				)
			)
		)
	)
	(footprint ""
		(layer "F.Cu")
		(at 159.893 -155.6766 -90)
		(property "Reference" "SR727"
			(at 0 0 270)
			(layer "F.SilkS")
			(hide yes)
			(effects
				(font
					(size 1.27 1.27)
				)
			)
		)
		(property "Value" "0R2J-2-GP"
			(at 0.064008 -3.993896 270)
			(unlocked yes)
			(layer "F.Fab")
			(hide yes)
			(effects
				(font
					(size 1.016 1.016)
					(thickness 0.1524)
				)
			)
		)
		(property "Device Type" "R402H16"
			(at 0.064008 -5.517896 270)
			(unlocked yes)
			(layer "F.Fab")
			(hide yes)
			(effects
				(font
					(size 1.016 1.016)
					(thickness 0.1524)
				)
			)
		)
		(duplicate_pad_numbers_are_jumpers no)
		(fp_line
			(start -0.508 -0.9398)
			(end -0.508 0.9398)
			(stroke
				(width 0.1524)
				(type default)
			)
			(layer "F.SilkS")
		)
		(fp_line
			(start 0.508 -0.9398)
			(end -0.508 -0.9398)
			(stroke
				(width 0.1524)
				(type default)
			)
			(layer "F.SilkS")
		)
		(fp_rect
			(start -0.508 0.9398)
			(end 0.508 -0.9398)
			(stroke
				(width 0)
				(type default)
			)
			(fill no)
			(layer "F.CrtYd")
		)
		(fp_rect
			(start -0.508 0.9398)
			(end 0.508 -0.9398)
			(stroke
				(width 0)
				(type default)
			)
			(fill no)
			(layer "F.Fab")
		)
		(pad "1" smd custom
			(at 0 -0.4445 270)
			(size 0.1397 0.1397)
			(layers "F.Cu" "F.Mask" "F.Paste")
			(net "IOC_P3V3_R_SCL_14")
			(options
				(clearance outline)
				(anchor circle)
			)
			(primitives
				(gr_poly
					(pts
						(arc
							(start -0.1778 -0.2794)
							(mid -0.249642 -0.249642)
							(end -0.2794 -0.1778)
						)
						(arc
							(start -0.2794 0.1778)
							(mid -0.249642 0.249642)
							(end -0.1778 0.2794)
						)
						(arc
							(start 0.1778 0.2794)
							(mid 0.249642 0.249642)
							(end 0.2794 0.1778)
						)
						(arc
							(start 0.2794 -0.1778)
							(mid 0.249642 -0.249642)
							(end 0.1778 -0.2794)
						)
					)
					(width 0)
					(fill yes)
				)
			)
		)
		(pad "2" smd custom
			(at 0 0.4445 270)
			(size 0.1397 0.1397)
			(layers "F.Cu" "F.Mask" "F.Paste")
			(net "IOC_P3V3_SCL_14")
			(options
				(clearance outline)
				(anchor circle)
			)
			(primitives
				(gr_poly
					(pts
						(arc
							(start -0.1778 -0.2794)
							(mid -0.249642 -0.249642)
							(end -0.2794 -0.1778)
						)
						(arc
							(start -0.2794 0.1778)
							(mid -0.249642 0.249642)
							(end -0.1778 0.2794)
						)
						(arc
							(start 0.1778 0.2794)
							(mid 0.249642 0.249642)
							(end 0.2794 0.1778)
						)
						(arc
							(start 0.2794 -0.1778)
							(mid 0.249642 -0.249642)
							(end 0.1778 -0.2794)
						)
					)
					(width 0)
					(fill yes)
				)
			)
		)
	)
	(footprint ""
		(layer "F.Cu")
		(at 152.019 -52.07 90)
		(property "Reference" "SR698"
			(at 0 0 90)
			(layer "F.SilkS")
			(hide yes)
			(effects
				(font
					(size 1.27 1.27)
				)
			)
		)
		(property "Value" "10KR2F-2-GP"
			(at 0.064008 -3.993896 90)
			(unlocked yes)
			(layer "F.Fab")
			(hide yes)
			(effects
				(font
					(size 1.016 1.016)
					(thickness 0.1524)
				)
			)
		)
		(property "Device Type" "R402H16"
			(at 0.064008 -5.517896 90)
			(unlocked yes)
			(layer "F.Fab")
			(hide yes)
			(effects
				(font
					(size 1.016 1.016)
					(thickness 0.1524)
				)
			)
		)
		(duplicate_pad_numbers_are_jumpers no)
		(fp_line
			(start 0.508 -0.9398)
			(end -0.508 -0.9398)
			(stroke
				(width 0.1524)
				(type default)
			)
			(layer "F.SilkS")
		)
		(fp_line
			(start -0.508 -0.9398)
			(end -0.508 0.9398)
			(stroke
				(width 0.1524)
				(type default)
			)
			(layer "F.SilkS")
		)
		(fp_rect
			(start -0.508 0.9398)
			(end 0.508 -0.9398)
			(stroke
				(width 0)
				(type default)
			)
			(fill no)
			(layer "F.CrtYd")
		)
		(fp_rect
			(start -0.508 0.9398)
			(end 0.508 -0.9398)
			(stroke
				(width 0)
				(type default)
			)
			(fill no)
			(layer "F.Fab")
		)
		(pad "1" smd custom
			(at 0 -0.4445 90)
			(size 0.1397 0.1397)
			(layers "F.Cu" "F.Mask" "F.Paste")
			(net "XM_ADDR_4")
			(options
				(clearance outline)
				(anchor circle)
			)
			(primitives
				(gr_poly
					(pts
						(arc
							(start -0.1778 -0.2794)
							(mid -0.249642 -0.249642)
							(end -0.2794 -0.1778)
						)
						(arc
							(start -0.2794 0.1778)
							(mid -0.249642 0.249642)
							(end -0.1778 0.2794)
						)
						(arc
							(start 0.1778 0.2794)
							(mid 0.249642 0.249642)
							(end 0.2794 0.1778)
						)
						(arc
							(start 0.2794 -0.1778)
							(mid 0.249642 -0.249642)
							(end 0.1778 -0.2794)
						)
					)
					(width 0)
					(fill yes)
				)
			)
		)
		(pad "2" smd custom
			(at 0 0.4445 90)
			(size 0.1397 0.1397)
			(layers "F.Cu" "F.Mask" "F.Paste")
			(net "GND")
			(options
				(clearance outline)
				(anchor circle)
			)
			(primitives
				(gr_poly
					(pts
						(arc
							(start -0.1778 -0.2794)
							(mid -0.249642 -0.249642)
							(end -0.2794 -0.1778)
						)
						(arc
							(start -0.2794 0.1778)
							(mid -0.249642 0.249642)
							(end -0.1778 0.2794)
						)
						(arc
							(start 0.1778 0.2794)
							(mid 0.249642 0.249642)
							(end 0.2794 0.1778)
						)
						(arc
							(start 0.2794 -0.1778)
							(mid 0.249642 -0.249642)
							(end 0.1778 -0.2794)
						)
					)
					(width 0)
					(fill yes)
				)
			)
		)
	)
	(footprint ""
		(layer "F.Cu")
		(at 92.27947 -105.283 90)
		(property "Reference" "SR819"
			(at 0 0 90)
			(layer "F.SilkS")
			(hide yes)
			(effects
				(font
					(size 1.27 1.27)
				)
			)
		)
		(property "Value" "4K75R2F-1-GP"
			(at 0.064008 -3.993896 90)
			(unlocked yes)
			(layer "F.Fab")
			(hide yes)
			(effects
				(font
					(size 1.016 1.016)
					(thickness 0.1524)
				)
			)
		)
		(property "Device Type" "R402H16"
			(at 0.064008 -5.517896 90)
			(unlocked yes)
			(layer "F.Fab")
			(hide yes)
			(effects
				(font
					(size 1.016 1.016)
					(thickness 0.1524)
				)
			)
		)
		(duplicate_pad_numbers_are_jumpers no)
		(fp_line
			(start 0.508 -0.9398)
			(end -0.508 -0.9398)
			(stroke
				(width 0.1524)
				(type default)
			)
			(layer "F.SilkS")
		)
		(fp_line
			(start -0.508 -0.9398)
			(end -0.508 0.9398)
			(stroke
				(width 0.1524)
				(type default)
			)
			(layer "F.SilkS")
		)
		(fp_rect
			(start -0.508 0.9398)
			(end 0.508 -0.9398)
			(stroke
				(width 0)
				(type default)
			)
			(fill no)
			(layer "F.CrtYd")
		)
		(fp_rect
			(start -0.508 0.9398)
			(end 0.508 -0.9398)
			(stroke
				(width 0)
				(type default)
			)
			(fill no)
			(layer "F.Fab")
		)
		(pad "1" smd custom
			(at 0 -0.4445 90)
			(size 0.1397 0.1397)
			(layers "F.Cu" "F.Mask" "F.Paste")
			(net "P1V8_E")
			(options
				(clearance outline)
				(anchor circle)
			)
			(primitives
				(gr_poly
					(pts
						(arc
							(start -0.1778 -0.2794)
							(mid -0.249642 -0.249642)
							(end -0.2794 -0.1778)
						)
						(arc
							(start -0.2794 0.1778)
							(mid -0.249642 0.249642)
							(end -0.1778 0.2794)
						)
						(arc
							(start 0.1778 0.2794)
							(mid 0.249642 0.249642)
							(end 0.2794 0.1778)
						)
						(arc
							(start 0.2794 -0.1778)
							(mid 0.249642 -0.249642)
							(end 0.1778 -0.2794)
						)
					)
					(width 0)
					(fill yes)
				)
			)
		)
		(pad "2" smd custom
			(at 0 0.4445 90)
			(size 0.1397 0.1397)
			(layers "F.Cu" "F.Mask" "F.Paste")
			(net "SAS_SMART_TX")
			(options
				(clearance outline)
				(anchor circle)
			)
			(primitives
				(gr_poly
					(pts
						(arc
							(start -0.1778 -0.2794)
							(mid -0.249642 -0.249642)
							(end -0.2794 -0.1778)
						)
						(arc
							(start -0.2794 0.1778)
							(mid -0.249642 0.249642)
							(end -0.1778 0.2794)
						)
						(arc
							(start 0.1778 0.2794)
							(mid 0.249642 0.249642)
							(end 0.2794 0.1778)
						)
						(arc
							(start 0.2794 -0.1778)
							(mid 0.249642 -0.249642)
							(end 0.1778 -0.2794)
						)
					)
					(width 0)
					(fill yes)
				)
			)
		)
	)
	(footprint ""
		(layer "F.Cu")
		(at 78.848966 -67.564 180)
		(property "Reference" "SC983"
			(at 0 0 180)
			(layer "F.SilkS")
			(hide yes)
			(effects
				(font
					(size 1.27 1.27)
				)
			)
		)
		(property "Value" "SCD1U16V2KX-3GP"
			(at 1.1811 -2.7051 180)
			(unlocked yes)
			(layer "F.Fab")
			(hide yes)
			(effects
				(font
					(size 1.016 1.016)
					(thickness 0.1524)
				)
			)
		)
		(property "Device Type" "C402H22"
			(at 1.1811 -4.2291 180)
			(unlocked yes)
			(layer "F.Fab")
			(hide yes)
			(effects
				(font
					(size 1.016 1.016)
					(thickness 0.1524)
				)
			)
		)
		(duplicate_pad_numbers_are_jumpers no)
		(fp_rect
			(start -0.4318 0.9525)
			(end 0.4318 -0.9525)
			(stroke
				(width 0)
				(type default)
			)
			(fill no)
			(layer "F.CrtYd")
		)
		(fp_rect
			(start -0.4318 0.9525)
			(end 0.4318 -0.9525)
			(stroke
				(width 0)
				(type default)
			)
			(fill no)
			(layer "F.Fab")
		)
		(pad "1" smd custom
			(at 0 -0.4445 180)
			(size 0.1524 0.1524)
			(layers "F.Cu" "F.Mask" "F.Paste")
			(net "P1V8_C")
			(options
				(clearance outline)
				(anchor circle)
			)
			(primitives
				(gr_poly
					(pts
						(arc
							(start 0.3048 -0.2032)
							(mid 0.275042 -0.275042)
							(end 0.2032 -0.3048)
						)
						(arc
							(start -0.2032 -0.3048)
							(mid -0.275042 -0.275042)
							(end -0.3048 -0.2032)
						)
						(arc
							(start -0.3048 0.2032)
							(mid -0.275042 0.275042)
							(end -0.2032 0.3048)
						)
						(arc
							(start 0.2032 0.3048)
							(mid 0.275042 0.275042)
							(end 0.3048 0.2032)
						)
					)
					(width 0)
					(fill yes)
				)
			)
		)
		(pad "2" smd custom
			(at 0 0.4445 180)
			(size 0.1524 0.1524)
			(layers "F.Cu" "F.Mask" "F.Paste")
			(net "GND")
			(options
				(clearance outline)
				(anchor circle)
			)
			(primitives
				(gr_poly
					(pts
						(arc
							(start 0.3048 -0.2032)
							(mid 0.275042 -0.275042)
							(end 0.2032 -0.3048)
						)
						(arc
							(start -0.2032 -0.3048)
							(mid -0.275042 -0.275042)
							(end -0.3048 -0.2032)
						)
						(arc
							(start -0.3048 0.2032)
							(mid -0.275042 0.275042)
							(end -0.2032 0.3048)
						)
						(arc
							(start 0.2032 0.3048)
							(mid 0.275042 0.275042)
							(end 0.3048 0.2032)
						)
					)
					(width 0)
					(fill yes)
				)
			)
		)
	)
	(footprint ""
		(layer "F.Cu")
		(at 94.869 -4.191)
		(property "Reference" "SC1045"
			(at 0 0 0)
			(layer "F.SilkS")
			(hide yes)
			(effects
				(font
					(size 1.27 1.27)
				)
			)
		)
		(property "Value" "SCD1U16V2KX-3GP"
			(at 1.1811 -2.7051 0)
			(unlocked yes)
			(layer "F.Fab")
			(hide yes)
			(effects
				(font
					(size 1.016 1.016)
					(thickness 0.1524)
				)
			)
		)
		(property "Device Type" "C402H22"
			(at 1.1811 -4.2291 0)
			(unlocked yes)
			(layer "F.Fab")
			(hide yes)
			(effects
				(font
					(size 1.016 1.016)
					(thickness 0.1524)
				)
			)
		)
		(duplicate_pad_numbers_are_jumpers no)
		(fp_rect
			(start -0.4318 0.9525)
			(end 0.4318 -0.9525)
			(stroke
				(width 0)
				(type default)
			)
			(fill no)
			(layer "F.CrtYd")
		)
		(fp_rect
			(start -0.4318 0.9525)
			(end 0.4318 -0.9525)
			(stroke
				(width 0)
				(type default)
			)
			(fill no)
			(layer "F.Fab")
		)
		(pad "1" smd custom
			(at 0 -0.4445)
			(size 0.1524 0.1524)
			(layers "F.Cu" "F.Mask" "F.Paste")
			(net "P0V955_C")
			(options
				(clearance outline)
				(anchor circle)
			)
			(primitives
				(gr_poly
					(pts
						(arc
							(start 0.3048 -0.2032)
							(mid 0.275042 -0.275042)
							(end 0.2032 -0.3048)
						)
						(arc
							(start -0.2032 -0.3048)
							(mid -0.275042 -0.275042)
							(end -0.3048 -0.2032)
						)
						(arc
							(start -0.3048 0.2032)
							(mid -0.275042 0.275042)
							(end -0.2032 0.3048)
						)
						(arc
							(start 0.2032 0.3048)
							(mid 0.275042 0.275042)
							(end 0.3048 0.2032)
						)
					)
					(width 0)
					(fill yes)
				)
			)
		)
		(pad "2" smd custom
			(at 0 0.4445)
			(size 0.1524 0.1524)
			(layers "F.Cu" "F.Mask" "F.Paste")
			(net "GND")
			(options
				(clearance outline)
				(anchor circle)
			)
			(primitives
				(gr_poly
					(pts
						(arc
							(start 0.3048 -0.2032)
							(mid 0.275042 -0.275042)
							(end 0.2032 -0.3048)
						)
						(arc
							(start -0.2032 -0.3048)
							(mid -0.275042 -0.275042)
							(end -0.3048 -0.2032)
						)
						(arc
							(start -0.3048 0.2032)
							(mid -0.275042 0.275042)
							(end -0.2032 0.3048)
						)
						(arc
							(start 0.2032 0.3048)
							(mid 0.275042 0.275042)
							(end 0.3048 0.2032)
						)
					)
					(width 0)
					(fill yes)
				)
			)
		)
	)
	(footprint ""
		(layer "F.Cu")
		(at 341.532718 -150.726648 -90)
		(property "Reference" "U183"
			(at 0 0 270)
			(layer "F.SilkS")
			(hide yes)
			(effects
				(font
					(size 1.27 1.27)
				)
			)
		)
		(property "Value" "USB2514B-AEZC-TR-GP"
			(at -5.5372 -5.2832 270)
			(unlocked yes)
			(layer "F.Fab")
			(hide yes)
			(effects
				(font
					(size 1.016 1.016)
					(thickness 0.1524)
				)
			)
		)
		(property "Device Type" "QFN36-G3D85H40"
			(at -5.5372 -6.8072 270)
			(unlocked yes)
			(layer "F.Fab")
			(hide yes)
			(effects
				(font
					(size 1.016 1.016)
					(thickness 0.1524)
				)
			)
		)
		(duplicate_pad_numbers_are_jumpers no)
		(fp_line
			(start 0.9906 4.318)
			(end 0.9906 3.81)
			(stroke
				(width 0.1524)
				(type default)
			)
			(layer "F.SilkS")
		)
		(fp_line
			(start -4.0132 4.0132)
			(end -4.0132 2.7432)
			(stroke
				(width 0.1524)
				(type default)
			)
			(layer "F.SilkS")
		)
		(fp_line
			(start -2.7432 4.0132)
			(end -4.0132 4.0132)
			(stroke
				(width 0.1524)
				(type default)
			)
			(layer "F.SilkS")
		)
		(fp_line
			(start 2.7432 4.0132)
			(end 4.0132 4.0132)
			(stroke
				(width 0.1524)
				(type default)
			)
			(layer "F.SilkS")
		)
		(fp_line
			(start 4.0132 4.0132)
			(end 4.0132 2.7432)
			(stroke
				(width 0.1524)
				(type default)
			)
			(layer "F.SilkS")
		)
		(fp_line
			(start -1.4986 3.8354)
			(end -1.4986 4.445)
			(stroke
				(width 0.1524)
				(type default)
			)
			(layer "F.SilkS")
		)
		(fp_line
			(start 4.4958 0.9652)
			(end 3.81 0.9652)
			(stroke
				(width 0.1524)
				(type default)
			)
			(layer "F.SilkS")
		)
		(fp_line
			(start -3.8608 0.4826)
			(end -4.318 0.4826)
			(stroke
				(width 0.1524)
				(type default)
			)
			(layer "F.SilkS")
		)
		(fp_line
			(start 4.3434 -1.524)
			(end 3.8608 -1.524)
			(stroke
				(width 0.1524)
				(type default)
			)
			(layer "F.SilkS")
		)
		(fp_line
			(start -3.7846 -2.0066)
			(end -4.4704 -2.0066)
			(stroke
				(width 0.1524)
				(type default)
			)
			(layer "F.SilkS")
		)
		(fp_line
			(start -4.0132 -2.7432)
			(end -4.0132 -4.0132)
			(stroke
				(width 0.1524)
				(type default)
			)
			(layer "F.SilkS")
		)
		(fp_line
			(start -0.0254 -3.7846)
			(end -0.0254 -4.2926)
			(stroke
				(width 0.1524)
				(type default)
			)
			(layer "F.SilkS")
		)
		(fp_line
			(start -4.0132 -4.0132)
			(end -2.7432 -4.0132)
			(stroke
				(width 0.1524)
				(type default)
			)
			(layer "F.SilkS")
		)
		(fp_poly
			(pts
				(xy 2.7432 -4.0132) (xy 4.0132 -2.7432) (xy 4.0132 -4.0132)
			)
			(stroke
				(width 0)
				(type default)
			)
			(fill yes)
			(layer "F.SilkS")
		)
		(fp_rect
			(start -4.0132 4.0132)
			(end 4.0132 -4.0132)
			(stroke
				(width 0)
				(type default)
			)
			(fill no)
			(layer "F.CrtYd")
		)
		(fp_rect
			(start -4.0132 4.0132)
			(end 4.0132 -4.0132)
			(stroke
				(width 0)
				(type default)
			)
			(fill no)
			(layer "F.Fab")
		)
		(pad "1" smd rect
			(at 1.999996 -2.9591 270)
			(size 0.3048 1.0922)
			(layers "F.Cu" "F.Mask" "F.Paste")
			(net "USB_P1_DN")
		)
		(pad "2" smd rect
			(at 1.500124 -2.8702 270)
			(size 0.3048 1.27)
			(layers "F.Cu" "F.Mask" "F.Paste")
			(net "USB_P1_DP")
		)
		(pad "3" smd rect
			(at 0.999998 -2.8702 270)
			(size 0.3048 1.27)
			(layers "F.Cu" "F.Mask" "F.Paste")
			(net "USB_P2_DN")
		)
		(pad "4" smd rect
			(at 0.500126 -2.8702 270)
			(size 0.3048 1.27)
			(layers "F.Cu" "F.Mask" "F.Paste")
			(net "USB_P2_DP")
		)
		(pad "5" smd rect
			(at 0 -2.8702 270)
			(size 0.3048 1.27)
			(layers "F.Cu" "F.Mask" "F.Paste")
			(net "P3V3_STBY")
		)
		(pad "6" smd rect
			(at -0.500126 -2.8702 270)
			(size 0.3048 1.27)
			(layers "F.Cu" "F.Mask" "F.Paste")
			(net "USB_P3_DN")
		)
		(pad "7" smd rect
			(at -0.999998 -2.8702 270)
			(size 0.3048 1.27)
			(layers "F.Cu" "F.Mask" "F.Paste")
			(net "USB_P3_DP")
		)
		(pad "8" smd rect
			(at -1.500124 -2.8702 270)
			(size 0.3048 1.27)
			(layers "F.Cu" "F.Mask" "F.Paste")
			(net "USB_P4_DN")
		)
		(pad "9" smd rect
			(at -1.999996 -2.9591 270)
			(size 0.3048 1.0922)
			(layers "F.Cu" "F.Mask" "F.Paste")
			(net "USB_P4_DP")
		)
		(pad "10" smd rect
			(at -2.9591 -1.999996 270)
			(size 1.0922 0.3048)
			(layers "F.Cu" "F.Mask" "F.Paste")
			(net "P3V3_STBY")
		)
		(pad "11" smd rect
			(at -2.8702 -1.500124 270)
			(size 1.27 0.3048)
			(layers "F.Cu" "F.Mask" "F.Paste")
			(net "GND")
		)
		(pad "12" smd rect
			(at -2.8702 -0.999998 270)
			(size 1.27 0.3048)
			(layers "F.Cu" "F.Mask" "F.Paste")
			(net "USB_EN_1")
		)
		(pad "13" smd rect
			(at -2.8702 -0.500126 270)
			(size 1.27 0.3048)
			(layers "F.Cu" "F.Mask" "F.Paste")
			(net "USB_OCS_N1")
		)
		(pad "14" smd rect
			(at -2.8702 0 270)
			(size 1.27 0.3048)
			(layers "F.Cu" "F.Mask" "F.Paste")
			(net "CRFILT")
		)
		(pad "15" smd rect
			(at -2.8702 0.500126 270)
			(size 1.27 0.3048)
			(layers "F.Cu" "F.Mask" "F.Paste")
			(net "P3V3_STBY")
		)
		(pad "16" smd rect
			(at -2.8702 0.999998 270)
			(size 1.27 0.3048)
			(layers "F.Cu" "F.Mask" "F.Paste")
			(net "USB_EN_2")
		)
		(pad "17" smd rect
			(at -2.8702 1.500124 270)
			(size 1.27 0.3048)
			(layers "F.Cu" "F.Mask" "F.Paste")
			(net "USB_OCS_N2")
		)
		(pad "18" smd rect
			(at -2.9591 1.999996 270)
			(size 1.0922 0.3048)
			(layers "F.Cu" "F.Mask" "F.Paste")
			(net "USB_EN_3")
		)
		(pad "19" smd rect
			(at -1.999996 2.9591 270)
			(size 0.3048 1.0922)
			(layers "F.Cu" "F.Mask" "F.Paste")
			(net "USB_OCS_N3")
		)
		(pad "20" smd rect
			(at -1.500124 2.8702 270)
			(size 0.3048 1.27)
			(layers "F.Cu" "F.Mask" "F.Paste")
			(net "USB_EN_4")
		)
		(pad "21" smd rect
			(at -0.999998 2.8702 270)
			(size 0.3048 1.27)
			(layers "F.Cu" "F.Mask" "F.Paste")
			(net "USB_OCS_N4")
		)
		(pad "22" smd rect
			(at -0.500126 2.8702 270)
			(size 0.3048 1.27)
			(layers "F.Cu" "F.Mask" "F.Paste")
			(net "BMC_I2C_D_SDA")
		)
		(pad "23" smd rect
			(at 0 2.8702 270)
			(size 0.3048 1.27)
			(layers "F.Cu" "F.Mask" "F.Paste")
			(net "P3V3_STBY")
		)
		(pad "24" smd rect
			(at 0.500126 2.8702 270)
			(size 0.3048 1.27)
			(layers "F.Cu" "F.Mask" "F.Paste")
			(net "CFG_SEL0")
		)
		(pad "25" smd rect
			(at 0.999998 2.8702 270)
			(size 0.3048 1.27)
			(layers "F.Cu" "F.Mask" "F.Paste")
			(net "CFG_SEL1")
		)
		(pad "26" smd rect
			(at 1.500124 2.8702 270)
			(size 0.3048 1.27)
			(layers "F.Cu" "F.Mask" "F.Paste")
			(net "USB_RESET_N")
		)
		(pad "27" smd rect
			(at 1.999996 2.9591 270)
			(size 0.3048 1.0922)
			(layers "F.Cu" "F.Mask" "F.Paste")
			(net "VBUS_DET")
		)
		(pad "28" smd rect
			(at 2.9591 1.999996 270)
			(size 1.0922 0.3048)
			(layers "F.Cu" "F.Mask" "F.Paste")
			(net "USB_SUSP_IND")
		)
		(pad "29" smd rect
			(at 2.8702 1.500124 270)
			(size 1.27 0.3048)
			(layers "F.Cu" "F.Mask" "F.Paste")
			(net "P3V3_STBY")
		)
		(pad "30" smd rect
			(at 2.8702 0.999998 270)
			(size 1.27 0.3048)
			(layers "F.Cu" "F.Mask" "F.Paste")
			(net "USB_P0_DN_R")
		)
		(pad "31" smd rect
			(at 2.8702 0.500126 270)
			(size 1.27 0.3048)
			(layers "F.Cu" "F.Mask" "F.Paste")
			(net "USB_P0_DP_R")
		)
		(pad "32" smd rect
			(at 2.8702 0 270)
			(size 1.27 0.3048)
			(layers "F.Cu" "F.Mask" "F.Paste")
			(net "USB_HUB_XTAL_OUT")
		)
		(pad "33" smd rect
			(at 2.8702 -0.500126 270)
			(size 1.27 0.3048)
			(layers "F.Cu" "F.Mask" "F.Paste")
			(net "USB_HUB_XTAL_IN")
		)
		(pad "34" smd rect
			(at 2.8702 -0.999998 270)
			(size 1.27 0.3048)
			(layers "F.Cu" "F.Mask" "F.Paste")
			(net "PLLFILT")
		)
		(pad "35" smd rect
			(at 2.8702 -1.500124 270)
			(size 1.27 0.3048)
			(layers "F.Cu" "F.Mask" "F.Paste")
			(net "RBIAS")
		)
		(pad "36" smd rect
			(at 2.9591 -1.999996 270)
			(size 1.0922 0.3048)
			(layers "F.Cu" "F.Mask" "F.Paste")
			(net "P3V3_STBY")
		)
		(pad "37" smd rect
			(at 0 0 270)
			(size 3.8608 3.8608)
			(layers "F.Cu" "F.Mask" "F.Paste")
			(net "GND")
		)
	)
	(footprint ""
		(layer "F.Cu")
		(at 110.617 -68.199 90)
		(property "Reference" "C328"
			(at 0 0 90)
			(layer "F.SilkS")
			(hide yes)
			(effects
				(font
					(size 1.27 1.27)
				)
			)
		)
		(property "Value" "SCD1U16V2KX-3GP"
			(at 1.1811 -2.7051 90)
			(unlocked yes)
			(layer "F.Fab")
			(hide yes)
			(effects
				(font
					(size 1.016 1.016)
					(thickness 0.1524)
				)
			)
		)
		(property "Device Type" "C402H22"
			(at 1.1811 -4.2291 90)
			(unlocked yes)
			(layer "F.Fab")
			(hide yes)
			(effects
				(font
					(size 1.016 1.016)
					(thickness 0.1524)
				)
			)
		)
		(duplicate_pad_numbers_are_jumpers no)
		(fp_rect
			(start -0.4318 0.9525)
			(end 0.4318 -0.9525)
			(stroke
				(width 0)
				(type default)
			)
			(fill no)
			(layer "F.CrtYd")
		)
		(fp_rect
			(start -0.4318 0.9525)
			(end 0.4318 -0.9525)
			(stroke
				(width 0)
				(type default)
			)
			(fill no)
			(layer "F.Fab")
		)
		(pad "1" smd custom
			(at 0 -0.4445 90)
			(size 0.1524 0.1524)
			(layers "F.Cu" "F.Mask" "F.Paste")
			(net "P3V3_STBY")
			(options
				(clearance outline)
				(anchor circle)
			)
			(primitives
				(gr_poly
					(pts
						(arc
							(start 0.3048 -0.2032)
							(mid 0.275042 -0.275042)
							(end 0.2032 -0.3048)
						)
						(arc
							(start -0.2032 -0.3048)
							(mid -0.275042 -0.275042)
							(end -0.3048 -0.2032)
						)
						(arc
							(start -0.3048 0.2032)
							(mid -0.275042 0.275042)
							(end -0.2032 0.3048)
						)
						(arc
							(start 0.2032 0.3048)
							(mid 0.275042 0.275042)
							(end 0.3048 0.2032)
						)
					)
					(width 0)
					(fill yes)
				)
			)
		)
		(pad "2" smd custom
			(at 0 0.4445 90)
			(size 0.1524 0.1524)
			(layers "F.Cu" "F.Mask" "F.Paste")
			(net "GND")
			(options
				(clearance outline)
				(anchor circle)
			)
			(primitives
				(gr_poly
					(pts
						(arc
							(start 0.3048 -0.2032)
							(mid 0.275042 -0.275042)
							(end 0.2032 -0.3048)
						)
						(arc
							(start -0.2032 -0.3048)
							(mid -0.275042 -0.275042)
							(end -0.3048 -0.2032)
						)
						(arc
							(start -0.3048 0.2032)
							(mid -0.275042 0.275042)
							(end -0.2032 0.3048)
						)
						(arc
							(start 0.2032 0.3048)
							(mid 0.275042 0.275042)
							(end 0.3048 0.2032)
						)
					)
					(width 0)
					(fill yes)
				)
			)
		)
	)
	(footprint ""
		(layer "F.Cu")
		(at 184.712864 -38.172136 180)
		(property "Reference" "R374"
			(at 0 0 180)
			(layer "F.SilkS")
			(hide yes)
			(effects
				(font
					(size 1.27 1.27)
				)
			)
		)
		(property "Value" "2K2R2J-2-GP"
			(at 0.064008 -3.993896 180)
			(unlocked yes)
			(layer "F.Fab")
			(hide yes)
			(effects
				(font
					(size 1.016 1.016)
					(thickness 0.1524)
				)
			)
		)
		(property "Device Type" "R402H16"
			(at 0.064008 -5.517896 180)
			(unlocked yes)
			(layer "F.Fab")
			(hide yes)
			(effects
				(font
					(size 1.016 1.016)
					(thickness 0.1524)
				)
			)
		)
		(duplicate_pad_numbers_are_jumpers no)
		(fp_line
			(start 0.508 -0.9398)
			(end -0.508 -0.9398)
			(stroke
				(width 0.1524)
				(type default)
			)
			(layer "F.SilkS")
		)
		(fp_line
			(start -0.508 -0.9398)
			(end -0.508 0.9398)
			(stroke
				(width 0.1524)
				(type default)
			)
			(layer "F.SilkS")
		)
		(fp_rect
			(start -0.508 0.9398)
			(end 0.508 -0.9398)
			(stroke
				(width 0)
				(type default)
			)
			(fill no)
			(layer "F.CrtYd")
		)
		(fp_rect
			(start -0.508 0.9398)
			(end 0.508 -0.9398)
			(stroke
				(width 0)
				(type default)
			)
			(fill no)
			(layer "F.Fab")
		)
		(pad "1" smd custom
			(at 0 -0.4445 180)
			(size 0.1397 0.1397)
			(layers "F.Cu" "F.Mask" "F.Paste")
			(net "PHY_RESET#")
			(options
				(clearance outline)
				(anchor circle)
			)
			(primitives
				(gr_poly
					(pts
						(arc
							(start -0.1778 -0.2794)
							(mid -0.249642 -0.249642)
							(end -0.2794 -0.1778)
						)
						(arc
							(start -0.2794 0.1778)
							(mid -0.249642 0.249642)
							(end -0.1778 0.2794)
						)
						(arc
							(start 0.1778 0.2794)
							(mid 0.249642 0.249642)
							(end 0.2794 0.1778)
						)
						(arc
							(start 0.2794 -0.1778)
							(mid 0.249642 -0.249642)
							(end 0.1778 -0.2794)
						)
					)
					(width 0)
					(fill yes)
				)
			)
		)
		(pad "2" smd custom
			(at 0 0.4445 180)
			(size 0.1397 0.1397)
			(layers "F.Cu" "F.Mask" "F.Paste")
			(net "GND")
			(options
				(clearance outline)
				(anchor circle)
			)
			(primitives
				(gr_poly
					(pts
						(arc
							(start -0.1778 -0.2794)
							(mid -0.249642 -0.249642)
							(end -0.2794 -0.1778)
						)
						(arc
							(start -0.2794 0.1778)
							(mid -0.249642 0.249642)
							(end -0.1778 0.2794)
						)
						(arc
							(start 0.1778 0.2794)
							(mid 0.249642 0.249642)
							(end 0.2794 0.1778)
						)
						(arc
							(start 0.2794 -0.1778)
							(mid 0.249642 -0.249642)
							(end 0.1778 -0.2794)
						)
					)
					(width 0)
					(fill yes)
				)
			)
		)
	)
	(footprint ""
		(layer "F.Cu")
		(at 78.99019 -59.911488 -90)
		(property "Reference" "SC928"
			(at 0 0 270)
			(layer "F.SilkS")
			(hide yes)
			(effects
				(font
					(size 1.27 1.27)
				)
			)
		)
		(property "Value" "SC10U6D3V5KX-4GP"
			(at -0.0762 -6.1214 270)
			(unlocked yes)
			(layer "F.Fab")
			(hide yes)
			(effects
				(font
					(size 1.016 1.016)
					(thickness 0.1524)
				)
			)
		)
		(property "Device Type" "C805H58"
			(at -0.0762 -8.1534 270)
			(unlocked yes)
			(layer "F.Fab")
			(hide yes)
			(effects
				(font
					(size 1.016 1.016)
					(thickness 0.1524)
				)
			)
		)
		(duplicate_pad_numbers_are_jumpers no)
		(fp_line
			(start 0.635 0)
			(end -0.635 0)
			(stroke
				(width 0.508)
				(type default)
			)
			(layer "F.SilkS")
		)
		(fp_rect
			(start -0.9652 1.778)
			(end 0.9652 -1.778)
			(stroke
				(width 0)
				(type default)
			)
			(fill no)
			(layer "F.CrtYd")
		)
		(fp_poly
			(pts
				(xy -0.9652 -1.778) (xy 0.9652 -1.778) (xy 0.9652 1.778) (xy -0.9652 1.778)
			)
			(stroke
				(width 0)
				(type default)
			)
			(fill no)
			(layer "F.Fab")
		)
		(pad "1" smd rect
			(at 0 -0.9652 270)
			(size 1.397 1.143)
			(layers "F.Cu" "F.Mask" "F.Paste")
			(net "SHELL_PLL_VDD")
		)
		(pad "2" smd rect
			(at 0 0.9652 270)
			(size 1.397 1.143)
			(layers "F.Cu" "F.Mask" "F.Paste")
			(net "GND")
		)
	)
	(footprint ""
		(layer "F.Cu")
		(at 100.11537 -116.84)
		(property "Reference" "TP263"
			(at 0 0 0)
			(layer "F.SilkS")
			(hide yes)
			(effects
				(font
					(size 1.27 1.27)
				)
			)
		)
		(property "Value" "TPAD28"
			(at 0.0127 -1.8034 0)
			(unlocked yes)
			(layer "F.Fab")
			(hide yes)
			(effects
				(font
					(size 1.016 1.016)
					(thickness 0.1524)
				)
			)
		)
		(property "Device Type" "TPAD28"
			(at 0.0127 -3.3274 0)
			(unlocked yes)
			(layer "F.Fab")
			(hide yes)
			(effects
				(font
					(size 1.016 1.016)
					(thickness 0.1524)
				)
			)
		)
		(duplicate_pad_numbers_are_jumpers no)
		(fp_poly
			(pts
				(arc
					(start 0.3556 0)
					(mid -0.3556 0)
					(end 0.3556 0)
				)
			)
			(stroke
				(width 0)
				(type default)
			)
			(fill no)
			(layer "F.CrtYd")
		)
		(fp_poly
			(pts
				(arc
					(start 0.6096 0)
					(mid -0.6096 0)
					(end 0.6096 0)
				)
			)
			(stroke
				(width 0)
				(type default)
			)
			(fill no)
			(layer "F.Fab")
		)
		(pad "1" smd circle
			(at 0 0)
			(size 0.7112 0.7112)
			(layers "F.Cu" "F.Mask" "F.Paste")
			(net "SIO_D_IN")
		)
	)
	(footprint ""
		(layer "F.Cu")
		(at 195.014596 -113.811812 90)
		(property "Reference" "PR9019"
			(at 0 0 90)
			(layer "F.SilkS")
			(hide yes)
			(effects
				(font
					(size 1.27 1.27)
				)
			)
		)
		(property "Value" "3D01R5F-GP"
			(at 0 -8.9535 90)
			(unlocked yes)
			(layer "F.Fab")
			(hide yes)
			(effects
				(font
					(size 1.27 1.016)
					(thickness 0.1524)
				)
			)
		)
		(property "Device Type" "R805H24"
			(at 0 -10.6299 90)
			(unlocked yes)
			(layer "F.Fab")
			(hide yes)
			(effects
				(font
					(size 1.27 1.016)
					(thickness 0.1524)
				)
			)
		)
		(duplicate_pad_numbers_are_jumpers no)
		(fp_line
			(start 0.889 -1.7018)
			(end -0.889 -1.7018)
			(stroke
				(width 0.1524)
				(type default)
			)
			(layer "F.SilkS")
		)
		(fp_line
			(start 0.889 -1.7018)
			(end 0.889 -0.381)
			(stroke
				(width 0.1524)
				(type default)
			)
			(layer "F.SilkS")
		)
		(fp_line
			(start -0.889 -1.7018)
			(end -0.889 0.2794)
			(stroke
				(width 0.1524)
				(type default)
			)
			(layer "F.SilkS")
		)
		(fp_line
			(start -0.889 0.0762)
			(end -0.889 1.7018)
			(stroke
				(width 0.1524)
				(type default)
			)
			(layer "F.SilkS")
		)
		(fp_line
			(start 0.889 1.7018)
			(end 0.889 -0.508)
			(stroke
				(width 0.1524)
				(type default)
			)
			(layer "F.SilkS")
		)
		(fp_line
			(start -0.889 1.7018)
			(end 0.889 1.7018)
			(stroke
				(width 0.1524)
				(type default)
			)
			(layer "F.SilkS")
		)
		(fp_poly
			(pts
				(xy 0.9652 -1.778) (xy 0.9652 1.778) (xy -0.9652 1.778) (xy -0.9652 -1.778)
			)
			(stroke
				(width 0)
				(type default)
			)
			(fill no)
			(layer "F.CrtYd")
		)
		(fp_rect
			(start -0.9652 1.778)
			(end 0.9652 -1.778)
			(stroke
				(width 0)
				(type default)
			)
			(fill no)
			(layer "F.Fab")
		)
		(pad "1" smd rect
			(at 0 -0.9652 90)
			(size 1.397 1.143)
			(layers "F.Cu" "F.Mask" "F.Paste")
			(net "P1V5_E_SNB")
		)
		(pad "2" smd rect
			(at 0 0.9652 90)
			(size 1.397 1.143)
			(layers "F.Cu" "F.Mask" "F.Paste")
			(net "GND")
		)
	)
	(footprint ""
		(layer "F.Cu")
		(at 340.262718 -142.852648 -90)
		(property "Reference" "C8091"
			(at 0 0 270)
			(layer "F.SilkS")
			(hide yes)
			(effects
				(font
					(size 1.27 1.27)
				)
			)
		)
		(property "Value" "SC18P50V3JN-1-GP"
			(at 0 -2.8194 270)
			(unlocked yes)
			(layer "F.Fab")
			(hide yes)
			(effects
				(font
					(size 1.016 1.016)
					(thickness 0.1524)
				)
			)
		)
		(property "Device Type" "C603"
			(at 0 -4.3434 270)
			(unlocked yes)
			(layer "F.Fab")
			(hide yes)
			(effects
				(font
					(size 1.016 1.016)
					(thickness 0.1524)
				)
			)
		)
		(duplicate_pad_numbers_are_jumpers no)
		(fp_line
			(start 0.508 0)
			(end -0.508 0)
			(stroke
				(width 0.2032)
				(type default)
			)
			(layer "F.SilkS")
		)
		(fp_rect
			(start -0.5842 1.3335)
			(end 0.5842 -1.3335)
			(stroke
				(width 0)
				(type default)
			)
			(fill no)
			(layer "F.CrtYd")
		)
		(fp_rect
			(start -0.5842 1.3335)
			(end 0.5842 -1.3335)
			(stroke
				(width 0)
				(type default)
			)
			(fill no)
			(layer "F.Fab")
		)
		(pad "1" smd custom
			(at 0 -0.762 270)
			(size 0.2159 0.2159)
			(layers "F.Cu" "F.Mask" "F.Paste")
			(net "USB_HUB_XTAL_OUT")
			(options
				(clearance outline)
				(anchor circle)
			)
			(primitives
				(gr_poly
					(pts
						(arc
							(start -0.3302 -0.4318)
							(mid -0.402042 -0.402042)
							(end -0.4318 -0.3302)
						)
						(arc
							(start -0.4318 0.3302)
							(mid -0.402042 0.402042)
							(end -0.3302 0.4318)
						)
						(arc
							(start 0.3302 0.4318)
							(mid 0.402042 0.402042)
							(end 0.4318 0.3302)
						)
						(arc
							(start 0.4318 -0.3302)
							(mid 0.402042 -0.402042)
							(end 0.3302 -0.4318)
						)
					)
					(width 0)
					(fill yes)
				)
			)
		)
		(pad "2" smd custom
			(at 0 0.762 270)
			(size 0.2159 0.2159)
			(layers "F.Cu" "F.Mask" "F.Paste")
			(net "GND")
			(options
				(clearance outline)
				(anchor circle)
			)
			(primitives
				(gr_poly
					(pts
						(arc
							(start -0.3302 -0.4318)
							(mid -0.402042 -0.402042)
							(end -0.4318 -0.3302)
						)
						(arc
							(start -0.4318 0.3302)
							(mid -0.402042 0.402042)
							(end -0.3302 0.4318)
						)
						(arc
							(start 0.3302 0.4318)
							(mid 0.402042 0.402042)
							(end 0.4318 0.3302)
						)
						(arc
							(start 0.4318 -0.3302)
							(mid 0.402042 -0.402042)
							(end 0.3302 -0.4318)
						)
					)
					(width 0)
					(fill yes)
				)
			)
		)
	)
	(footprint ""
		(layer "F.Cu")
		(at 300.99 -219.837)
		(property "Reference" "PQ7"
			(at 0 0 0)
			(layer "F.SilkS")
			(hide yes)
			(effects
				(font
					(size 1.27 1.27)
				)
			)
		)
		(property "Value" "2N7002A-7-GP"
			(at 0.127 -8.9662 0)
			(unlocked yes)
			(layer "F.Fab")
			(hide yes)
			(effects
				(font
					(size 1.016 1.016)
					(thickness 0.1524)
				)
			)
		)
		(property "Device Type" "SOT23DGS2D4H48"
			(at 0.127 -10.4902 0)
			(unlocked yes)
			(layer "F.Fab")
			(hide yes)
			(effects
				(font
					(size 1.016 1.016)
					(thickness 0.1524)
				)
			)
		)
		(duplicate_pad_numbers_are_jumpers no)
		(fp_line
			(start -1.651 -1.778)
			(end -1.651 1.778)
			(stroke
				(width 0.1524)
				(type default)
			)
			(layer "F.SilkS")
		)
		(fp_line
			(start -1.651 1.778)
			(end 1.651 1.778)
			(stroke
				(width 0.1524)
				(type default)
			)
			(layer "F.SilkS")
		)
		(fp_line
			(start 1.651 -1.778)
			(end -1.651 -1.778)
			(stroke
				(width 0.1524)
				(type default)
			)
			(layer "F.SilkS")
		)
		(fp_line
			(start 1.651 1.778)
			(end 1.651 -1.778)
			(stroke
				(width 0.1524)
				(type default)
			)
			(layer "F.SilkS")
		)
		(fp_poly
			(pts
				(xy -1.778 1.8796) (xy -1.778 -1.8796) (xy 1.778 -1.8796) (xy 1.778 1.8796)
			)
			(stroke
				(width 0)
				(type default)
			)
			(fill no)
			(layer "F.CrtYd")
		)
		(fp_poly
			(pts
				(xy -1.778 1.8796) (xy -1.778 -1.8796) (xy 1.778 -1.8796) (xy 1.778 1.8796)
			)
			(stroke
				(width 0)
				(type default)
			)
			(fill no)
			(layer "F.Fab")
		)
		(pad "D" smd custom
			(at 0 -0.9525)
			(size 0.1905 0.1905)
			(layers "F.Cu" "F.Mask" "F.Paste")
			(net "DEBUG_OE_1_N")
			(options
				(clearance outline)
				(anchor circle)
			)
			(primitives
				(gr_poly
					(pts
						(arc
							(start -0.1778 0.5715)
							(mid -0.321484 0.511984)
							(end -0.381 0.3683)
						)
						(arc
							(start -0.381 -0.3683)
							(mid -0.321484 -0.511984)
							(end -0.1778 -0.5715)
						)
						(arc
							(start 0.1778 -0.5715)
							(mid 0.321484 -0.511984)
							(end 0.381 -0.3683)
						)
						(arc
							(start 0.381 0.3683)
							(mid 0.321484 0.511984)
							(end 0.1778 0.5715)
						)
					)
					(width 0)
					(fill yes)
				)
			)
		)
		(pad "G" smd custom
			(at -0.98425 0.9525)
			(size 0.1905 0.1905)
			(layers "F.Cu" "F.Mask" "F.Paste")
			(net "PMU_PLTRST_N")
			(options
				(clearance outline)
				(anchor circle)
			)
			(primitives
				(gr_poly
					(pts
						(arc
							(start -0.1778 0.5715)
							(mid -0.321484 0.511984)
							(end -0.381 0.3683)
						)
						(arc
							(start -0.381 -0.3683)
							(mid -0.321484 -0.511984)
							(end -0.1778 -0.5715)
						)
						(arc
							(start 0.1778 -0.5715)
							(mid 0.321484 -0.511984)
							(end 0.381 -0.3683)
						)
						(arc
							(start 0.381 0.3683)
							(mid 0.321484 0.511984)
							(end 0.1778 0.5715)
						)
					)
					(width 0)
					(fill yes)
				)
			)
		)
		(pad "S" smd custom
			(at 0.98425 0.9525)
			(size 0.1905 0.1905)
			(layers "F.Cu" "F.Mask" "F.Paste")
			(net "GND")
			(options
				(clearance outline)
				(anchor circle)
			)
			(primitives
				(gr_poly
					(pts
						(arc
							(start -0.1778 0.5715)
							(mid -0.321484 0.511984)
							(end -0.381 0.3683)
						)
						(arc
							(start -0.381 -0.3683)
							(mid -0.321484 -0.511984)
							(end -0.1778 -0.5715)
						)
						(arc
							(start 0.1778 -0.5715)
							(mid 0.321484 -0.511984)
							(end 0.381 -0.3683)
						)
						(arc
							(start 0.381 0.3683)
							(mid 0.321484 0.511984)
							(end 0.1778 0.5715)
						)
					)
					(width 0)
					(fill yes)
				)
			)
		)
	)
	(footprint ""
		(layer "F.Cu")
		(at 23.064216 -200.71588 90)
		(property "Reference" "R564"
			(at 0 0 90)
			(layer "F.SilkS")
			(hide yes)
			(effects
				(font
					(size 1.27 1.27)
				)
			)
		)
		(property "Value" "0R2J-2-GP"
			(at 0.064008 -3.993896 90)
			(unlocked yes)
			(layer "F.Fab")
			(hide yes)
			(effects
				(font
					(size 1.016 1.016)
					(thickness 0.1524)
				)
			)
		)
		(property "Device Type" "R402H16"
			(at 0.064008 -5.517896 90)
			(unlocked yes)
			(layer "F.Fab")
			(hide yes)
			(effects
				(font
					(size 1.016 1.016)
					(thickness 0.1524)
				)
			)
		)
		(duplicate_pad_numbers_are_jumpers no)
		(fp_line
			(start 0.508 -0.9398)
			(end -0.508 -0.9398)
			(stroke
				(width 0.1524)
				(type default)
			)
			(layer "F.SilkS")
		)
		(fp_line
			(start -0.508 -0.9398)
			(end -0.508 0.9398)
			(stroke
				(width 0.1524)
				(type default)
			)
			(layer "F.SilkS")
		)
		(fp_rect
			(start -0.508 0.9398)
			(end 0.508 -0.9398)
			(stroke
				(width 0)
				(type default)
			)
			(fill no)
			(layer "F.CrtYd")
		)
		(fp_rect
			(start -0.508 0.9398)
			(end 0.508 -0.9398)
			(stroke
				(width 0)
				(type default)
			)
			(fill no)
			(layer "F.Fab")
		)
		(pad "1" smd custom
			(at 0 -0.4445 90)
			(size 0.1397 0.1397)
			(layers "F.Cu" "F.Mask" "F.Paste")
			(net "ADC_P0V955_C")
			(options
				(clearance outline)
				(anchor circle)
			)
			(primitives
				(gr_poly
					(pts
						(arc
							(start -0.1778 -0.2794)
							(mid -0.249642 -0.249642)
							(end -0.2794 -0.1778)
						)
						(arc
							(start -0.2794 0.1778)
							(mid -0.249642 0.249642)
							(end -0.1778 0.2794)
						)
						(arc
							(start 0.1778 0.2794)
							(mid 0.249642 0.249642)
							(end 0.2794 0.1778)
						)
						(arc
							(start 0.2794 -0.1778)
							(mid 0.249642 -0.249642)
							(end 0.1778 -0.2794)
						)
					)
					(width 0)
					(fill yes)
				)
			)
		)
		(pad "2" smd custom
			(at 0 0.4445 90)
			(size 0.1397 0.1397)
			(layers "F.Cu" "F.Mask" "F.Paste")
			(net "P0V955_C_SENSE")
			(options
				(clearance outline)
				(anchor circle)
			)
			(primitives
				(gr_poly
					(pts
						(arc
							(start -0.1778 -0.2794)
							(mid -0.249642 -0.249642)
							(end -0.2794 -0.1778)
						)
						(arc
							(start -0.2794 0.1778)
							(mid -0.249642 0.249642)
							(end -0.1778 0.2794)
						)
						(arc
							(start 0.1778 0.2794)
							(mid 0.249642 0.249642)
							(end 0.2794 0.1778)
						)
						(arc
							(start 0.2794 -0.1778)
							(mid 0.249642 -0.249642)
							(end 0.1778 -0.2794)
						)
					)
					(width 0)
					(fill yes)
				)
			)
		)
	)
	(footprint ""
		(layer "F.Cu")
		(at 184.776872 -198.496936 180)
		(property "Reference" "C243"
			(at 0 0 180)
			(layer "F.SilkS")
			(hide yes)
			(effects
				(font
					(size 1.27 1.27)
				)
			)
		)
		(property "Value" "SCD1U16V2KX-3GP"
			(at 1.1811 -2.7051 180)
			(unlocked yes)
			(layer "F.Fab")
			(hide yes)
			(effects
				(font
					(size 1.016 1.016)
					(thickness 0.1524)
				)
			)
		)
		(property "Device Type" "C402H22"
			(at 1.1811 -4.2291 180)
			(unlocked yes)
			(layer "F.Fab")
			(hide yes)
			(effects
				(font
					(size 1.016 1.016)
					(thickness 0.1524)
				)
			)
		)
		(duplicate_pad_numbers_are_jumpers no)
		(fp_rect
			(start -0.4318 0.9525)
			(end 0.4318 -0.9525)
			(stroke
				(width 0)
				(type default)
			)
			(fill no)
			(layer "F.CrtYd")
		)
		(fp_rect
			(start -0.4318 0.9525)
			(end 0.4318 -0.9525)
			(stroke
				(width 0)
				(type default)
			)
			(fill no)
			(layer "F.Fab")
		)
		(pad "1" smd custom
			(at 0 -0.4445 180)
			(size 0.1524 0.1524)
			(layers "F.Cu" "F.Mask" "F.Paste")
			(net "P3V3_STBY")
			(options
				(clearance outline)
				(anchor circle)
			)
			(primitives
				(gr_poly
					(pts
						(arc
							(start 0.3048 -0.2032)
							(mid 0.275042 -0.275042)
							(end 0.2032 -0.3048)
						)
						(arc
							(start -0.2032 -0.3048)
							(mid -0.275042 -0.275042)
							(end -0.3048 -0.2032)
						)
						(arc
							(start -0.3048 0.2032)
							(mid -0.275042 0.275042)
							(end -0.2032 0.3048)
						)
						(arc
							(start 0.2032 0.3048)
							(mid 0.275042 0.275042)
							(end 0.3048 0.2032)
						)
					)
					(width 0)
					(fill yes)
				)
			)
		)
		(pad "2" smd custom
			(at 0 0.4445 180)
			(size 0.1524 0.1524)
			(layers "F.Cu" "F.Mask" "F.Paste")
			(net "GND")
			(options
				(clearance outline)
				(anchor circle)
			)
			(primitives
				(gr_poly
					(pts
						(arc
							(start 0.3048 -0.2032)
							(mid 0.275042 -0.275042)
							(end 0.2032 -0.3048)
						)
						(arc
							(start -0.2032 -0.3048)
							(mid -0.275042 -0.275042)
							(end -0.3048 -0.2032)
						)
						(arc
							(start -0.3048 0.2032)
							(mid -0.275042 0.275042)
							(end -0.2032 0.3048)
						)
						(arc
							(start 0.2032 0.3048)
							(mid 0.275042 0.275042)
							(end 0.3048 0.2032)
						)
					)
					(width 0)
					(fill yes)
				)
			)
		)
	)
	(footprint ""
		(layer "F.Cu")
		(at 176.012348 -113.401856 180)
		(property "Reference" "PR154"
			(at 0 0 180)
			(layer "F.SilkS")
			(hide yes)
			(effects
				(font
					(size 1.27 1.27)
				)
			)
		)
		(property "Value" "3D01R5F-GP"
			(at 0 -8.9535 180)
			(unlocked yes)
			(layer "F.Fab")
			(hide yes)
			(effects
				(font
					(size 1.27 1.016)
					(thickness 0.1524)
				)
			)
		)
		(property "Device Type" "R805H24"
			(at 0 -10.6299 180)
			(unlocked yes)
			(layer "F.Fab")
			(hide yes)
			(effects
				(font
					(size 1.27 1.016)
					(thickness 0.1524)
				)
			)
		)
		(duplicate_pad_numbers_are_jumpers no)
		(fp_line
			(start 0.889 1.7018)
			(end 0.889 -0.508)
			(stroke
				(width 0.1524)
				(type default)
			)
			(layer "F.SilkS")
		)
		(fp_line
			(start 0.889 -1.7018)
			(end 0.889 -0.381)
			(stroke
				(width 0.1524)
				(type default)
			)
			(layer "F.SilkS")
		)
		(fp_line
			(start 0.889 -1.7018)
			(end -0.889 -1.7018)
			(stroke
				(width 0.1524)
				(type default)
			)
			(layer "F.SilkS")
		)
		(fp_line
			(start -0.889 1.7018)
			(end 0.889 1.7018)
			(stroke
				(width 0.1524)
				(type default)
			)
			(layer "F.SilkS")
		)
		(fp_line
			(start -0.889 0.0762)
			(end -0.889 1.7018)
			(stroke
				(width 0.1524)
				(type default)
			)
			(layer "F.SilkS")
		)
		(fp_line
			(start -0.889 -1.7018)
			(end -0.889 0.2794)
			(stroke
				(width 0.1524)
				(type default)
			)
			(layer "F.SilkS")
		)
		(fp_poly
			(pts
				(xy 0.9652 -1.778) (xy 0.9652 1.778) (xy -0.9652 1.778) (xy -0.9652 -1.778)
			)
			(stroke
				(width 0)
				(type default)
			)
			(fill no)
			(layer "F.CrtYd")
		)
		(fp_rect
			(start -0.9652 1.778)
			(end 0.9652 -1.778)
			(stroke
				(width 0)
				(type default)
			)
			(fill no)
			(layer "F.Fab")
		)
		(pad "1" smd rect
			(at 0 -0.9652 180)
			(size 1.397 1.143)
			(layers "F.Cu" "F.Mask" "F.Paste")
			(net "P0V9_E_LX")
		)
		(pad "2" smd rect
			(at 0 0.9652 180)
			(size 1.397 1.143)
			(layers "F.Cu" "F.Mask" "F.Paste")
			(net "P0V9_E_SNB")
		)
	)
	(footprint ""
		(layer "F.Cu")
		(at 19.381216 -225.98888 90)
		(property "Reference" "R634"
			(at 0 0 90)
			(layer "F.SilkS")
			(hide yes)
			(effects
				(font
					(size 1.27 1.27)
				)
			)
		)
		(property "Value" "4K7R2F-GP"
			(at 0.064008 -3.993896 90)
			(unlocked yes)
			(layer "F.Fab")
			(hide yes)
			(effects
				(font
					(size 1.016 1.016)
					(thickness 0.1524)
				)
			)
		)
		(property "Device Type" "R402H16"
			(at 0.064008 -5.517896 90)
			(unlocked yes)
			(layer "F.Fab")
			(hide yes)
			(effects
				(font
					(size 1.016 1.016)
					(thickness 0.1524)
				)
			)
		)
		(duplicate_pad_numbers_are_jumpers no)
		(fp_line
			(start 0.508 -0.9398)
			(end -0.508 -0.9398)
			(stroke
				(width 0.1524)
				(type default)
			)
			(layer "F.SilkS")
		)
		(fp_line
			(start -0.508 -0.9398)
			(end -0.508 0.9398)
			(stroke
				(width 0.1524)
				(type default)
			)
			(layer "F.SilkS")
		)
		(fp_rect
			(start -0.508 0.9398)
			(end 0.508 -0.9398)
			(stroke
				(width 0)
				(type default)
			)
			(fill no)
			(layer "F.CrtYd")
		)
		(fp_rect
			(start -0.508 0.9398)
			(end 0.508 -0.9398)
			(stroke
				(width 0)
				(type default)
			)
			(fill no)
			(layer "F.Fab")
		)
		(pad "1" smd custom
			(at 0 -0.4445 90)
			(size 0.1397 0.1397)
			(layers "F.Cu" "F.Mask" "F.Paste")
			(net "IO_EXP_HDD_PWR_A3")
			(options
				(clearance outline)
				(anchor circle)
			)
			(primitives
				(gr_poly
					(pts
						(arc
							(start -0.1778 -0.2794)
							(mid -0.249642 -0.249642)
							(end -0.2794 -0.1778)
						)
						(arc
							(start -0.2794 0.1778)
							(mid -0.249642 0.249642)
							(end -0.1778 0.2794)
						)
						(arc
							(start 0.1778 0.2794)
							(mid 0.249642 0.249642)
							(end 0.2794 0.1778)
						)
						(arc
							(start 0.2794 -0.1778)
							(mid 0.249642 -0.249642)
							(end 0.1778 -0.2794)
						)
					)
					(width 0)
					(fill yes)
				)
			)
		)
		(pad "2" smd custom
			(at 0 0.4445 90)
			(size 0.1397 0.1397)
			(layers "F.Cu" "F.Mask" "F.Paste")
			(net "GND")
			(options
				(clearance outline)
				(anchor circle)
			)
			(primitives
				(gr_poly
					(pts
						(arc
							(start -0.1778 -0.2794)
							(mid -0.249642 -0.249642)
							(end -0.2794 -0.1778)
						)
						(arc
							(start -0.2794 0.1778)
							(mid -0.249642 0.249642)
							(end -0.1778 0.2794)
						)
						(arc
							(start 0.1778 0.2794)
							(mid 0.249642 0.249642)
							(end 0.2794 0.1778)
						)
						(arc
							(start 0.2794 -0.1778)
							(mid 0.249642 -0.249642)
							(end 0.1778 -0.2794)
						)
					)
					(width 0)
					(fill yes)
				)
			)
		)
	)
	(footprint ""
		(layer "F.Cu")
		(at 23.445216 -213.79688 180)
		(property "Reference" "R632"
			(at 0 0 180)
			(layer "F.SilkS")
			(hide yes)
			(effects
				(font
					(size 1.27 1.27)
				)
			)
		)
		(property "Value" "4K7R2F-GP"
			(at 0.064008 -3.993896 180)
			(unlocked yes)
			(layer "F.Fab")
			(hide yes)
			(effects
				(font
					(size 1.016 1.016)
					(thickness 0.1524)
				)
			)
		)
		(property "Device Type" "R402H16"
			(at 0.064008 -5.517896 180)
			(unlocked yes)
			(layer "F.Fab")
			(hide yes)
			(effects
				(font
					(size 1.016 1.016)
					(thickness 0.1524)
				)
			)
		)
		(duplicate_pad_numbers_are_jumpers no)
		(fp_line
			(start 0.508 -0.9398)
			(end -0.508 -0.9398)
			(stroke
				(width 0.1524)
				(type default)
			)
			(layer "F.SilkS")
		)
		(fp_line
			(start -0.508 -0.9398)
			(end -0.508 0.9398)
			(stroke
				(width 0.1524)
				(type default)
			)
			(layer "F.SilkS")
		)
		(fp_rect
			(start -0.508 0.9398)
			(end 0.508 -0.9398)
			(stroke
				(width 0)
				(type default)
			)
			(fill no)
			(layer "F.CrtYd")
		)
		(fp_rect
			(start -0.508 0.9398)
			(end 0.508 -0.9398)
			(stroke
				(width 0)
				(type default)
			)
			(fill no)
			(layer "F.Fab")
		)
		(pad "1" smd custom
			(at 0 -0.4445 180)
			(size 0.1397 0.1397)
			(layers "F.Cu" "F.Mask" "F.Paste")
			(net "P3V3_STBY")
			(options
				(clearance outline)
				(anchor circle)
			)
			(primitives
				(gr_poly
					(pts
						(arc
							(start -0.1778 -0.2794)
							(mid -0.249642 -0.249642)
							(end -0.2794 -0.1778)
						)
						(arc
							(start -0.2794 0.1778)
							(mid -0.249642 0.249642)
							(end -0.1778 0.2794)
						)
						(arc
							(start 0.1778 0.2794)
							(mid 0.249642 0.249642)
							(end 0.2794 0.1778)
						)
						(arc
							(start 0.2794 -0.1778)
							(mid 0.249642 -0.249642)
							(end 0.1778 -0.2794)
						)
					)
					(width 0)
					(fill yes)
				)
			)
		)
		(pad "2" smd custom
			(at 0 0.4445 180)
			(size 0.1397 0.1397)
			(layers "F.Cu" "F.Mask" "F.Paste")
			(net "IO_EXP_HDD_PWR_A1")
			(options
				(clearance outline)
				(anchor circle)
			)
			(primitives
				(gr_poly
					(pts
						(arc
							(start -0.1778 -0.2794)
							(mid -0.249642 -0.249642)
							(end -0.2794 -0.1778)
						)
						(arc
							(start -0.2794 0.1778)
							(mid -0.249642 0.249642)
							(end -0.1778 0.2794)
						)
						(arc
							(start 0.1778 0.2794)
							(mid 0.249642 0.249642)
							(end 0.2794 0.1778)
						)
						(arc
							(start 0.2794 -0.1778)
							(mid 0.249642 -0.249642)
							(end 0.1778 -0.2794)
						)
					)
					(width 0)
					(fill yes)
				)
			)
		)
	)
	(footprint ""
		(layer "F.Cu")
		(at 92.27947 -104.14 90)
		(property "Reference" "SR817"
			(at 0 0 90)
			(layer "F.SilkS")
			(hide yes)
			(effects
				(font
					(size 1.27 1.27)
				)
			)
		)
		(property "Value" "4K75R2F-1-GP"
			(at 0.064008 -3.993896 90)
			(unlocked yes)
			(layer "F.Fab")
			(hide yes)
			(effects
				(font
					(size 1.016 1.016)
					(thickness 0.1524)
				)
			)
		)
		(property "Device Type" "R402H16"
			(at 0.064008 -5.517896 90)
			(unlocked yes)
			(layer "F.Fab")
			(hide yes)
			(effects
				(font
					(size 1.016 1.016)
					(thickness 0.1524)
				)
			)
		)
		(duplicate_pad_numbers_are_jumpers no)
		(fp_line
			(start 0.508 -0.9398)
			(end -0.508 -0.9398)
			(stroke
				(width 0.1524)
				(type default)
			)
			(layer "F.SilkS")
		)
		(fp_line
			(start -0.508 -0.9398)
			(end -0.508 0.9398)
			(stroke
				(width 0.1524)
				(type default)
			)
			(layer "F.SilkS")
		)
		(fp_rect
			(start -0.508 0.9398)
			(end 0.508 -0.9398)
			(stroke
				(width 0)
				(type default)
			)
			(fill no)
			(layer "F.CrtYd")
		)
		(fp_rect
			(start -0.508 0.9398)
			(end 0.508 -0.9398)
			(stroke
				(width 0)
				(type default)
			)
			(fill no)
			(layer "F.Fab")
		)
		(pad "1" smd custom
			(at 0 -0.4445 90)
			(size 0.1397 0.1397)
			(layers "F.Cu" "F.Mask" "F.Paste")
			(net "P1V8_E")
			(options
				(clearance outline)
				(anchor circle)
			)
			(primitives
				(gr_poly
					(pts
						(arc
							(start -0.1778 -0.2794)
							(mid -0.249642 -0.249642)
							(end -0.2794 -0.1778)
						)
						(arc
							(start -0.2794 0.1778)
							(mid -0.249642 0.249642)
							(end -0.1778 0.2794)
						)
						(arc
							(start 0.1778 0.2794)
							(mid 0.249642 0.249642)
							(end 0.2794 0.1778)
						)
						(arc
							(start 0.2794 -0.1778)
							(mid 0.249642 -0.249642)
							(end 0.1778 -0.2794)
						)
					)
					(width 0)
					(fill yes)
				)
			)
		)
		(pad "2" smd custom
			(at 0 0.4445 90)
			(size 0.1397 0.1397)
			(layers "F.Cu" "F.Mask" "F.Paste")
			(net "SDB_TX")
			(options
				(clearance outline)
				(anchor circle)
			)
			(primitives
				(gr_poly
					(pts
						(arc
							(start -0.1778 -0.2794)
							(mid -0.249642 -0.249642)
							(end -0.2794 -0.1778)
						)
						(arc
							(start -0.2794 0.1778)
							(mid -0.249642 0.249642)
							(end -0.1778 0.2794)
						)
						(arc
							(start 0.1778 0.2794)
							(mid 0.249642 0.249642)
							(end 0.2794 0.1778)
						)
						(arc
							(start 0.2794 -0.1778)
							(mid 0.249642 -0.249642)
							(end 0.1778 -0.2794)
						)
					)
					(width 0)
					(fill yes)
				)
			)
		)
	)
	(footprint ""
		(layer "F.Cu")
		(at 274.193 -183.515 90)
		(property "Reference" "R354"
			(at 0 0 90)
			(layer "F.SilkS")
			(hide yes)
			(effects
				(font
					(size 1.27 1.27)
				)
			)
		)
		(property "Value" "3K3R2F-2-GP"
			(at 0.064008 -3.993896 90)
			(unlocked yes)
			(layer "F.Fab")
			(hide yes)
			(effects
				(font
					(size 1.016 1.016)
					(thickness 0.1524)
				)
			)
		)
		(property "Device Type" "R402H16"
			(at 0.064008 -5.517896 90)
			(unlocked yes)
			(layer "F.Fab")
			(hide yes)
			(effects
				(font
					(size 1.016 1.016)
					(thickness 0.1524)
				)
			)
		)
		(duplicate_pad_numbers_are_jumpers no)
		(fp_line
			(start 0.508 -0.9398)
			(end -0.508 -0.9398)
			(stroke
				(width 0.1524)
				(type default)
			)
			(layer "F.SilkS")
		)
		(fp_line
			(start -0.508 -0.9398)
			(end -0.508 0.9398)
			(stroke
				(width 0.1524)
				(type default)
			)
			(layer "F.SilkS")
		)
		(fp_rect
			(start -0.508 0.9398)
			(end 0.508 -0.9398)
			(stroke
				(width 0)
				(type default)
			)
			(fill no)
			(layer "F.CrtYd")
		)
		(fp_rect
			(start -0.508 0.9398)
			(end 0.508 -0.9398)
			(stroke
				(width 0)
				(type default)
			)
			(fill no)
			(layer "F.Fab")
		)
		(pad "1" smd custom
			(at 0 -0.4445 90)
			(size 0.1397 0.1397)
			(layers "F.Cu" "F.Mask" "F.Paste")
			(net "P3V3_STBY")
			(options
				(clearance outline)
				(anchor circle)
			)
			(primitives
				(gr_poly
					(pts
						(arc
							(start -0.1778 -0.2794)
							(mid -0.249642 -0.249642)
							(end -0.2794 -0.1778)
						)
						(arc
							(start -0.2794 0.1778)
							(mid -0.249642 0.249642)
							(end -0.1778 0.2794)
						)
						(arc
							(start 0.1778 0.2794)
							(mid 0.249642 0.249642)
							(end 0.2794 0.1778)
						)
						(arc
							(start 0.2794 -0.1778)
							(mid 0.249642 -0.249642)
							(end 0.1778 -0.2794)
						)
					)
					(width 0)
					(fill yes)
				)
			)
		)
		(pad "2" smd custom
			(at 0 0.4445 90)
			(size 0.1397 0.1397)
			(layers "F.Cu" "F.Mask" "F.Paste")
			(net "ROMD3")
			(options
				(clearance outline)
				(anchor circle)
			)
			(primitives
				(gr_poly
					(pts
						(arc
							(start -0.1778 -0.2794)
							(mid -0.249642 -0.249642)
							(end -0.2794 -0.1778)
						)
						(arc
							(start -0.2794 0.1778)
							(mid -0.249642 0.249642)
							(end -0.1778 0.2794)
						)
						(arc
							(start 0.1778 0.2794)
							(mid 0.249642 0.249642)
							(end 0.2794 0.1778)
						)
						(arc
							(start 0.2794 -0.1778)
							(mid 0.249642 -0.249642)
							(end 0.1778 -0.2794)
						)
					)
					(width 0)
					(fill yes)
				)
			)
		)
	)
	(footprint ""
		(layer "F.Cu")
		(at 309.118 -160.655 180)
		(property "Reference" "R260"
			(at 0 0 180)
			(layer "F.SilkS")
			(hide yes)
			(effects
				(font
					(size 1.27 1.27)
				)
			)
		)
		(property "Value" "10KR2F-2-GP"
			(at 0.064008 -3.993896 180)
			(unlocked yes)
			(layer "F.Fab")
			(hide yes)
			(effects
				(font
					(size 1.016 1.016)
					(thickness 0.1524)
				)
			)
		)
		(property "Device Type" "R402H16"
			(at 0.064008 -5.517896 180)
			(unlocked yes)
			(layer "F.Fab")
			(hide yes)
			(effects
				(font
					(size 1.016 1.016)
					(thickness 0.1524)
				)
			)
		)
		(duplicate_pad_numbers_are_jumpers no)
		(fp_line
			(start 0.508 -0.9398)
			(end -0.508 -0.9398)
			(stroke
				(width 0.1524)
				(type default)
			)
			(layer "F.SilkS")
		)
		(fp_line
			(start -0.508 -0.9398)
			(end -0.508 0.9398)
			(stroke
				(width 0.1524)
				(type default)
			)
			(layer "F.SilkS")
		)
		(fp_rect
			(start -0.508 0.9398)
			(end 0.508 -0.9398)
			(stroke
				(width 0)
				(type default)
			)
			(fill no)
			(layer "F.CrtYd")
		)
		(fp_rect
			(start -0.508 0.9398)
			(end 0.508 -0.9398)
			(stroke
				(width 0)
				(type default)
			)
			(fill no)
			(layer "F.Fab")
		)
		(pad "1" smd custom
			(at 0 -0.4445 180)
			(size 0.1397 0.1397)
			(layers "F.Cu" "F.Mask" "F.Paste")
			(net "P3V3_STBY")
			(options
				(clearance outline)
				(anchor circle)
			)
			(primitives
				(gr_poly
					(pts
						(arc
							(start -0.1778 -0.2794)
							(mid -0.249642 -0.249642)
							(end -0.2794 -0.1778)
						)
						(arc
							(start -0.2794 0.1778)
							(mid -0.249642 0.249642)
							(end -0.1778 0.2794)
						)
						(arc
							(start 0.1778 0.2794)
							(mid 0.249642 0.249642)
							(end 0.2794 0.1778)
						)
						(arc
							(start 0.2794 -0.1778)
							(mid 0.249642 -0.249642)
							(end 0.1778 -0.2794)
						)
					)
					(width 0)
					(fill yes)
				)
			)
		)
		(pad "2" smd custom
			(at 0 0.4445 180)
			(size 0.1397 0.1397)
			(layers "F.Cu" "F.Mask" "F.Paste")
			(net "PU_BMC0_SCL11")
			(options
				(clearance outline)
				(anchor circle)
			)
			(primitives
				(gr_poly
					(pts
						(arc
							(start -0.1778 -0.2794)
							(mid -0.249642 -0.249642)
							(end -0.2794 -0.1778)
						)
						(arc
							(start -0.2794 0.1778)
							(mid -0.249642 0.249642)
							(end -0.1778 0.2794)
						)
						(arc
							(start 0.1778 0.2794)
							(mid 0.249642 0.249642)
							(end 0.2794 0.1778)
						)
						(arc
							(start 0.2794 -0.1778)
							(mid 0.249642 -0.249642)
							(end 0.1778 -0.2794)
						)
					)
					(width 0)
					(fill yes)
				)
			)
		)
	)
	(footprint ""
		(layer "F.Cu")
		(at 80.76819 -62.705488)
		(property "Reference" "SR710"
			(at 0 0 0)
			(layer "F.SilkS")
			(hide yes)
			(effects
				(font
					(size 1.27 1.27)
				)
			)
		)
		(property "Value" "10R2F-L-GP"
			(at 0.064008 -3.993896 0)
			(unlocked yes)
			(layer "F.Fab")
			(hide yes)
			(effects
				(font
					(size 1.016 1.016)
					(thickness 0.1524)
				)
			)
		)
		(property "Device Type" "R402H14"
			(at 0.064008 -5.517896 0)
			(unlocked yes)
			(layer "F.Fab")
			(hide yes)
			(effects
				(font
					(size 1.016 1.016)
					(thickness 0.1524)
				)
			)
		)
		(duplicate_pad_numbers_are_jumpers no)
		(fp_line
			(start -0.508 -0.9398)
			(end -0.508 0.9398)
			(stroke
				(width 0.1524)
				(type default)
			)
			(layer "F.SilkS")
		)
		(fp_line
			(start 0.508 -0.9398)
			(end -0.508 -0.9398)
			(stroke
				(width 0.1524)
				(type default)
			)
			(layer "F.SilkS")
		)
		(fp_rect
			(start -0.508 0.9398)
			(end 0.508 -0.9398)
			(stroke
				(width 0)
				(type default)
			)
			(fill no)
			(layer "F.CrtYd")
		)
		(fp_rect
			(start -0.508 0.9398)
			(end 0.508 -0.9398)
			(stroke
				(width 0)
				(type default)
			)
			(fill no)
			(layer "F.Fab")
		)
		(pad "1" smd custom
			(at 0 -0.4445)
			(size 0.1397 0.1397)
			(layers "F.Cu" "F.Mask" "F.Paste")
			(net "P1V8_C")
			(options
				(clearance outline)
				(anchor circle)
			)
			(primitives
				(gr_poly
					(pts
						(arc
							(start -0.1778 -0.2794)
							(mid -0.249642 -0.249642)
							(end -0.2794 -0.1778)
						)
						(arc
							(start -0.2794 0.1778)
							(mid -0.249642 0.249642)
							(end -0.1778 0.2794)
						)
						(arc
							(start 0.1778 0.2794)
							(mid 0.249642 0.249642)
							(end 0.2794 0.1778)
						)
						(arc
							(start 0.2794 -0.1778)
							(mid 0.249642 -0.249642)
							(end 0.1778 -0.2794)
						)
					)
					(width 0)
					(fill yes)
				)
			)
		)
		(pad "2" smd custom
			(at 0 0.4445)
			(size 0.1397 0.1397)
			(layers "F.Cu" "F.Mask" "F.Paste")
			(net "SYS_PLL_VDD")
			(options
				(clearance outline)
				(anchor circle)
			)
			(primitives
				(gr_poly
					(pts
						(arc
							(start -0.1778 -0.2794)
							(mid -0.249642 -0.249642)
							(end -0.2794 -0.1778)
						)
						(arc
							(start -0.2794 0.1778)
							(mid -0.249642 0.249642)
							(end -0.1778 0.2794)
						)
						(arc
							(start 0.1778 0.2794)
							(mid 0.249642 0.249642)
							(end 0.2794 0.1778)
						)
						(arc
							(start 0.2794 -0.1778)
							(mid 0.249642 -0.249642)
							(end 0.1778 -0.2794)
						)
					)
					(width 0)
					(fill yes)
				)
			)
		)
	)
	(footprint ""
		(layer "F.Cu")
		(at 216.281 -96.139 -90)
		(property "Reference" "PC139"
			(at 0 0 270)
			(layer "F.SilkS")
			(hide yes)
			(effects
				(font
					(size 1.27 1.27)
				)
			)
		)
		(property "Value" "SC10U6D3V5KX-1GP"
			(at -0.0762 -6.1214 270)
			(unlocked yes)
			(layer "F.Fab")
			(hide yes)
			(effects
				(font
					(size 1.016 1.016)
					(thickness 0.1524)
				)
			)
		)
		(property "Device Type" "C805H54"
			(at -0.0762 -8.1534 270)
			(unlocked yes)
			(layer "F.Fab")
			(hide yes)
			(effects
				(font
					(size 1.016 1.016)
					(thickness 0.1524)
				)
			)
		)
		(duplicate_pad_numbers_are_jumpers no)
		(fp_line
			(start 0.635 0)
			(end -0.635 0)
			(stroke
				(width 0.508)
				(type default)
			)
			(layer "F.SilkS")
		)
		(fp_rect
			(start -0.9652 1.778)
			(end 0.9652 -1.778)
			(stroke
				(width 0)
				(type default)
			)
			(fill no)
			(layer "F.CrtYd")
		)
		(fp_poly
			(pts
				(xy -0.9652 -1.778) (xy 0.9652 -1.778) (xy 0.9652 1.778) (xy -0.9652 1.778)
			)
			(stroke
				(width 0)
				(type default)
			)
			(fill no)
			(layer "F.Fab")
		)
		(pad "1" smd rect
			(at 0 -0.9652 270)
			(size 1.397 1.143)
			(layers "F.Cu" "F.Mask" "F.Paste")
			(net "TPS74801_P1V5_C_IN")
		)
		(pad "2" smd rect
			(at 0 0.9652 270)
			(size 1.397 1.143)
			(layers "F.Cu" "F.Mask" "F.Paste")
			(net "GND")
		)
	)
	(footprint ""
		(layer "F.Cu")
		(at 14.99997 -94.799912 90)
		(property "Reference" "CN4"
			(at 0 0 90)
			(layer "F.SilkS")
			(hide yes)
			(effects
				(font
					(size 1.27 1.27)
				)
			)
		)
		(property "Value" "MLX-CON7-20-GP"
			(at -26.3652 -0.4572 90)
			(unlocked yes)
			(layer "F.Fab")
			(hide yes)
			(effects
				(font
					(size 1.016 1.016)
					(thickness 0.1524)
				)
			)
		)
		(property "Device Type" "74548-0211-U"
			(at -26.3652 -1.9812 90)
			(unlocked yes)
			(layer "F.Fab")
			(hide yes)
			(effects
				(font
					(size 1.016 1.016)
					(thickness 0.1524)
				)
			)
		)
		(duplicate_pad_numbers_are_jumpers no)
		(fp_line
			(start 15.1892 -12.3571)
			(end -16.800068 -12.3571)
			(stroke
				(width 0.1524)
				(type default)
			)
			(layer "F.SilkS")
		)
		(fp_line
			(start -16.800068 -12.3571)
			(end -25.3492 -12.3571)
			(stroke
				(width 0.1524)
				(type default)
			)
			(layer "F.SilkS")
		)
		(fp_line
			(start -16.800068 -12.3571)
			(end -16.800068 12.3571)
			(stroke
				(width 0.1524)
				(type default)
			)
			(layer "F.SilkS")
		)
		(fp_line
			(start -25.3492 -12.3571)
			(end -25.3492 12.3571)
			(stroke
				(width 0.1524)
				(type default)
			)
			(layer "F.SilkS")
		)
		(fp_line
			(start 15.1892 12.3571)
			(end 15.1892 -12.3571)
			(stroke
				(width 0.1524)
				(type default)
			)
			(layer "F.SilkS")
		)
		(fp_line
			(start -16.800068 12.3571)
			(end 15.1892 12.3571)
			(stroke
				(width 0.1524)
				(type default)
			)
			(layer "F.SilkS")
		)
		(fp_line
			(start -25.3492 12.3571)
			(end -16.800068 12.3571)
			(stroke
				(width 0.1524)
				(type default)
			)
			(layer "F.SilkS")
		)
		(fp_circle
			(center 5.999988 -10.104882)
			(end 5.999988 -7.742682)
			(stroke
				(width 0.3048)
				(type default)
			)
			(fill no)
			(layer "F.SilkS")
		)
		(fp_circle
			(center -8.999982 -10.104882)
			(end -8.999982 -7.742682)
			(stroke
				(width 0.3048)
				(type default)
			)
			(fill no)
			(layer "F.SilkS")
		)
		(fp_circle
			(center 5.999988 10.104882)
			(end 5.999988 12.467082)
			(stroke
				(width 0.3048)
				(type default)
			)
			(fill no)
			(layer "F.SilkS")
		)
		(fp_circle
			(center -8.999982 10.104882)
			(end -8.999982 12.467082)
			(stroke
				(width 0.3048)
				(type default)
			)
			(fill no)
			(layer "F.SilkS")
		)
		(fp_poly
			(pts
				(xy -16.800068 -8.86968) (xy -11.3157 -8.86968) (xy -11.3157 -11.469624) (xy -16.800068 -11.469624)
			)
			(stroke
				(width 0)
				(type default)
			)
			(fill yes)
			(layer "F.Paste")
		)
		(fp_poly
			(pts
				(xy -16.800068 -6.023102) (xy -12.599924 -6.023102) (xy -12.599924 -8.20928) (xy -16.800068 -8.20928)
			)
			(stroke
				(width 0)
				(type default)
			)
			(fill yes)
			(layer "F.Paste")
		)
		(fp_poly
			(pts
				(xy -16.800068 -3.176524) (xy -12.599924 -3.176524) (xy -12.599924 -5.362702) (xy -16.800068 -5.362702)
			)
			(stroke
				(width 0)
				(type default)
			)
			(fill yes)
			(layer "F.Paste")
		)
		(fp_poly
			(pts
				(xy -16.800068 -0.329946) (xy -12.599924 -0.329946) (xy -12.599924 -2.516124) (xy -16.800068 -2.516124)
			)
			(stroke
				(width 0)
				(type default)
			)
			(fill yes)
			(layer "F.Paste")
		)
		(fp_poly
			(pts
				(xy -16.800068 2.516632) (xy -12.599924 2.516632) (xy -12.599924 0.330454) (xy -16.800068 0.330454)
			)
			(stroke
				(width 0)
				(type default)
			)
			(fill yes)
			(layer "F.Paste")
		)
		(fp_poly
			(pts
				(xy -16.800068 5.36321) (xy -12.599924 5.36321) (xy -12.599924 3.177032) (xy -16.800068 3.177032)
			)
			(stroke
				(width 0)
				(type default)
			)
			(fill yes)
			(layer "F.Paste")
		)
		(fp_poly
			(pts
				(xy -16.800068 8.209788) (xy -12.599924 8.209788) (xy -12.599924 6.02361) (xy -16.800068 6.02361)
			)
			(stroke
				(width 0)
				(type default)
			)
			(fill yes)
			(layer "F.Paste")
		)
		(fp_poly
			(pts
				(xy -16.800068 11.469624) (xy -11.3157 11.469624) (xy -11.3157 8.86968) (xy -16.800068 8.86968)
			)
			(stroke
				(width 0)
				(type default)
			)
			(fill yes)
			(layer "F.Paste")
		)
		(fp_poly
			(pts
				(xy 8.31215 -8.86968) (xy 11.5697 -8.86968) (xy 11.5697 -4.549648) (xy 13.679932 -4.549648) (xy 13.679932 -11.469624)
				(xy 8.31215 -11.469624)
			)
			(stroke
				(width 0)
				(type default)
			)
			(fill yes)
			(layer "F.Paste")
		)
		(fp_poly
			(pts
				(xy 8.3185 8.86968) (xy 11.5697 8.86968) (xy 11.5697 4.149852) (xy 13.679932 4.149852) (xy 13.679932 11.469624)
				(xy 8.3185 11.469624)
			)
			(stroke
				(width 0)
				(type default)
			)
			(fill yes)
			(layer "F.Paste")
		)
		(fp_poly
			(pts
				(xy -6.68655 -11.469624) (xy 3.68935 -11.469624) (xy 3.68935 -8.86968) (xy 1.0922 -8.86968)
				(arc
					(start 1.0922 -9.373108)
					(mid 0 -10.727704)
					(end -1.0922 -9.373108)
				)
				(xy -1.0922 -8.86968) (xy -6.68655 -8.86968)
			)
			(stroke
				(width 0)
				(type default)
			)
			(fill yes)
			(layer "F.Paste")
		)
		(fp_poly
			(pts
				(xy -6.68655 8.86968) (xy -1.0922 8.86968)
				(arc
					(start -1.0922 9.373108)
					(mid 0 10.727704)
					(end 1.0922 9.373108)
				)
				(xy 1.0922 8.86968) (xy 3.683 8.86968) (xy 3.683 11.469624) (xy -6.68655 11.469624)
			)
			(stroke
				(width 0)
				(type default)
			)
			(fill yes)
			(layer "F.Paste")
		)
		(fp_rect
			(start -25.0952 11.3665)
			(end 14.9352 -11.3665)
			(stroke
				(width 0)
				(type default)
			)
			(fill no)
			(layer "F.CrtYd")
		)
		(fp_poly
			(pts
				(xy -25.6032 12.6111) (xy -25.6032 -12.6111) (xy 15.4432 -12.6111) (xy 15.4432 -8.5725) (xy 14.9352 -8.5725)
				(xy 14.9352 -11.3665) (xy -25.0952 -11.3665) (xy -25.0952 11.3665) (xy 14.9352 11.3665) (xy 14.9352 -8.5598)
				(xy 15.4432 -8.5598) (xy 15.4432 12.6111)
			)
			(stroke
				(width 0)
				(type default)
			)
			(fill no)
			(layer "F.CrtYd")
		)
		(fp_rect
			(start -25.6032 12.6111)
			(end 15.4432 -12.6111)
			(stroke
				(width 0)
				(type default)
			)
			(fill no)
			(layer "F.Fab")
		)
		(pad "" np_thru_hole circle
			(at 0 -9.61009 90)
			(size 0.254 0.254)
			(drill 1.5748)
			(layers "*.Cu" "*.Mask")
			(clearance 1.016)
			(thermal_gap 1.016)
		)
		(pad "" np_thru_hole circle
			(at 0 9.61009 90)
			(size 0.254 0.254)
			(drill 1.5748)
			(layers "*.Cu" "*.Mask")
			(clearance 1.016)
			(thermal_gap 1.016)
		)
		(pad "Z1" thru_hole circle
			(at -8.999982 10.104882 90)
			(size 4.0132 4.0132)
			(drill 2.5146)
			(layers "*.Cu" "*.Mask")
			(remove_unused_layers no)
			(net "GND")
			(clearance -0.2413)
			(thermal_gap 0.3048)
			(padstack
				(mode front_inner_back)
				(layer "Inner"
					(shape circle)
					(size 2.921 2.921)
					(clearance 0.3048)
				)
				(layer "B.Cu"
					(shape circle)
					(size 4.0132 4.0132)
					(clearance -0.2413)
				)
			)
		)
		(pad "Z2" thru_hole circle
			(at 5.999988 10.104882 90)
			(size 4.0132 4.0132)
			(drill 2.5146)
			(layers "*.Cu" "*.Mask")
			(remove_unused_layers no)
			(net "GND")
			(clearance -0.2413)
			(thermal_gap 0.3048)
			(padstack
				(mode front_inner_back)
				(layer "Inner"
					(shape circle)
					(size 2.921 2.921)
					(clearance 0.3048)
				)
				(layer "B.Cu"
					(shape circle)
					(size 4.0132 4.0132)
					(clearance -0.2413)
				)
			)
		)
		(pad "Z3" thru_hole circle
			(at 5.999988 -10.104882 90)
			(size 4.0132 4.0132)
			(drill 2.5146)
			(layers "*.Cu" "*.Mask")
			(remove_unused_layers no)
			(net "GND")
			(clearance -0.2413)
			(thermal_gap 0.3048)
			(padstack
				(mode front_inner_back)
				(layer "Inner"
					(shape circle)
					(size 2.921 2.921)
					(clearance 0.3048)
				)
				(layer "B.Cu"
					(shape circle)
					(size 4.0132 4.0132)
					(clearance -0.2413)
				)
			)
		)
		(pad "Z4" thru_hole circle
			(at -8.999982 -10.104882 90)
			(size 4.0132 4.0132)
			(drill 2.5146)
			(layers "*.Cu" "*.Mask")
			(remove_unused_layers no)
			(net "GND")
			(clearance -0.2413)
			(thermal_gap 0.3048)
			(padstack
				(mode front_inner_back)
				(layer "Inner"
					(shape circle)
					(size 2.921 2.921)
					(clearance 0.3048)
				)
				(layer "B.Cu"
					(shape circle)
					(size 4.0132 4.0132)
					(clearance -0.2413)
				)
			)
		)
		(pad "Z5" smd rect
			(at 12.62507 -2.59969 90)
			(size 2.1082 0.889)
			(layers "F.Cu" "F.Mask" "F.Paste")
			(net "GND")
		)
		(pad "Z6" smd rect
			(at 12.62507 -0.199898 90)
			(size 2.1082 0.889)
			(layers "F.Cu" "F.Mask" "F.Paste")
			(net "GND")
		)
		(pad "Z7" smd rect
			(at 12.62507 2.200148 90)
			(size 2.1082 0.889)
			(layers "F.Cu" "F.Mask" "F.Paste")
			(net "GND")
		)
		(zone
			(layers "F.Cu" "B.Cu" "In1.Cu" "In2.Cu" "In3.Cu" "In4.Cu" "In5.Cu" "In6.Cu")
			(hatch none 0.5)
			(connect_pads
				(clearance 0)
			)
			(min_thickness 0.25)
			(keepout
				(tracks not_allowed)
				(vias allowed)
				(pads allowed)
				(copperpour not_allowed)
				(footprints allowed)
			)
			(placement
				(enabled no)
				(sheetname "")
			)
			(fill
				(thermal_gap 0.5)
				(thermal_bridge_width 0.5)
				(island_removal_mode 0)
			)
			(polygon
				(pts
					(arc
						(start 6.48208 -94.799912)
						(mid 4.29768 -94.799912)
						(end 6.48208 -94.799912)
					)
				)
			)
		)
		(zone
			(layers "F.Cu" "B.Cu" "In1.Cu" "In2.Cu" "In3.Cu" "In4.Cu" "In5.Cu" "In6.Cu")
			(hatch none 0.5)
			(connect_pads
				(clearance 0)
			)
			(min_thickness 0.25)
			(keepout
				(tracks not_allowed)
				(vias allowed)
				(pads allowed)
				(copperpour not_allowed)
				(footprints allowed)
			)
			(placement
				(enabled no)
				(sheetname "")
			)
			(fill
				(thermal_gap 0.5)
				(thermal_bridge_width 0.5)
				(island_removal_mode 0)
			)
			(polygon
				(pts
					(arc
						(start 25.70226 -94.799912)
						(mid 23.51786 -94.799912)
						(end 25.70226 -94.799912)
					)
				)
			)
		)
	)
	(footprint ""
		(layer "F.Cu")
		(at 121.990612 -221.996 180)
		(property "Reference" "SR872"
			(at 0 0 180)
			(layer "F.SilkS")
			(hide yes)
			(effects
				(font
					(size 1.27 1.27)
				)
			)
		)
		(property "Value" "0R2J-2-GP"
			(at 0.064008 -3.993896 180)
			(unlocked yes)
			(layer "F.Fab")
			(hide yes)
			(effects
				(font
					(size 1.016 1.016)
					(thickness 0.1524)
				)
			)
		)
		(property "Device Type" "R402H16"
			(at 0.064008 -5.517896 180)
			(unlocked yes)
			(layer "F.Fab")
			(hide yes)
			(effects
				(font
					(size 1.016 1.016)
					(thickness 0.1524)
				)
			)
		)
		(duplicate_pad_numbers_are_jumpers no)
		(fp_line
			(start 0.508 -0.9398)
			(end -0.508 -0.9398)
			(stroke
				(width 0.1524)
				(type default)
			)
			(layer "F.SilkS")
		)
		(fp_line
			(start -0.508 -0.9398)
			(end -0.508 0.9398)
			(stroke
				(width 0.1524)
				(type default)
			)
			(layer "F.SilkS")
		)
		(fp_rect
			(start -0.508 0.9398)
			(end 0.508 -0.9398)
			(stroke
				(width 0)
				(type default)
			)
			(fill no)
			(layer "F.CrtYd")
		)
		(fp_rect
			(start -0.508 0.9398)
			(end 0.508 -0.9398)
			(stroke
				(width 0)
				(type default)
			)
			(fill no)
			(layer "F.Fab")
		)
		(pad "1" smd custom
			(at 0 -0.4445 180)
			(size 0.1397 0.1397)
			(layers "F.Cu" "F.Mask" "F.Paste")
			(net "REDV_TX7_P")
			(options
				(clearance outline)
				(anchor circle)
			)
			(primitives
				(gr_poly
					(pts
						(arc
							(start -0.1778 -0.2794)
							(mid -0.249642 -0.249642)
							(end -0.2794 -0.1778)
						)
						(arc
							(start -0.2794 0.1778)
							(mid -0.249642 0.249642)
							(end -0.1778 0.2794)
						)
						(arc
							(start 0.1778 0.2794)
							(mid 0.249642 0.249642)
							(end 0.2794 0.1778)
						)
						(arc
							(start 0.2794 -0.1778)
							(mid 0.249642 -0.249642)
							(end 0.1778 -0.2794)
						)
					)
					(width 0)
					(fill yes)
				)
			)
		)
		(pad "2" smd custom
			(at 0 0.4445 180)
			(size 0.1397 0.1397)
			(layers "F.Cu" "F.Mask" "F.Paste")
			(net "SAS_HDD_CONN_TX7_P")
			(options
				(clearance outline)
				(anchor circle)
			)
			(primitives
				(gr_poly
					(pts
						(arc
							(start -0.1778 -0.2794)
							(mid -0.249642 -0.249642)
							(end -0.2794 -0.1778)
						)
						(arc
							(start -0.2794 0.1778)
							(mid -0.249642 0.249642)
							(end -0.1778 0.2794)
						)
						(arc
							(start 0.1778 0.2794)
							(mid 0.249642 0.249642)
							(end 0.2794 0.1778)
						)
						(arc
							(start 0.2794 -0.1778)
							(mid 0.249642 -0.249642)
							(end 0.1778 -0.2794)
						)
					)
					(width 0)
					(fill yes)
				)
			)
		)
	)
	(footprint ""
		(layer "F.Cu")
		(at 53.34 -211.074)
		(property "Reference" "R2113"
			(at 0 0 0)
			(layer "F.SilkS")
			(hide yes)
			(effects
				(font
					(size 1.27 1.27)
				)
			)
		)
		(property "Value" "0R2J-2-GP"
			(at 0.064008 -3.993896 0)
			(unlocked yes)
			(layer "F.Fab")
			(hide yes)
			(effects
				(font
					(size 1.016 1.016)
					(thickness 0.1524)
				)
			)
		)
		(property "Device Type" "R402H16"
			(at 0.064008 -5.517896 0)
			(unlocked yes)
			(layer "F.Fab")
			(hide yes)
			(effects
				(font
					(size 1.016 1.016)
					(thickness 0.1524)
				)
			)
		)
		(duplicate_pad_numbers_are_jumpers no)
		(fp_line
			(start -0.508 -0.9398)
			(end -0.508 0.9398)
			(stroke
				(width 0.1524)
				(type default)
			)
			(layer "F.SilkS")
		)
		(fp_line
			(start 0.508 -0.9398)
			(end -0.508 -0.9398)
			(stroke
				(width 0.1524)
				(type default)
			)
			(layer "F.SilkS")
		)
		(fp_rect
			(start -0.508 0.9398)
			(end 0.508 -0.9398)
			(stroke
				(width 0)
				(type default)
			)
			(fill no)
			(layer "F.CrtYd")
		)
		(fp_rect
			(start -0.508 0.9398)
			(end 0.508 -0.9398)
			(stroke
				(width 0)
				(type default)
			)
			(fill no)
			(layer "F.Fab")
		)
		(pad "1" smd custom
			(at 0 -0.4445)
			(size 0.1397 0.1397)
			(layers "F.Cu" "F.Mask" "F.Paste")
			(net "MB0_SPISS_PD")
			(options
				(clearance outline)
				(anchor circle)
			)
			(primitives
				(gr_poly
					(pts
						(arc
							(start -0.1778 -0.2794)
							(mid -0.249642 -0.249642)
							(end -0.2794 -0.1778)
						)
						(arc
							(start -0.2794 0.1778)
							(mid -0.249642 0.249642)
							(end -0.1778 0.2794)
						)
						(arc
							(start 0.1778 0.2794)
							(mid 0.249642 0.249642)
							(end 0.2794 0.1778)
						)
						(arc
							(start 0.2794 -0.1778)
							(mid 0.249642 -0.249642)
							(end 0.1778 -0.2794)
						)
					)
					(width 0)
					(fill yes)
				)
			)
		)
		(pad "2" smd custom
			(at 0 0.4445)
			(size 0.1397 0.1397)
			(layers "F.Cu" "F.Mask" "F.Paste")
			(net "AGND_CURRENT_MON")
			(options
				(clearance outline)
				(anchor circle)
			)
			(primitives
				(gr_poly
					(pts
						(arc
							(start -0.1778 -0.2794)
							(mid -0.249642 -0.249642)
							(end -0.2794 -0.1778)
						)
						(arc
							(start -0.2794 0.1778)
							(mid -0.249642 0.249642)
							(end -0.1778 0.2794)
						)
						(arc
							(start 0.1778 0.2794)
							(mid 0.249642 0.249642)
							(end 0.2794 0.1778)
						)
						(arc
							(start 0.2794 -0.1778)
							(mid 0.249642 -0.249642)
							(end 0.1778 -0.2794)
						)
					)
					(width 0)
					(fill yes)
				)
			)
		)
	)
	(footprint ""
		(layer "F.Cu")
		(at 79.4766 -15.6718 90)
		(property "Reference" "PC209"
			(at 0 0 90)
			(layer "F.SilkS")
			(hide yes)
			(effects
				(font
					(size 1.27 1.27)
				)
			)
		)
		(property "Value" "SC1U25V3KX-GP"
			(at 0 -2.8194 90)
			(unlocked yes)
			(layer "F.Fab")
			(hide yes)
			(effects
				(font
					(size 1.016 1.016)
					(thickness 0.1524)
				)
			)
		)
		(property "Device Type" "C603H36"
			(at 0 -4.3434 90)
			(unlocked yes)
			(layer "F.Fab")
			(hide yes)
			(effects
				(font
					(size 1.016 1.016)
					(thickness 0.1524)
				)
			)
		)
		(duplicate_pad_numbers_are_jumpers no)
		(fp_line
			(start 0.508 0)
			(end -0.508 0)
			(stroke
				(width 0.2032)
				(type default)
			)
			(layer "F.SilkS")
		)
		(fp_rect
			(start -0.5842 1.3335)
			(end 0.5842 -1.3335)
			(stroke
				(width 0)
				(type default)
			)
			(fill no)
			(layer "F.CrtYd")
		)
		(fp_rect
			(start -0.5842 1.3335)
			(end 0.5842 -1.3335)
			(stroke
				(width 0)
				(type default)
			)
			(fill no)
			(layer "F.Fab")
		)
		(pad "1" smd custom
			(at 0 -0.762 90)
			(size 0.2159 0.2159)
			(layers "F.Cu" "F.Mask" "F.Paste")
			(net "VT235_VDDH")
			(options
				(clearance outline)
				(anchor circle)
			)
			(primitives
				(gr_poly
					(pts
						(arc
							(start -0.3302 -0.4318)
							(mid -0.402042 -0.402042)
							(end -0.4318 -0.3302)
						)
						(arc
							(start -0.4318 0.3302)
							(mid -0.402042 0.402042)
							(end -0.3302 0.4318)
						)
						(arc
							(start 0.3302 0.4318)
							(mid 0.402042 0.402042)
							(end 0.4318 0.3302)
						)
						(arc
							(start 0.4318 -0.3302)
							(mid 0.402042 -0.402042)
							(end 0.3302 -0.4318)
						)
					)
					(width 0)
					(fill yes)
				)
			)
		)
		(pad "2" smd custom
			(at 0 0.762 90)
			(size 0.2159 0.2159)
			(layers "F.Cu" "F.Mask" "F.Paste")
			(net "GND")
			(options
				(clearance outline)
				(anchor circle)
			)
			(primitives
				(gr_poly
					(pts
						(arc
							(start -0.3302 -0.4318)
							(mid -0.402042 -0.402042)
							(end -0.4318 -0.3302)
						)
						(arc
							(start -0.4318 0.3302)
							(mid -0.402042 0.402042)
							(end -0.3302 0.4318)
						)
						(arc
							(start 0.3302 0.4318)
							(mid 0.402042 0.402042)
							(end 0.4318 0.3302)
						)
						(arc
							(start 0.4318 -0.3302)
							(mid 0.402042 -0.402042)
							(end 0.3302 -0.4318)
						)
					)
					(width 0)
					(fill yes)
				)
			)
		)
	)
	(footprint ""
		(layer "F.Cu")
		(at 218.059 -180.594 -90)
		(property "Reference" "R501"
			(at 0 0 270)
			(layer "F.SilkS")
			(hide yes)
			(effects
				(font
					(size 1.27 1.27)
				)
			)
		)
		(property "Value" "1KR2F-3-GP"
			(at 0.064008 -3.993896 270)
			(unlocked yes)
			(layer "F.Fab")
			(hide yes)
			(effects
				(font
					(size 1.016 1.016)
					(thickness 0.1524)
				)
			)
		)
		(property "Device Type" "R402H16"
			(at 0.064008 -5.517896 270)
			(unlocked yes)
			(layer "F.Fab")
			(hide yes)
			(effects
				(font
					(size 1.016 1.016)
					(thickness 0.1524)
				)
			)
		)
		(duplicate_pad_numbers_are_jumpers no)
		(fp_line
			(start -0.508 -0.9398)
			(end -0.508 0.9398)
			(stroke
				(width 0.1524)
				(type default)
			)
			(layer "F.SilkS")
		)
		(fp_line
			(start 0.508 -0.9398)
			(end -0.508 -0.9398)
			(stroke
				(width 0.1524)
				(type default)
			)
			(layer "F.SilkS")
		)
		(fp_rect
			(start -0.508 0.9398)
			(end 0.508 -0.9398)
			(stroke
				(width 0)
				(type default)
			)
			(fill no)
			(layer "F.CrtYd")
		)
		(fp_rect
			(start -0.508 0.9398)
			(end 0.508 -0.9398)
			(stroke
				(width 0)
				(type default)
			)
			(fill no)
			(layer "F.Fab")
		)
		(pad "1" smd custom
			(at 0 -0.4445 270)
			(size 0.1397 0.1397)
			(layers "F.Cu" "F.Mask" "F.Paste")
			(net "DIVIDER 2_IN_EXP")
			(options
				(clearance outline)
				(anchor circle)
			)
			(primitives
				(gr_poly
					(pts
						(arc
							(start -0.1778 -0.2794)
							(mid -0.249642 -0.249642)
							(end -0.2794 -0.1778)
						)
						(arc
							(start -0.2794 0.1778)
							(mid -0.249642 0.249642)
							(end -0.1778 0.2794)
						)
						(arc
							(start 0.1778 0.2794)
							(mid 0.249642 0.249642)
							(end 0.2794 0.1778)
						)
						(arc
							(start 0.2794 -0.1778)
							(mid 0.249642 -0.249642)
							(end 0.1778 -0.2794)
						)
					)
					(width 0)
					(fill yes)
				)
			)
		)
		(pad "2" smd custom
			(at 0 0.4445 270)
			(size 0.1397 0.1397)
			(layers "F.Cu" "F.Mask" "F.Paste")
			(net "GND")
			(options
				(clearance outline)
				(anchor circle)
			)
			(primitives
				(gr_poly
					(pts
						(arc
							(start -0.1778 -0.2794)
							(mid -0.249642 -0.249642)
							(end -0.2794 -0.1778)
						)
						(arc
							(start -0.2794 0.1778)
							(mid -0.249642 0.249642)
							(end -0.1778 0.2794)
						)
						(arc
							(start 0.1778 0.2794)
							(mid 0.249642 0.249642)
							(end 0.2794 0.1778)
						)
						(arc
							(start 0.2794 -0.1778)
							(mid 0.249642 -0.249642)
							(end 0.1778 -0.2794)
						)
					)
					(width 0)
					(fill yes)
				)
			)
		)
	)
	(footprint ""
		(layer "F.Cu")
		(at 275.59 -107.315)
		(property "Reference" "Q78"
			(at 0 0 0)
			(layer "F.SilkS")
			(hide yes)
			(effects
				(font
					(size 1.27 1.27)
				)
			)
		)
		(property "Value" "FDN359BN-GP-U"
			(at -3.175 0.254 0)
			(unlocked yes)
			(layer "F.Fab")
			(hide yes)
			(effects
				(font
					(size 1.016 1.016)
					(thickness 0.1524)
				)
			)
		)
		(property "Device Type" "SOT23DGS2D6H45"
			(at -3.175 -1.27 0)
			(unlocked yes)
			(layer "F.Fab")
			(hide yes)
			(effects
				(font
					(size 1.016 1.016)
					(thickness 0.1524)
				)
			)
		)
		(duplicate_pad_numbers_are_jumpers no)
		(fp_line
			(start -1.7018 -1.905)
			(end 1.7018 -1.905)
			(stroke
				(width 0.1524)
				(type default)
			)
			(layer "F.SilkS")
		)
		(fp_line
			(start -1.7018 1.905)
			(end -1.7018 -1.905)
			(stroke
				(width 0.1524)
				(type default)
			)
			(layer "F.SilkS")
		)
		(fp_line
			(start 1.7018 -1.905)
			(end 1.7018 1.905)
			(stroke
				(width 0.1524)
				(type default)
			)
			(layer "F.SilkS")
		)
		(fp_line
			(start 1.7018 1.905)
			(end -1.7018 1.905)
			(stroke
				(width 0.1524)
				(type default)
			)
			(layer "F.SilkS")
		)
		(fp_rect
			(start -2.0066 1.9812)
			(end 2.0066 -1.9812)
			(stroke
				(width 0)
				(type default)
			)
			(fill no)
			(layer "F.CrtYd")
		)
		(fp_rect
			(start -2.0066 1.9812)
			(end 2.0066 -1.9812)
			(stroke
				(width 0)
				(type default)
			)
			(fill no)
			(layer "F.Fab")
		)
		(pad "D" smd custom
			(at 0 -1.0922)
			(size 0.1651 0.1651)
			(layers "F.Cu" "F.Mask" "F.Paste")
			(net "P1V8_STBY")
			(options
				(clearance outline)
				(anchor circle)
			)
			(primitives
				(gr_poly
					(pts
						(arc
							(start 0.3302 -0.381)
							(mid 0.270684 -0.524684)
							(end 0.127 -0.5842)
						)
						(arc
							(start -0.127 -0.5842)
							(mid -0.270684 -0.524684)
							(end -0.3302 -0.381)
						)
						(arc
							(start -0.3302 0.381)
							(mid -0.270684 0.524684)
							(end -0.127 0.5842)
						)
						(arc
							(start 0.127 0.5842)
							(mid 0.270684 0.524684)
							(end 0.3302 0.381)
						)
					)
					(width 0)
					(fill yes)
				)
			)
		)
		(pad "G" smd custom
			(at -0.94996 1.0922)
			(size 0.1651 0.1651)
			(layers "F.Cu" "F.Mask" "F.Paste")
			(net "P1V8_C_EN_LV")
			(options
				(clearance outline)
				(anchor circle)
			)
			(primitives
				(gr_poly
					(pts
						(arc
							(start 0.3302 -0.381)
							(mid 0.270684 -0.524684)
							(end 0.127 -0.5842)
						)
						(arc
							(start -0.127 -0.5842)
							(mid -0.270684 -0.524684)
							(end -0.3302 -0.381)
						)
						(arc
							(start -0.3302 0.381)
							(mid -0.270684 0.524684)
							(end -0.127 0.5842)
						)
						(arc
							(start 0.127 0.5842)
							(mid 0.270684 0.524684)
							(end 0.3302 0.381)
						)
					)
					(width 0)
					(fill yes)
				)
			)
		)
		(pad "S" smd custom
			(at 0.94996 1.0922)
			(size 0.1651 0.1651)
			(layers "F.Cu" "F.Mask" "F.Paste")
			(net "P1V8_C")
			(options
				(clearance outline)
				(anchor circle)
			)
			(primitives
				(gr_poly
					(pts
						(arc
							(start 0.3302 -0.381)
							(mid 0.270684 -0.524684)
							(end 0.127 -0.5842)
						)
						(arc
							(start -0.127 -0.5842)
							(mid -0.270684 -0.524684)
							(end -0.3302 -0.381)
						)
						(arc
							(start -0.3302 0.381)
							(mid -0.270684 0.524684)
							(end -0.127 0.5842)
						)
						(arc
							(start 0.127 0.5842)
							(mid 0.270684 0.524684)
							(end 0.3302 0.381)
						)
					)
					(width 0)
					(fill yes)
				)
			)
		)
	)
	(footprint ""
		(layer "F.Cu")
		(at 333.912718 -151.234648 -90)
		(property "Reference" "R7898"
			(at 0 0 270)
			(layer "F.SilkS")
			(hide yes)
			(effects
				(font
					(size 1.27 1.27)
				)
			)
		)
		(property "Value" "4K7R2F-GP"
			(at 0.064008 -3.993896 270)
			(unlocked yes)
			(layer "F.Fab")
			(hide yes)
			(effects
				(font
					(size 1.016 1.016)
					(thickness 0.1524)
				)
			)
		)
		(property "Device Type" "R402H16"
			(at 0.064008 -5.517896 270)
			(unlocked yes)
			(layer "F.Fab")
			(hide yes)
			(effects
				(font
					(size 1.016 1.016)
					(thickness 0.1524)
				)
			)
		)
		(duplicate_pad_numbers_are_jumpers no)
		(fp_line
			(start -0.508 -0.9398)
			(end -0.508 0.9398)
			(stroke
				(width 0.1524)
				(type default)
			)
			(layer "F.SilkS")
		)
		(fp_line
			(start 0.508 -0.9398)
			(end -0.508 -0.9398)
			(stroke
				(width 0.1524)
				(type default)
			)
			(layer "F.SilkS")
		)
		(fp_rect
			(start -0.508 0.9398)
			(end 0.508 -0.9398)
			(stroke
				(width 0)
				(type default)
			)
			(fill no)
			(layer "F.CrtYd")
		)
		(fp_rect
			(start -0.508 0.9398)
			(end 0.508 -0.9398)
			(stroke
				(width 0)
				(type default)
			)
			(fill no)
			(layer "F.Fab")
		)
		(pad "1" smd custom
			(at 0 -0.4445 270)
			(size 0.1397 0.1397)
			(layers "F.Cu" "F.Mask" "F.Paste")
			(net "CFG_SEL0")
			(options
				(clearance outline)
				(anchor circle)
			)
			(primitives
				(gr_poly
					(pts
						(arc
							(start -0.1778 -0.2794)
							(mid -0.249642 -0.249642)
							(end -0.2794 -0.1778)
						)
						(arc
							(start -0.2794 0.1778)
							(mid -0.249642 0.249642)
							(end -0.1778 0.2794)
						)
						(arc
							(start 0.1778 0.2794)
							(mid 0.249642 0.249642)
							(end 0.2794 0.1778)
						)
						(arc
							(start 0.2794 -0.1778)
							(mid 0.249642 -0.249642)
							(end 0.1778 -0.2794)
						)
					)
					(width 0)
					(fill yes)
				)
			)
		)
		(pad "2" smd custom
			(at 0 0.4445 270)
			(size 0.1397 0.1397)
			(layers "F.Cu" "F.Mask" "F.Paste")
			(net "GND")
			(options
				(clearance outline)
				(anchor circle)
			)
			(primitives
				(gr_poly
					(pts
						(arc
							(start -0.1778 -0.2794)
							(mid -0.249642 -0.249642)
							(end -0.2794 -0.1778)
						)
						(arc
							(start -0.2794 0.1778)
							(mid -0.249642 0.249642)
							(end -0.1778 0.2794)
						)
						(arc
							(start 0.1778 0.2794)
							(mid 0.249642 0.249642)
							(end 0.2794 0.1778)
						)
						(arc
							(start 0.2794 -0.1778)
							(mid 0.249642 -0.249642)
							(end 0.1778 -0.2794)
						)
					)
					(width 0)
					(fill yes)
				)
			)
		)
	)
	(footprint ""
		(layer "F.Cu")
		(at 6.2992 -216.9668 90)
		(property "Reference" "R625"
			(at 0 0 90)
			(layer "F.SilkS")
			(hide yes)
			(effects
				(font
					(size 1.27 1.27)
				)
			)
		)
		(property "Value" "0R2J-2-GP"
			(at 0.064008 -3.993896 90)
			(unlocked yes)
			(layer "F.Fab")
			(hide yes)
			(effects
				(font
					(size 1.016 1.016)
					(thickness 0.1524)
				)
			)
		)
		(property "Device Type" "R402H16"
			(at 0.064008 -5.517896 90)
			(unlocked yes)
			(layer "F.Fab")
			(hide yes)
			(effects
				(font
					(size 1.016 1.016)
					(thickness 0.1524)
				)
			)
		)
		(duplicate_pad_numbers_are_jumpers no)
		(fp_line
			(start 0.508 -0.9398)
			(end -0.508 -0.9398)
			(stroke
				(width 0.1524)
				(type default)
			)
			(layer "F.SilkS")
		)
		(fp_line
			(start -0.508 -0.9398)
			(end -0.508 0.9398)
			(stroke
				(width 0.1524)
				(type default)
			)
			(layer "F.SilkS")
		)
		(fp_rect
			(start -0.508 0.9398)
			(end 0.508 -0.9398)
			(stroke
				(width 0)
				(type default)
			)
			(fill no)
			(layer "F.CrtYd")
		)
		(fp_rect
			(start -0.508 0.9398)
			(end 0.508 -0.9398)
			(stroke
				(width 0)
				(type default)
			)
			(fill no)
			(layer "F.Fab")
		)
		(pad "1" smd custom
			(at 0 -0.4445 90)
			(size 0.1397 0.1397)
			(layers "F.Cu" "F.Mask" "F.Paste")
			(net "P3V3_STBY_PG")
			(options
				(clearance outline)
				(anchor circle)
			)
			(primitives
				(gr_poly
					(pts
						(arc
							(start -0.1778 -0.2794)
							(mid -0.249642 -0.249642)
							(end -0.2794 -0.1778)
						)
						(arc
							(start -0.2794 0.1778)
							(mid -0.249642 0.249642)
							(end -0.1778 0.2794)
						)
						(arc
							(start 0.1778 0.2794)
							(mid 0.249642 0.249642)
							(end 0.2794 0.1778)
						)
						(arc
							(start 0.2794 -0.1778)
							(mid 0.249642 -0.249642)
							(end 0.1778 -0.2794)
						)
					)
					(width 0)
					(fill yes)
				)
			)
		)
		(pad "2" smd custom
			(at 0 0.4445 90)
			(size 0.1397 0.1397)
			(layers "F.Cu" "F.Mask" "F.Paste")
			(net "PRSNT_AND_1")
			(options
				(clearance outline)
				(anchor circle)
			)
			(primitives
				(gr_poly
					(pts
						(arc
							(start -0.1778 -0.2794)
							(mid -0.249642 -0.249642)
							(end -0.2794 -0.1778)
						)
						(arc
							(start -0.2794 0.1778)
							(mid -0.249642 0.249642)
							(end -0.1778 0.2794)
						)
						(arc
							(start 0.1778 0.2794)
							(mid 0.249642 0.249642)
							(end 0.2794 0.1778)
						)
						(arc
							(start 0.2794 -0.1778)
							(mid 0.249642 -0.249642)
							(end 0.1778 -0.2794)
						)
					)
					(width 0)
					(fill yes)
				)
			)
		)
	)
	(footprint ""
		(layer "F.Cu")
		(at 190.054992 -30.099)
		(property "Reference" "TP126"
			(at 0 0 0)
			(layer "F.SilkS")
			(hide yes)
			(effects
				(font
					(size 1.27 1.27)
				)
			)
		)
		(property "Value" "TPAD28"
			(at 0.0127 -1.8034 0)
			(unlocked yes)
			(layer "F.Fab")
			(hide yes)
			(effects
				(font
					(size 1.016 1.016)
					(thickness 0.1524)
				)
			)
		)
		(property "Device Type" "TPAD28"
			(at 0.0127 -3.3274 0)
			(unlocked yes)
			(layer "F.Fab")
			(hide yes)
			(effects
				(font
					(size 1.016 1.016)
					(thickness 0.1524)
				)
			)
		)
		(duplicate_pad_numbers_are_jumpers no)
		(fp_poly
			(pts
				(arc
					(start 0.3556 0)
					(mid -0.3556 0)
					(end 0.3556 0)
				)
			)
			(stroke
				(width 0)
				(type default)
			)
			(fill no)
			(layer "F.CrtYd")
		)
		(fp_poly
			(pts
				(arc
					(start 0.6096 0)
					(mid -0.6096 0)
					(end 0.6096 0)
				)
			)
			(stroke
				(width 0)
				(type default)
			)
			(fill no)
			(layer "F.Fab")
		)
		(pad "1" smd circle
			(at 0 0)
			(size 0.7112 0.7112)
			(layers "F.Cu" "F.Mask" "F.Paste")
			(net "NC_PHY_TXC")
		)
	)
	(footprint ""
		(layer "F.Cu")
		(at 46.62297 -134.62 -90)
		(property "Reference" "SR914"
			(at 0 0 270)
			(layer "F.SilkS")
			(hide yes)
			(effects
				(font
					(size 1.27 1.27)
				)
			)
		)
		(property "Value" "0R2J-2-GP"
			(at 0.064008 -3.993896 270)
			(unlocked yes)
			(layer "F.Fab")
			(hide yes)
			(effects
				(font
					(size 1.016 1.016)
					(thickness 0.1524)
				)
			)
		)
		(property "Device Type" "R402H16"
			(at 0.064008 -5.517896 270)
			(unlocked yes)
			(layer "F.Fab")
			(hide yes)
			(effects
				(font
					(size 1.016 1.016)
					(thickness 0.1524)
				)
			)
		)
		(duplicate_pad_numbers_are_jumpers no)
		(fp_line
			(start -0.508 -0.9398)
			(end -0.508 0.9398)
			(stroke
				(width 0.1524)
				(type default)
			)
			(layer "F.SilkS")
		)
		(fp_line
			(start 0.508 -0.9398)
			(end -0.508 -0.9398)
			(stroke
				(width 0.1524)
				(type default)
			)
			(layer "F.SilkS")
		)
		(fp_rect
			(start -0.508 0.9398)
			(end 0.508 -0.9398)
			(stroke
				(width 0)
				(type default)
			)
			(fill no)
			(layer "F.CrtYd")
		)
		(fp_rect
			(start -0.508 0.9398)
			(end 0.508 -0.9398)
			(stroke
				(width 0)
				(type default)
			)
			(fill no)
			(layer "F.Fab")
		)
		(pad "1" smd custom
			(at 0 -0.4445 270)
			(size 0.1397 0.1397)
			(layers "F.Cu" "F.Mask" "F.Paste")
			(net "BMC_EXP_RESET_N")
			(options
				(clearance outline)
				(anchor circle)
			)
			(primitives
				(gr_poly
					(pts
						(arc
							(start -0.1778 -0.2794)
							(mid -0.249642 -0.249642)
							(end -0.2794 -0.1778)
						)
						(arc
							(start -0.2794 0.1778)
							(mid -0.249642 0.249642)
							(end -0.1778 0.2794)
						)
						(arc
							(start 0.1778 0.2794)
							(mid 0.249642 0.249642)
							(end 0.2794 0.1778)
						)
						(arc
							(start 0.2794 -0.1778)
							(mid 0.249642 -0.249642)
							(end 0.1778 -0.2794)
						)
					)
					(width 0)
					(fill yes)
				)
			)
		)
		(pad "2" smd custom
			(at 0 0.4445 270)
			(size 0.1397 0.1397)
			(layers "F.Cu" "F.Mask" "F.Paste")
			(net "EXP_RST_R")
			(options
				(clearance outline)
				(anchor circle)
			)
			(primitives
				(gr_poly
					(pts
						(arc
							(start -0.1778 -0.2794)
							(mid -0.249642 -0.249642)
							(end -0.2794 -0.1778)
						)
						(arc
							(start -0.2794 0.1778)
							(mid -0.249642 0.249642)
							(end -0.1778 0.2794)
						)
						(arc
							(start 0.1778 0.2794)
							(mid 0.249642 0.249642)
							(end 0.2794 0.1778)
						)
						(arc
							(start 0.2794 -0.1778)
							(mid 0.249642 -0.249642)
							(end 0.1778 -0.2794)
						)
					)
					(width 0)
					(fill yes)
				)
			)
		)
	)
	(footprint ""
		(layer "F.Cu")
		(at 310.769 -211.201 -90)
		(property "Reference" "R575"
			(at 0 0 270)
			(layer "F.SilkS")
			(hide yes)
			(effects
				(font
					(size 1.27 1.27)
				)
			)
		)
		(property "Value" "0R2J-2-GP"
			(at 0.064008 -3.993896 270)
			(unlocked yes)
			(layer "F.Fab")
			(hide yes)
			(effects
				(font
					(size 1.016 1.016)
					(thickness 0.1524)
				)
			)
		)
		(property "Device Type" "R402H16"
			(at 0.064008 -5.517896 270)
			(unlocked yes)
			(layer "F.Fab")
			(hide yes)
			(effects
				(font
					(size 1.016 1.016)
					(thickness 0.1524)
				)
			)
		)
		(duplicate_pad_numbers_are_jumpers no)
		(fp_line
			(start -0.508 -0.9398)
			(end -0.508 0.9398)
			(stroke
				(width 0.1524)
				(type default)
			)
			(layer "F.SilkS")
		)
		(fp_line
			(start 0.508 -0.9398)
			(end -0.508 -0.9398)
			(stroke
				(width 0.1524)
				(type default)
			)
			(layer "F.SilkS")
		)
		(fp_rect
			(start -0.508 0.9398)
			(end 0.508 -0.9398)
			(stroke
				(width 0)
				(type default)
			)
			(fill no)
			(layer "F.CrtYd")
		)
		(fp_rect
			(start -0.508 0.9398)
			(end 0.508 -0.9398)
			(stroke
				(width 0)
				(type default)
			)
			(fill no)
			(layer "F.Fab")
		)
		(pad "1" smd custom
			(at 0 -0.4445 270)
			(size 0.1397 0.1397)
			(layers "F.Cu" "F.Mask" "F.Paste")
			(net "JTAG_IOC_L_TDI_R")
			(options
				(clearance outline)
				(anchor circle)
			)
			(primitives
				(gr_poly
					(pts
						(arc
							(start -0.1778 -0.2794)
							(mid -0.249642 -0.249642)
							(end -0.2794 -0.1778)
						)
						(arc
							(start -0.2794 0.1778)
							(mid -0.249642 0.249642)
							(end -0.1778 0.2794)
						)
						(arc
							(start 0.1778 0.2794)
							(mid 0.249642 0.249642)
							(end 0.2794 0.1778)
						)
						(arc
							(start 0.2794 -0.1778)
							(mid 0.249642 -0.249642)
							(end 0.1778 -0.2794)
						)
					)
					(width 0)
					(fill yes)
				)
			)
		)
		(pad "2" smd custom
			(at 0 0.4445 270)
			(size 0.1397 0.1397)
			(layers "F.Cu" "F.Mask" "F.Paste")
			(net "JTAG_IOC_L_TDI")
			(options
				(clearance outline)
				(anchor circle)
			)
			(primitives
				(gr_poly
					(pts
						(arc
							(start -0.1778 -0.2794)
							(mid -0.249642 -0.249642)
							(end -0.2794 -0.1778)
						)
						(arc
							(start -0.2794 0.1778)
							(mid -0.249642 0.249642)
							(end -0.1778 0.2794)
						)
						(arc
							(start 0.1778 0.2794)
							(mid 0.249642 0.249642)
							(end 0.2794 0.1778)
						)
						(arc
							(start 0.2794 -0.1778)
							(mid 0.249642 -0.249642)
							(end 0.1778 -0.2794)
						)
					)
					(width 0)
					(fill yes)
				)
			)
		)
	)
	(footprint ""
		(layer "F.Cu")
		(at 166.846504 -24.184356 180)
		(property "Reference" "R414"
			(at 0 0 180)
			(layer "F.SilkS")
			(hide yes)
			(effects
				(font
					(size 1.27 1.27)
				)
			)
		)
		(property "Value" "0R2J-2-GP"
			(at 0.064008 -3.993896 180)
			(unlocked yes)
			(layer "F.Fab")
			(hide yes)
			(effects
				(font
					(size 1.016 1.016)
					(thickness 0.1524)
				)
			)
		)
		(property "Device Type" "R402H16"
			(at 0.064008 -5.517896 180)
			(unlocked yes)
			(layer "F.Fab")
			(hide yes)
			(effects
				(font
					(size 1.016 1.016)
					(thickness 0.1524)
				)
			)
		)
		(duplicate_pad_numbers_are_jumpers no)
		(fp_line
			(start 0.508 -0.9398)
			(end -0.508 -0.9398)
			(stroke
				(width 0.1524)
				(type default)
			)
			(layer "F.SilkS")
		)
		(fp_line
			(start -0.508 -0.9398)
			(end -0.508 0.9398)
			(stroke
				(width 0.1524)
				(type default)
			)
			(layer "F.SilkS")
		)
		(fp_rect
			(start -0.508 0.9398)
			(end 0.508 -0.9398)
			(stroke
				(width 0)
				(type default)
			)
			(fill no)
			(layer "F.CrtYd")
		)
		(fp_rect
			(start -0.508 0.9398)
			(end 0.508 -0.9398)
			(stroke
				(width 0)
				(type default)
			)
			(fill no)
			(layer "F.Fab")
		)
		(pad "1" smd custom
			(at 0 -0.4445 180)
			(size 0.1397 0.1397)
			(layers "F.Cu" "F.Mask" "F.Paste")
			(net "RJ45_GND_7")
			(options
				(clearance outline)
				(anchor circle)
			)
			(primitives
				(gr_poly
					(pts
						(arc
							(start -0.1778 -0.2794)
							(mid -0.249642 -0.249642)
							(end -0.2794 -0.1778)
						)
						(arc
							(start -0.2794 0.1778)
							(mid -0.249642 0.249642)
							(end -0.1778 0.2794)
						)
						(arc
							(start 0.1778 0.2794)
							(mid 0.249642 0.249642)
							(end 0.2794 0.1778)
						)
						(arc
							(start 0.2794 -0.1778)
							(mid 0.249642 -0.249642)
							(end 0.1778 -0.2794)
						)
					)
					(width 0)
					(fill yes)
				)
			)
		)
		(pad "2" smd custom
			(at 0 0.4445 180)
			(size 0.1397 0.1397)
			(layers "F.Cu" "F.Mask" "F.Paste")
			(net "GND")
			(options
				(clearance outline)
				(anchor circle)
			)
			(primitives
				(gr_poly
					(pts
						(arc
							(start -0.1778 -0.2794)
							(mid -0.249642 -0.249642)
							(end -0.2794 -0.1778)
						)
						(arc
							(start -0.2794 0.1778)
							(mid -0.249642 0.249642)
							(end -0.1778 0.2794)
						)
						(arc
							(start 0.1778 0.2794)
							(mid 0.249642 0.249642)
							(end 0.2794 0.1778)
						)
						(arc
							(start 0.2794 -0.1778)
							(mid 0.249642 -0.249642)
							(end 0.1778 -0.2794)
						)
					)
					(width 0)
					(fill yes)
				)
			)
		)
	)
	(footprint ""
		(layer "F.Cu")
		(at 317.6524 -212.6234 180)
		(property "Reference" "R573"
			(at 0 0 180)
			(layer "F.SilkS")
			(hide yes)
			(effects
				(font
					(size 1.27 1.27)
				)
			)
		)
		(property "Value" "10KR2F-2-GP"
			(at 0.064008 -3.993896 180)
			(unlocked yes)
			(layer "F.Fab")
			(hide yes)
			(effects
				(font
					(size 1.016 1.016)
					(thickness 0.1524)
				)
			)
		)
		(property "Device Type" "R402H16"
			(at 0.064008 -5.517896 180)
			(unlocked yes)
			(layer "F.Fab")
			(hide yes)
			(effects
				(font
					(size 1.016 1.016)
					(thickness 0.1524)
				)
			)
		)
		(duplicate_pad_numbers_are_jumpers no)
		(fp_line
			(start 0.508 -0.9398)
			(end -0.508 -0.9398)
			(stroke
				(width 0.1524)
				(type default)
			)
			(layer "F.SilkS")
		)
		(fp_line
			(start -0.508 -0.9398)
			(end -0.508 0.9398)
			(stroke
				(width 0.1524)
				(type default)
			)
			(layer "F.SilkS")
		)
		(fp_rect
			(start -0.508 0.9398)
			(end 0.508 -0.9398)
			(stroke
				(width 0)
				(type default)
			)
			(fill no)
			(layer "F.CrtYd")
		)
		(fp_rect
			(start -0.508 0.9398)
			(end 0.508 -0.9398)
			(stroke
				(width 0)
				(type default)
			)
			(fill no)
			(layer "F.Fab")
		)
		(pad "1" smd custom
			(at 0 -0.4445 180)
			(size 0.1397 0.1397)
			(layers "F.Cu" "F.Mask" "F.Paste")
			(net "P1V8_STBY")
			(options
				(clearance outline)
				(anchor circle)
			)
			(primitives
				(gr_poly
					(pts
						(arc
							(start -0.1778 -0.2794)
							(mid -0.249642 -0.249642)
							(end -0.2794 -0.1778)
						)
						(arc
							(start -0.2794 0.1778)
							(mid -0.249642 0.249642)
							(end -0.1778 0.2794)
						)
						(arc
							(start 0.1778 0.2794)
							(mid 0.249642 0.249642)
							(end 0.2794 0.1778)
						)
						(arc
							(start 0.2794 -0.1778)
							(mid 0.249642 -0.249642)
							(end 0.1778 -0.2794)
						)
					)
					(width 0)
					(fill yes)
				)
			)
		)
		(pad "2" smd custom
			(at 0 0.4445 180)
			(size 0.1397 0.1397)
			(layers "F.Cu" "F.Mask" "F.Paste")
			(net "EXP_TDO_EN")
			(options
				(clearance outline)
				(anchor circle)
			)
			(primitives
				(gr_poly
					(pts
						(arc
							(start -0.1778 -0.2794)
							(mid -0.249642 -0.249642)
							(end -0.2794 -0.1778)
						)
						(arc
							(start -0.2794 0.1778)
							(mid -0.249642 0.249642)
							(end -0.1778 0.2794)
						)
						(arc
							(start 0.1778 0.2794)
							(mid 0.249642 0.249642)
							(end 0.2794 0.1778)
						)
						(arc
							(start 0.2794 -0.1778)
							(mid 0.249642 -0.249642)
							(end 0.1778 -0.2794)
						)
					)
					(width 0)
					(fill yes)
				)
			)
		)
	)
	(footprint ""
		(layer "F.Cu")
		(at 171.365164 -22.490176 180)
		(property "Reference" "R403"
			(at 0 0 180)
			(layer "F.SilkS")
			(hide yes)
			(effects
				(font
					(size 1.27 1.27)
				)
			)
		)
		(property "Value" "0R2J-2-GP"
			(at 0.064008 -3.993896 180)
			(unlocked yes)
			(layer "F.Fab")
			(hide yes)
			(effects
				(font
					(size 1.016 1.016)
					(thickness 0.1524)
				)
			)
		)
		(property "Device Type" "R402H16"
			(at 0.064008 -5.517896 180)
			(unlocked yes)
			(layer "F.Fab")
			(hide yes)
			(effects
				(font
					(size 1.016 1.016)
					(thickness 0.1524)
				)
			)
		)
		(duplicate_pad_numbers_are_jumpers no)
		(fp_line
			(start 0.508 -0.9398)
			(end -0.508 -0.9398)
			(stroke
				(width 0.1524)
				(type default)
			)
			(layer "F.SilkS")
		)
		(fp_line
			(start -0.508 -0.9398)
			(end -0.508 0.9398)
			(stroke
				(width 0.1524)
				(type default)
			)
			(layer "F.SilkS")
		)
		(fp_rect
			(start -0.508 0.9398)
			(end 0.508 -0.9398)
			(stroke
				(width 0)
				(type default)
			)
			(fill no)
			(layer "F.CrtYd")
		)
		(fp_rect
			(start -0.508 0.9398)
			(end 0.508 -0.9398)
			(stroke
				(width 0)
				(type default)
			)
			(fill no)
			(layer "F.Fab")
		)
		(pad "1" smd custom
			(at 0 -0.4445 180)
			(size 0.1397 0.1397)
			(layers "F.Cu" "F.Mask" "F.Paste")
			(net "P3V3_STBY")
			(options
				(clearance outline)
				(anchor circle)
			)
			(primitives
				(gr_poly
					(pts
						(arc
							(start -0.1778 -0.2794)
							(mid -0.249642 -0.249642)
							(end -0.2794 -0.1778)
						)
						(arc
							(start -0.2794 0.1778)
							(mid -0.249642 0.249642)
							(end -0.1778 0.2794)
						)
						(arc
							(start 0.1778 0.2794)
							(mid 0.249642 0.249642)
							(end 0.2794 0.1778)
						)
						(arc
							(start 0.2794 -0.1778)
							(mid 0.249642 -0.249642)
							(end 0.1778 -0.2794)
						)
					)
					(width 0)
					(fill yes)
				)
			)
		)
		(pad "2" smd custom
			(at 0 0.4445 180)
			(size 0.1397 0.1397)
			(layers "F.Cu" "F.Mask" "F.Paste")
			(net "MOD_IMC_FAB_D_COP")
			(options
				(clearance outline)
				(anchor circle)
			)
			(primitives
				(gr_poly
					(pts
						(arc
							(start -0.1778 -0.2794)
							(mid -0.249642 -0.249642)
							(end -0.2794 -0.1778)
						)
						(arc
							(start -0.2794 0.1778)
							(mid -0.249642 0.249642)
							(end -0.1778 0.2794)
						)
						(arc
							(start 0.1778 0.2794)
							(mid 0.249642 0.249642)
							(end 0.2794 0.1778)
						)
						(arc
							(start 0.2794 -0.1778)
							(mid 0.249642 -0.249642)
							(end 0.1778 -0.2794)
						)
					)
					(width 0)
					(fill yes)
				)
			)
		)
	)
	(footprint ""
		(layer "F.Cu")
		(at 317.8048 -53.2638 90)
		(property "Reference" "C281"
			(at 0 0 90)
			(layer "F.SilkS")
			(hide yes)
			(effects
				(font
					(size 1.27 1.27)
				)
			)
		)
		(property "Value" "SC1U25V3KX-GP"
			(at 0 -2.8194 90)
			(unlocked yes)
			(layer "F.Fab")
			(hide yes)
			(effects
				(font
					(size 1.016 1.016)
					(thickness 0.1524)
				)
			)
		)
		(property "Device Type" "C603H36"
			(at 0 -4.3434 90)
			(unlocked yes)
			(layer "F.Fab")
			(hide yes)
			(effects
				(font
					(size 1.016 1.016)
					(thickness 0.1524)
				)
			)
		)
		(duplicate_pad_numbers_are_jumpers no)
		(fp_line
			(start 0.508 0)
			(end -0.508 0)
			(stroke
				(width 0.2032)
				(type default)
			)
			(layer "F.SilkS")
		)
		(fp_rect
			(start -0.5842 1.3335)
			(end 0.5842 -1.3335)
			(stroke
				(width 0)
				(type default)
			)
			(fill no)
			(layer "F.CrtYd")
		)
		(fp_rect
			(start -0.5842 1.3335)
			(end 0.5842 -1.3335)
			(stroke
				(width 0)
				(type default)
			)
			(fill no)
			(layer "F.Fab")
		)
		(pad "1" smd custom
			(at 0 -0.762 90)
			(size 0.2159 0.2159)
			(layers "F.Cu" "F.Mask" "F.Paste")
			(net "P5V_STBY")
			(options
				(clearance outline)
				(anchor circle)
			)
			(primitives
				(gr_poly
					(pts
						(arc
							(start -0.3302 -0.4318)
							(mid -0.402042 -0.402042)
							(end -0.4318 -0.3302)
						)
						(arc
							(start -0.4318 0.3302)
							(mid -0.402042 0.402042)
							(end -0.3302 0.4318)
						)
						(arc
							(start 0.3302 0.4318)
							(mid 0.402042 0.402042)
							(end 0.4318 0.3302)
						)
						(arc
							(start 0.4318 -0.3302)
							(mid 0.402042 -0.402042)
							(end 0.3302 -0.4318)
						)
					)
					(width 0)
					(fill yes)
				)
			)
		)
		(pad "2" smd custom
			(at 0 0.762 90)
			(size 0.2159 0.2159)
			(layers "F.Cu" "F.Mask" "F.Paste")
			(net "GND")
			(options
				(clearance outline)
				(anchor circle)
			)
			(primitives
				(gr_poly
					(pts
						(arc
							(start -0.3302 -0.4318)
							(mid -0.402042 -0.402042)
							(end -0.4318 -0.3302)
						)
						(arc
							(start -0.4318 0.3302)
							(mid -0.402042 0.402042)
							(end -0.3302 0.4318)
						)
						(arc
							(start 0.3302 0.4318)
							(mid 0.402042 0.402042)
							(end 0.4318 0.3302)
						)
						(arc
							(start 0.4318 -0.3302)
							(mid 0.402042 -0.402042)
							(end 0.3302 -0.4318)
						)
					)
					(width 0)
					(fill yes)
				)
			)
		)
	)
	(footprint ""
		(layer "F.Cu")
		(at 151.003 -61.468)
		(property "Reference" "SC914"
			(at 0 0 0)
			(layer "F.SilkS")
			(hide yes)
			(effects
				(font
					(size 1.27 1.27)
				)
			)
		)
		(property "Value" "SCD1U16V2KX-3GP"
			(at 1.1811 -2.7051 0)
			(unlocked yes)
			(layer "F.Fab")
			(hide yes)
			(effects
				(font
					(size 1.016 1.016)
					(thickness 0.1524)
				)
			)
		)
		(property "Device Type" "C402H22"
			(at 1.1811 -4.2291 0)
			(unlocked yes)
			(layer "F.Fab")
			(hide yes)
			(effects
				(font
					(size 1.016 1.016)
					(thickness 0.1524)
				)
			)
		)
		(duplicate_pad_numbers_are_jumpers no)
		(fp_rect
			(start -0.4318 0.9525)
			(end 0.4318 -0.9525)
			(stroke
				(width 0)
				(type default)
			)
			(fill no)
			(layer "F.CrtYd")
		)
		(fp_rect
			(start -0.4318 0.9525)
			(end 0.4318 -0.9525)
			(stroke
				(width 0)
				(type default)
			)
			(fill no)
			(layer "F.Fab")
		)
		(pad "1" smd custom
			(at 0 -0.4445)
			(size 0.1524 0.1524)
			(layers "F.Cu" "F.Mask" "F.Paste")
			(net "P1V8_C")
			(options
				(clearance outline)
				(anchor circle)
			)
			(primitives
				(gr_poly
					(pts
						(arc
							(start 0.3048 -0.2032)
							(mid 0.275042 -0.275042)
							(end 0.2032 -0.3048)
						)
						(arc
							(start -0.2032 -0.3048)
							(mid -0.275042 -0.275042)
							(end -0.3048 -0.2032)
						)
						(arc
							(start -0.3048 0.2032)
							(mid -0.275042 0.275042)
							(end -0.2032 0.3048)
						)
						(arc
							(start 0.2032 0.3048)
							(mid 0.275042 0.275042)
							(end 0.3048 0.2032)
						)
					)
					(width 0)
					(fill yes)
				)
			)
		)
		(pad "2" smd custom
			(at 0 0.4445)
			(size 0.1524 0.1524)
			(layers "F.Cu" "F.Mask" "F.Paste")
			(net "GND")
			(options
				(clearance outline)
				(anchor circle)
			)
			(primitives
				(gr_poly
					(pts
						(arc
							(start 0.3048 -0.2032)
							(mid 0.275042 -0.275042)
							(end 0.2032 -0.3048)
						)
						(arc
							(start -0.2032 -0.3048)
							(mid -0.275042 -0.275042)
							(end -0.3048 -0.2032)
						)
						(arc
							(start -0.3048 0.2032)
							(mid -0.275042 0.275042)
							(end -0.2032 0.3048)
						)
						(arc
							(start 0.2032 0.3048)
							(mid 0.275042 0.275042)
							(end 0.3048 0.2032)
						)
					)
					(width 0)
					(fill yes)
				)
			)
		)
	)
	(footprint ""
		(layer "F.Cu")
		(at 44.577 -230.759)
		(property "Reference" "C301"
			(at 0 0 0)
			(layer "F.SilkS")
			(hide yes)
			(effects
				(font
					(size 1.27 1.27)
				)
			)
		)
		(property "Value" "SCD1U25V2KX-2-GP"
			(at 1.1811 -2.7051 0)
			(unlocked yes)
			(layer "F.Fab")
			(hide yes)
			(effects
				(font
					(size 1.016 1.016)
					(thickness 0.1524)
				)
			)
		)
		(property "Device Type" "C402H22"
			(at 1.1811 -4.2291 0)
			(unlocked yes)
			(layer "F.Fab")
			(hide yes)
			(effects
				(font
					(size 1.016 1.016)
					(thickness 0.1524)
				)
			)
		)
		(duplicate_pad_numbers_are_jumpers no)
		(fp_rect
			(start -0.4318 0.9525)
			(end 0.4318 -0.9525)
			(stroke
				(width 0)
				(type default)
			)
			(fill no)
			(layer "F.CrtYd")
		)
		(fp_rect
			(start -0.4318 0.9525)
			(end 0.4318 -0.9525)
			(stroke
				(width 0)
				(type default)
			)
			(fill no)
			(layer "F.Fab")
		)
		(pad "1" smd custom
			(at 0 -0.4445)
			(size 0.1524 0.1524)
			(layers "F.Cu" "F.Mask" "F.Paste")
			(net "P12V_PCIE")
			(options
				(clearance outline)
				(anchor circle)
			)
			(primitives
				(gr_poly
					(pts
						(arc
							(start 0.3048 -0.2032)
							(mid 0.275042 -0.275042)
							(end 0.2032 -0.3048)
						)
						(arc
							(start -0.2032 -0.3048)
							(mid -0.275042 -0.275042)
							(end -0.3048 -0.2032)
						)
						(arc
							(start -0.3048 0.2032)
							(mid -0.275042 0.275042)
							(end -0.2032 0.3048)
						)
						(arc
							(start 0.2032 0.3048)
							(mid 0.275042 0.275042)
							(end 0.3048 0.2032)
						)
					)
					(width 0)
					(fill yes)
				)
			)
		)
		(pad "2" smd custom
			(at 0 0.4445)
			(size 0.1524 0.1524)
			(layers "F.Cu" "F.Mask" "F.Paste")
			(net "GND")
			(options
				(clearance outline)
				(anchor circle)
			)
			(primitives
				(gr_poly
					(pts
						(arc
							(start 0.3048 -0.2032)
							(mid 0.275042 -0.275042)
							(end 0.2032 -0.3048)
						)
						(arc
							(start -0.2032 -0.3048)
							(mid -0.275042 -0.275042)
							(end -0.3048 -0.2032)
						)
						(arc
							(start -0.3048 0.2032)
							(mid -0.275042 0.275042)
							(end -0.2032 0.3048)
						)
						(arc
							(start 0.2032 0.3048)
							(mid 0.275042 0.275042)
							(end 0.3048 0.2032)
						)
					)
					(width 0)
					(fill yes)
				)
			)
		)
	)
	(footprint ""
		(layer "F.Cu")
		(at 76.748386 -108.630212 180)
		(property "Reference" "PC191"
			(at 0 0 180)
			(layer "F.SilkS")
			(hide yes)
			(effects
				(font
					(size 1.27 1.27)
				)
			)
		)
		(property "Value" "SCD47U25V3KX-3-GP"
			(at 0 -2.8194 180)
			(unlocked yes)
			(layer "F.Fab")
			(hide yes)
			(effects
				(font
					(size 1.016 1.016)
					(thickness 0.1524)
				)
			)
		)
		(property "Device Type" "C603H36"
			(at 0 -4.3434 180)
			(unlocked yes)
			(layer "F.Fab")
			(hide yes)
			(effects
				(font
					(size 1.016 1.016)
					(thickness 0.1524)
				)
			)
		)
		(duplicate_pad_numbers_are_jumpers no)
		(fp_line
			(start 0.508 0)
			(end -0.508 0)
			(stroke
				(width 0.2032)
				(type default)
			)
			(layer "F.SilkS")
		)
		(fp_rect
			(start -0.5842 1.3335)
			(end 0.5842 -1.3335)
			(stroke
				(width 0)
				(type default)
			)
			(fill no)
			(layer "F.CrtYd")
		)
		(fp_rect
			(start -0.5842 1.3335)
			(end 0.5842 -1.3335)
			(stroke
				(width 0)
				(type default)
			)
			(fill no)
			(layer "F.Fab")
		)
		(pad "1" smd custom
			(at 0 -0.762 180)
			(size 0.2159 0.2159)
			(layers "F.Cu" "F.Mask" "F.Paste")
			(net "P1V8_EN_LV")
			(options
				(clearance outline)
				(anchor circle)
			)
			(primitives
				(gr_poly
					(pts
						(arc
							(start -0.3302 -0.4318)
							(mid -0.402042 -0.402042)
							(end -0.4318 -0.3302)
						)
						(arc
							(start -0.4318 0.3302)
							(mid -0.402042 0.402042)
							(end -0.3302 0.4318)
						)
						(arc
							(start 0.3302 0.4318)
							(mid 0.402042 0.402042)
							(end 0.4318 0.3302)
						)
						(arc
							(start 0.4318 -0.3302)
							(mid 0.402042 -0.402042)
							(end 0.3302 -0.4318)
						)
					)
					(width 0)
					(fill yes)
				)
			)
		)
		(pad "2" smd custom
			(at 0 0.762 180)
			(size 0.2159 0.2159)
			(layers "F.Cu" "F.Mask" "F.Paste")
			(net "P1V8_E")
			(options
				(clearance outline)
				(anchor circle)
			)
			(primitives
				(gr_poly
					(pts
						(arc
							(start -0.3302 -0.4318)
							(mid -0.402042 -0.402042)
							(end -0.4318 -0.3302)
						)
						(arc
							(start -0.4318 0.3302)
							(mid -0.402042 0.402042)
							(end -0.3302 0.4318)
						)
						(arc
							(start 0.3302 0.4318)
							(mid 0.402042 0.402042)
							(end 0.4318 0.3302)
						)
						(arc
							(start 0.4318 -0.3302)
							(mid 0.402042 -0.402042)
							(end 0.3302 -0.4318)
						)
					)
					(width 0)
					(fill yes)
				)
			)
		)
	)
	(footprint ""
		(layer "F.Cu")
		(at 297.942 -98.679)
		(property "Reference" "C326"
			(at 0 0 0)
			(layer "F.SilkS")
			(hide yes)
			(effects
				(font
					(size 1.27 1.27)
				)
			)
		)
		(property "Value" "SCD1U16V2KX-3GP"
			(at 1.1811 -2.7051 0)
			(unlocked yes)
			(layer "F.Fab")
			(hide yes)
			(effects
				(font
					(size 1.016 1.016)
					(thickness 0.1524)
				)
			)
		)
		(property "Device Type" "C402H22"
			(at 1.1811 -4.2291 0)
			(unlocked yes)
			(layer "F.Fab")
			(hide yes)
			(effects
				(font
					(size 1.016 1.016)
					(thickness 0.1524)
				)
			)
		)
		(duplicate_pad_numbers_are_jumpers no)
		(fp_rect
			(start -0.4318 0.9525)
			(end 0.4318 -0.9525)
			(stroke
				(width 0)
				(type default)
			)
			(fill no)
			(layer "F.CrtYd")
		)
		(fp_rect
			(start -0.4318 0.9525)
			(end 0.4318 -0.9525)
			(stroke
				(width 0)
				(type default)
			)
			(fill no)
			(layer "F.Fab")
		)
		(pad "1" smd custom
			(at 0 -0.4445)
			(size 0.1524 0.1524)
			(layers "F.Cu" "F.Mask" "F.Paste")
			(net "P3V3_STBY")
			(options
				(clearance outline)
				(anchor circle)
			)
			(primitives
				(gr_poly
					(pts
						(arc
							(start 0.3048 -0.2032)
							(mid 0.275042 -0.275042)
							(end 0.2032 -0.3048)
						)
						(arc
							(start -0.2032 -0.3048)
							(mid -0.275042 -0.275042)
							(end -0.3048 -0.2032)
						)
						(arc
							(start -0.3048 0.2032)
							(mid -0.275042 0.275042)
							(end -0.2032 0.3048)
						)
						(arc
							(start 0.2032 0.3048)
							(mid 0.275042 0.275042)
							(end 0.3048 0.2032)
						)
					)
					(width 0)
					(fill yes)
				)
			)
		)
		(pad "2" smd custom
			(at 0 0.4445)
			(size 0.1524 0.1524)
			(layers "F.Cu" "F.Mask" "F.Paste")
			(net "GND")
			(options
				(clearance outline)
				(anchor circle)
			)
			(primitives
				(gr_poly
					(pts
						(arc
							(start 0.3048 -0.2032)
							(mid 0.275042 -0.275042)
							(end 0.2032 -0.3048)
						)
						(arc
							(start -0.2032 -0.3048)
							(mid -0.275042 -0.275042)
							(end -0.3048 -0.2032)
						)
						(arc
							(start -0.3048 0.2032)
							(mid -0.275042 0.275042)
							(end -0.2032 0.3048)
						)
						(arc
							(start 0.2032 0.3048)
							(mid 0.275042 0.275042)
							(end 0.3048 0.2032)
						)
					)
					(width 0)
					(fill yes)
				)
			)
		)
	)
	(footprint ""
		(layer "F.Cu")
		(at 48.768 -217.551 -90)
		(property "Reference" "R9023"
			(at 0 0 270)
			(layer "F.SilkS")
			(hide yes)
			(effects
				(font
					(size 1.27 1.27)
				)
			)
		)
		(property "Value" "57K6R2F-GP"
			(at 0.064008 -3.993896 270)
			(unlocked yes)
			(layer "F.Fab")
			(hide yes)
			(effects
				(font
					(size 1.016 1.016)
					(thickness 0.1524)
				)
			)
		)
		(property "Device Type" "R402H16"
			(at 0.064008 -5.517896 270)
			(unlocked yes)
			(layer "F.Fab")
			(hide yes)
			(effects
				(font
					(size 1.016 1.016)
					(thickness 0.1524)
				)
			)
		)
		(duplicate_pad_numbers_are_jumpers no)
		(fp_line
			(start -0.508 -0.9398)
			(end -0.508 0.9398)
			(stroke
				(width 0.1524)
				(type default)
			)
			(layer "F.SilkS")
		)
		(fp_line
			(start 0.508 -0.9398)
			(end -0.508 -0.9398)
			(stroke
				(width 0.1524)
				(type default)
			)
			(layer "F.SilkS")
		)
		(fp_rect
			(start -0.508 0.9398)
			(end 0.508 -0.9398)
			(stroke
				(width 0)
				(type default)
			)
			(fill no)
			(layer "F.CrtYd")
		)
		(fp_rect
			(start -0.508 0.9398)
			(end 0.508 -0.9398)
			(stroke
				(width 0)
				(type default)
			)
			(fill no)
			(layer "F.Fab")
		)
		(pad "1" smd custom
			(at 0 -0.4445 270)
			(size 0.1397 0.1397)
			(layers "F.Cu" "F.Mask" "F.Paste")
			(net "MB0_ISTART_R")
			(options
				(clearance outline)
				(anchor circle)
			)
			(primitives
				(gr_poly
					(pts
						(arc
							(start -0.1778 -0.2794)
							(mid -0.249642 -0.249642)
							(end -0.2794 -0.1778)
						)
						(arc
							(start -0.2794 0.1778)
							(mid -0.249642 0.249642)
							(end -0.1778 0.2794)
						)
						(arc
							(start 0.1778 0.2794)
							(mid 0.249642 0.249642)
							(end 0.2794 0.1778)
						)
						(arc
							(start 0.2794 -0.1778)
							(mid 0.249642 -0.249642)
							(end 0.1778 -0.2794)
						)
					)
					(width 0)
					(fill yes)
				)
			)
		)
		(pad "2" smd custom
			(at 0 0.4445 270)
			(size 0.1397 0.1397)
			(layers "F.Cu" "F.Mask" "F.Paste")
			(net "AGND_CURRENT_MON")
			(options
				(clearance outline)
				(anchor circle)
			)
			(primitives
				(gr_poly
					(pts
						(arc
							(start -0.1778 -0.2794)
							(mid -0.249642 -0.249642)
							(end -0.2794 -0.1778)
						)
						(arc
							(start -0.2794 0.1778)
							(mid -0.249642 0.249642)
							(end -0.1778 0.2794)
						)
						(arc
							(start 0.1778 0.2794)
							(mid 0.249642 0.249642)
							(end 0.2794 0.1778)
						)
						(arc
							(start 0.2794 -0.1778)
							(mid 0.249642 -0.249642)
							(end 0.1778 -0.2794)
						)
					)
					(width 0)
					(fill yes)
				)
			)
		)
	)
	(footprint ""
		(layer "F.Cu")
		(at 205.74 -121.158)
		(property "Reference" "PR9013"
			(at 0 0 0)
			(layer "F.SilkS")
			(hide yes)
			(effects
				(font
					(size 1.27 1.27)
				)
			)
		)
		(property "Value" "10R3F-GP"
			(at -0.0254 -2.5146 0)
			(unlocked yes)
			(layer "F.Fab")
			(hide yes)
			(effects
				(font
					(size 1.016 1.016)
					(thickness 0.1524)
				)
			)
		)
		(property "Device Type" "R603H22"
			(at -0.0254 -4.0386 0)
			(unlocked yes)
			(layer "F.Fab")
			(hide yes)
			(effects
				(font
					(size 1.016 1.016)
					(thickness 0.1524)
				)
			)
		)
		(duplicate_pad_numbers_are_jumpers no)
		(fp_line
			(start -0.4826 0)
			(end -0.2032 0)
			(stroke
				(width 0.2032)
				(type default)
			)
			(layer "F.SilkS")
		)
		(fp_line
			(start 0.2032 0)
			(end 0.4826 0)
			(stroke
				(width 0.2032)
				(type default)
			)
			(layer "F.SilkS")
		)
		(fp_rect
			(start -0.5842 1.3335)
			(end 0.5842 -1.3335)
			(stroke
				(width 0)
				(type default)
			)
			(fill no)
			(layer "F.CrtYd")
		)
		(fp_rect
			(start -0.5842 1.3335)
			(end 0.5842 -1.3335)
			(stroke
				(width 0)
				(type default)
			)
			(fill no)
			(layer "F.Fab")
		)
		(pad "1" smd custom
			(at 0 -0.762)
			(size 0.2159 0.2159)
			(layers "F.Cu" "F.Mask" "F.Paste")
			(net "P1V5_E_CC")
			(options
				(clearance outline)
				(anchor circle)
			)
			(primitives
				(gr_poly
					(pts
						(arc
							(start -0.3302 -0.4318)
							(mid -0.402042 -0.402042)
							(end -0.4318 -0.3302)
						)
						(arc
							(start -0.4318 0.3302)
							(mid -0.402042 0.402042)
							(end -0.3302 0.4318)
						)
						(arc
							(start 0.3302 0.4318)
							(mid 0.402042 0.402042)
							(end 0.4318 0.3302)
						)
						(arc
							(start 0.4318 -0.3302)
							(mid 0.402042 -0.402042)
							(end 0.3302 -0.4318)
						)
					)
					(width 0)
					(fill yes)
				)
			)
		)
		(pad "2" smd custom
			(at 0 0.762)
			(size 0.2159 0.2159)
			(layers "F.Cu" "F.Mask" "F.Paste")
			(net "P1V5_E_CC_R")
			(options
				(clearance outline)
				(anchor circle)
			)
			(primitives
				(gr_poly
					(pts
						(arc
							(start -0.3302 -0.4318)
							(mid -0.402042 -0.402042)
							(end -0.4318 -0.3302)
						)
						(arc
							(start -0.4318 0.3302)
							(mid -0.402042 0.402042)
							(end -0.3302 0.4318)
						)
						(arc
							(start 0.3302 0.4318)
							(mid 0.402042 0.402042)
							(end 0.4318 0.3302)
						)
						(arc
							(start 0.4318 -0.3302)
							(mid 0.402042 -0.402042)
							(end 0.3302 -0.4318)
						)
					)
					(width 0)
					(fill yes)
				)
			)
		)
	)
	(footprint ""
		(layer "F.Cu")
		(at 284.48 -159.893)
		(property "Reference" "TP115"
			(at 0 0 0)
			(layer "F.SilkS")
			(hide yes)
			(effects
				(font
					(size 1.27 1.27)
				)
			)
		)
		(property "Value" "TPAD28"
			(at 0.0127 -1.8034 0)
			(unlocked yes)
			(layer "F.Fab")
			(hide yes)
			(effects
				(font
					(size 1.016 1.016)
					(thickness 0.1524)
				)
			)
		)
		(property "Device Type" "TPAD28"
			(at 0.0127 -3.3274 0)
			(unlocked yes)
			(layer "F.Fab")
			(hide yes)
			(effects
				(font
					(size 1.016 1.016)
					(thickness 0.1524)
				)
			)
		)
		(duplicate_pad_numbers_are_jumpers no)
		(fp_poly
			(pts
				(arc
					(start 0.3556 0)
					(mid -0.3556 0)
					(end 0.3556 0)
				)
			)
			(stroke
				(width 0)
				(type default)
			)
			(fill no)
			(layer "F.CrtYd")
		)
		(fp_poly
			(pts
				(arc
					(start 0.6096 0)
					(mid -0.6096 0)
					(end 0.6096 0)
				)
			)
			(stroke
				(width 0)
				(type default)
			)
			(fill no)
			(layer "F.Fab")
		)
		(pad "1" smd circle
			(at 0 0)
			(size 0.7112 0.7112)
			(layers "F.Cu" "F.Mask" "F.Paste")
			(net "TP_BMC_GPIOF2")
		)
	)
	(footprint ""
		(layer "F.Cu")
		(at 274.193 -176.657 90)
		(property "Reference" "R357"
			(at 0 0 90)
			(layer "F.SilkS")
			(hide yes)
			(effects
				(font
					(size 1.27 1.27)
				)
			)
		)
		(property "Value" "3K3R2F-2-GP"
			(at 0.064008 -3.993896 90)
			(unlocked yes)
			(layer "F.Fab")
			(hide yes)
			(effects
				(font
					(size 1.016 1.016)
					(thickness 0.1524)
				)
			)
		)
		(property "Device Type" "R402H16"
			(at 0.064008 -5.517896 90)
			(unlocked yes)
			(layer "F.Fab")
			(hide yes)
			(effects
				(font
					(size 1.016 1.016)
					(thickness 0.1524)
				)
			)
		)
		(duplicate_pad_numbers_are_jumpers no)
		(fp_line
			(start 0.508 -0.9398)
			(end -0.508 -0.9398)
			(stroke
				(width 0.1524)
				(type default)
			)
			(layer "F.SilkS")
		)
		(fp_line
			(start -0.508 -0.9398)
			(end -0.508 0.9398)
			(stroke
				(width 0.1524)
				(type default)
			)
			(layer "F.SilkS")
		)
		(fp_rect
			(start -0.508 0.9398)
			(end 0.508 -0.9398)
			(stroke
				(width 0)
				(type default)
			)
			(fill no)
			(layer "F.CrtYd")
		)
		(fp_rect
			(start -0.508 0.9398)
			(end 0.508 -0.9398)
			(stroke
				(width 0)
				(type default)
			)
			(fill no)
			(layer "F.Fab")
		)
		(pad "1" smd custom
			(at 0 -0.4445 90)
			(size 0.1397 0.1397)
			(layers "F.Cu" "F.Mask" "F.Paste")
			(net "P3V3_STBY")
			(options
				(clearance outline)
				(anchor circle)
			)
			(primitives
				(gr_poly
					(pts
						(arc
							(start -0.1778 -0.2794)
							(mid -0.249642 -0.249642)
							(end -0.2794 -0.1778)
						)
						(arc
							(start -0.2794 0.1778)
							(mid -0.249642 0.249642)
							(end -0.1778 0.2794)
						)
						(arc
							(start 0.1778 0.2794)
							(mid 0.249642 0.249642)
							(end 0.2794 0.1778)
						)
						(arc
							(start 0.2794 -0.1778)
							(mid 0.249642 -0.249642)
							(end 0.1778 -0.2794)
						)
					)
					(width 0)
					(fill yes)
				)
			)
		)
		(pad "2" smd custom
			(at 0 0.4445 90)
			(size 0.1397 0.1397)
			(layers "F.Cu" "F.Mask" "F.Paste")
			(net "ROMA20")
			(options
				(clearance outline)
				(anchor circle)
			)
			(primitives
				(gr_poly
					(pts
						(arc
							(start -0.1778 -0.2794)
							(mid -0.249642 -0.249642)
							(end -0.2794 -0.1778)
						)
						(arc
							(start -0.2794 0.1778)
							(mid -0.249642 0.249642)
							(end -0.1778 0.2794)
						)
						(arc
							(start 0.1778 0.2794)
							(mid 0.249642 0.249642)
							(end 0.2794 0.1778)
						)
						(arc
							(start 0.2794 -0.1778)
							(mid 0.249642 -0.249642)
							(end 0.1778 -0.2794)
						)
					)
					(width 0)
					(fill yes)
				)
			)
		)
	)
	(footprint ""
		(layer "F.Cu")
		(at 86.49716 -41.275 -90)
		(property "Reference" "SC894"
			(at 0 0 270)
			(layer "F.SilkS")
			(hide yes)
			(effects
				(font
					(size 1.27 1.27)
				)
			)
		)
		(property "Value" "SCD01U10V1KX-GP"
			(at -2.8321 -1.7399 270)
			(unlocked yes)
			(layer "F.Fab")
			(hide yes)
			(effects
				(font
					(size 1.016 1.016)
					(thickness 0.1524)
				)
			)
		)
		(property "Device Type" "C0201H13"
			(at -2.8321 -3.2639 270)
			(unlocked yes)
			(layer "F.Fab")
			(hide yes)
			(effects
				(font
					(size 1.016 1.016)
					(thickness 0.1524)
				)
			)
		)
		(duplicate_pad_numbers_are_jumpers no)
		(fp_rect
			(start -0.2794 0.6477)
			(end 0.2794 -0.6477)
			(stroke
				(width 0)
				(type default)
			)
			(fill no)
			(layer "F.CrtYd")
		)
		(fp_rect
			(start -0.2794 0.6477)
			(end 0.2794 -0.6477)
			(stroke
				(width 0)
				(type default)
			)
			(fill no)
			(layer "F.Fab")
		)
		(pad "1" smd custom
			(at 0 -0.2794 270)
			(size 0.0762 0.0762)
			(layers "F.Cu" "F.Mask" "F.Paste")
			(net "SAS3008_RAID_TX_C_N6")
			(options
				(clearance outline)
				(anchor circle)
			)
			(primitives
				(gr_poly
					(pts
						(arc
							(start 0.1524 -0.127)
							(mid 0.137521 -0.162921)
							(end 0.1016 -0.1778)
						)
						(arc
							(start -0.1016 -0.1778)
							(mid -0.137521 -0.162921)
							(end -0.1524 -0.127)
						)
						(arc
							(start -0.1524 0.127)
							(mid -0.137521 0.162921)
							(end -0.1016 0.1778)
						)
						(arc
							(start 0.1016 0.1778)
							(mid 0.137521 0.162921)
							(end 0.1524 0.127)
						)
					)
					(width 0)
					(fill yes)
				)
			)
		)
		(pad "2" smd custom
			(at 0 0.2794 270)
			(size 0.0762 0.0762)
			(layers "F.Cu" "F.Mask" "F.Paste")
			(net "IOC_RAID_TX_N6")
			(options
				(clearance outline)
				(anchor circle)
			)
			(primitives
				(gr_poly
					(pts
						(arc
							(start 0.1524 -0.127)
							(mid 0.137521 -0.162921)
							(end 0.1016 -0.1778)
						)
						(arc
							(start -0.1016 -0.1778)
							(mid -0.137521 -0.162921)
							(end -0.1524 -0.127)
						)
						(arc
							(start -0.1524 0.127)
							(mid -0.137521 0.162921)
							(end -0.1016 0.1778)
						)
						(arc
							(start 0.1016 0.1778)
							(mid 0.137521 0.162921)
							(end 0.1524 0.127)
						)
					)
					(width 0)
					(fill yes)
				)
			)
		)
	)
	(footprint ""
		(layer "F.Cu")
		(at 84.328 -31.75 180)
		(property "Reference" "SC964"
			(at 0 0 180)
			(layer "F.SilkS")
			(hide yes)
			(effects
				(font
					(size 1.27 1.27)
				)
			)
		)
		(property "Value" "SCD1U6D3V1KX-GP"
			(at -2.8321 -1.7399 180)
			(unlocked yes)
			(layer "F.Fab")
			(hide yes)
			(effects
				(font
					(size 1.016 1.016)
					(thickness 0.1524)
				)
			)
		)
		(property "Device Type" "C0201H13"
			(at -2.8321 -3.2639 180)
			(unlocked yes)
			(layer "F.Fab")
			(hide yes)
			(effects
				(font
					(size 1.016 1.016)
					(thickness 0.1524)
				)
			)
		)
		(duplicate_pad_numbers_are_jumpers no)
		(fp_rect
			(start -0.2794 0.6477)
			(end 0.2794 -0.6477)
			(stroke
				(width 0)
				(type default)
			)
			(fill no)
			(layer "F.CrtYd")
		)
		(fp_rect
			(start -0.2794 0.6477)
			(end 0.2794 -0.6477)
			(stroke
				(width 0)
				(type default)
			)
			(fill no)
			(layer "F.Fab")
		)
		(pad "1" smd custom
			(at 0 -0.2794 180)
			(size 0.0762 0.0762)
			(layers "F.Cu" "F.Mask" "F.Paste")
			(net "SAS0_AVDD")
			(options
				(clearance outline)
				(anchor circle)
			)
			(primitives
				(gr_poly
					(pts
						(arc
							(start 0.1524 -0.127)
							(mid 0.137521 -0.162921)
							(end 0.1016 -0.1778)
						)
						(arc
							(start -0.1016 -0.1778)
							(mid -0.137521 -0.162921)
							(end -0.1524 -0.127)
						)
						(arc
							(start -0.1524 0.127)
							(mid -0.137521 0.162921)
							(end -0.1016 0.1778)
						)
						(arc
							(start 0.1016 0.1778)
							(mid 0.137521 0.162921)
							(end 0.1524 0.127)
						)
					)
					(width 0)
					(fill yes)
				)
			)
		)
		(pad "2" smd custom
			(at 0 0.2794 180)
			(size 0.0762 0.0762)
			(layers "F.Cu" "F.Mask" "F.Paste")
			(net "GND")
			(options
				(clearance outline)
				(anchor circle)
			)
			(primitives
				(gr_poly
					(pts
						(arc
							(start 0.1524 -0.127)
							(mid 0.137521 -0.162921)
							(end 0.1016 -0.1778)
						)
						(arc
							(start -0.1016 -0.1778)
							(mid -0.137521 -0.162921)
							(end -0.1524 -0.127)
						)
						(arc
							(start -0.1524 0.127)
							(mid -0.137521 0.162921)
							(end -0.1016 0.1778)
						)
						(arc
							(start 0.1016 0.1778)
							(mid 0.137521 0.162921)
							(end 0.1524 0.127)
						)
					)
					(width 0)
					(fill yes)
				)
			)
		)
	)
	(footprint ""
		(layer "F.Cu")
		(at 302.006 -188.976)
		(property "Reference" "R613"
			(at 0 0 0)
			(layer "F.SilkS")
			(hide yes)
			(effects
				(font
					(size 1.27 1.27)
				)
			)
		)
		(property "Value" "0R2J-2-GP"
			(at 0.064008 -3.993896 0)
			(unlocked yes)
			(layer "F.Fab")
			(hide yes)
			(effects
				(font
					(size 1.016 1.016)
					(thickness 0.1524)
				)
			)
		)
		(property "Device Type" "R402H16"
			(at 0.064008 -5.517896 0)
			(unlocked yes)
			(layer "F.Fab")
			(hide yes)
			(effects
				(font
					(size 1.016 1.016)
					(thickness 0.1524)
				)
			)
		)
		(duplicate_pad_numbers_are_jumpers no)
		(fp_line
			(start -0.508 -0.9398)
			(end -0.508 0.9398)
			(stroke
				(width 0.1524)
				(type default)
			)
			(layer "F.SilkS")
		)
		(fp_line
			(start 0.508 -0.9398)
			(end -0.508 -0.9398)
			(stroke
				(width 0.1524)
				(type default)
			)
			(layer "F.SilkS")
		)
		(fp_rect
			(start -0.508 0.9398)
			(end 0.508 -0.9398)
			(stroke
				(width 0)
				(type default)
			)
			(fill no)
			(layer "F.CrtYd")
		)
		(fp_rect
			(start -0.508 0.9398)
			(end 0.508 -0.9398)
			(stroke
				(width 0)
				(type default)
			)
			(fill no)
			(layer "F.Fab")
		)
		(pad "1" smd custom
			(at 0 -0.4445)
			(size 0.1397 0.1397)
			(layers "F.Cu" "F.Mask" "F.Paste")
			(net "BMC_UART_SWITCH_1")
			(options
				(clearance outline)
				(anchor circle)
			)
			(primitives
				(gr_poly
					(pts
						(arc
							(start -0.1778 -0.2794)
							(mid -0.249642 -0.249642)
							(end -0.2794 -0.1778)
						)
						(arc
							(start -0.2794 0.1778)
							(mid -0.249642 0.249642)
							(end -0.1778 0.2794)
						)
						(arc
							(start 0.1778 0.2794)
							(mid 0.249642 0.249642)
							(end 0.2794 0.1778)
						)
						(arc
							(start 0.2794 -0.1778)
							(mid 0.249642 -0.249642)
							(end 0.1778 -0.2794)
						)
					)
					(width 0)
					(fill yes)
				)
			)
		)
		(pad "2" smd custom
			(at 0 0.4445)
			(size 0.1397 0.1397)
			(layers "F.Cu" "F.Mask" "F.Paste")
			(net "BMC0_TACH11")
			(options
				(clearance outline)
				(anchor circle)
			)
			(primitives
				(gr_poly
					(pts
						(arc
							(start -0.1778 -0.2794)
							(mid -0.249642 -0.249642)
							(end -0.2794 -0.1778)
						)
						(arc
							(start -0.2794 0.1778)
							(mid -0.249642 0.249642)
							(end -0.1778 0.2794)
						)
						(arc
							(start 0.1778 0.2794)
							(mid 0.249642 0.249642)
							(end 0.2794 0.1778)
						)
						(arc
							(start 0.2794 -0.1778)
							(mid 0.249642 -0.249642)
							(end 0.1778 -0.2794)
						)
					)
					(width 0)
					(fill yes)
				)
			)
		)
	)
	(footprint ""
		(layer "F.Cu")
		(at 131.318 -91.948 90)
		(property "Reference" "SC1105"
			(at 0 0 90)
			(layer "F.SilkS")
			(hide yes)
			(effects
				(font
					(size 1.27 1.27)
				)
			)
		)
		(property "Value" "SCD01U10V1KX-GP"
			(at -2.8321 -1.7399 90)
			(unlocked yes)
			(layer "F.Fab")
			(hide yes)
			(effects
				(font
					(size 1.016 1.016)
					(thickness 0.1524)
				)
			)
		)
		(property "Device Type" "C0201H13"
			(at -2.8321 -3.2639 90)
			(unlocked yes)
			(layer "F.Fab")
			(hide yes)
			(effects
				(font
					(size 1.016 1.016)
					(thickness 0.1524)
				)
			)
		)
		(duplicate_pad_numbers_are_jumpers no)
		(fp_rect
			(start -0.2794 0.6477)
			(end 0.2794 -0.6477)
			(stroke
				(width 0)
				(type default)
			)
			(fill no)
			(layer "F.CrtYd")
		)
		(fp_rect
			(start -0.2794 0.6477)
			(end 0.2794 -0.6477)
			(stroke
				(width 0)
				(type default)
			)
			(fill no)
			(layer "F.Fab")
		)
		(pad "1" smd custom
			(at 0 -0.2794 90)
			(size 0.0762 0.0762)
			(layers "F.Cu" "F.Mask" "F.Paste")
			(net "3X24_SAS_TX19_N")
			(options
				(clearance outline)
				(anchor circle)
			)
			(primitives
				(gr_poly
					(pts
						(arc
							(start 0.1524 -0.127)
							(mid 0.137521 -0.162921)
							(end 0.1016 -0.1778)
						)
						(arc
							(start -0.1016 -0.1778)
							(mid -0.137521 -0.162921)
							(end -0.1524 -0.127)
						)
						(arc
							(start -0.1524 0.127)
							(mid -0.137521 0.162921)
							(end -0.1016 0.1778)
						)
						(arc
							(start 0.1016 0.1778)
							(mid 0.137521 0.162921)
							(end 0.1524 0.127)
						)
					)
					(width 0)
					(fill yes)
				)
			)
		)
		(pad "2" smd custom
			(at 0 0.2794 90)
			(size 0.0762 0.0762)
			(layers "F.Cu" "F.Mask" "F.Paste")
			(net "SAS_EXP2CONN_TX_N_23")
			(options
				(clearance outline)
				(anchor circle)
			)
			(primitives
				(gr_poly
					(pts
						(arc
							(start 0.1524 -0.127)
							(mid 0.137521 -0.162921)
							(end 0.1016 -0.1778)
						)
						(arc
							(start -0.1016 -0.1778)
							(mid -0.137521 -0.162921)
							(end -0.1524 -0.127)
						)
						(arc
							(start -0.1524 0.127)
							(mid -0.137521 0.162921)
							(end -0.1016 0.1778)
						)
						(arc
							(start 0.1016 0.1778)
							(mid 0.137521 0.162921)
							(end 0.1524 0.127)
						)
					)
					(width 0)
					(fill yes)
				)
			)
		)
	)
	(footprint ""
		(layer "F.Cu")
		(at 205.74 -185.42 180)
		(property "Reference" "R485"
			(at 0 0 180)
			(layer "F.SilkS")
			(hide yes)
			(effects
				(font
					(size 1.27 1.27)
				)
			)
		)
		(property "Value" "1KR2F-3-GP"
			(at 0.064008 -3.993896 180)
			(unlocked yes)
			(layer "F.Fab")
			(hide yes)
			(effects
				(font
					(size 1.016 1.016)
					(thickness 0.1524)
				)
			)
		)
		(property "Device Type" "R402H16"
			(at 0.064008 -5.517896 180)
			(unlocked yes)
			(layer "F.Fab")
			(hide yes)
			(effects
				(font
					(size 1.016 1.016)
					(thickness 0.1524)
				)
			)
		)
		(duplicate_pad_numbers_are_jumpers no)
		(fp_line
			(start 0.508 -0.9398)
			(end -0.508 -0.9398)
			(stroke
				(width 0.1524)
				(type default)
			)
			(layer "F.SilkS")
		)
		(fp_line
			(start -0.508 -0.9398)
			(end -0.508 0.9398)
			(stroke
				(width 0.1524)
				(type default)
			)
			(layer "F.SilkS")
		)
		(fp_rect
			(start -0.508 0.9398)
			(end 0.508 -0.9398)
			(stroke
				(width 0)
				(type default)
			)
			(fill no)
			(layer "F.CrtYd")
		)
		(fp_rect
			(start -0.508 0.9398)
			(end 0.508 -0.9398)
			(stroke
				(width 0)
				(type default)
			)
			(fill no)
			(layer "F.Fab")
		)
		(pad "1" smd custom
			(at 0 -0.4445 180)
			(size 0.1397 0.1397)
			(layers "F.Cu" "F.Mask" "F.Paste")
			(net "DIVIDER 2_IN")
			(options
				(clearance outline)
				(anchor circle)
			)
			(primitives
				(gr_poly
					(pts
						(arc
							(start -0.1778 -0.2794)
							(mid -0.249642 -0.249642)
							(end -0.2794 -0.1778)
						)
						(arc
							(start -0.2794 0.1778)
							(mid -0.249642 0.249642)
							(end -0.1778 0.2794)
						)
						(arc
							(start 0.1778 0.2794)
							(mid 0.249642 0.249642)
							(end 0.2794 0.1778)
						)
						(arc
							(start 0.2794 -0.1778)
							(mid 0.249642 -0.249642)
							(end 0.1778 -0.2794)
						)
					)
					(width 0)
					(fill yes)
				)
			)
		)
		(pad "2" smd custom
			(at 0 0.4445 180)
			(size 0.1397 0.1397)
			(layers "F.Cu" "F.Mask" "F.Paste")
			(net "GND")
			(options
				(clearance outline)
				(anchor circle)
			)
			(primitives
				(gr_poly
					(pts
						(arc
							(start -0.1778 -0.2794)
							(mid -0.249642 -0.249642)
							(end -0.2794 -0.1778)
						)
						(arc
							(start -0.2794 0.1778)
							(mid -0.249642 0.249642)
							(end -0.1778 0.2794)
						)
						(arc
							(start 0.1778 0.2794)
							(mid 0.249642 0.249642)
							(end 0.2794 0.1778)
						)
						(arc
							(start 0.2794 -0.1778)
							(mid 0.249642 -0.249642)
							(end 0.1778 -0.2794)
						)
					)
					(width 0)
					(fill yes)
				)
			)
		)
	)
	(footprint ""
		(layer "F.Cu")
		(at 333.912718 -157.838648 90)
		(property "Reference" "R216"
			(at 0 0 90)
			(layer "F.SilkS")
			(hide yes)
			(effects
				(font
					(size 1.27 1.27)
				)
			)
		)
		(property "Value" "4K7R2F-GP"
			(at 0.064008 -3.993896 90)
			(unlocked yes)
			(layer "F.Fab")
			(hide yes)
			(effects
				(font
					(size 1.016 1.016)
					(thickness 0.1524)
				)
			)
		)
		(property "Device Type" "R402H16"
			(at 0.064008 -5.517896 90)
			(unlocked yes)
			(layer "F.Fab")
			(hide yes)
			(effects
				(font
					(size 1.016 1.016)
					(thickness 0.1524)
				)
			)
		)
		(duplicate_pad_numbers_are_jumpers no)
		(fp_line
			(start 0.508 -0.9398)
			(end -0.508 -0.9398)
			(stroke
				(width 0.1524)
				(type default)
			)
			(layer "F.SilkS")
		)
		(fp_line
			(start -0.508 -0.9398)
			(end -0.508 0.9398)
			(stroke
				(width 0.1524)
				(type default)
			)
			(layer "F.SilkS")
		)
		(fp_rect
			(start -0.508 0.9398)
			(end 0.508 -0.9398)
			(stroke
				(width 0)
				(type default)
			)
			(fill no)
			(layer "F.CrtYd")
		)
		(fp_rect
			(start -0.508 0.9398)
			(end 0.508 -0.9398)
			(stroke
				(width 0)
				(type default)
			)
			(fill no)
			(layer "F.Fab")
		)
		(pad "1" smd custom
			(at 0 -0.4445 90)
			(size 0.1397 0.1397)
			(layers "F.Cu" "F.Mask" "F.Paste")
			(net "P3V3_STBY")
			(options
				(clearance outline)
				(anchor circle)
			)
			(primitives
				(gr_poly
					(pts
						(arc
							(start -0.1778 -0.2794)
							(mid -0.249642 -0.249642)
							(end -0.2794 -0.1778)
						)
						(arc
							(start -0.2794 0.1778)
							(mid -0.249642 0.249642)
							(end -0.1778 0.2794)
						)
						(arc
							(start 0.1778 0.2794)
							(mid 0.249642 0.249642)
							(end 0.2794 0.1778)
						)
						(arc
							(start 0.2794 -0.1778)
							(mid 0.249642 -0.249642)
							(end 0.1778 -0.2794)
						)
					)
					(width 0)
					(fill yes)
				)
			)
		)
		(pad "2" smd custom
			(at 0 0.4445 90)
			(size 0.1397 0.1397)
			(layers "F.Cu" "F.Mask" "F.Paste")
			(net "USB_OCS_N3")
			(options
				(clearance outline)
				(anchor circle)
			)
			(primitives
				(gr_poly
					(pts
						(arc
							(start -0.1778 -0.2794)
							(mid -0.249642 -0.249642)
							(end -0.2794 -0.1778)
						)
						(arc
							(start -0.2794 0.1778)
							(mid -0.249642 0.249642)
							(end -0.1778 0.2794)
						)
						(arc
							(start 0.1778 0.2794)
							(mid 0.249642 0.249642)
							(end 0.2794 0.1778)
						)
						(arc
							(start 0.2794 -0.1778)
							(mid 0.249642 -0.249642)
							(end 0.1778 -0.2794)
						)
					)
					(width 0)
					(fill yes)
				)
			)
		)
	)
	(footprint ""
		(layer "F.Cu")
		(at 341.122 -116.586 180)
		(property "Reference" "PC13"
			(at 0 0 180)
			(layer "F.SilkS")
			(hide yes)
			(effects
				(font
					(size 1.27 1.27)
				)
			)
		)
		(property "Value" "SC1U16V3KX-5GP"
			(at 0 -2.8194 180)
			(unlocked yes)
			(layer "F.Fab")
			(hide yes)
			(effects
				(font
					(size 1.016 1.016)
					(thickness 0.1524)
				)
			)
		)
		(property "Device Type" "C603H36"
			(at 0 -4.3434 180)
			(unlocked yes)
			(layer "F.Fab")
			(hide yes)
			(effects
				(font
					(size 1.016 1.016)
					(thickness 0.1524)
				)
			)
		)
		(duplicate_pad_numbers_are_jumpers no)
		(fp_line
			(start 0.508 0)
			(end -0.508 0)
			(stroke
				(width 0.2032)
				(type default)
			)
			(layer "F.SilkS")
		)
		(fp_rect
			(start -0.5842 1.3335)
			(end 0.5842 -1.3335)
			(stroke
				(width 0)
				(type default)
			)
			(fill no)
			(layer "F.CrtYd")
		)
		(fp_rect
			(start -0.5842 1.3335)
			(end 0.5842 -1.3335)
			(stroke
				(width 0)
				(type default)
			)
			(fill no)
			(layer "F.Fab")
		)
		(pad "1" smd custom
			(at 0 -0.762 180)
			(size 0.2159 0.2159)
			(layers "F.Cu" "F.Mask" "F.Paste")
			(net "P5V_STBY_VRG5")
			(options
				(clearance outline)
				(anchor circle)
			)
			(primitives
				(gr_poly
					(pts
						(arc
							(start -0.3302 -0.4318)
							(mid -0.402042 -0.402042)
							(end -0.4318 -0.3302)
						)
						(arc
							(start -0.4318 0.3302)
							(mid -0.402042 0.402042)
							(end -0.3302 0.4318)
						)
						(arc
							(start 0.3302 0.4318)
							(mid 0.402042 0.402042)
							(end 0.4318 0.3302)
						)
						(arc
							(start 0.4318 -0.3302)
							(mid 0.402042 -0.402042)
							(end 0.3302 -0.4318)
						)
					)
					(width 0)
					(fill yes)
				)
			)
		)
		(pad "2" smd custom
			(at 0 0.762 180)
			(size 0.2159 0.2159)
			(layers "F.Cu" "F.Mask" "F.Paste")
			(net "GND")
			(options
				(clearance outline)
				(anchor circle)
			)
			(primitives
				(gr_poly
					(pts
						(arc
							(start -0.3302 -0.4318)
							(mid -0.402042 -0.402042)
							(end -0.4318 -0.3302)
						)
						(arc
							(start -0.4318 0.3302)
							(mid -0.402042 0.402042)
							(end -0.3302 0.4318)
						)
						(arc
							(start 0.3302 0.4318)
							(mid 0.402042 0.402042)
							(end 0.4318 0.3302)
						)
						(arc
							(start 0.4318 -0.3302)
							(mid 0.402042 -0.402042)
							(end 0.3302 -0.4318)
						)
					)
					(width 0)
					(fill yes)
				)
			)
		)
	)
	(footprint ""
		(layer "F.Cu")
		(at 288.408872 -223.719136 180)
		(property "Reference" "PC86"
			(at 0 0 180)
			(layer "F.SilkS")
			(hide yes)
			(effects
				(font
					(size 1.27 1.27)
				)
			)
		)
		(property "Value" "SCD1U10V2KX-5GP"
			(at 1.1811 -2.7051 180)
			(unlocked yes)
			(layer "F.Fab")
			(hide yes)
			(effects
				(font
					(size 1.016 1.016)
					(thickness 0.1524)
				)
			)
		)
		(property "Device Type" "C402H22"
			(at 1.1811 -4.2291 180)
			(unlocked yes)
			(layer "F.Fab")
			(hide yes)
			(effects
				(font
					(size 1.016 1.016)
					(thickness 0.1524)
				)
			)
		)
		(duplicate_pad_numbers_are_jumpers no)
		(fp_rect
			(start -0.4318 0.9525)
			(end 0.4318 -0.9525)
			(stroke
				(width 0)
				(type default)
			)
			(fill no)
			(layer "F.CrtYd")
		)
		(fp_rect
			(start -0.4318 0.9525)
			(end 0.4318 -0.9525)
			(stroke
				(width 0)
				(type default)
			)
			(fill no)
			(layer "F.Fab")
		)
		(pad "1" smd custom
			(at 0 -0.4445 180)
			(size 0.1524 0.1524)
			(layers "F.Cu" "F.Mask" "F.Paste")
			(net "TPS74801_1V53_STBY_OUT")
			(options
				(clearance outline)
				(anchor circle)
			)
			(primitives
				(gr_poly
					(pts
						(arc
							(start 0.3048 -0.2032)
							(mid 0.275042 -0.275042)
							(end 0.2032 -0.3048)
						)
						(arc
							(start -0.2032 -0.3048)
							(mid -0.275042 -0.275042)
							(end -0.3048 -0.2032)
						)
						(arc
							(start -0.3048 0.2032)
							(mid -0.275042 0.275042)
							(end -0.2032 0.3048)
						)
						(arc
							(start 0.2032 0.3048)
							(mid 0.275042 0.275042)
							(end 0.3048 0.2032)
						)
					)
					(width 0)
					(fill yes)
				)
			)
		)
		(pad "2" smd custom
			(at 0 0.4445 180)
			(size 0.1524 0.1524)
			(layers "F.Cu" "F.Mask" "F.Paste")
			(net "GND")
			(options
				(clearance outline)
				(anchor circle)
			)
			(primitives
				(gr_poly
					(pts
						(arc
							(start 0.3048 -0.2032)
							(mid 0.275042 -0.275042)
							(end 0.2032 -0.3048)
						)
						(arc
							(start -0.2032 -0.3048)
							(mid -0.275042 -0.275042)
							(end -0.3048 -0.2032)
						)
						(arc
							(start -0.3048 0.2032)
							(mid -0.275042 0.275042)
							(end -0.2032 0.3048)
						)
						(arc
							(start 0.2032 0.3048)
							(mid 0.275042 0.275042)
							(end 0.3048 0.2032)
						)
					)
					(width 0)
					(fill yes)
				)
			)
		)
	)
	(footprint ""
		(layer "F.Cu")
		(at 222.123 -116.332 180)
		(property "Reference" "Q97"
			(at 0 0 180)
			(layer "F.SilkS")
			(hide yes)
			(effects
				(font
					(size 1.27 1.27)
				)
			)
		)
		(property "Value" "2N7002A-7-GP"
			(at 0.127 -8.9662 180)
			(unlocked yes)
			(layer "F.Fab")
			(hide yes)
			(effects
				(font
					(size 1.016 1.016)
					(thickness 0.1524)
				)
			)
		)
		(property "Device Type" "SOT23DGS2D4H48"
			(at 0.127 -10.4902 180)
			(unlocked yes)
			(layer "F.Fab")
			(hide yes)
			(effects
				(font
					(size 1.016 1.016)
					(thickness 0.1524)
				)
			)
		)
		(duplicate_pad_numbers_are_jumpers no)
		(fp_line
			(start 1.651 1.778)
			(end 1.651 -1.778)
			(stroke
				(width 0.1524)
				(type default)
			)
			(layer "F.SilkS")
		)
		(fp_line
			(start 1.651 -1.778)
			(end -1.651 -1.778)
			(stroke
				(width 0.1524)
				(type default)
			)
			(layer "F.SilkS")
		)
		(fp_line
			(start -1.651 1.778)
			(end 1.651 1.778)
			(stroke
				(width 0.1524)
				(type default)
			)
			(layer "F.SilkS")
		)
		(fp_line
			(start -1.651 -1.778)
			(end -1.651 1.778)
			(stroke
				(width 0.1524)
				(type default)
			)
			(layer "F.SilkS")
		)
		(fp_poly
			(pts
				(xy -1.778 1.8796) (xy -1.778 -1.8796) (xy 1.778 -1.8796) (xy 1.778 1.8796)
			)
			(stroke
				(width 0)
				(type default)
			)
			(fill no)
			(layer "F.CrtYd")
		)
		(fp_poly
			(pts
				(xy -1.778 1.8796) (xy -1.778 -1.8796) (xy 1.778 -1.8796) (xy 1.778 1.8796)
			)
			(stroke
				(width 0)
				(type default)
			)
			(fill no)
			(layer "F.Fab")
		)
		(pad "D" smd custom
			(at 0 -0.9525 180)
			(size 0.1905 0.1905)
			(layers "F.Cu" "F.Mask" "F.Paste")
			(net "P1V8_PG_R_2")
			(options
				(clearance outline)
				(anchor circle)
			)
			(primitives
				(gr_poly
					(pts
						(arc
							(start -0.1778 0.5715)
							(mid -0.321484 0.511984)
							(end -0.381 0.3683)
						)
						(arc
							(start -0.381 -0.3683)
							(mid -0.321484 -0.511984)
							(end -0.1778 -0.5715)
						)
						(arc
							(start 0.1778 -0.5715)
							(mid 0.321484 -0.511984)
							(end 0.381 -0.3683)
						)
						(arc
							(start 0.381 0.3683)
							(mid 0.321484 0.511984)
							(end 0.1778 0.5715)
						)
					)
					(width 0)
					(fill yes)
				)
			)
		)
		(pad "G" smd custom
			(at -0.98425 0.9525 180)
			(size 0.1905 0.1905)
			(layers "F.Cu" "F.Mask" "F.Paste")
			(net "P3V3_STBY_B3")
			(options
				(clearance outline)
				(anchor circle)
			)
			(primitives
				(gr_poly
					(pts
						(arc
							(start -0.1778 0.5715)
							(mid -0.321484 0.511984)
							(end -0.381 0.3683)
						)
						(arc
							(start -0.381 -0.3683)
							(mid -0.321484 -0.511984)
							(end -0.1778 -0.5715)
						)
						(arc
							(start 0.1778 -0.5715)
							(mid 0.321484 -0.511984)
							(end 0.381 -0.3683)
						)
						(arc
							(start 0.381 0.3683)
							(mid 0.321484 0.511984)
							(end 0.1778 0.5715)
						)
					)
					(width 0)
					(fill yes)
				)
			)
		)
		(pad "S" smd custom
			(at 0.98425 0.9525 180)
			(size 0.1905 0.1905)
			(layers "F.Cu" "F.Mask" "F.Paste")
			(net "GND")
			(options
				(clearance outline)
				(anchor circle)
			)
			(primitives
				(gr_poly
					(pts
						(arc
							(start -0.1778 0.5715)
							(mid -0.321484 0.511984)
							(end -0.381 0.3683)
						)
						(arc
							(start -0.381 -0.3683)
							(mid -0.321484 -0.511984)
							(end -0.1778 -0.5715)
						)
						(arc
							(start 0.1778 -0.5715)
							(mid 0.321484 -0.511984)
							(end 0.381 -0.3683)
						)
						(arc
							(start 0.381 0.3683)
							(mid 0.321484 0.511984)
							(end 0.1778 0.5715)
						)
					)
					(width 0)
					(fill yes)
				)
			)
		)
	)
	(footprint ""
		(layer "F.Cu")
		(at 35.500056 -258.59994 180)
		(property "Reference" "GF6"
			(at 0 0 180)
			(layer "F.SilkS")
			(hide yes)
			(effects
				(font
					(size 1.27 1.27)
				)
			)
		)
		(property "Value" "GF-PCIE-36P-GP"
			(at -5.118354 -8.09879 180)
			(unlocked yes)
			(layer "F.Fab")
			(hide yes)
			(effects
				(font
					(size 1.016 1.016)
					(thickness 0.1524)
				)
			)
		)
		(property "Device Type" "GF-PCIE-36P"
			(at -5.118354 -9.62279 180)
			(unlocked yes)
			(layer "F.Fab")
			(hide yes)
			(effects
				(font
					(size 1.016 1.016)
					(thickness 0.1524)
				)
			)
		)
		(duplicate_pad_numbers_are_jumpers no)
		(fp_rect
			(start -13.8811 2.032)
			(end 9.8933 -6.223)
			(stroke
				(width 0)
				(type default)
			)
			(fill no)
			(layer "B.CrtYd")
		)
		(fp_rect
			(start -13.8811 2.032)
			(end 9.8933 -6.223)
			(stroke
				(width 0)
				(type default)
			)
			(fill no)
			(layer "F.CrtYd")
		)
		(fp_rect
			(start -13.8811 2.032)
			(end 9.8933 -6.223)
			(stroke
				(width 0)
				(type default)
			)
			(fill no)
			(layer "B.Fab")
		)
		(fp_rect
			(start -13.8811 2.032)
			(end 9.8933 -6.223)
			(stroke
				(width 0)
				(type default)
			)
			(fill no)
			(layer "F.Fab")
		)
		(fp_text user "02 Do not mirror"
			(at -10.94613 2.91084 180)
			(unlocked yes)
			(layer "F.Fab")
			(effects
				(font
					(size 1.016 1.016)
					(thickness 0.1524)
				)
				(justify left)
			)
		)
		(pad "A1" smd rect
			(at -11.49985 -2.0955 180)
			(size 0.7112 3.2004)
			(drill
				(offset 0 -0.4953)
			)
			(layers "F.Cu" "F.Mask" "F.Paste")
			(net "SAS_HDD_PRE0")
		)
		(pad "A2" smd rect
			(at -10.50036 -2.0955 180)
			(size 0.7112 4.191)
			(layers "F.Cu" "F.Mask" "F.Paste")
			(net "SAS_HDD_PRE1")
		)
		(pad "A3" smd rect
			(at -9.4996 -2.0955 180)
			(size 0.7112 4.191)
			(layers "F.Cu" "F.Mask" "F.Paste")
			(net "SAS_HDD_PRE2")
		)
		(pad "A4" smd rect
			(at -8.50011 -2.0955 180)
			(size 0.7112 4.191)
			(layers "F.Cu" "F.Mask" "F.Paste")
			(net "SAS_HDD_PRE3")
		)
		(pad "A5" smd rect
			(at -7.49935 -2.0955 180)
			(size 0.7112 4.191)
			(layers "F.Cu" "F.Mask" "F.Paste")
			(net "SAS_HDD_PRE4")
		)
		(pad "A6" smd rect
			(at -6.49986 -2.0955 180)
			(size 0.7112 4.191)
			(layers "F.Cu" "F.Mask" "F.Paste")
			(net "SAS_HDD_PRE5")
		)
		(pad "A7" smd rect
			(at -5.50037 -2.0955 180)
			(size 0.7112 4.191)
			(layers "F.Cu" "F.Mask" "F.Paste")
			(net "SAS_HDD_PRE6")
		)
		(pad "A8" smd rect
			(at -4.49961 -2.0955 180)
			(size 0.7112 4.191)
			(layers "F.Cu" "F.Mask" "F.Paste")
			(net "SAS_HDD_PRE7")
		)
		(pad "A9" smd rect
			(at -3.50012 -2.0955 180)
			(size 0.7112 4.191)
			(layers "F.Cu" "F.Mask" "F.Paste")
			(net "SAS_HDD_PRE8")
		)
		(pad "A10" smd rect
			(at -2.49936 -2.0955 180)
			(size 0.7112 4.191)
			(layers "F.Cu" "F.Mask" "F.Paste")
			(net "SAS_HDD_PRE9")
		)
		(pad "A11" smd rect
			(at -1.49987 -2.0955 180)
			(size 0.7112 4.191)
			(layers "F.Cu" "F.Mask" "F.Paste")
			(net "SAS_HDD_PRE10")
		)
		(pad "A12" smd rect
			(at 1.49987 -2.0955 180)
			(size 0.7112 4.191)
			(layers "F.Cu" "F.Mask" "F.Paste")
			(net "SAS_HDD_PRE11")
		)
		(pad "A13" smd rect
			(at 2.50063 -2.0955 180)
			(size 0.7112 4.191)
			(layers "F.Cu" "F.Mask" "F.Paste")
			(net "SAS_HDD_PRE12")
		)
		(pad "A14" smd rect
			(at 3.50012 -2.0955 180)
			(size 0.7112 4.191)
			(layers "F.Cu" "F.Mask" "F.Paste")
			(net "SAS_HDD_PRE13")
		)
		(pad "A15" smd rect
			(at 4.49961 -2.0955 180)
			(size 0.7112 4.191)
			(layers "F.Cu" "F.Mask" "F.Paste")
			(net "SAS_HDD_PRE14")
		)
		(pad "A16" smd rect
			(at 5.50037 -2.0955 180)
			(size 0.7112 4.191)
			(layers "F.Cu" "F.Mask" "F.Paste")
			(net "SELF_TRAY")
		)
		(pad "A17" smd rect
			(at 6.49986 -2.0955 180)
			(size 0.7112 4.191)
			(layers "F.Cu" "F.Mask" "F.Paste")
			(net "PEER_TRAY")
		)
		(pad "A18" smd rect
			(at 7.50062 -2.0955 180)
			(size 0.7112 4.191)
			(layers "F.Cu" "F.Mask" "F.Paste")
			(net "GND")
		)
		(pad "B1" smd rect
			(at -11.49985 -2.3495 180)
			(size 0.7112 4.191)
			(drill
				(offset 0 0.254)
			)
			(layers "F.Cu" "F.Mask" "F.Paste")
			(net "SAS_HDD_PWR0_PCIE")
		)
		(pad "B2" smd rect
			(at -10.50036 -2.3495 180)
			(size 0.7112 4.191)
			(drill
				(offset 0 0.254)
			)
			(layers "F.Cu" "F.Mask" "F.Paste")
			(net "SAS_HDD_PWR1_PCIE")
		)
		(pad "B3" smd rect
			(at -9.4996 -2.3495 180)
			(size 0.7112 4.191)
			(drill
				(offset 0 0.254)
			)
			(layers "F.Cu" "F.Mask" "F.Paste")
			(net "SAS_HDD_PWR2_PCIE")
		)
		(pad "B4" smd rect
			(at -8.50011 -2.3495 180)
			(size 0.7112 4.191)
			(drill
				(offset 0 0.254)
			)
			(layers "F.Cu" "F.Mask" "F.Paste")
			(net "SAS_HDD_PWR3_PCIE")
		)
		(pad "B5" smd rect
			(at -7.49935 -2.3495 180)
			(size 0.7112 4.191)
			(drill
				(offset 0 0.254)
			)
			(layers "F.Cu" "F.Mask" "F.Paste")
			(net "SAS_HDD_PWR4_PCIE")
		)
		(pad "B6" smd rect
			(at -6.49986 -2.3495 180)
			(size 0.7112 4.191)
			(drill
				(offset 0 0.254)
			)
			(layers "F.Cu" "F.Mask" "F.Paste")
			(net "SAS_HDD_PWR5_PCIE")
		)
		(pad "B7" smd rect
			(at -5.50037 -2.3495 180)
			(size 0.7112 4.191)
			(drill
				(offset 0 0.254)
			)
			(layers "F.Cu" "F.Mask" "F.Paste")
			(net "SAS_HDD_PWR6_PCIE")
		)
		(pad "B8" smd rect
			(at -4.49961 -2.3495 180)
			(size 0.7112 4.191)
			(drill
				(offset 0 0.254)
			)
			(layers "F.Cu" "F.Mask" "F.Paste")
			(net "SAS_HDD_PWR7_PCIE")
		)
		(pad "B9" smd rect
			(at -3.50012 -2.3495 180)
			(size 0.7112 4.191)
			(drill
				(offset 0 0.254)
			)
			(layers "F.Cu" "F.Mask" "F.Paste")
			(net "SAS_HDD_PWR8_PCIE")
		)
		(pad "B10" smd rect
			(at -2.49936 -2.3495 180)
			(size 0.7112 4.191)
			(drill
				(offset 0 0.254)
			)
			(layers "F.Cu" "F.Mask" "F.Paste")
			(net "SAS_HDD_PWR9_PCIE")
		)
		(pad "B11" smd rect
			(at -1.49987 -2.3495 180)
			(size 0.7112 4.191)
			(drill
				(offset 0 0.254)
			)
			(layers "F.Cu" "F.Mask" "F.Paste")
			(net "SAS_HDD_PWR10_PCIE")
		)
		(pad "B12" smd rect
			(at 1.49987 -2.3495 180)
			(size 0.7112 4.191)
			(drill
				(offset 0 0.254)
			)
			(layers "F.Cu" "F.Mask" "F.Paste")
			(net "SAS_HDD_PWR11_PCIE")
		)
		(pad "B13" smd rect
			(at 2.50063 -2.3495 180)
			(size 0.7112 4.191)
			(drill
				(offset 0 0.254)
			)
			(layers "F.Cu" "F.Mask" "F.Paste")
			(net "SAS_HDD_PWR12_PCIE")
		)
		(pad "B14" smd rect
			(at 3.50012 -2.3495 180)
			(size 0.7112 4.191)
			(drill
				(offset 0 0.254)
			)
			(layers "F.Cu" "F.Mask" "F.Paste")
			(net "SAS_HDD_PWR13_PCIE")
		)
		(pad "B15" smd rect
			(at 4.49961 -2.3495 180)
			(size 0.7112 4.191)
			(drill
				(offset 0 0.254)
			)
			(layers "F.Cu" "F.Mask" "F.Paste")
			(net "SAS_HDD_PWR14_PCIE")
		)
		(pad "B16" smd rect
			(at 5.50037 -2.3495 180)
			(size 0.7112 4.191)
			(drill
				(offset 0 0.254)
			)
			(layers "F.Cu" "F.Mask" "F.Paste")
			(net "SAS_HDD_PWR15_PCIE")
		)
		(pad "B17" smd rect
			(at 6.49986 -2.3495 180)
			(size 0.7112 3.2004)
			(drill
				(offset 0 -0.2413)
			)
			(layers "F.Cu" "F.Mask" "F.Paste")
			(net "PCIE_MATED#_A")
		)
		(pad "B18" smd rect
			(at 7.50062 -2.3495 180)
			(size 0.7112 4.191)
			(drill
				(offset 0 0.254)
			)
			(layers "F.Cu" "F.Mask" "F.Paste")
			(net "SAS_SEB_PEER_PRSNT")
		)
		(zone
			(layer "F.Cu")
			(hatch none 0.5)
			(connect_pads
				(clearance 0)
			)
			(min_thickness 0.25)
			(keepout
				(tracks allowed)
				(vias not_allowed)
				(pads allowed)
				(copperpour not_allowed)
				(footprints allowed)
			)
			(placement
				(enabled no)
				(sheetname "")
			)
			(fill
				(thermal_gap 0.5)
				(thermal_bridge_width 0.5)
				(island_removal_mode 0)
			)
			(polygon
				(pts
					(xy 48.370236 -259.61594) (xy 26.627836 -259.61594) (xy 26.627836 -253.39294) (xy 48.370236 -253.39294)
				)
			)
		)
		(zone
			(layer "F.Cu")
			(hatch none 0.5)
			(connect_pads
				(clearance 0)
			)
			(min_thickness 0.25)
			(keepout
				(tracks not_allowed)
				(vias allowed)
				(pads allowed)
				(copperpour not_allowed)
				(footprints allowed)
			)
			(placement
				(enabled no)
				(sheetname "")
			)
			(fill
				(thermal_gap 0.5)
				(thermal_bridge_width 0.5)
				(island_removal_mode 0)
			)
			(polygon
				(pts
					(xy 48.370236 -258.59994) (xy 48.370236 -259.61594) (xy 26.627836 -259.61594) (xy 26.627836 -258.59994)
				)
			)
		)
		(zone
			(layer "B.Cu")
			(hatch none 0.5)
			(connect_pads
				(clearance 0)
			)
			(min_thickness 0.25)
			(keepout
				(tracks not_allowed)
				(vias allowed)
				(pads allowed)
				(copperpour not_allowed)
				(footprints allowed)
			)
			(placement
				(enabled no)
				(sheetname "")
			)
			(fill
				(thermal_gap 0.5)
				(thermal_bridge_width 0.5)
				(island_removal_mode 0)
			)
			(polygon
				(pts
					(xy 48.370236 -259.61594) (xy 26.627836 -259.61594) (xy 26.627836 -258.59994) (xy 48.370236 -258.59994)
				)
			)
		)
		(zone
			(layer "B.Cu")
			(hatch none 0.5)
			(connect_pads
				(clearance 0)
			)
			(min_thickness 0.25)
			(keepout
				(tracks allowed)
				(vias not_allowed)
				(pads allowed)
				(copperpour not_allowed)
				(footprints allowed)
			)
			(placement
				(enabled no)
				(sheetname "")
			)
			(fill
				(thermal_gap 0.5)
				(thermal_bridge_width 0.5)
				(island_removal_mode 0)
			)
			(polygon
				(pts
					(xy 48.370236 -259.61594) (xy 26.627836 -259.61594) (xy 26.627836 -253.39294) (xy 48.370236 -253.39294)
				)
			)
		)
	)
	(footprint ""
		(layer "F.Cu")
		(at 305.299872 -193.747136)
		(property "Reference" "R163"
			(at 0 0 0)
			(layer "F.SilkS")
			(hide yes)
			(effects
				(font
					(size 1.27 1.27)
				)
			)
		)
		(property "Value" "4K7R2F-GP"
			(at 0.064008 -3.993896 0)
			(unlocked yes)
			(layer "F.Fab")
			(hide yes)
			(effects
				(font
					(size 1.016 1.016)
					(thickness 0.1524)
				)
			)
		)
		(property "Device Type" "R402H16"
			(at 0.064008 -5.517896 0)
			(unlocked yes)
			(layer "F.Fab")
			(hide yes)
			(effects
				(font
					(size 1.016 1.016)
					(thickness 0.1524)
				)
			)
		)
		(duplicate_pad_numbers_are_jumpers no)
		(fp_line
			(start -0.508 -0.9398)
			(end -0.508 0.9398)
			(stroke
				(width 0.1524)
				(type default)
			)
			(layer "F.SilkS")
		)
		(fp_line
			(start 0.508 -0.9398)
			(end -0.508 -0.9398)
			(stroke
				(width 0.1524)
				(type default)
			)
			(layer "F.SilkS")
		)
		(fp_rect
			(start -0.508 0.9398)
			(end 0.508 -0.9398)
			(stroke
				(width 0)
				(type default)
			)
			(fill no)
			(layer "F.CrtYd")
		)
		(fp_rect
			(start -0.508 0.9398)
			(end 0.508 -0.9398)
			(stroke
				(width 0)
				(type default)
			)
			(fill no)
			(layer "F.Fab")
		)
		(pad "1" smd custom
			(at 0 -0.4445)
			(size 0.1397 0.1397)
			(layers "F.Cu" "F.Mask" "F.Paste")
			(net "LED_DR_A0")
			(options
				(clearance outline)
				(anchor circle)
			)
			(primitives
				(gr_poly
					(pts
						(arc
							(start -0.1778 -0.2794)
							(mid -0.249642 -0.249642)
							(end -0.2794 -0.1778)
						)
						(arc
							(start -0.2794 0.1778)
							(mid -0.249642 0.249642)
							(end -0.1778 0.2794)
						)
						(arc
							(start 0.1778 0.2794)
							(mid 0.249642 0.249642)
							(end 0.2794 0.1778)
						)
						(arc
							(start 0.2794 -0.1778)
							(mid 0.249642 -0.249642)
							(end 0.1778 -0.2794)
						)
					)
					(width 0)
					(fill yes)
				)
			)
		)
		(pad "2" smd custom
			(at 0 0.4445)
			(size 0.1397 0.1397)
			(layers "F.Cu" "F.Mask" "F.Paste")
			(net "GND")
			(options
				(clearance outline)
				(anchor circle)
			)
			(primitives
				(gr_poly
					(pts
						(arc
							(start -0.1778 -0.2794)
							(mid -0.249642 -0.249642)
							(end -0.2794 -0.1778)
						)
						(arc
							(start -0.2794 0.1778)
							(mid -0.249642 0.249642)
							(end -0.1778 0.2794)
						)
						(arc
							(start 0.1778 0.2794)
							(mid 0.249642 0.249642)
							(end 0.2794 0.1778)
						)
						(arc
							(start 0.2794 -0.1778)
							(mid 0.249642 -0.249642)
							(end 0.1778 -0.2794)
						)
					)
					(width 0)
					(fill yes)
				)
			)
		)
	)
	(footprint ""
		(layer "F.Cu")
		(at 325.374 -179.705)
		(property "Reference" "R5769"
			(at 0 0 0)
			(layer "F.SilkS")
			(hide yes)
			(effects
				(font
					(size 1.27 1.27)
				)
			)
		)
		(property "Value" "1KR2F-3-GP"
			(at 0.064008 -3.993896 0)
			(unlocked yes)
			(layer "F.Fab")
			(hide yes)
			(effects
				(font
					(size 1.016 1.016)
					(thickness 0.1524)
				)
			)
		)
		(property "Device Type" "R402H16"
			(at 0.064008 -5.517896 0)
			(unlocked yes)
			(layer "F.Fab")
			(hide yes)
			(effects
				(font
					(size 1.016 1.016)
					(thickness 0.1524)
				)
			)
		)
		(duplicate_pad_numbers_are_jumpers no)
		(fp_line
			(start -0.508 -0.9398)
			(end -0.508 0.9398)
			(stroke
				(width 0.1524)
				(type default)
			)
			(layer "F.SilkS")
		)
		(fp_line
			(start 0.508 -0.9398)
			(end -0.508 -0.9398)
			(stroke
				(width 0.1524)
				(type default)
			)
			(layer "F.SilkS")
		)
		(fp_rect
			(start -0.508 0.9398)
			(end 0.508 -0.9398)
			(stroke
				(width 0)
				(type default)
			)
			(fill no)
			(layer "F.CrtYd")
		)
		(fp_rect
			(start -0.508 0.9398)
			(end 0.508 -0.9398)
			(stroke
				(width 0)
				(type default)
			)
			(fill no)
			(layer "F.Fab")
		)
		(pad "1" smd custom
			(at 0 -0.4445)
			(size 0.1397 0.1397)
			(layers "F.Cu" "F.Mask" "F.Paste")
			(net "P1V5_C")
			(options
				(clearance outline)
				(anchor circle)
			)
			(primitives
				(gr_poly
					(pts
						(arc
							(start -0.1778 -0.2794)
							(mid -0.249642 -0.249642)
							(end -0.2794 -0.1778)
						)
						(arc
							(start -0.2794 0.1778)
							(mid -0.249642 0.249642)
							(end -0.1778 0.2794)
						)
						(arc
							(start 0.1778 0.2794)
							(mid 0.249642 0.249642)
							(end 0.2794 0.1778)
						)
						(arc
							(start 0.2794 -0.1778)
							(mid 0.249642 -0.249642)
							(end 0.1778 -0.2794)
						)
					)
					(width 0)
					(fill yes)
				)
			)
		)
		(pad "2" smd custom
			(at 0 0.4445)
			(size 0.1397 0.1397)
			(layers "F.Cu" "F.Mask" "F.Paste")
			(net "ADC_P1V5_C")
			(options
				(clearance outline)
				(anchor circle)
			)
			(primitives
				(gr_poly
					(pts
						(arc
							(start -0.1778 -0.2794)
							(mid -0.249642 -0.249642)
							(end -0.2794 -0.1778)
						)
						(arc
							(start -0.2794 0.1778)
							(mid -0.249642 0.249642)
							(end -0.1778 0.2794)
						)
						(arc
							(start 0.1778 0.2794)
							(mid 0.249642 0.249642)
							(end 0.2794 0.1778)
						)
						(arc
							(start 0.2794 -0.1778)
							(mid 0.249642 -0.249642)
							(end 0.1778 -0.2794)
						)
					)
					(width 0)
					(fill yes)
				)
			)
		)
	)
	(footprint ""
		(layer "F.Cu")
		(at 317.881 -51.181 90)
		(property "Reference" "C282"
			(at 0 0 90)
			(layer "F.SilkS")
			(hide yes)
			(effects
				(font
					(size 1.27 1.27)
				)
			)
		)
		(property "Value" "SCD1U25V2KX-2-GP"
			(at 1.1811 -2.7051 90)
			(unlocked yes)
			(layer "F.Fab")
			(hide yes)
			(effects
				(font
					(size 1.016 1.016)
					(thickness 0.1524)
				)
			)
		)
		(property "Device Type" "C402H22"
			(at 1.1811 -4.2291 90)
			(unlocked yes)
			(layer "F.Fab")
			(hide yes)
			(effects
				(font
					(size 1.016 1.016)
					(thickness 0.1524)
				)
			)
		)
		(duplicate_pad_numbers_are_jumpers no)
		(fp_rect
			(start -0.4318 0.9525)
			(end 0.4318 -0.9525)
			(stroke
				(width 0)
				(type default)
			)
			(fill no)
			(layer "F.CrtYd")
		)
		(fp_rect
			(start -0.4318 0.9525)
			(end 0.4318 -0.9525)
			(stroke
				(width 0)
				(type default)
			)
			(fill no)
			(layer "F.Fab")
		)
		(pad "1" smd custom
			(at 0 -0.4445 90)
			(size 0.1524 0.1524)
			(layers "F.Cu" "F.Mask" "F.Paste")
			(net "P5V_STBY")
			(options
				(clearance outline)
				(anchor circle)
			)
			(primitives
				(gr_poly
					(pts
						(arc
							(start 0.3048 -0.2032)
							(mid 0.275042 -0.275042)
							(end 0.2032 -0.3048)
						)
						(arc
							(start -0.2032 -0.3048)
							(mid -0.275042 -0.275042)
							(end -0.3048 -0.2032)
						)
						(arc
							(start -0.3048 0.2032)
							(mid -0.275042 0.275042)
							(end -0.2032 0.3048)
						)
						(arc
							(start 0.2032 0.3048)
							(mid 0.275042 0.275042)
							(end 0.3048 0.2032)
						)
					)
					(width 0)
					(fill yes)
				)
			)
		)
		(pad "2" smd custom
			(at 0 0.4445 90)
			(size 0.1524 0.1524)
			(layers "F.Cu" "F.Mask" "F.Paste")
			(net "GND")
			(options
				(clearance outline)
				(anchor circle)
			)
			(primitives
				(gr_poly
					(pts
						(arc
							(start 0.3048 -0.2032)
							(mid 0.275042 -0.275042)
							(end 0.2032 -0.3048)
						)
						(arc
							(start -0.2032 -0.3048)
							(mid -0.275042 -0.275042)
							(end -0.3048 -0.2032)
						)
						(arc
							(start -0.3048 0.2032)
							(mid -0.275042 0.275042)
							(end -0.2032 0.3048)
						)
						(arc
							(start 0.2032 0.3048)
							(mid 0.275042 0.275042)
							(end 0.3048 0.2032)
						)
					)
					(width 0)
					(fill yes)
				)
			)
		)
	)
	(footprint ""
		(layer "F.Cu")
		(at 102.616 -224.79 90)
		(property "Reference" "R645"
			(at 0 0 90)
			(layer "F.SilkS")
			(hide yes)
			(effects
				(font
					(size 1.27 1.27)
				)
			)
		)
		(property "Value" "4K7R2F-GP"
			(at 0.064008 -3.993896 90)
			(unlocked yes)
			(layer "F.Fab")
			(hide yes)
			(effects
				(font
					(size 1.016 1.016)
					(thickness 0.1524)
				)
			)
		)
		(property "Device Type" "R402H16"
			(at 0.064008 -5.517896 90)
			(unlocked yes)
			(layer "F.Fab")
			(hide yes)
			(effects
				(font
					(size 1.016 1.016)
					(thickness 0.1524)
				)
			)
		)
		(duplicate_pad_numbers_are_jumpers no)
		(fp_line
			(start 0.508 -0.9398)
			(end -0.508 -0.9398)
			(stroke
				(width 0.1524)
				(type default)
			)
			(layer "F.SilkS")
		)
		(fp_line
			(start -0.508 -0.9398)
			(end -0.508 0.9398)
			(stroke
				(width 0.1524)
				(type default)
			)
			(layer "F.SilkS")
		)
		(fp_rect
			(start -0.508 0.9398)
			(end 0.508 -0.9398)
			(stroke
				(width 0)
				(type default)
			)
			(fill no)
			(layer "F.CrtYd")
		)
		(fp_rect
			(start -0.508 0.9398)
			(end 0.508 -0.9398)
			(stroke
				(width 0)
				(type default)
			)
			(fill no)
			(layer "F.Fab")
		)
		(pad "1" smd custom
			(at 0 -0.4445 90)
			(size 0.1397 0.1397)
			(layers "F.Cu" "F.Mask" "F.Paste")
			(net "IO_EXP_HDD_FAULT_A2")
			(options
				(clearance outline)
				(anchor circle)
			)
			(primitives
				(gr_poly
					(pts
						(arc
							(start -0.1778 -0.2794)
							(mid -0.249642 -0.249642)
							(end -0.2794 -0.1778)
						)
						(arc
							(start -0.2794 0.1778)
							(mid -0.249642 0.249642)
							(end -0.1778 0.2794)
						)
						(arc
							(start 0.1778 0.2794)
							(mid 0.249642 0.249642)
							(end 0.2794 0.1778)
						)
						(arc
							(start 0.2794 -0.1778)
							(mid 0.249642 -0.249642)
							(end 0.1778 -0.2794)
						)
					)
					(width 0)
					(fill yes)
				)
			)
		)
		(pad "2" smd custom
			(at 0 0.4445 90)
			(size 0.1397 0.1397)
			(layers "F.Cu" "F.Mask" "F.Paste")
			(net "GND")
			(options
				(clearance outline)
				(anchor circle)
			)
			(primitives
				(gr_poly
					(pts
						(arc
							(start -0.1778 -0.2794)
							(mid -0.249642 -0.249642)
							(end -0.2794 -0.1778)
						)
						(arc
							(start -0.2794 0.1778)
							(mid -0.249642 0.249642)
							(end -0.1778 0.2794)
						)
						(arc
							(start 0.1778 0.2794)
							(mid 0.249642 0.249642)
							(end 0.2794 0.1778)
						)
						(arc
							(start 0.2794 -0.1778)
							(mid 0.249642 -0.249642)
							(end 0.1778 -0.2794)
						)
					)
					(width 0)
					(fill yes)
				)
			)
		)
	)
	(footprint ""
		(layer "F.Cu")
		(at 182.888128 -14.151864 180)
		(property "Reference" "R188"
			(at 0 0 180)
			(layer "F.SilkS")
			(hide yes)
			(effects
				(font
					(size 1.27 1.27)
				)
			)
		)
		(property "Value" "4K7R2F-GP"
			(at 0.064008 -3.993896 180)
			(unlocked yes)
			(layer "F.Fab")
			(hide yes)
			(effects
				(font
					(size 1.016 1.016)
					(thickness 0.1524)
				)
			)
		)
		(property "Device Type" "R402H16"
			(at 0.064008 -5.517896 180)
			(unlocked yes)
			(layer "F.Fab")
			(hide yes)
			(effects
				(font
					(size 1.016 1.016)
					(thickness 0.1524)
				)
			)
		)
		(duplicate_pad_numbers_are_jumpers no)
		(fp_line
			(start 0.508 -0.9398)
			(end -0.508 -0.9398)
			(stroke
				(width 0.1524)
				(type default)
			)
			(layer "F.SilkS")
		)
		(fp_line
			(start -0.508 -0.9398)
			(end -0.508 0.9398)
			(stroke
				(width 0.1524)
				(type default)
			)
			(layer "F.SilkS")
		)
		(fp_rect
			(start -0.508 0.9398)
			(end 0.508 -0.9398)
			(stroke
				(width 0)
				(type default)
			)
			(fill no)
			(layer "F.CrtYd")
		)
		(fp_rect
			(start -0.508 0.9398)
			(end 0.508 -0.9398)
			(stroke
				(width 0)
				(type default)
			)
			(fill no)
			(layer "F.Fab")
		)
		(pad "1" smd custom
			(at 0 -0.4445 180)
			(size 0.1397 0.1397)
			(layers "F.Cu" "F.Mask" "F.Paste")
			(net "P3V3_STBY")
			(options
				(clearance outline)
				(anchor circle)
			)
			(primitives
				(gr_poly
					(pts
						(arc
							(start -0.1778 -0.2794)
							(mid -0.249642 -0.249642)
							(end -0.2794 -0.1778)
						)
						(arc
							(start -0.2794 0.1778)
							(mid -0.249642 0.249642)
							(end -0.1778 0.2794)
						)
						(arc
							(start 0.1778 0.2794)
							(mid 0.249642 0.249642)
							(end 0.2794 0.1778)
						)
						(arc
							(start 0.2794 -0.1778)
							(mid 0.249642 -0.249642)
							(end 0.1778 -0.2794)
						)
					)
					(width 0)
					(fill yes)
				)
			)
		)
		(pad "2" smd custom
			(at 0 0.4445 180)
			(size 0.1397 0.1397)
			(layers "F.Cu" "F.Mask" "F.Paste")
			(net "TEMP_1_A0")
			(options
				(clearance outline)
				(anchor circle)
			)
			(primitives
				(gr_poly
					(pts
						(arc
							(start -0.1778 -0.2794)
							(mid -0.249642 -0.249642)
							(end -0.2794 -0.1778)
						)
						(arc
							(start -0.2794 0.1778)
							(mid -0.249642 0.249642)
							(end -0.1778 0.2794)
						)
						(arc
							(start 0.1778 0.2794)
							(mid 0.249642 0.249642)
							(end 0.2794 0.1778)
						)
						(arc
							(start 0.2794 -0.1778)
							(mid 0.249642 -0.249642)
							(end 0.1778 -0.2794)
						)
					)
					(width 0)
					(fill yes)
				)
			)
		)
	)
	(footprint ""
		(layer "F.Cu")
		(at 346.231718 -143.233648)
		(property "Reference" "R700"
			(at 0 0 0)
			(layer "F.SilkS")
			(hide yes)
			(effects
				(font
					(size 1.27 1.27)
				)
			)
		)
		(property "Value" "12KR2J-L-GP"
			(at 0.064008 -3.993896 0)
			(unlocked yes)
			(layer "F.Fab")
			(hide yes)
			(effects
				(font
					(size 1.016 1.016)
					(thickness 0.1524)
				)
			)
		)
		(property "Device Type" "R402H16"
			(at 0.064008 -5.517896 0)
			(unlocked yes)
			(layer "F.Fab")
			(hide yes)
			(effects
				(font
					(size 1.016 1.016)
					(thickness 0.1524)
				)
			)
		)
		(duplicate_pad_numbers_are_jumpers no)
		(fp_line
			(start -0.508 -0.9398)
			(end -0.508 0.9398)
			(stroke
				(width 0.1524)
				(type default)
			)
			(layer "F.SilkS")
		)
		(fp_line
			(start 0.508 -0.9398)
			(end -0.508 -0.9398)
			(stroke
				(width 0.1524)
				(type default)
			)
			(layer "F.SilkS")
		)
		(fp_rect
			(start -0.508 0.9398)
			(end 0.508 -0.9398)
			(stroke
				(width 0)
				(type default)
			)
			(fill no)
			(layer "F.CrtYd")
		)
		(fp_rect
			(start -0.508 0.9398)
			(end 0.508 -0.9398)
			(stroke
				(width 0)
				(type default)
			)
			(fill no)
			(layer "F.Fab")
		)
		(pad "1" smd custom
			(at 0 -0.4445)
			(size 0.1397 0.1397)
			(layers "F.Cu" "F.Mask" "F.Paste")
			(net "RBIAS")
			(options
				(clearance outline)
				(anchor circle)
			)
			(primitives
				(gr_poly
					(pts
						(arc
							(start -0.1778 -0.2794)
							(mid -0.249642 -0.249642)
							(end -0.2794 -0.1778)
						)
						(arc
							(start -0.2794 0.1778)
							(mid -0.249642 0.249642)
							(end -0.1778 0.2794)
						)
						(arc
							(start 0.1778 0.2794)
							(mid 0.249642 0.249642)
							(end 0.2794 0.1778)
						)
						(arc
							(start 0.2794 -0.1778)
							(mid 0.249642 -0.249642)
							(end 0.1778 -0.2794)
						)
					)
					(width 0)
					(fill yes)
				)
			)
		)
		(pad "2" smd custom
			(at 0 0.4445)
			(size 0.1397 0.1397)
			(layers "F.Cu" "F.Mask" "F.Paste")
			(net "GND")
			(options
				(clearance outline)
				(anchor circle)
			)
			(primitives
				(gr_poly
					(pts
						(arc
							(start -0.1778 -0.2794)
							(mid -0.249642 -0.249642)
							(end -0.2794 -0.1778)
						)
						(arc
							(start -0.2794 0.1778)
							(mid -0.249642 0.249642)
							(end -0.1778 0.2794)
						)
						(arc
							(start 0.1778 0.2794)
							(mid 0.249642 0.249642)
							(end 0.2794 0.1778)
						)
						(arc
							(start 0.2794 -0.1778)
							(mid 0.249642 -0.249642)
							(end 0.1778 -0.2794)
						)
					)
					(width 0)
					(fill yes)
				)
			)
		)
	)
	(footprint ""
		(layer "F.Cu")
		(at 290.313872 -64.207136 90)
		(property "Reference" "PC137"
			(at 0 0 90)
			(layer "F.SilkS")
			(hide yes)
			(effects
				(font
					(size 1.27 1.27)
				)
			)
		)
		(property "Value" "SCD47U25V3KX-3-GP"
			(at 0 -2.8194 90)
			(unlocked yes)
			(layer "F.Fab")
			(hide yes)
			(effects
				(font
					(size 1.016 1.016)
					(thickness 0.1524)
				)
			)
		)
		(property "Device Type" "C603H36"
			(at 0 -4.3434 90)
			(unlocked yes)
			(layer "F.Fab")
			(hide yes)
			(effects
				(font
					(size 1.016 1.016)
					(thickness 0.1524)
				)
			)
		)
		(duplicate_pad_numbers_are_jumpers no)
		(fp_line
			(start 0.508 0)
			(end -0.508 0)
			(stroke
				(width 0.2032)
				(type default)
			)
			(layer "F.SilkS")
		)
		(fp_rect
			(start -0.5842 1.3335)
			(end 0.5842 -1.3335)
			(stroke
				(width 0)
				(type default)
			)
			(fill no)
			(layer "F.CrtYd")
		)
		(fp_rect
			(start -0.5842 1.3335)
			(end 0.5842 -1.3335)
			(stroke
				(width 0)
				(type default)
			)
			(fill no)
			(layer "F.Fab")
		)
		(pad "1" smd custom
			(at 0 -0.762 90)
			(size 0.2159 0.2159)
			(layers "F.Cu" "F.Mask" "F.Paste")
			(net "P3V3_EN_LV")
			(options
				(clearance outline)
				(anchor circle)
			)
			(primitives
				(gr_poly
					(pts
						(arc
							(start -0.3302 -0.4318)
							(mid -0.402042 -0.402042)
							(end -0.4318 -0.3302)
						)
						(arc
							(start -0.4318 0.3302)
							(mid -0.402042 0.402042)
							(end -0.3302 0.4318)
						)
						(arc
							(start 0.3302 0.4318)
							(mid 0.402042 0.402042)
							(end 0.4318 0.3302)
						)
						(arc
							(start 0.4318 -0.3302)
							(mid 0.402042 -0.402042)
							(end 0.3302 -0.4318)
						)
					)
					(width 0)
					(fill yes)
				)
			)
		)
		(pad "2" smd custom
			(at 0 0.762 90)
			(size 0.2159 0.2159)
			(layers "F.Cu" "F.Mask" "F.Paste")
			(net "P3V3")
			(options
				(clearance outline)
				(anchor circle)
			)
			(primitives
				(gr_poly
					(pts
						(arc
							(start -0.3302 -0.4318)
							(mid -0.402042 -0.402042)
							(end -0.4318 -0.3302)
						)
						(arc
							(start -0.4318 0.3302)
							(mid -0.402042 0.402042)
							(end -0.3302 0.4318)
						)
						(arc
							(start 0.3302 0.4318)
							(mid 0.402042 0.402042)
							(end 0.4318 0.3302)
						)
						(arc
							(start 0.4318 -0.3302)
							(mid 0.402042 -0.402042)
							(end 0.3302 -0.4318)
						)
					)
					(width 0)
					(fill yes)
				)
			)
		)
	)
	(footprint ""
		(layer "F.Cu")
		(at 199.009 -90.297 -90)
		(property "Reference" "PC234"
			(at 0 0 270)
			(layer "F.SilkS")
			(hide yes)
			(effects
				(font
					(size 1.27 1.27)
				)
			)
		)
		(property "Value" "SCD1U16V2KX-3GP"
			(at 1.1811 -2.7051 270)
			(unlocked yes)
			(layer "F.Fab")
			(hide yes)
			(effects
				(font
					(size 1.016 1.016)
					(thickness 0.1524)
				)
			)
		)
		(property "Device Type" "C402H22"
			(at 1.1811 -4.2291 270)
			(unlocked yes)
			(layer "F.Fab")
			(hide yes)
			(effects
				(font
					(size 1.016 1.016)
					(thickness 0.1524)
				)
			)
		)
		(duplicate_pad_numbers_are_jumpers no)
		(fp_rect
			(start -0.4318 0.9525)
			(end 0.4318 -0.9525)
			(stroke
				(width 0)
				(type default)
			)
			(fill no)
			(layer "F.CrtYd")
		)
		(fp_rect
			(start -0.4318 0.9525)
			(end 0.4318 -0.9525)
			(stroke
				(width 0)
				(type default)
			)
			(fill no)
			(layer "F.Fab")
		)
		(pad "1" smd custom
			(at 0 -0.4445 270)
			(size 0.1524 0.1524)
			(layers "F.Cu" "F.Mask" "F.Paste")
			(net "P1V5_E")
			(options
				(clearance outline)
				(anchor circle)
			)
			(primitives
				(gr_poly
					(pts
						(arc
							(start 0.3048 -0.2032)
							(mid 0.275042 -0.275042)
							(end 0.2032 -0.3048)
						)
						(arc
							(start -0.2032 -0.3048)
							(mid -0.275042 -0.275042)
							(end -0.3048 -0.2032)
						)
						(arc
							(start -0.3048 0.2032)
							(mid -0.275042 0.275042)
							(end -0.2032 0.3048)
						)
						(arc
							(start 0.2032 0.3048)
							(mid 0.275042 0.275042)
							(end 0.3048 0.2032)
						)
					)
					(width 0)
					(fill yes)
				)
			)
		)
		(pad "2" smd custom
			(at 0 0.4445 270)
			(size 0.1524 0.1524)
			(layers "F.Cu" "F.Mask" "F.Paste")
			(net "GND")
			(options
				(clearance outline)
				(anchor circle)
			)
			(primitives
				(gr_poly
					(pts
						(arc
							(start 0.3048 -0.2032)
							(mid 0.275042 -0.275042)
							(end 0.2032 -0.3048)
						)
						(arc
							(start -0.2032 -0.3048)
							(mid -0.275042 -0.275042)
							(end -0.3048 -0.2032)
						)
						(arc
							(start -0.3048 0.2032)
							(mid -0.275042 0.275042)
							(end -0.2032 0.3048)
						)
						(arc
							(start 0.2032 0.3048)
							(mid 0.275042 0.275042)
							(end 0.3048 0.2032)
						)
					)
					(width 0)
					(fill yes)
				)
			)
		)
	)
	(footprint ""
		(layer "F.Cu")
		(at 201.364596 -121.177812)
		(property "Reference" "PC239"
			(at 0 0 0)
			(layer "F.SilkS")
			(hide yes)
			(effects
				(font
					(size 1.27 1.27)
				)
			)
		)
		(property "Value" "SC1KP50V2KX-1GP"
			(at 1.1811 -2.7051 0)
			(unlocked yes)
			(layer "F.Fab")
			(hide yes)
			(effects
				(font
					(size 1.016 1.016)
					(thickness 0.1524)
				)
			)
		)
		(property "Device Type" "C402H22"
			(at 1.1811 -4.2291 0)
			(unlocked yes)
			(layer "F.Fab")
			(hide yes)
			(effects
				(font
					(size 1.016 1.016)
					(thickness 0.1524)
				)
			)
		)
		(duplicate_pad_numbers_are_jumpers no)
		(fp_rect
			(start -0.4318 0.9525)
			(end 0.4318 -0.9525)
			(stroke
				(width 0)
				(type default)
			)
			(fill no)
			(layer "F.CrtYd")
		)
		(fp_rect
			(start -0.4318 0.9525)
			(end 0.4318 -0.9525)
			(stroke
				(width 0)
				(type default)
			)
			(fill no)
			(layer "F.Fab")
		)
		(pad "1" smd custom
			(at 0 -0.4445)
			(size 0.1524 0.1524)
			(layers "F.Cu" "F.Mask" "F.Paste")
			(net "P1V5_E_VFB_R")
			(options
				(clearance outline)
				(anchor circle)
			)
			(primitives
				(gr_poly
					(pts
						(arc
							(start 0.3048 -0.2032)
							(mid 0.275042 -0.275042)
							(end 0.2032 -0.3048)
						)
						(arc
							(start -0.2032 -0.3048)
							(mid -0.275042 -0.275042)
							(end -0.3048 -0.2032)
						)
						(arc
							(start -0.3048 0.2032)
							(mid -0.275042 0.275042)
							(end -0.2032 0.3048)
						)
						(arc
							(start 0.2032 0.3048)
							(mid 0.275042 0.275042)
							(end 0.3048 0.2032)
						)
					)
					(width 0)
					(fill yes)
				)
			)
		)
		(pad "2" smd custom
			(at 0 0.4445)
			(size 0.1524 0.1524)
			(layers "F.Cu" "F.Mask" "F.Paste")
			(net "P1V5_E_VFB")
			(options
				(clearance outline)
				(anchor circle)
			)
			(primitives
				(gr_poly
					(pts
						(arc
							(start 0.3048 -0.2032)
							(mid 0.275042 -0.275042)
							(end 0.2032 -0.3048)
						)
						(arc
							(start -0.2032 -0.3048)
							(mid -0.275042 -0.275042)
							(end -0.3048 -0.2032)
						)
						(arc
							(start -0.3048 0.2032)
							(mid -0.275042 0.275042)
							(end -0.2032 0.3048)
						)
						(arc
							(start 0.2032 0.3048)
							(mid 0.275042 0.275042)
							(end 0.3048 0.2032)
						)
					)
					(width 0)
					(fill yes)
				)
			)
		)
	)
	(footprint ""
		(layer "F.Cu")
		(at 91.313 -231.775 180)
		(property "Reference" "R560"
			(at 0 0 180)
			(layer "F.SilkS")
			(hide yes)
			(effects
				(font
					(size 1.27 1.27)
				)
			)
		)
		(property "Value" "0R2J-2-GP"
			(at 0.064008 -3.993896 180)
			(unlocked yes)
			(layer "F.Fab")
			(hide yes)
			(effects
				(font
					(size 1.016 1.016)
					(thickness 0.1524)
				)
			)
		)
		(property "Device Type" "R402H16"
			(at 0.064008 -5.517896 180)
			(unlocked yes)
			(layer "F.Fab")
			(hide yes)
			(effects
				(font
					(size 1.016 1.016)
					(thickness 0.1524)
				)
			)
		)
		(duplicate_pad_numbers_are_jumpers no)
		(fp_line
			(start 0.508 -0.9398)
			(end -0.508 -0.9398)
			(stroke
				(width 0.1524)
				(type default)
			)
			(layer "F.SilkS")
		)
		(fp_line
			(start -0.508 -0.9398)
			(end -0.508 0.9398)
			(stroke
				(width 0.1524)
				(type default)
			)
			(layer "F.SilkS")
		)
		(fp_rect
			(start -0.508 0.9398)
			(end 0.508 -0.9398)
			(stroke
				(width 0)
				(type default)
			)
			(fill no)
			(layer "F.CrtYd")
		)
		(fp_rect
			(start -0.508 0.9398)
			(end 0.508 -0.9398)
			(stroke
				(width 0)
				(type default)
			)
			(fill no)
			(layer "F.Fab")
		)
		(pad "1" smd custom
			(at 0 -0.4445 180)
			(size 0.1397 0.1397)
			(layers "F.Cu" "F.Mask" "F.Paste")
			(net "SAS_FAULT_LED15")
			(options
				(clearance outline)
				(anchor circle)
			)
			(primitives
				(gr_poly
					(pts
						(arc
							(start -0.1778 -0.2794)
							(mid -0.249642 -0.249642)
							(end -0.2794 -0.1778)
						)
						(arc
							(start -0.2794 0.1778)
							(mid -0.249642 0.249642)
							(end -0.1778 0.2794)
						)
						(arc
							(start 0.1778 0.2794)
							(mid 0.249642 0.249642)
							(end 0.2794 0.1778)
						)
						(arc
							(start 0.2794 -0.1778)
							(mid 0.249642 -0.249642)
							(end 0.1778 -0.2794)
						)
					)
					(width 0)
					(fill yes)
				)
			)
		)
		(pad "2" smd custom
			(at 0 0.4445 180)
			(size 0.1397 0.1397)
			(layers "F.Cu" "F.Mask" "F.Paste")
			(net "SAS_HDD_LED_15")
			(options
				(clearance outline)
				(anchor circle)
			)
			(primitives
				(gr_poly
					(pts
						(arc
							(start -0.1778 -0.2794)
							(mid -0.249642 -0.249642)
							(end -0.2794 -0.1778)
						)
						(arc
							(start -0.2794 0.1778)
							(mid -0.249642 0.249642)
							(end -0.1778 0.2794)
						)
						(arc
							(start 0.1778 0.2794)
							(mid 0.249642 0.249642)
							(end 0.2794 0.1778)
						)
						(arc
							(start 0.2794 -0.1778)
							(mid 0.249642 -0.249642)
							(end 0.1778 -0.2794)
						)
					)
					(width 0)
					(fill yes)
				)
			)
		)
	)
	(footprint ""
		(layer "F.Cu")
		(at 60.706 -106.426 -90)
		(property "Reference" "SR821"
			(at 0 0 270)
			(layer "F.SilkS")
			(hide yes)
			(effects
				(font
					(size 1.27 1.27)
				)
			)
		)
		(property "Value" "4K75R2F-1-GP"
			(at 0.064008 -3.993896 270)
			(unlocked yes)
			(layer "F.Fab")
			(hide yes)
			(effects
				(font
					(size 1.016 1.016)
					(thickness 0.1524)
				)
			)
		)
		(property "Device Type" "R402H16"
			(at 0.064008 -5.517896 270)
			(unlocked yes)
			(layer "F.Fab")
			(hide yes)
			(effects
				(font
					(size 1.016 1.016)
					(thickness 0.1524)
				)
			)
		)
		(duplicate_pad_numbers_are_jumpers no)
		(fp_line
			(start -0.508 -0.9398)
			(end -0.508 0.9398)
			(stroke
				(width 0.1524)
				(type default)
			)
			(layer "F.SilkS")
		)
		(fp_line
			(start 0.508 -0.9398)
			(end -0.508 -0.9398)
			(stroke
				(width 0.1524)
				(type default)
			)
			(layer "F.SilkS")
		)
		(fp_rect
			(start -0.508 0.9398)
			(end 0.508 -0.9398)
			(stroke
				(width 0)
				(type default)
			)
			(fill no)
			(layer "F.CrtYd")
		)
		(fp_rect
			(start -0.508 0.9398)
			(end 0.508 -0.9398)
			(stroke
				(width 0)
				(type default)
			)
			(fill no)
			(layer "F.Fab")
		)
		(pad "1" smd custom
			(at 0 -0.4445 270)
			(size 0.1397 0.1397)
			(layers "F.Cu" "F.Mask" "F.Paste")
			(net "EXP_FW_DET_BOARD_VER_2")
			(options
				(clearance outline)
				(anchor circle)
			)
			(primitives
				(gr_poly
					(pts
						(arc
							(start -0.1778 -0.2794)
							(mid -0.249642 -0.249642)
							(end -0.2794 -0.1778)
						)
						(arc
							(start -0.2794 0.1778)
							(mid -0.249642 0.249642)
							(end -0.1778 0.2794)
						)
						(arc
							(start 0.1778 0.2794)
							(mid 0.249642 0.249642)
							(end 0.2794 0.1778)
						)
						(arc
							(start 0.2794 -0.1778)
							(mid 0.249642 -0.249642)
							(end 0.1778 -0.2794)
						)
					)
					(width 0)
					(fill yes)
				)
			)
		)
		(pad "2" smd custom
			(at 0 0.4445 270)
			(size 0.1397 0.1397)
			(layers "F.Cu" "F.Mask" "F.Paste")
			(net "GND")
			(options
				(clearance outline)
				(anchor circle)
			)
			(primitives
				(gr_poly
					(pts
						(arc
							(start -0.1778 -0.2794)
							(mid -0.249642 -0.249642)
							(end -0.2794 -0.1778)
						)
						(arc
							(start -0.2794 0.1778)
							(mid -0.249642 0.249642)
							(end -0.1778 0.2794)
						)
						(arc
							(start 0.1778 0.2794)
							(mid 0.249642 0.249642)
							(end 0.2794 0.1778)
						)
						(arc
							(start 0.2794 -0.1778)
							(mid 0.249642 -0.249642)
							(end 0.1778 -0.2794)
						)
					)
					(width 0)
					(fill yes)
				)
			)
		)
	)
	(footprint ""
		(layer "F.Cu")
		(at 333.912718 -147.805648 90)
		(property "Reference" "R552"
			(at 0 0 90)
			(layer "F.SilkS")
			(hide yes)
			(effects
				(font
					(size 1.27 1.27)
				)
			)
		)
		(property "Value" "4K7R2F-GP"
			(at 0.064008 -3.993896 90)
			(unlocked yes)
			(layer "F.Fab")
			(hide yes)
			(effects
				(font
					(size 1.016 1.016)
					(thickness 0.1524)
				)
			)
		)
		(property "Device Type" "R402H16"
			(at 0.064008 -5.517896 90)
			(unlocked yes)
			(layer "F.Fab")
			(hide yes)
			(effects
				(font
					(size 1.016 1.016)
					(thickness 0.1524)
				)
			)
		)
		(duplicate_pad_numbers_are_jumpers no)
		(fp_line
			(start 0.508 -0.9398)
			(end -0.508 -0.9398)
			(stroke
				(width 0.1524)
				(type default)
			)
			(layer "F.SilkS")
		)
		(fp_line
			(start -0.508 -0.9398)
			(end -0.508 0.9398)
			(stroke
				(width 0.1524)
				(type default)
			)
			(layer "F.SilkS")
		)
		(fp_rect
			(start -0.508 0.9398)
			(end 0.508 -0.9398)
			(stroke
				(width 0)
				(type default)
			)
			(fill no)
			(layer "F.CrtYd")
		)
		(fp_rect
			(start -0.508 0.9398)
			(end 0.508 -0.9398)
			(stroke
				(width 0)
				(type default)
			)
			(fill no)
			(layer "F.Fab")
		)
		(pad "1" smd custom
			(at 0 -0.4445 90)
			(size 0.1397 0.1397)
			(layers "F.Cu" "F.Mask" "F.Paste")
			(net "P3V3_STBY")
			(options
				(clearance outline)
				(anchor circle)
			)
			(primitives
				(gr_poly
					(pts
						(arc
							(start -0.1778 -0.2794)
							(mid -0.249642 -0.249642)
							(end -0.2794 -0.1778)
						)
						(arc
							(start -0.2794 0.1778)
							(mid -0.249642 0.249642)
							(end -0.1778 0.2794)
						)
						(arc
							(start 0.1778 0.2794)
							(mid 0.249642 0.249642)
							(end 0.2794 0.1778)
						)
						(arc
							(start 0.2794 -0.1778)
							(mid 0.249642 -0.249642)
							(end 0.1778 -0.2794)
						)
					)
					(width 0)
					(fill yes)
				)
			)
		)
		(pad "2" smd custom
			(at 0 0.4445 90)
			(size 0.1397 0.1397)
			(layers "F.Cu" "F.Mask" "F.Paste")
			(net "CFG_SEL1")
			(options
				(clearance outline)
				(anchor circle)
			)
			(primitives
				(gr_poly
					(pts
						(arc
							(start -0.1778 -0.2794)
							(mid -0.249642 -0.249642)
							(end -0.2794 -0.1778)
						)
						(arc
							(start -0.2794 0.1778)
							(mid -0.249642 0.249642)
							(end -0.1778 0.2794)
						)
						(arc
							(start 0.1778 0.2794)
							(mid 0.249642 0.249642)
							(end 0.2794 0.1778)
						)
						(arc
							(start 0.2794 -0.1778)
							(mid 0.249642 -0.249642)
							(end 0.1778 -0.2794)
						)
					)
					(width 0)
					(fill yes)
				)
			)
		)
	)
	(footprint ""
		(layer "F.Cu")
		(at 205.301596 -119.272812 90)
		(property "Reference" "PR9015"
			(at 0 0 90)
			(layer "F.SilkS")
			(hide yes)
			(effects
				(font
					(size 1.27 1.27)
				)
			)
		)
		(property "Value" "0R2J-2-GP"
			(at 0.064008 -3.993896 90)
			(unlocked yes)
			(layer "F.Fab")
			(hide yes)
			(effects
				(font
					(size 1.016 1.016)
					(thickness 0.1524)
				)
			)
		)
		(property "Device Type" "R402H16"
			(at 0.064008 -5.517896 90)
			(unlocked yes)
			(layer "F.Fab")
			(hide yes)
			(effects
				(font
					(size 1.016 1.016)
					(thickness 0.1524)
				)
			)
		)
		(duplicate_pad_numbers_are_jumpers no)
		(fp_line
			(start 0.508 -0.9398)
			(end -0.508 -0.9398)
			(stroke
				(width 0.1524)
				(type default)
			)
			(layer "F.SilkS")
		)
		(fp_line
			(start -0.508 -0.9398)
			(end -0.508 0.9398)
			(stroke
				(width 0.1524)
				(type default)
			)
			(layer "F.SilkS")
		)
		(fp_rect
			(start -0.508 0.9398)
			(end 0.508 -0.9398)
			(stroke
				(width 0)
				(type default)
			)
			(fill no)
			(layer "F.CrtYd")
		)
		(fp_rect
			(start -0.508 0.9398)
			(end 0.508 -0.9398)
			(stroke
				(width 0)
				(type default)
			)
			(fill no)
			(layer "F.Fab")
		)
		(pad "1" smd custom
			(at 0 -0.4445 90)
			(size 0.1397 0.1397)
			(layers "F.Cu" "F.Mask" "F.Paste")
			(net "P1V5_E_VO")
			(options
				(clearance outline)
				(anchor circle)
			)
			(primitives
				(gr_poly
					(pts
						(arc
							(start -0.1778 -0.2794)
							(mid -0.249642 -0.249642)
							(end -0.2794 -0.1778)
						)
						(arc
							(start -0.2794 0.1778)
							(mid -0.249642 0.249642)
							(end -0.1778 0.2794)
						)
						(arc
							(start 0.1778 0.2794)
							(mid 0.249642 0.249642)
							(end 0.2794 0.1778)
						)
						(arc
							(start 0.2794 -0.1778)
							(mid 0.249642 -0.249642)
							(end 0.1778 -0.2794)
						)
					)
					(width 0)
					(fill yes)
				)
			)
		)
		(pad "2" smd custom
			(at 0 0.4445 90)
			(size 0.1397 0.1397)
			(layers "F.Cu" "F.Mask" "F.Paste")
			(net "P1V5_E_CC_R")
			(options
				(clearance outline)
				(anchor circle)
			)
			(primitives
				(gr_poly
					(pts
						(arc
							(start -0.1778 -0.2794)
							(mid -0.249642 -0.249642)
							(end -0.2794 -0.1778)
						)
						(arc
							(start -0.2794 0.1778)
							(mid -0.249642 0.249642)
							(end -0.1778 0.2794)
						)
						(arc
							(start 0.1778 0.2794)
							(mid 0.249642 0.249642)
							(end 0.2794 0.1778)
						)
						(arc
							(start 0.2794 -0.1778)
							(mid 0.249642 -0.249642)
							(end 0.1778 -0.2794)
						)
					)
					(width 0)
					(fill yes)
				)
			)
		)
	)
	(footprint ""
		(layer "F.Cu")
		(at 308.737 -216.789)
		(property "Reference" "R658"
			(at 0 0 0)
			(layer "F.SilkS")
			(hide yes)
			(effects
				(font
					(size 1.27 1.27)
				)
			)
		)
		(property "Value" "0R2J-2-GP"
			(at 0.064008 -3.993896 0)
			(unlocked yes)
			(layer "F.Fab")
			(hide yes)
			(effects
				(font
					(size 1.016 1.016)
					(thickness 0.1524)
				)
			)
		)
		(property "Device Type" "R402H16"
			(at 0.064008 -5.517896 0)
			(unlocked yes)
			(layer "F.Fab")
			(hide yes)
			(effects
				(font
					(size 1.016 1.016)
					(thickness 0.1524)
				)
			)
		)
		(duplicate_pad_numbers_are_jumpers no)
		(fp_line
			(start -0.508 -0.9398)
			(end -0.508 0.9398)
			(stroke
				(width 0.1524)
				(type default)
			)
			(layer "F.SilkS")
		)
		(fp_line
			(start 0.508 -0.9398)
			(end -0.508 -0.9398)
			(stroke
				(width 0.1524)
				(type default)
			)
			(layer "F.SilkS")
		)
		(fp_rect
			(start -0.508 0.9398)
			(end 0.508 -0.9398)
			(stroke
				(width 0)
				(type default)
			)
			(fill no)
			(layer "F.CrtYd")
		)
		(fp_rect
			(start -0.508 0.9398)
			(end 0.508 -0.9398)
			(stroke
				(width 0)
				(type default)
			)
			(fill no)
			(layer "F.Fab")
		)
		(pad "1" smd custom
			(at 0 -0.4445)
			(size 0.1397 0.1397)
			(layers "F.Cu" "F.Mask" "F.Paste")
			(net "BMC_DEBUG_OE_2_N")
			(options
				(clearance outline)
				(anchor circle)
			)
			(primitives
				(gr_poly
					(pts
						(arc
							(start -0.1778 -0.2794)
							(mid -0.249642 -0.249642)
							(end -0.2794 -0.1778)
						)
						(arc
							(start -0.2794 0.1778)
							(mid -0.249642 0.249642)
							(end -0.1778 0.2794)
						)
						(arc
							(start 0.1778 0.2794)
							(mid 0.249642 0.249642)
							(end 0.2794 0.1778)
						)
						(arc
							(start 0.2794 -0.1778)
							(mid 0.249642 -0.249642)
							(end 0.1778 -0.2794)
						)
					)
					(width 0)
					(fill yes)
				)
			)
		)
		(pad "2" smd custom
			(at 0 0.4445)
			(size 0.1397 0.1397)
			(layers "F.Cu" "F.Mask" "F.Paste")
			(net "BMC0_TACH10")
			(options
				(clearance outline)
				(anchor circle)
			)
			(primitives
				(gr_poly
					(pts
						(arc
							(start -0.1778 -0.2794)
							(mid -0.249642 -0.249642)
							(end -0.2794 -0.1778)
						)
						(arc
							(start -0.2794 0.1778)
							(mid -0.249642 0.249642)
							(end -0.1778 0.2794)
						)
						(arc
							(start 0.1778 0.2794)
							(mid 0.249642 0.249642)
							(end 0.2794 0.1778)
						)
						(arc
							(start 0.2794 -0.1778)
							(mid 0.249642 -0.249642)
							(end 0.1778 -0.2794)
						)
					)
					(width 0)
					(fill yes)
				)
			)
		)
	)
	(footprint ""
		(layer "F.Cu")
		(at 95.89897 -93.091 -90)
		(property "Reference" "SR814"
			(at 0 0 270)
			(layer "F.SilkS")
			(hide yes)
			(effects
				(font
					(size 1.27 1.27)
				)
			)
		)
		(property "Value" "1KR2F-3-GP"
			(at 0.064008 -3.993896 270)
			(unlocked yes)
			(layer "F.Fab")
			(hide yes)
			(effects
				(font
					(size 1.016 1.016)
					(thickness 0.1524)
				)
			)
		)
		(property "Device Type" "R402H16"
			(at 0.064008 -5.517896 270)
			(unlocked yes)
			(layer "F.Fab")
			(hide yes)
			(effects
				(font
					(size 1.016 1.016)
					(thickness 0.1524)
				)
			)
		)
		(duplicate_pad_numbers_are_jumpers no)
		(fp_line
			(start -0.508 -0.9398)
			(end -0.508 0.9398)
			(stroke
				(width 0.1524)
				(type default)
			)
			(layer "F.SilkS")
		)
		(fp_line
			(start 0.508 -0.9398)
			(end -0.508 -0.9398)
			(stroke
				(width 0.1524)
				(type default)
			)
			(layer "F.SilkS")
		)
		(fp_rect
			(start -0.508 0.9398)
			(end 0.508 -0.9398)
			(stroke
				(width 0)
				(type default)
			)
			(fill no)
			(layer "F.CrtYd")
		)
		(fp_rect
			(start -0.508 0.9398)
			(end 0.508 -0.9398)
			(stroke
				(width 0)
				(type default)
			)
			(fill no)
			(layer "F.Fab")
		)
		(pad "1" smd custom
			(at 0 -0.4445 270)
			(size 0.1397 0.1397)
			(layers "F.Cu" "F.Mask" "F.Paste")
			(net "LSI_SCAN_ENABLE")
			(options
				(clearance outline)
				(anchor circle)
			)
			(primitives
				(gr_poly
					(pts
						(arc
							(start -0.1778 -0.2794)
							(mid -0.249642 -0.249642)
							(end -0.2794 -0.1778)
						)
						(arc
							(start -0.2794 0.1778)
							(mid -0.249642 0.249642)
							(end -0.1778 0.2794)
						)
						(arc
							(start 0.1778 0.2794)
							(mid 0.249642 0.249642)
							(end 0.2794 0.1778)
						)
						(arc
							(start 0.2794 -0.1778)
							(mid 0.249642 -0.249642)
							(end 0.1778 -0.2794)
						)
					)
					(width 0)
					(fill yes)
				)
			)
		)
		(pad "2" smd custom
			(at 0 0.4445 270)
			(size 0.1397 0.1397)
			(layers "F.Cu" "F.Mask" "F.Paste")
			(net "P1V8_E")
			(options
				(clearance outline)
				(anchor circle)
			)
			(primitives
				(gr_poly
					(pts
						(arc
							(start -0.1778 -0.2794)
							(mid -0.249642 -0.249642)
							(end -0.2794 -0.1778)
						)
						(arc
							(start -0.2794 0.1778)
							(mid -0.249642 0.249642)
							(end -0.1778 0.2794)
						)
						(arc
							(start 0.1778 0.2794)
							(mid 0.249642 0.249642)
							(end 0.2794 0.1778)
						)
						(arc
							(start 0.2794 -0.1778)
							(mid 0.249642 -0.249642)
							(end 0.1778 -0.2794)
						)
					)
					(width 0)
					(fill yes)
				)
			)
		)
	)
	(footprint ""
		(layer "F.Cu")
		(at 113.792 -29.083 -90)
		(property "Reference" "SR670"
			(at 0 0 270)
			(layer "F.SilkS")
			(hide yes)
			(effects
				(font
					(size 1.27 1.27)
				)
			)
		)
		(property "Value" "4K7R2F-GP"
			(at 0.064008 -3.993896 270)
			(unlocked yes)
			(layer "F.Fab")
			(hide yes)
			(effects
				(font
					(size 1.016 1.016)
					(thickness 0.1524)
				)
			)
		)
		(property "Device Type" "R402H16"
			(at 0.064008 -5.517896 270)
			(unlocked yes)
			(layer "F.Fab")
			(hide yes)
			(effects
				(font
					(size 1.016 1.016)
					(thickness 0.1524)
				)
			)
		)
		(duplicate_pad_numbers_are_jumpers no)
		(fp_line
			(start -0.508 -0.9398)
			(end -0.508 0.9398)
			(stroke
				(width 0.1524)
				(type default)
			)
			(layer "F.SilkS")
		)
		(fp_line
			(start 0.508 -0.9398)
			(end -0.508 -0.9398)
			(stroke
				(width 0.1524)
				(type default)
			)
			(layer "F.SilkS")
		)
		(fp_rect
			(start -0.508 0.9398)
			(end 0.508 -0.9398)
			(stroke
				(width 0)
				(type default)
			)
			(fill no)
			(layer "F.CrtYd")
		)
		(fp_rect
			(start -0.508 0.9398)
			(end 0.508 -0.9398)
			(stroke
				(width 0)
				(type default)
			)
			(fill no)
			(layer "F.Fab")
		)
		(pad "1" smd custom
			(at 0 -0.4445 270)
			(size 0.1397 0.1397)
			(layers "F.Cu" "F.Mask" "F.Paste")
			(net "P1V8_C")
			(options
				(clearance outline)
				(anchor circle)
			)
			(primitives
				(gr_poly
					(pts
						(arc
							(start -0.1778 -0.2794)
							(mid -0.249642 -0.249642)
							(end -0.2794 -0.1778)
						)
						(arc
							(start -0.2794 0.1778)
							(mid -0.249642 0.249642)
							(end -0.1778 0.2794)
						)
						(arc
							(start 0.1778 0.2794)
							(mid 0.249642 0.249642)
							(end 0.2794 0.1778)
						)
						(arc
							(start 0.2794 -0.1778)
							(mid 0.249642 -0.249642)
							(end 0.1778 -0.2794)
						)
					)
					(width 0)
					(fill yes)
				)
			)
		)
		(pad "2" smd custom
			(at 0 0.4445 270)
			(size 0.1397 0.1397)
			(layers "F.Cu" "F.Mask" "F.Paste")
			(net "SYS_HALT0#")
			(options
				(clearance outline)
				(anchor circle)
			)
			(primitives
				(gr_poly
					(pts
						(arc
							(start -0.1778 -0.2794)
							(mid -0.249642 -0.249642)
							(end -0.2794 -0.1778)
						)
						(arc
							(start -0.2794 0.1778)
							(mid -0.249642 0.249642)
							(end -0.1778 0.2794)
						)
						(arc
							(start 0.1778 0.2794)
							(mid 0.249642 0.249642)
							(end 0.2794 0.1778)
						)
						(arc
							(start 0.2794 -0.1778)
							(mid 0.249642 -0.249642)
							(end 0.1778 -0.2794)
						)
					)
					(width 0)
					(fill yes)
				)
			)
		)
	)
	(footprint ""
		(layer "F.Cu")
		(at 164.211 -111.76 90)
		(property "Reference" "PR151"
			(at 0 0 90)
			(layer "F.SilkS")
			(hide yes)
			(effects
				(font
					(size 1.27 1.27)
				)
			)
		)
		(property "Value" "100KR2F-L1-GP"
			(at 0.064008 -3.993896 90)
			(unlocked yes)
			(layer "F.Fab")
			(hide yes)
			(effects
				(font
					(size 1.016 1.016)
					(thickness 0.1524)
				)
			)
		)
		(property "Device Type" "R402H16"
			(at 0.064008 -5.517896 90)
			(unlocked yes)
			(layer "F.Fab")
			(hide yes)
			(effects
				(font
					(size 1.016 1.016)
					(thickness 0.1524)
				)
			)
		)
		(duplicate_pad_numbers_are_jumpers no)
		(fp_line
			(start 0.508 -0.9398)
			(end -0.508 -0.9398)
			(stroke
				(width 0.1524)
				(type default)
			)
			(layer "F.SilkS")
		)
		(fp_line
			(start -0.508 -0.9398)
			(end -0.508 0.9398)
			(stroke
				(width 0.1524)
				(type default)
			)
			(layer "F.SilkS")
		)
		(fp_rect
			(start -0.508 0.9398)
			(end 0.508 -0.9398)
			(stroke
				(width 0)
				(type default)
			)
			(fill no)
			(layer "F.CrtYd")
		)
		(fp_rect
			(start -0.508 0.9398)
			(end 0.508 -0.9398)
			(stroke
				(width 0)
				(type default)
			)
			(fill no)
			(layer "F.Fab")
		)
		(pad "1" smd custom
			(at 0 -0.4445 90)
			(size 0.1397 0.1397)
			(layers "F.Cu" "F.Mask" "F.Paste")
			(net "P12V")
			(options
				(clearance outline)
				(anchor circle)
			)
			(primitives
				(gr_poly
					(pts
						(arc
							(start -0.1778 -0.2794)
							(mid -0.249642 -0.249642)
							(end -0.2794 -0.1778)
						)
						(arc
							(start -0.2794 0.1778)
							(mid -0.249642 0.249642)
							(end -0.1778 0.2794)
						)
						(arc
							(start 0.1778 0.2794)
							(mid 0.249642 0.249642)
							(end 0.2794 0.1778)
						)
						(arc
							(start 0.2794 -0.1778)
							(mid 0.249642 -0.249642)
							(end 0.1778 -0.2794)
						)
					)
					(width 0)
					(fill yes)
				)
			)
		)
		(pad "2" smd custom
			(at 0 0.4445 90)
			(size 0.1397 0.1397)
			(layers "F.Cu" "F.Mask" "F.Paste")
			(net "P0V9_E_EN")
			(options
				(clearance outline)
				(anchor circle)
			)
			(primitives
				(gr_poly
					(pts
						(arc
							(start -0.1778 -0.2794)
							(mid -0.249642 -0.249642)
							(end -0.2794 -0.1778)
						)
						(arc
							(start -0.2794 0.1778)
							(mid -0.249642 0.249642)
							(end -0.1778 0.2794)
						)
						(arc
							(start 0.1778 0.2794)
							(mid 0.249642 0.249642)
							(end 0.2794 0.1778)
						)
						(arc
							(start 0.2794 -0.1778)
							(mid 0.249642 -0.249642)
							(end 0.1778 -0.2794)
						)
					)
					(width 0)
					(fill yes)
				)
			)
		)
	)
	(footprint ""
		(layer "F.Cu")
		(at 282.829 -71.12 90)
		(property "Reference" "C267"
			(at 0 0 90)
			(layer "F.SilkS")
			(hide yes)
			(effects
				(font
					(size 1.27 1.27)
				)
			)
		)
		(property "Value" "SCD1U25V3KX-GP"
			(at 0 -2.8194 90)
			(unlocked yes)
			(layer "F.Fab")
			(hide yes)
			(effects
				(font
					(size 1.016 1.016)
					(thickness 0.1524)
				)
			)
		)
		(property "Device Type" "C603H36"
			(at 0 -4.3434 90)
			(unlocked yes)
			(layer "F.Fab")
			(hide yes)
			(effects
				(font
					(size 1.016 1.016)
					(thickness 0.1524)
				)
			)
		)
		(duplicate_pad_numbers_are_jumpers no)
		(fp_line
			(start 0.508 0)
			(end -0.508 0)
			(stroke
				(width 0.2032)
				(type default)
			)
			(layer "F.SilkS")
		)
		(fp_rect
			(start -0.5842 1.3335)
			(end 0.5842 -1.3335)
			(stroke
				(width 0)
				(type default)
			)
			(fill no)
			(layer "F.CrtYd")
		)
		(fp_rect
			(start -0.5842 1.3335)
			(end 0.5842 -1.3335)
			(stroke
				(width 0)
				(type default)
			)
			(fill no)
			(layer "F.Fab")
		)
		(pad "1" smd custom
			(at 0 -0.762 90)
			(size 0.2159 0.2159)
			(layers "F.Cu" "F.Mask" "F.Paste")
			(net "P12V_PCIE")
			(options
				(clearance outline)
				(anchor circle)
			)
			(primitives
				(gr_poly
					(pts
						(arc
							(start -0.3302 -0.4318)
							(mid -0.402042 -0.402042)
							(end -0.4318 -0.3302)
						)
						(arc
							(start -0.4318 0.3302)
							(mid -0.402042 0.402042)
							(end -0.3302 0.4318)
						)
						(arc
							(start 0.3302 0.4318)
							(mid 0.402042 0.402042)
							(end 0.4318 0.3302)
						)
						(arc
							(start 0.4318 -0.3302)
							(mid 0.402042 -0.402042)
							(end 0.3302 -0.4318)
						)
					)
					(width 0)
					(fill yes)
				)
			)
		)
		(pad "2" smd custom
			(at 0 0.762 90)
			(size 0.2159 0.2159)
			(layers "F.Cu" "F.Mask" "F.Paste")
			(net "GND")
			(options
				(clearance outline)
				(anchor circle)
			)
			(primitives
				(gr_poly
					(pts
						(arc
							(start -0.3302 -0.4318)
							(mid -0.402042 -0.402042)
							(end -0.4318 -0.3302)
						)
						(arc
							(start -0.4318 0.3302)
							(mid -0.402042 0.402042)
							(end -0.3302 0.4318)
						)
						(arc
							(start 0.3302 0.4318)
							(mid 0.402042 0.402042)
							(end 0.4318 0.3302)
						)
						(arc
							(start 0.4318 -0.3302)
							(mid 0.402042 -0.402042)
							(end 0.3302 -0.4318)
						)
					)
					(width 0)
					(fill yes)
				)
			)
		)
	)
	(footprint ""
		(layer "F.Cu")
		(at 80.499966 -83.439 -90)
		(property "Reference" "SL14"
			(at 0 0 270)
			(layer "F.SilkS")
			(hide yes)
			(effects
				(font
					(size 1.27 1.27)
				)
			)
		)
		(property "Value" "MPZ2012S601AT-GP"
			(at 0 -4.2418 270)
			(unlocked yes)
			(layer "F.Fab")
			(hide yes)
			(effects
				(font
					(size 1.016 1.016)
					(thickness 0.1524)
				)
			)
		)
		(property "Device Type" "L805H42"
			(at 0 -5.7912 270)
			(unlocked yes)
			(layer "F.Fab")
			(hide yes)
			(effects
				(font
					(size 1.016 1.016)
					(thickness 0.1524)
				)
			)
		)
		(duplicate_pad_numbers_are_jumpers no)
		(fp_line
			(start -0.889 1.7018)
			(end -0.889 -1.7018)
			(stroke
				(width 0.1524)
				(type default)
			)
			(layer "F.SilkS")
		)
		(fp_line
			(start 0.889 1.7018)
			(end -0.889 1.7018)
			(stroke
				(width 0.1524)
				(type default)
			)
			(layer "F.SilkS")
		)
		(fp_line
			(start -0.889 -1.7018)
			(end 0.889 -1.7018)
			(stroke
				(width 0.1524)
				(type default)
			)
			(layer "F.SilkS")
		)
		(fp_line
			(start 0.889 -1.7018)
			(end 0.889 1.7018)
			(stroke
				(width 0.1524)
				(type default)
			)
			(layer "F.SilkS")
		)
		(fp_rect
			(start -0.9652 1.778)
			(end 0.9652 -1.778)
			(stroke
				(width 0)
				(type default)
			)
			(fill no)
			(layer "F.CrtYd")
		)
		(fp_rect
			(start -0.9652 1.778)
			(end 0.9652 -1.778)
			(stroke
				(width 0)
				(type default)
			)
			(fill no)
			(layer "F.Fab")
		)
		(pad "1" smd rect
			(at 0 -0.9652 270)
			(size 1.397 1.143)
			(layers "F.Cu" "F.Mask" "F.Paste")
			(net "PLLDDR_VDDA18")
		)
		(pad "2" smd rect
			(at 0 0.9652 270)
			(size 1.397 1.143)
			(layers "F.Cu" "F.Mask" "F.Paste")
			(net "P1V8_E")
		)
	)
	(footprint ""
		(layer "F.Cu")
		(at 336.296 -13.462 180)
		(property "Reference" "SLED28"
			(at 0 0 180)
			(layer "F.SilkS")
			(hide yes)
			(effects
				(font
					(size 1.27 1.27)
				)
			)
		)
		(property "Value" "LED-YG-51-GP"
			(at -2.6924 -1.4224 180)
			(unlocked yes)
			(layer "F.Fab")
			(hide yes)
			(effects
				(font
					(size 1.016 1.016)
					(thickness 0.1524)
				)
			)
		)
		(property "Device Type" "LED1608AKH40"
			(at -2.6924 -2.9464 180)
			(unlocked yes)
			(layer "F.Fab")
			(hide yes)
			(effects
				(font
					(size 1.016 1.016)
					(thickness 0.1524)
				)
			)
		)
		(duplicate_pad_numbers_are_jumpers no)
		(fp_line
			(start 0.7493 1.651)
			(end 0.7493 1.1811)
			(stroke
				(width 0.3302)
				(type default)
			)
			(layer "F.SilkS")
		)
		(fp_line
			(start 0.6604 1.3716)
			(end -0.6604 1.3716)
			(stroke
				(width 0.1524)
				(type default)
			)
			(layer "F.SilkS")
		)
		(fp_line
			(start 0.6604 -1.3716)
			(end 0.6604 1.3716)
			(stroke
				(width 0.1524)
				(type default)
			)
			(layer "F.SilkS")
		)
		(fp_line
			(start -0.5969 1.5494)
			(end 0.5842 1.5494)
			(stroke
				(width 0.508)
				(type default)
			)
			(layer "F.SilkS")
		)
		(fp_line
			(start -0.6604 1.3716)
			(end -0.6604 -1.3716)
			(stroke
				(width 0.1524)
				(type default)
			)
			(layer "F.SilkS")
		)
		(fp_line
			(start -0.6604 -1.3716)
			(end 0.6604 -1.3716)
			(stroke
				(width 0.1524)
				(type default)
			)
			(layer "F.SilkS")
		)
		(fp_line
			(start -0.7493 1.651)
			(end -0.7493 1.1811)
			(stroke
				(width 0.3302)
				(type default)
			)
			(layer "F.SilkS")
		)
		(fp_rect
			(start -0.6223 1.3335)
			(end 0.6223 -1.3335)
			(stroke
				(width 0)
				(type default)
			)
			(fill no)
			(layer "F.CrtYd")
		)
		(fp_rect
			(start -0.6223 1.3335)
			(end 0.6223 -1.3335)
			(stroke
				(width 0)
				(type default)
			)
			(fill no)
			(layer "F.Fab")
		)
		(pad "A" smd custom
			(at 0 -0.762 180)
			(size 0.2159 0.2159)
			(layers "F.Cu" "F.Mask" "F.Paste")
			(net "EXP_BMC_HB_LED_R")
			(options
				(clearance outline)
				(anchor circle)
			)
			(primitives
				(gr_poly
					(pts
						(arc
							(start -0.3302 -0.4318)
							(mid -0.402042 -0.402042)
							(end -0.4318 -0.3302)
						)
						(arc
							(start -0.4318 0.3302)
							(mid -0.402042 0.402042)
							(end -0.3302 0.4318)
						)
						(arc
							(start 0.3302 0.4318)
							(mid 0.402042 0.402042)
							(end 0.4318 0.3302)
						)
						(arc
							(start 0.4318 -0.3302)
							(mid 0.402042 -0.402042)
							(end 0.3302 -0.4318)
						)
					)
					(width 0)
					(fill yes)
				)
			)
		)
		(pad "K" smd custom
			(at 0 0.762 180)
			(size 0.2159 0.2159)
			(layers "F.Cu" "F.Mask" "F.Paste")
			(net "EXP_BMC_HB_LED_D")
			(options
				(clearance outline)
				(anchor circle)
			)
			(primitives
				(gr_poly
					(pts
						(arc
							(start -0.3302 -0.4318)
							(mid -0.402042 -0.402042)
							(end -0.4318 -0.3302)
						)
						(arc
							(start -0.4318 0.3302)
							(mid -0.402042 0.402042)
							(end -0.3302 0.4318)
						)
						(arc
							(start 0.3302 0.4318)
							(mid 0.402042 0.402042)
							(end 0.4318 0.3302)
						)
						(arc
							(start 0.4318 -0.3302)
							(mid 0.402042 -0.402042)
							(end 0.3302 -0.4318)
						)
					)
					(width 0)
					(fill yes)
				)
			)
		)
	)
	(footprint ""
		(layer "F.Cu")
		(at 267.772896 -75.223624 90)
		(property "Reference" "C261"
			(at 0 0 90)
			(layer "F.SilkS")
			(hide yes)
			(effects
				(font
					(size 1.27 1.27)
				)
			)
		)
		(property "Value" "SCD1U25V2KX-2-GP"
			(at 1.1811 -2.7051 90)
			(unlocked yes)
			(layer "F.Fab")
			(hide yes)
			(effects
				(font
					(size 1.016 1.016)
					(thickness 0.1524)
				)
			)
		)
		(property "Device Type" "C402H22"
			(at 1.1811 -4.2291 90)
			(unlocked yes)
			(layer "F.Fab")
			(hide yes)
			(effects
				(font
					(size 1.016 1.016)
					(thickness 0.1524)
				)
			)
		)
		(duplicate_pad_numbers_are_jumpers no)
		(fp_rect
			(start -0.4318 0.9525)
			(end 0.4318 -0.9525)
			(stroke
				(width 0)
				(type default)
			)
			(fill no)
			(layer "F.CrtYd")
		)
		(fp_rect
			(start -0.4318 0.9525)
			(end 0.4318 -0.9525)
			(stroke
				(width 0)
				(type default)
			)
			(fill no)
			(layer "F.Fab")
		)
		(pad "1" smd custom
			(at 0 -0.4445 90)
			(size 0.1524 0.1524)
			(layers "F.Cu" "F.Mask" "F.Paste")
			(net "P12V_MSB")
			(options
				(clearance outline)
				(anchor circle)
			)
			(primitives
				(gr_poly
					(pts
						(arc
							(start 0.3048 -0.2032)
							(mid 0.275042 -0.275042)
							(end 0.2032 -0.3048)
						)
						(arc
							(start -0.2032 -0.3048)
							(mid -0.275042 -0.275042)
							(end -0.3048 -0.2032)
						)
						(arc
							(start -0.3048 0.2032)
							(mid -0.275042 0.275042)
							(end -0.2032 0.3048)
						)
						(arc
							(start 0.2032 0.3048)
							(mid 0.275042 0.275042)
							(end 0.3048 0.2032)
						)
					)
					(width 0)
					(fill yes)
				)
			)
		)
		(pad "2" smd custom
			(at 0 0.4445 90)
			(size 0.1524 0.1524)
			(layers "F.Cu" "F.Mask" "F.Paste")
			(net "GND")
			(options
				(clearance outline)
				(anchor circle)
			)
			(primitives
				(gr_poly
					(pts
						(arc
							(start 0.3048 -0.2032)
							(mid 0.275042 -0.275042)
							(end 0.2032 -0.3048)
						)
						(arc
							(start -0.2032 -0.3048)
							(mid -0.275042 -0.275042)
							(end -0.3048 -0.2032)
						)
						(arc
							(start -0.3048 0.2032)
							(mid -0.275042 0.275042)
							(end -0.2032 0.3048)
						)
						(arc
							(start 0.2032 0.3048)
							(mid 0.275042 0.275042)
							(end 0.3048 0.2032)
						)
					)
					(width 0)
					(fill yes)
				)
			)
		)
	)
	(footprint ""
		(layer "F.Cu")
		(at 39.0652 -119.3292 90)
		(property "Reference" "SR841"
			(at 0 0 90)
			(layer "F.SilkS")
			(hide yes)
			(effects
				(font
					(size 1.27 1.27)
				)
			)
		)
		(property "Value" "10KR2F-2-GP"
			(at 0.064008 -3.993896 90)
			(unlocked yes)
			(layer "F.Fab")
			(hide yes)
			(effects
				(font
					(size 1.016 1.016)
					(thickness 0.1524)
				)
			)
		)
		(property "Device Type" "R402H16"
			(at 0.064008 -5.517896 90)
			(unlocked yes)
			(layer "F.Fab")
			(hide yes)
			(effects
				(font
					(size 1.016 1.016)
					(thickness 0.1524)
				)
			)
		)
		(duplicate_pad_numbers_are_jumpers no)
		(fp_line
			(start 0.508 -0.9398)
			(end -0.508 -0.9398)
			(stroke
				(width 0.1524)
				(type default)
			)
			(layer "F.SilkS")
		)
		(fp_line
			(start -0.508 -0.9398)
			(end -0.508 0.9398)
			(stroke
				(width 0.1524)
				(type default)
			)
			(layer "F.SilkS")
		)
		(fp_rect
			(start -0.508 0.9398)
			(end 0.508 -0.9398)
			(stroke
				(width 0)
				(type default)
			)
			(fill no)
			(layer "F.CrtYd")
		)
		(fp_rect
			(start -0.508 0.9398)
			(end 0.508 -0.9398)
			(stroke
				(width 0)
				(type default)
			)
			(fill no)
			(layer "F.Fab")
		)
		(pad "1" smd custom
			(at 0 -0.4445 90)
			(size 0.1397 0.1397)
			(layers "F.Cu" "F.Mask" "F.Paste")
			(net "P1V8_E")
			(options
				(clearance outline)
				(anchor circle)
			)
			(primitives
				(gr_poly
					(pts
						(arc
							(start -0.1778 -0.2794)
							(mid -0.249642 -0.249642)
							(end -0.2794 -0.1778)
						)
						(arc
							(start -0.2794 0.1778)
							(mid -0.249642 0.249642)
							(end -0.1778 0.2794)
						)
						(arc
							(start 0.1778 0.2794)
							(mid 0.249642 0.249642)
							(end 0.2794 0.1778)
						)
						(arc
							(start 0.2794 -0.1778)
							(mid 0.249642 -0.249642)
							(end 0.1778 -0.2794)
						)
					)
					(width 0)
					(fill yes)
				)
			)
		)
		(pad "2" smd custom
			(at 0 0.4445 90)
			(size 0.1397 0.1397)
			(layers "F.Cu" "F.Mask" "F.Paste")
			(net "SDB_UART_EN")
			(options
				(clearance outline)
				(anchor circle)
			)
			(primitives
				(gr_poly
					(pts
						(arc
							(start -0.1778 -0.2794)
							(mid -0.249642 -0.249642)
							(end -0.2794 -0.1778)
						)
						(arc
							(start -0.2794 0.1778)
							(mid -0.249642 0.249642)
							(end -0.1778 0.2794)
						)
						(arc
							(start 0.1778 0.2794)
							(mid 0.249642 0.249642)
							(end 0.2794 0.1778)
						)
						(arc
							(start 0.2794 -0.1778)
							(mid 0.249642 -0.249642)
							(end 0.1778 -0.2794)
						)
					)
					(width 0)
					(fill yes)
				)
			)
		)
	)
	(footprint ""
		(layer "F.Cu")
		(at 106.31297 -76.454)
		(property "Reference" "SR867"
			(at 0 0 0)
			(layer "F.SilkS")
			(hide yes)
			(effects
				(font
					(size 1.27 1.27)
				)
			)
		)
		(property "Value" "0R2J-2-GP"
			(at 0.064008 -3.993896 0)
			(unlocked yes)
			(layer "F.Fab")
			(hide yes)
			(effects
				(font
					(size 1.016 1.016)
					(thickness 0.1524)
				)
			)
		)
		(property "Device Type" "R402H16"
			(at 0.064008 -5.517896 0)
			(unlocked yes)
			(layer "F.Fab")
			(hide yes)
			(effects
				(font
					(size 1.016 1.016)
					(thickness 0.1524)
				)
			)
		)
		(duplicate_pad_numbers_are_jumpers no)
		(fp_line
			(start -0.508 -0.9398)
			(end -0.508 0.9398)
			(stroke
				(width 0.1524)
				(type default)
			)
			(layer "F.SilkS")
		)
		(fp_line
			(start 0.508 -0.9398)
			(end -0.508 -0.9398)
			(stroke
				(width 0.1524)
				(type default)
			)
			(layer "F.SilkS")
		)
		(fp_rect
			(start -0.508 0.9398)
			(end 0.508 -0.9398)
			(stroke
				(width 0)
				(type default)
			)
			(fill no)
			(layer "F.CrtYd")
		)
		(fp_rect
			(start -0.508 0.9398)
			(end 0.508 -0.9398)
			(stroke
				(width 0)
				(type default)
			)
			(fill no)
			(layer "F.Fab")
		)
		(pad "1" smd custom
			(at 0 -0.4445)
			(size 0.1397 0.1397)
			(layers "F.Cu" "F.Mask" "F.Paste")
			(net "LSI_TRST_N")
			(options
				(clearance outline)
				(anchor circle)
			)
			(primitives
				(gr_poly
					(pts
						(arc
							(start -0.1778 -0.2794)
							(mid -0.249642 -0.249642)
							(end -0.2794 -0.1778)
						)
						(arc
							(start -0.2794 0.1778)
							(mid -0.249642 0.249642)
							(end -0.1778 0.2794)
						)
						(arc
							(start 0.1778 0.2794)
							(mid 0.249642 0.249642)
							(end 0.2794 0.1778)
						)
						(arc
							(start 0.2794 -0.1778)
							(mid 0.249642 -0.249642)
							(end 0.1778 -0.2794)
						)
					)
					(width 0)
					(fill yes)
				)
			)
		)
		(pad "2" smd custom
			(at 0 0.4445)
			(size 0.1397 0.1397)
			(layers "F.Cu" "F.Mask" "F.Paste")
			(net "JTAG_EXP_IOC_RST")
			(options
				(clearance outline)
				(anchor circle)
			)
			(primitives
				(gr_poly
					(pts
						(arc
							(start -0.1778 -0.2794)
							(mid -0.249642 -0.249642)
							(end -0.2794 -0.1778)
						)
						(arc
							(start -0.2794 0.1778)
							(mid -0.249642 0.249642)
							(end -0.1778 0.2794)
						)
						(arc
							(start 0.1778 0.2794)
							(mid 0.249642 0.249642)
							(end 0.2794 0.1778)
						)
						(arc
							(start 0.2794 -0.1778)
							(mid 0.249642 -0.249642)
							(end 0.1778 -0.2794)
						)
					)
					(width 0)
					(fill yes)
				)
			)
		)
	)
	(footprint ""
		(layer "F.Cu")
		(at 318.008 -181.864 -90)
		(property "Reference" "R338"
			(at 0 0 270)
			(layer "F.SilkS")
			(hide yes)
			(effects
				(font
					(size 1.27 1.27)
				)
			)
		)
		(property "Value" "2K74R3F-GP"
			(at -0.0254 -2.5146 270)
			(unlocked yes)
			(layer "F.Fab")
			(hide yes)
			(effects
				(font
					(size 1.016 1.016)
					(thickness 0.1524)
				)
			)
		)
		(property "Device Type" "R603H22"
			(at -0.0254 -4.0386 270)
			(unlocked yes)
			(layer "F.Fab")
			(hide yes)
			(effects
				(font
					(size 1.016 1.016)
					(thickness 0.1524)
				)
			)
		)
		(duplicate_pad_numbers_are_jumpers no)
		(fp_line
			(start -0.4826 0)
			(end -0.2032 0)
			(stroke
				(width 0.2032)
				(type default)
			)
			(layer "F.SilkS")
		)
		(fp_line
			(start 0.2032 0)
			(end 0.4826 0)
			(stroke
				(width 0.2032)
				(type default)
			)
			(layer "F.SilkS")
		)
		(fp_rect
			(start -0.5842 1.3335)
			(end 0.5842 -1.3335)
			(stroke
				(width 0)
				(type default)
			)
			(fill no)
			(layer "F.CrtYd")
		)
		(fp_rect
			(start -0.5842 1.3335)
			(end 0.5842 -1.3335)
			(stroke
				(width 0)
				(type default)
			)
			(fill no)
			(layer "F.Fab")
		)
		(pad "1" smd custom
			(at 0 -0.762 270)
			(size 0.2159 0.2159)
			(layers "F.Cu" "F.Mask" "F.Paste")
			(net "GND")
			(options
				(clearance outline)
				(anchor circle)
			)
			(primitives
				(gr_poly
					(pts
						(arc
							(start -0.3302 -0.4318)
							(mid -0.402042 -0.402042)
							(end -0.4318 -0.3302)
						)
						(arc
							(start -0.4318 0.3302)
							(mid -0.402042 0.402042)
							(end -0.3302 0.4318)
						)
						(arc
							(start 0.3302 0.4318)
							(mid 0.402042 0.402042)
							(end 0.4318 0.3302)
						)
						(arc
							(start 0.4318 -0.3302)
							(mid 0.402042 -0.402042)
							(end 0.3302 -0.4318)
						)
					)
					(width 0)
					(fill yes)
				)
			)
		)
		(pad "2" smd custom
			(at 0 0.762 270)
			(size 0.2159 0.2159)
			(layers "F.Cu" "F.Mask" "F.Paste")
			(net "DACRSET")
			(options
				(clearance outline)
				(anchor circle)
			)
			(primitives
				(gr_poly
					(pts
						(arc
							(start -0.3302 -0.4318)
							(mid -0.402042 -0.402042)
							(end -0.4318 -0.3302)
						)
						(arc
							(start -0.4318 0.3302)
							(mid -0.402042 0.402042)
							(end -0.3302 0.4318)
						)
						(arc
							(start 0.3302 0.4318)
							(mid 0.402042 0.402042)
							(end 0.4318 0.3302)
						)
						(arc
							(start 0.4318 -0.3302)
							(mid 0.402042 -0.402042)
							(end 0.3302 -0.4318)
						)
					)
					(width 0)
					(fill yes)
				)
			)
		)
	)
	(footprint ""
		(layer "F.Cu")
		(at 204.089 -216.154 -90)
		(property "Reference" "R1585"
			(at 0 0 270)
			(layer "F.SilkS")
			(hide yes)
			(effects
				(font
					(size 1.27 1.27)
				)
			)
		)
		(property "Value" "4K7R2F-GP"
			(at 0.064008 -3.993896 270)
			(unlocked yes)
			(layer "F.Fab")
			(hide yes)
			(effects
				(font
					(size 1.016 1.016)
					(thickness 0.1524)
				)
			)
		)
		(property "Device Type" "R402H16"
			(at 0.064008 -5.517896 270)
			(unlocked yes)
			(layer "F.Fab")
			(hide yes)
			(effects
				(font
					(size 1.016 1.016)
					(thickness 0.1524)
				)
			)
		)
		(duplicate_pad_numbers_are_jumpers no)
		(fp_line
			(start -0.508 -0.9398)
			(end -0.508 0.9398)
			(stroke
				(width 0.1524)
				(type default)
			)
			(layer "F.SilkS")
		)
		(fp_line
			(start 0.508 -0.9398)
			(end -0.508 -0.9398)
			(stroke
				(width 0.1524)
				(type default)
			)
			(layer "F.SilkS")
		)
		(fp_rect
			(start -0.508 0.9398)
			(end 0.508 -0.9398)
			(stroke
				(width 0)
				(type default)
			)
			(fill no)
			(layer "F.CrtYd")
		)
		(fp_rect
			(start -0.508 0.9398)
			(end 0.508 -0.9398)
			(stroke
				(width 0)
				(type default)
			)
			(fill no)
			(layer "F.Fab")
		)
		(pad "1" smd custom
			(at 0 -0.4445 270)
			(size 0.1397 0.1397)
			(layers "F.Cu" "F.Mask" "F.Paste")
			(net "P3V3_STBY")
			(options
				(clearance outline)
				(anchor circle)
			)
			(primitives
				(gr_poly
					(pts
						(arc
							(start -0.1778 -0.2794)
							(mid -0.249642 -0.249642)
							(end -0.2794 -0.1778)
						)
						(arc
							(start -0.2794 0.1778)
							(mid -0.249642 0.249642)
							(end -0.1778 0.2794)
						)
						(arc
							(start 0.1778 0.2794)
							(mid 0.249642 0.249642)
							(end 0.2794 0.1778)
						)
						(arc
							(start 0.2794 -0.1778)
							(mid 0.249642 -0.249642)
							(end 0.1778 -0.2794)
						)
					)
					(width 0)
					(fill yes)
				)
			)
		)
		(pad "2" smd custom
			(at 0 0.4445 270)
			(size 0.1397 0.1397)
			(layers "F.Cu" "F.Mask" "F.Paste")
			(net "CPU_EXP_RESET_N")
			(options
				(clearance outline)
				(anchor circle)
			)
			(primitives
				(gr_poly
					(pts
						(arc
							(start -0.1778 -0.2794)
							(mid -0.249642 -0.249642)
							(end -0.2794 -0.1778)
						)
						(arc
							(start -0.2794 0.1778)
							(mid -0.249642 0.249642)
							(end -0.1778 0.2794)
						)
						(arc
							(start 0.1778 0.2794)
							(mid 0.249642 0.249642)
							(end 0.2794 0.1778)
						)
						(arc
							(start 0.2794 -0.1778)
							(mid 0.249642 -0.249642)
							(end 0.1778 -0.2794)
						)
					)
					(width 0)
					(fill yes)
				)
			)
		)
	)
	(footprint ""
		(layer "F.Cu")
		(at 60.071 -211.074 180)
		(property "Reference" "R688"
			(at 0 0 180)
			(layer "F.SilkS")
			(hide yes)
			(effects
				(font
					(size 1.27 1.27)
				)
			)
		)
		(property "Value" "10KR2J-3-GP"
			(at 0.064008 -3.993896 180)
			(unlocked yes)
			(layer "F.Fab")
			(hide yes)
			(effects
				(font
					(size 1.016 1.016)
					(thickness 0.1524)
				)
			)
		)
		(property "Device Type" "R402H16"
			(at 0.064008 -5.517896 180)
			(unlocked yes)
			(layer "F.Fab")
			(hide yes)
			(effects
				(font
					(size 1.016 1.016)
					(thickness 0.1524)
				)
			)
		)
		(duplicate_pad_numbers_are_jumpers no)
		(fp_line
			(start 0.508 -0.9398)
			(end -0.508 -0.9398)
			(stroke
				(width 0.1524)
				(type default)
			)
			(layer "F.SilkS")
		)
		(fp_line
			(start -0.508 -0.9398)
			(end -0.508 0.9398)
			(stroke
				(width 0.1524)
				(type default)
			)
			(layer "F.SilkS")
		)
		(fp_rect
			(start -0.508 0.9398)
			(end 0.508 -0.9398)
			(stroke
				(width 0)
				(type default)
			)
			(fill no)
			(layer "F.CrtYd")
		)
		(fp_rect
			(start -0.508 0.9398)
			(end 0.508 -0.9398)
			(stroke
				(width 0)
				(type default)
			)
			(fill no)
			(layer "F.Fab")
		)
		(pad "1" smd custom
			(at 0 -0.4445 180)
			(size 0.1397 0.1397)
			(layers "F.Cu" "F.Mask" "F.Paste")
			(net "GND")
			(options
				(clearance outline)
				(anchor circle)
			)
			(primitives
				(gr_poly
					(pts
						(arc
							(start -0.1778 -0.2794)
							(mid -0.249642 -0.249642)
							(end -0.2794 -0.1778)
						)
						(arc
							(start -0.2794 0.1778)
							(mid -0.249642 0.249642)
							(end -0.1778 0.2794)
						)
						(arc
							(start 0.1778 0.2794)
							(mid 0.249642 0.249642)
							(end 0.2794 0.1778)
						)
						(arc
							(start 0.2794 -0.1778)
							(mid 0.249642 -0.249642)
							(end 0.1778 -0.2794)
						)
					)
					(width 0)
					(fill yes)
				)
			)
		)
		(pad "2" smd custom
			(at 0 0.4445 180)
			(size 0.1397 0.1397)
			(layers "F.Cu" "F.Mask" "F.Paste")
			(net "MB0_RETRY_R")
			(options
				(clearance outline)
				(anchor circle)
			)
			(primitives
				(gr_poly
					(pts
						(arc
							(start -0.1778 -0.2794)
							(mid -0.249642 -0.249642)
							(end -0.2794 -0.1778)
						)
						(arc
							(start -0.2794 0.1778)
							(mid -0.249642 0.249642)
							(end -0.1778 0.2794)
						)
						(arc
							(start 0.1778 0.2794)
							(mid 0.249642 0.249642)
							(end 0.2794 0.1778)
						)
						(arc
							(start 0.2794 -0.1778)
							(mid 0.249642 -0.249642)
							(end 0.1778 -0.2794)
						)
					)
					(width 0)
					(fill yes)
				)
			)
		)
	)
	(footprint ""
		(layer "F.Cu")
		(at 323.342 -179.705 180)
		(property "Reference" "C8086"
			(at 0 0 180)
			(layer "F.SilkS")
			(hide yes)
			(effects
				(font
					(size 1.27 1.27)
				)
			)
		)
		(property "Value" "SCD1U25V2KX-2-GP"
			(at 1.1811 -2.7051 180)
			(unlocked yes)
			(layer "F.Fab")
			(hide yes)
			(effects
				(font
					(size 1.016 1.016)
					(thickness 0.1524)
				)
			)
		)
		(property "Device Type" "C402H22"
			(at 1.1811 -4.2291 180)
			(unlocked yes)
			(layer "F.Fab")
			(hide yes)
			(effects
				(font
					(size 1.016 1.016)
					(thickness 0.1524)
				)
			)
		)
		(duplicate_pad_numbers_are_jumpers no)
		(fp_rect
			(start -0.4318 0.9525)
			(end 0.4318 -0.9525)
			(stroke
				(width 0)
				(type default)
			)
			(fill no)
			(layer "F.CrtYd")
		)
		(fp_rect
			(start -0.4318 0.9525)
			(end 0.4318 -0.9525)
			(stroke
				(width 0)
				(type default)
			)
			(fill no)
			(layer "F.Fab")
		)
		(pad "1" smd custom
			(at 0 -0.4445 180)
			(size 0.1524 0.1524)
			(layers "F.Cu" "F.Mask" "F.Paste")
			(net "ADC_P1V5_C")
			(options
				(clearance outline)
				(anchor circle)
			)
			(primitives
				(gr_poly
					(pts
						(arc
							(start 0.3048 -0.2032)
							(mid 0.275042 -0.275042)
							(end 0.2032 -0.3048)
						)
						(arc
							(start -0.2032 -0.3048)
							(mid -0.275042 -0.275042)
							(end -0.3048 -0.2032)
						)
						(arc
							(start -0.3048 0.2032)
							(mid -0.275042 0.275042)
							(end -0.2032 0.3048)
						)
						(arc
							(start 0.2032 0.3048)
							(mid 0.275042 0.275042)
							(end 0.3048 0.2032)
						)
					)
					(width 0)
					(fill yes)
				)
			)
		)
		(pad "2" smd custom
			(at 0 0.4445 180)
			(size 0.1524 0.1524)
			(layers "F.Cu" "F.Mask" "F.Paste")
			(net "GND")
			(options
				(clearance outline)
				(anchor circle)
			)
			(primitives
				(gr_poly
					(pts
						(arc
							(start 0.3048 -0.2032)
							(mid 0.275042 -0.275042)
							(end 0.2032 -0.3048)
						)
						(arc
							(start -0.2032 -0.3048)
							(mid -0.275042 -0.275042)
							(end -0.3048 -0.2032)
						)
						(arc
							(start -0.3048 0.2032)
							(mid -0.275042 0.275042)
							(end -0.2032 0.3048)
						)
						(arc
							(start 0.2032 0.3048)
							(mid 0.275042 0.275042)
							(end 0.3048 0.2032)
						)
					)
					(width 0)
					(fill yes)
				)
			)
		)
	)
	(footprint ""
		(layer "F.Cu")
		(at 348.390718 -151.869648 -90)
		(property "Reference" "R452"
			(at 0 0 270)
			(layer "F.SilkS")
			(hide yes)
			(effects
				(font
					(size 1.27 1.27)
				)
			)
		)
		(property "Value" "0R2J-2-GP"
			(at 0.064008 -3.993896 270)
			(unlocked yes)
			(layer "F.Fab")
			(hide yes)
			(effects
				(font
					(size 1.016 1.016)
					(thickness 0.1524)
				)
			)
		)
		(property "Device Type" "R402H16"
			(at 0.064008 -5.517896 270)
			(unlocked yes)
			(layer "F.Fab")
			(hide yes)
			(effects
				(font
					(size 1.016 1.016)
					(thickness 0.1524)
				)
			)
		)
		(duplicate_pad_numbers_are_jumpers no)
		(fp_line
			(start -0.508 -0.9398)
			(end -0.508 0.9398)
			(stroke
				(width 0.1524)
				(type default)
			)
			(layer "F.SilkS")
		)
		(fp_line
			(start 0.508 -0.9398)
			(end -0.508 -0.9398)
			(stroke
				(width 0.1524)
				(type default)
			)
			(layer "F.SilkS")
		)
		(fp_rect
			(start -0.508 0.9398)
			(end 0.508 -0.9398)
			(stroke
				(width 0)
				(type default)
			)
			(fill no)
			(layer "F.CrtYd")
		)
		(fp_rect
			(start -0.508 0.9398)
			(end 0.508 -0.9398)
			(stroke
				(width 0)
				(type default)
			)
			(fill no)
			(layer "F.Fab")
		)
		(pad "1" smd custom
			(at 0 -0.4445 270)
			(size 0.1397 0.1397)
			(layers "F.Cu" "F.Mask" "F.Paste")
			(net "BMC_USB1_HDN")
			(options
				(clearance outline)
				(anchor circle)
			)
			(primitives
				(gr_poly
					(pts
						(arc
							(start -0.1778 -0.2794)
							(mid -0.249642 -0.249642)
							(end -0.2794 -0.1778)
						)
						(arc
							(start -0.2794 0.1778)
							(mid -0.249642 0.249642)
							(end -0.1778 0.2794)
						)
						(arc
							(start 0.1778 0.2794)
							(mid 0.249642 0.249642)
							(end 0.2794 0.1778)
						)
						(arc
							(start 0.2794 -0.1778)
							(mid 0.249642 -0.249642)
							(end 0.1778 -0.2794)
						)
					)
					(width 0)
					(fill yes)
				)
			)
		)
		(pad "2" smd custom
			(at 0 0.4445 270)
			(size 0.1397 0.1397)
			(layers "F.Cu" "F.Mask" "F.Paste")
			(net "USB_P3_DN")
			(options
				(clearance outline)
				(anchor circle)
			)
			(primitives
				(gr_poly
					(pts
						(arc
							(start -0.1778 -0.2794)
							(mid -0.249642 -0.249642)
							(end -0.2794 -0.1778)
						)
						(arc
							(start -0.2794 0.1778)
							(mid -0.249642 0.249642)
							(end -0.1778 0.2794)
						)
						(arc
							(start 0.1778 0.2794)
							(mid 0.249642 0.249642)
							(end 0.2794 0.1778)
						)
						(arc
							(start 0.2794 -0.1778)
							(mid 0.249642 -0.249642)
							(end 0.1778 -0.2794)
						)
					)
					(width 0)
					(fill yes)
				)
			)
		)
	)
	(footprint ""
		(layer "F.Cu")
		(at 52.0446 -231.01554)
		(property "Reference" "C300"
			(at 0 0 0)
			(layer "F.SilkS")
			(hide yes)
			(effects
				(font
					(size 1.27 1.27)
				)
			)
		)
		(property "Value" "SC22U25V5MX-GP"
			(at -0.0762 -6.1214 0)
			(unlocked yes)
			(layer "F.Fab")
			(hide yes)
			(effects
				(font
					(size 1.016 1.016)
					(thickness 0.1524)
				)
			)
		)
		(property "Device Type" "C805H58"
			(at -0.0762 -8.1534 0)
			(unlocked yes)
			(layer "F.Fab")
			(hide yes)
			(effects
				(font
					(size 1.016 1.016)
					(thickness 0.1524)
				)
			)
		)
		(duplicate_pad_numbers_are_jumpers no)
		(fp_line
			(start 0.635 0)
			(end -0.635 0)
			(stroke
				(width 0.508)
				(type default)
			)
			(layer "F.SilkS")
		)
		(fp_rect
			(start -0.9652 1.778)
			(end 0.9652 -1.778)
			(stroke
				(width 0)
				(type default)
			)
			(fill no)
			(layer "F.CrtYd")
		)
		(fp_poly
			(pts
				(xy -0.9652 -1.778) (xy 0.9652 -1.778) (xy 0.9652 1.778) (xy -0.9652 1.778)
			)
			(stroke
				(width 0)
				(type default)
			)
			(fill no)
			(layer "F.Fab")
		)
		(pad "1" smd rect
			(at 0 -0.9652)
			(size 1.397 1.143)
			(layers "F.Cu" "F.Mask" "F.Paste")
			(net "P12V_PCIE")
		)
		(pad "2" smd rect
			(at 0 0.9652)
			(size 1.397 1.143)
			(layers "F.Cu" "F.Mask" "F.Paste")
			(net "GND")
		)
	)
	(footprint ""
		(layer "F.Cu")
		(at 266.754864 -228.845872 90)
		(property "Reference" "PC90"
			(at 0 0 90)
			(layer "F.SilkS")
			(hide yes)
			(effects
				(font
					(size 1.27 1.27)
				)
			)
		)
		(property "Value" "SCD1U16V2KX-3GP"
			(at 1.1811 -2.7051 90)
			(unlocked yes)
			(layer "F.Fab")
			(hide yes)
			(effects
				(font
					(size 1.016 1.016)
					(thickness 0.1524)
				)
			)
		)
		(property "Device Type" "C402H22"
			(at 1.1811 -4.2291 90)
			(unlocked yes)
			(layer "F.Fab")
			(hide yes)
			(effects
				(font
					(size 1.016 1.016)
					(thickness 0.1524)
				)
			)
		)
		(duplicate_pad_numbers_are_jumpers no)
		(fp_rect
			(start -0.4318 0.9525)
			(end 0.4318 -0.9525)
			(stroke
				(width 0)
				(type default)
			)
			(fill no)
			(layer "F.CrtYd")
		)
		(fp_rect
			(start -0.4318 0.9525)
			(end 0.4318 -0.9525)
			(stroke
				(width 0)
				(type default)
			)
			(fill no)
			(layer "F.Fab")
		)
		(pad "1" smd custom
			(at 0 -0.4445 90)
			(size 0.1524 0.1524)
			(layers "F.Cu" "F.Mask" "F.Paste")
			(net "TPS74801_P1V26_STBY_IN")
			(options
				(clearance outline)
				(anchor circle)
			)
			(primitives
				(gr_poly
					(pts
						(arc
							(start 0.3048 -0.2032)
							(mid 0.275042 -0.275042)
							(end 0.2032 -0.3048)
						)
						(arc
							(start -0.2032 -0.3048)
							(mid -0.275042 -0.275042)
							(end -0.3048 -0.2032)
						)
						(arc
							(start -0.3048 0.2032)
							(mid -0.275042 0.275042)
							(end -0.2032 0.3048)
						)
						(arc
							(start 0.2032 0.3048)
							(mid 0.275042 0.275042)
							(end 0.3048 0.2032)
						)
					)
					(width 0)
					(fill yes)
				)
			)
		)
		(pad "2" smd custom
			(at 0 0.4445 90)
			(size 0.1524 0.1524)
			(layers "F.Cu" "F.Mask" "F.Paste")
			(net "GND")
			(options
				(clearance outline)
				(anchor circle)
			)
			(primitives
				(gr_poly
					(pts
						(arc
							(start 0.3048 -0.2032)
							(mid 0.275042 -0.275042)
							(end 0.2032 -0.3048)
						)
						(arc
							(start -0.2032 -0.3048)
							(mid -0.275042 -0.275042)
							(end -0.3048 -0.2032)
						)
						(arc
							(start -0.3048 0.2032)
							(mid -0.275042 0.275042)
							(end -0.2032 0.3048)
						)
						(arc
							(start 0.2032 0.3048)
							(mid 0.275042 0.275042)
							(end 0.3048 0.2032)
						)
					)
					(width 0)
					(fill yes)
				)
			)
		)
	)
	(footprint ""
		(layer "F.Cu")
		(at 335.407 -211.455 180)
		(property "Reference" "R5304"
			(at 0 0 180)
			(layer "F.SilkS")
			(hide yes)
			(effects
				(font
					(size 1.27 1.27)
				)
			)
		)
		(property "Value" "0R2J-2-GP"
			(at 0.064008 -3.993896 180)
			(unlocked yes)
			(layer "F.Fab")
			(hide yes)
			(effects
				(font
					(size 1.016 1.016)
					(thickness 0.1524)
				)
			)
		)
		(property "Device Type" "R402H16"
			(at 0.064008 -5.517896 180)
			(unlocked yes)
			(layer "F.Fab")
			(hide yes)
			(effects
				(font
					(size 1.016 1.016)
					(thickness 0.1524)
				)
			)
		)
		(duplicate_pad_numbers_are_jumpers no)
		(fp_line
			(start 0.508 -0.9398)
			(end -0.508 -0.9398)
			(stroke
				(width 0.1524)
				(type default)
			)
			(layer "F.SilkS")
		)
		(fp_line
			(start -0.508 -0.9398)
			(end -0.508 0.9398)
			(stroke
				(width 0.1524)
				(type default)
			)
			(layer "F.SilkS")
		)
		(fp_rect
			(start -0.508 0.9398)
			(end 0.508 -0.9398)
			(stroke
				(width 0)
				(type default)
			)
			(fill no)
			(layer "F.CrtYd")
		)
		(fp_rect
			(start -0.508 0.9398)
			(end 0.508 -0.9398)
			(stroke
				(width 0)
				(type default)
			)
			(fill no)
			(layer "F.Fab")
		)
		(pad "1" smd custom
			(at 0 -0.4445 180)
			(size 0.1397 0.1397)
			(layers "F.Cu" "F.Mask" "F.Paste")
			(net "EEPROM_SDA")
			(options
				(clearance outline)
				(anchor circle)
			)
			(primitives
				(gr_poly
					(pts
						(arc
							(start -0.1778 -0.2794)
							(mid -0.249642 -0.249642)
							(end -0.2794 -0.1778)
						)
						(arc
							(start -0.2794 0.1778)
							(mid -0.249642 0.249642)
							(end -0.1778 0.2794)
						)
						(arc
							(start 0.1778 0.2794)
							(mid 0.249642 0.249642)
							(end 0.2794 0.1778)
						)
						(arc
							(start 0.2794 -0.1778)
							(mid 0.249642 -0.249642)
							(end 0.1778 -0.2794)
						)
					)
					(width 0)
					(fill yes)
				)
			)
		)
		(pad "2" smd custom
			(at 0 0.4445 180)
			(size 0.1397 0.1397)
			(layers "F.Cu" "F.Mask" "F.Paste")
			(net "BMC_I2C_SDA_10")
			(options
				(clearance outline)
				(anchor circle)
			)
			(primitives
				(gr_poly
					(pts
						(arc
							(start -0.1778 -0.2794)
							(mid -0.249642 -0.249642)
							(end -0.2794 -0.1778)
						)
						(arc
							(start -0.2794 0.1778)
							(mid -0.249642 0.249642)
							(end -0.1778 0.2794)
						)
						(arc
							(start 0.1778 0.2794)
							(mid 0.249642 0.249642)
							(end 0.2794 0.1778)
						)
						(arc
							(start 0.2794 -0.1778)
							(mid 0.249642 -0.249642)
							(end 0.1778 -0.2794)
						)
					)
					(width 0)
					(fill yes)
				)
			)
		)
	)
	(footprint ""
		(layer "F.Cu")
		(at 293.996872 -223.592136 180)
		(property "Reference" "PC84"
			(at 0 0 180)
			(layer "F.SilkS")
			(hide yes)
			(effects
				(font
					(size 1.27 1.27)
				)
			)
		)
		(property "Value" "SC10U6D3V5KX-1GP"
			(at -0.0762 -6.1214 180)
			(unlocked yes)
			(layer "F.Fab")
			(hide yes)
			(effects
				(font
					(size 1.016 1.016)
					(thickness 0.1524)
				)
			)
		)
		(property "Device Type" "C805H54"
			(at -0.0762 -8.1534 180)
			(unlocked yes)
			(layer "F.Fab")
			(hide yes)
			(effects
				(font
					(size 1.016 1.016)
					(thickness 0.1524)
				)
			)
		)
		(duplicate_pad_numbers_are_jumpers no)
		(fp_line
			(start 0.635 0)
			(end -0.635 0)
			(stroke
				(width 0.508)
				(type default)
			)
			(layer "F.SilkS")
		)
		(fp_rect
			(start -0.9652 1.778)
			(end 0.9652 -1.778)
			(stroke
				(width 0)
				(type default)
			)
			(fill no)
			(layer "F.CrtYd")
		)
		(fp_poly
			(pts
				(xy -0.9652 -1.778) (xy 0.9652 -1.778) (xy 0.9652 1.778) (xy -0.9652 1.778)
			)
			(stroke
				(width 0)
				(type default)
			)
			(fill no)
			(layer "F.Fab")
		)
		(pad "1" smd rect
			(at 0 -0.9652 180)
			(size 1.397 1.143)
			(layers "F.Cu" "F.Mask" "F.Paste")
			(net "TPS74801_1V53_STBY_OUT")
		)
		(pad "2" smd rect
			(at 0 0.9652 180)
			(size 1.397 1.143)
			(layers "F.Cu" "F.Mask" "F.Paste")
			(net "GND")
		)
	)
	(footprint ""
		(layer "F.Cu")
		(at 276.733 -104.267)
		(property "Reference" "PR177"
			(at 0 0 0)
			(layer "F.SilkS")
			(hide yes)
			(effects
				(font
					(size 1.27 1.27)
				)
			)
		)
		(property "Value" "1KR2F-3-GP"
			(at 0.064008 -3.993896 0)
			(unlocked yes)
			(layer "F.Fab")
			(hide yes)
			(effects
				(font
					(size 1.016 1.016)
					(thickness 0.1524)
				)
			)
		)
		(property "Device Type" "R402H16"
			(at 0.064008 -5.517896 0)
			(unlocked yes)
			(layer "F.Fab")
			(hide yes)
			(effects
				(font
					(size 1.016 1.016)
					(thickness 0.1524)
				)
			)
		)
		(duplicate_pad_numbers_are_jumpers no)
		(fp_line
			(start -0.508 -0.9398)
			(end -0.508 0.9398)
			(stroke
				(width 0.1524)
				(type default)
			)
			(layer "F.SilkS")
		)
		(fp_line
			(start 0.508 -0.9398)
			(end -0.508 -0.9398)
			(stroke
				(width 0.1524)
				(type default)
			)
			(layer "F.SilkS")
		)
		(fp_rect
			(start -0.508 0.9398)
			(end 0.508 -0.9398)
			(stroke
				(width 0)
				(type default)
			)
			(fill no)
			(layer "F.CrtYd")
		)
		(fp_rect
			(start -0.508 0.9398)
			(end 0.508 -0.9398)
			(stroke
				(width 0)
				(type default)
			)
			(fill no)
			(layer "F.Fab")
		)
		(pad "1" smd custom
			(at 0 -0.4445)
			(size 0.1397 0.1397)
			(layers "F.Cu" "F.Mask" "F.Paste")
			(net "P1V8_C")
			(options
				(clearance outline)
				(anchor circle)
			)
			(primitives
				(gr_poly
					(pts
						(arc
							(start -0.1778 -0.2794)
							(mid -0.249642 -0.249642)
							(end -0.2794 -0.1778)
						)
						(arc
							(start -0.2794 0.1778)
							(mid -0.249642 0.249642)
							(end -0.1778 0.2794)
						)
						(arc
							(start 0.1778 0.2794)
							(mid 0.249642 0.249642)
							(end 0.2794 0.1778)
						)
						(arc
							(start 0.2794 -0.1778)
							(mid 0.249642 -0.249642)
							(end 0.1778 -0.2794)
						)
					)
					(width 0)
					(fill yes)
				)
			)
		)
		(pad "2" smd custom
			(at 0 0.4445)
			(size 0.1397 0.1397)
			(layers "F.Cu" "F.Mask" "F.Paste")
			(net "GND")
			(options
				(clearance outline)
				(anchor circle)
			)
			(primitives
				(gr_poly
					(pts
						(arc
							(start -0.1778 -0.2794)
							(mid -0.249642 -0.249642)
							(end -0.2794 -0.1778)
						)
						(arc
							(start -0.2794 0.1778)
							(mid -0.249642 0.249642)
							(end -0.1778 0.2794)
						)
						(arc
							(start 0.1778 0.2794)
							(mid 0.249642 0.249642)
							(end 0.2794 0.1778)
						)
						(arc
							(start 0.2794 -0.1778)
							(mid 0.249642 -0.249642)
							(end 0.1778 -0.2794)
						)
					)
					(width 0)
					(fill yes)
				)
			)
		)
	)
	(footprint ""
		(layer "F.Cu")
		(at 279.6794 -183.642)
		(property "Reference" "TP150"
			(at 0 0 0)
			(layer "F.SilkS")
			(hide yes)
			(effects
				(font
					(size 1.27 1.27)
				)
			)
		)
		(property "Value" "TPAD28"
			(at 0.0127 -1.8034 0)
			(unlocked yes)
			(layer "F.Fab")
			(hide yes)
			(effects
				(font
					(size 1.016 1.016)
					(thickness 0.1524)
				)
			)
		)
		(property "Device Type" "TPAD28"
			(at 0.0127 -3.3274 0)
			(unlocked yes)
			(layer "F.Fab")
			(hide yes)
			(effects
				(font
					(size 1.016 1.016)
					(thickness 0.1524)
				)
			)
		)
		(duplicate_pad_numbers_are_jumpers no)
		(fp_poly
			(pts
				(arc
					(start 0.3556 0)
					(mid -0.3556 0)
					(end 0.3556 0)
				)
			)
			(stroke
				(width 0)
				(type default)
			)
			(fill no)
			(layer "F.CrtYd")
		)
		(fp_poly
			(pts
				(arc
					(start 0.6096 0)
					(mid -0.6096 0)
					(end 0.6096 0)
				)
			)
			(stroke
				(width 0)
				(type default)
			)
			(fill no)
			(layer "F.Fab")
		)
		(pad "1" smd circle
			(at 0 0)
			(size 0.7112 0.7112)
			(layers "F.Cu" "F.Mask" "F.Paste")
			(net "TP_BMC_GPIOR5")
		)
	)
	(footprint ""
		(layer "F.Cu")
		(at 97.282 -239.522 90)
		(property "Reference" "SC434"
			(at 0 0 90)
			(layer "F.SilkS")
			(hide yes)
			(effects
				(font
					(size 1.27 1.27)
				)
			)
		)
		(property "Value" "SC1U10V3KX-4GP-U"
			(at 0 -2.8194 90)
			(unlocked yes)
			(layer "F.Fab")
			(hide yes)
			(effects
				(font
					(size 1.016 1.016)
					(thickness 0.1524)
				)
			)
		)
		(property "Device Type" "C603H36"
			(at 0 -4.3434 90)
			(unlocked yes)
			(layer "F.Fab")
			(hide yes)
			(effects
				(font
					(size 1.016 1.016)
					(thickness 0.1524)
				)
			)
		)
		(duplicate_pad_numbers_are_jumpers no)
		(fp_line
			(start 0.508 0)
			(end -0.508 0)
			(stroke
				(width 0.2032)
				(type default)
			)
			(layer "F.SilkS")
		)
		(fp_rect
			(start -0.5842 1.3335)
			(end 0.5842 -1.3335)
			(stroke
				(width 0)
				(type default)
			)
			(fill no)
			(layer "F.CrtYd")
		)
		(fp_rect
			(start -0.5842 1.3335)
			(end 0.5842 -1.3335)
			(stroke
				(width 0)
				(type default)
			)
			(fill no)
			(layer "F.Fab")
		)
		(pad "1" smd custom
			(at 0 -0.762 90)
			(size 0.2159 0.2159)
			(layers "F.Cu" "F.Mask" "F.Paste")
			(net "GND")
			(options
				(clearance outline)
				(anchor circle)
			)
			(primitives
				(gr_poly
					(pts
						(arc
							(start -0.3302 -0.4318)
							(mid -0.402042 -0.402042)
							(end -0.4318 -0.3302)
						)
						(arc
							(start -0.4318 0.3302)
							(mid -0.402042 0.402042)
							(end -0.3302 0.4318)
						)
						(arc
							(start 0.3302 0.4318)
							(mid 0.402042 0.402042)
							(end 0.4318 0.3302)
						)
						(arc
							(start 0.4318 -0.3302)
							(mid 0.402042 -0.402042)
							(end 0.3302 -0.4318)
						)
					)
					(width 0)
					(fill yes)
				)
			)
		)
		(pad "2" smd custom
			(at 0 0.762 90)
			(size 0.2159 0.2159)
			(layers "F.Cu" "F.Mask" "F.Paste")
			(net "P3V3_STBY")
			(options
				(clearance outline)
				(anchor circle)
			)
			(primitives
				(gr_poly
					(pts
						(arc
							(start -0.3302 -0.4318)
							(mid -0.402042 -0.402042)
							(end -0.4318 -0.3302)
						)
						(arc
							(start -0.4318 0.3302)
							(mid -0.402042 0.402042)
							(end -0.3302 0.4318)
						)
						(arc
							(start 0.3302 0.4318)
							(mid 0.402042 0.402042)
							(end 0.4318 0.3302)
						)
						(arc
							(start 0.4318 -0.3302)
							(mid 0.402042 -0.402042)
							(end 0.3302 -0.4318)
						)
					)
					(width 0)
					(fill yes)
				)
			)
		)
	)
	(footprint ""
		(layer "F.Cu")
		(at 94.914212 -249.936)
		(property "Reference" "R149"
			(at 0 0 0)
			(layer "F.SilkS")
			(hide yes)
			(effects
				(font
					(size 1.27 1.27)
				)
			)
		)
		(property "Value" "0R2J-2-GP"
			(at 0.064008 -3.993896 0)
			(unlocked yes)
			(layer "F.Fab")
			(hide yes)
			(effects
				(font
					(size 1.016 1.016)
					(thickness 0.1524)
				)
			)
		)
		(property "Device Type" "R402H16"
			(at 0.064008 -5.517896 0)
			(unlocked yes)
			(layer "F.Fab")
			(hide yes)
			(effects
				(font
					(size 1.016 1.016)
					(thickness 0.1524)
				)
			)
		)
		(duplicate_pad_numbers_are_jumpers no)
		(fp_line
			(start -0.508 -0.9398)
			(end -0.508 0.9398)
			(stroke
				(width 0.1524)
				(type default)
			)
			(layer "F.SilkS")
		)
		(fp_line
			(start 0.508 -0.9398)
			(end -0.508 -0.9398)
			(stroke
				(width 0.1524)
				(type default)
			)
			(layer "F.SilkS")
		)
		(fp_rect
			(start -0.508 0.9398)
			(end 0.508 -0.9398)
			(stroke
				(width 0)
				(type default)
			)
			(fill no)
			(layer "F.CrtYd")
		)
		(fp_rect
			(start -0.508 0.9398)
			(end 0.508 -0.9398)
			(stroke
				(width 0)
				(type default)
			)
			(fill no)
			(layer "F.Fab")
		)
		(pad "1" smd custom
			(at 0 -0.4445)
			(size 0.1397 0.1397)
			(layers "F.Cu" "F.Mask" "F.Paste")
			(net "HB_INPUT")
			(options
				(clearance outline)
				(anchor circle)
			)
			(primitives
				(gr_poly
					(pts
						(arc
							(start -0.1778 -0.2794)
							(mid -0.249642 -0.249642)
							(end -0.2794 -0.1778)
						)
						(arc
							(start -0.2794 0.1778)
							(mid -0.249642 0.249642)
							(end -0.1778 0.2794)
						)
						(arc
							(start 0.1778 0.2794)
							(mid 0.249642 0.249642)
							(end 0.2794 0.1778)
						)
						(arc
							(start 0.2794 -0.1778)
							(mid 0.249642 -0.249642)
							(end 0.1778 -0.2794)
						)
					)
					(width 0)
					(fill yes)
				)
			)
		)
		(pad "2" smd custom
			(at 0 0.4445)
			(size 0.1397 0.1397)
			(layers "F.Cu" "F.Mask" "F.Paste")
			(net "HB_B_SIDE_IN")
			(options
				(clearance outline)
				(anchor circle)
			)
			(primitives
				(gr_poly
					(pts
						(arc
							(start -0.1778 -0.2794)
							(mid -0.249642 -0.249642)
							(end -0.2794 -0.1778)
						)
						(arc
							(start -0.2794 0.1778)
							(mid -0.249642 0.249642)
							(end -0.1778 0.2794)
						)
						(arc
							(start 0.1778 0.2794)
							(mid 0.249642 0.249642)
							(end 0.2794 0.1778)
						)
						(arc
							(start 0.2794 -0.1778)
							(mid 0.249642 -0.249642)
							(end 0.1778 -0.2794)
						)
					)
					(width 0)
					(fill yes)
				)
			)
		)
	)
	(footprint ""
		(layer "F.Cu")
		(at 68.326 -231.902 180)
		(property "Reference" "C7279"
			(at 0 0 180)
			(layer "F.SilkS")
			(hide yes)
			(effects
				(font
					(size 1.27 1.27)
				)
			)
		)
		(property "Value" "SCD033U50V3KX-1GP"
			(at 0 -2.8194 180)
			(unlocked yes)
			(layer "F.Fab")
			(hide yes)
			(effects
				(font
					(size 1.016 1.016)
					(thickness 0.1524)
				)
			)
		)
		(property "Device Type" "C603H36"
			(at 0 -4.3434 180)
			(unlocked yes)
			(layer "F.Fab")
			(hide yes)
			(effects
				(font
					(size 1.016 1.016)
					(thickness 0.1524)
				)
			)
		)
		(duplicate_pad_numbers_are_jumpers no)
		(fp_line
			(start 0.508 0)
			(end -0.508 0)
			(stroke
				(width 0.2032)
				(type default)
			)
			(layer "F.SilkS")
		)
		(fp_rect
			(start -0.5842 1.3335)
			(end 0.5842 -1.3335)
			(stroke
				(width 0)
				(type default)
			)
			(fill no)
			(layer "F.CrtYd")
		)
		(fp_rect
			(start -0.5842 1.3335)
			(end 0.5842 -1.3335)
			(stroke
				(width 0)
				(type default)
			)
			(fill no)
			(layer "F.Fab")
		)
		(pad "1" smd custom
			(at 0 -0.762 180)
			(size 0.2159 0.2159)
			(layers "F.Cu" "F.Mask" "F.Paste")
			(net "MB0_CM_GATE_R")
			(options
				(clearance outline)
				(anchor circle)
			)
			(primitives
				(gr_poly
					(pts
						(arc
							(start -0.3302 -0.4318)
							(mid -0.402042 -0.402042)
							(end -0.4318 -0.3302)
						)
						(arc
							(start -0.4318 0.3302)
							(mid -0.402042 0.402042)
							(end -0.3302 0.4318)
						)
						(arc
							(start 0.3302 0.4318)
							(mid 0.402042 0.402042)
							(end 0.4318 0.3302)
						)
						(arc
							(start 0.4318 -0.3302)
							(mid 0.402042 -0.402042)
							(end 0.3302 -0.4318)
						)
					)
					(width 0)
					(fill yes)
				)
			)
		)
		(pad "2" smd custom
			(at 0 0.762 180)
			(size 0.2159 0.2159)
			(layers "F.Cu" "F.Mask" "F.Paste")
			(net "GND")
			(options
				(clearance outline)
				(anchor circle)
			)
			(primitives
				(gr_poly
					(pts
						(arc
							(start -0.3302 -0.4318)
							(mid -0.402042 -0.402042)
							(end -0.4318 -0.3302)
						)
						(arc
							(start -0.4318 0.3302)
							(mid -0.402042 0.402042)
							(end -0.3302 0.4318)
						)
						(arc
							(start 0.3302 0.4318)
							(mid 0.402042 0.402042)
							(end 0.4318 0.3302)
						)
						(arc
							(start 0.4318 -0.3302)
							(mid 0.402042 -0.402042)
							(end 0.3302 -0.4318)
						)
					)
					(width 0)
					(fill yes)
				)
			)
		)
	)
	(footprint ""
		(layer "F.Cu")
		(at 152.247092 -102.518464 -90)
		(property "Reference" "SL20"
			(at 0 0 270)
			(layer "F.SilkS")
			(hide yes)
			(effects
				(font
					(size 1.27 1.27)
				)
			)
		)
		(property "Value" "MPZ2012S300AT-GP"
			(at 0 -4.2418 270)
			(unlocked yes)
			(layer "F.Fab")
			(hide yes)
			(effects
				(font
					(size 1.016 1.016)
					(thickness 0.1524)
				)
			)
		)
		(property "Device Type" "L805H42"
			(at 0 -5.7912 270)
			(unlocked yes)
			(layer "F.Fab")
			(hide yes)
			(effects
				(font
					(size 1.016 1.016)
					(thickness 0.1524)
				)
			)
		)
		(duplicate_pad_numbers_are_jumpers no)
		(fp_line
			(start -0.889 1.7018)
			(end -0.889 -1.7018)
			(stroke
				(width 0.1524)
				(type default)
			)
			(layer "F.SilkS")
		)
		(fp_line
			(start 0.889 1.7018)
			(end -0.889 1.7018)
			(stroke
				(width 0.1524)
				(type default)
			)
			(layer "F.SilkS")
		)
		(fp_line
			(start -0.889 -1.7018)
			(end 0.889 -1.7018)
			(stroke
				(width 0.1524)
				(type default)
			)
			(layer "F.SilkS")
		)
		(fp_line
			(start 0.889 -1.7018)
			(end 0.889 1.7018)
			(stroke
				(width 0.1524)
				(type default)
			)
			(layer "F.SilkS")
		)
		(fp_rect
			(start -0.9652 1.778)
			(end 0.9652 -1.778)
			(stroke
				(width 0)
				(type default)
			)
			(fill no)
			(layer "F.CrtYd")
		)
		(fp_rect
			(start -0.9652 1.778)
			(end 0.9652 -1.778)
			(stroke
				(width 0)
				(type default)
			)
			(fill no)
			(layer "F.Fab")
		)
		(pad "1" smd rect
			(at 0 -0.9652 270)
			(size 1.397 1.143)
			(layers "F.Cu" "F.Mask" "F.Paste")
			(net "P0V9_E")
		)
		(pad "2" smd rect
			(at 0 0.9652 270)
			(size 1.397 1.143)
			(layers "F.Cu" "F.Mask" "F.Paste")
			(net "GB_VDDA")
		)
	)
	(footprint ""
		(layer "F.Cu")
		(at 199.39 -224.282)
		(property "Reference" "R1584"
			(at 0 0 0)
			(layer "F.SilkS")
			(hide yes)
			(effects
				(font
					(size 1.27 1.27)
				)
			)
		)
		(property "Value" "10KR2F-2-GP"
			(at 0.064008 -3.993896 0)
			(unlocked yes)
			(layer "F.Fab")
			(hide yes)
			(effects
				(font
					(size 1.016 1.016)
					(thickness 0.1524)
				)
			)
		)
		(property "Device Type" "R402H16"
			(at 0.064008 -5.517896 0)
			(unlocked yes)
			(layer "F.Fab")
			(hide yes)
			(effects
				(font
					(size 1.016 1.016)
					(thickness 0.1524)
				)
			)
		)
		(duplicate_pad_numbers_are_jumpers no)
		(fp_line
			(start -0.508 -0.9398)
			(end -0.508 0.9398)
			(stroke
				(width 0.1524)
				(type default)
			)
			(layer "F.SilkS")
		)
		(fp_line
			(start 0.508 -0.9398)
			(end -0.508 -0.9398)
			(stroke
				(width 0.1524)
				(type default)
			)
			(layer "F.SilkS")
		)
		(fp_rect
			(start -0.508 0.9398)
			(end 0.508 -0.9398)
			(stroke
				(width 0)
				(type default)
			)
			(fill no)
			(layer "F.CrtYd")
		)
		(fp_rect
			(start -0.508 0.9398)
			(end 0.508 -0.9398)
			(stroke
				(width 0)
				(type default)
			)
			(fill no)
			(layer "F.Fab")
		)
		(pad "1" smd custom
			(at 0 -0.4445)
			(size 0.1397 0.1397)
			(layers "F.Cu" "F.Mask" "F.Paste")
			(net "P3V3_STBY")
			(options
				(clearance outline)
				(anchor circle)
			)
			(primitives
				(gr_poly
					(pts
						(arc
							(start -0.1778 -0.2794)
							(mid -0.249642 -0.249642)
							(end -0.2794 -0.1778)
						)
						(arc
							(start -0.2794 0.1778)
							(mid -0.249642 0.249642)
							(end -0.1778 0.2794)
						)
						(arc
							(start 0.1778 0.2794)
							(mid 0.249642 0.249642)
							(end 0.2794 0.1778)
						)
						(arc
							(start 0.2794 -0.1778)
							(mid 0.249642 -0.249642)
							(end 0.1778 -0.2794)
						)
					)
					(width 0)
					(fill yes)
				)
			)
		)
		(pad "2" smd custom
			(at 0 0.4445)
			(size 0.1397 0.1397)
			(layers "F.Cu" "F.Mask" "F.Paste")
			(net "RSTBTN_FP_N")
			(options
				(clearance outline)
				(anchor circle)
			)
			(primitives
				(gr_poly
					(pts
						(arc
							(start -0.1778 -0.2794)
							(mid -0.249642 -0.249642)
							(end -0.2794 -0.1778)
						)
						(arc
							(start -0.2794 0.1778)
							(mid -0.249642 0.249642)
							(end -0.1778 0.2794)
						)
						(arc
							(start 0.1778 0.2794)
							(mid 0.249642 0.249642)
							(end 0.2794 0.1778)
						)
						(arc
							(start 0.2794 -0.1778)
							(mid 0.249642 -0.249642)
							(end 0.1778 -0.2794)
						)
					)
					(width 0)
					(fill yes)
				)
			)
		)
	)
	(footprint ""
		(layer "F.Cu")
		(at 90.424 -242.443 180)
		(property "Reference" "SR955"
			(at 0 0 180)
			(layer "F.SilkS")
			(hide yes)
			(effects
				(font
					(size 1.27 1.27)
				)
			)
		)
		(property "Value" "4K7R2F-GP"
			(at 0.064008 -3.993896 180)
			(unlocked yes)
			(layer "F.Fab")
			(hide yes)
			(effects
				(font
					(size 1.016 1.016)
					(thickness 0.1524)
				)
			)
		)
		(property "Device Type" "R402H16"
			(at 0.064008 -5.517896 180)
			(unlocked yes)
			(layer "F.Fab")
			(hide yes)
			(effects
				(font
					(size 1.016 1.016)
					(thickness 0.1524)
				)
			)
		)
		(duplicate_pad_numbers_are_jumpers no)
		(fp_line
			(start 0.508 -0.9398)
			(end -0.508 -0.9398)
			(stroke
				(width 0.1524)
				(type default)
			)
			(layer "F.SilkS")
		)
		(fp_line
			(start -0.508 -0.9398)
			(end -0.508 0.9398)
			(stroke
				(width 0.1524)
				(type default)
			)
			(layer "F.SilkS")
		)
		(fp_rect
			(start -0.508 0.9398)
			(end 0.508 -0.9398)
			(stroke
				(width 0)
				(type default)
			)
			(fill no)
			(layer "F.CrtYd")
		)
		(fp_rect
			(start -0.508 0.9398)
			(end 0.508 -0.9398)
			(stroke
				(width 0)
				(type default)
			)
			(fill no)
			(layer "F.Fab")
		)
		(pad "1" smd custom
			(at 0 -0.4445 180)
			(size 0.1397 0.1397)
			(layers "F.Cu" "F.Mask" "F.Paste")
			(net "SAS_FAULT_LED14")
			(options
				(clearance outline)
				(anchor circle)
			)
			(primitives
				(gr_poly
					(pts
						(arc
							(start -0.1778 -0.2794)
							(mid -0.249642 -0.249642)
							(end -0.2794 -0.1778)
						)
						(arc
							(start -0.2794 0.1778)
							(mid -0.249642 0.249642)
							(end -0.1778 0.2794)
						)
						(arc
							(start 0.1778 0.2794)
							(mid 0.249642 0.249642)
							(end 0.2794 0.1778)
						)
						(arc
							(start 0.2794 -0.1778)
							(mid 0.249642 -0.249642)
							(end 0.1778 -0.2794)
						)
					)
					(width 0)
					(fill yes)
				)
			)
		)
		(pad "2" smd custom
			(at 0 0.4445 180)
			(size 0.1397 0.1397)
			(layers "F.Cu" "F.Mask" "F.Paste")
			(net "P3V3_STBY")
			(options
				(clearance outline)
				(anchor circle)
			)
			(primitives
				(gr_poly
					(pts
						(arc
							(start -0.1778 -0.2794)
							(mid -0.249642 -0.249642)
							(end -0.2794 -0.1778)
						)
						(arc
							(start -0.2794 0.1778)
							(mid -0.249642 0.249642)
							(end -0.1778 0.2794)
						)
						(arc
							(start 0.1778 0.2794)
							(mid 0.249642 0.249642)
							(end 0.2794 0.1778)
						)
						(arc
							(start 0.2794 -0.1778)
							(mid 0.249642 -0.249642)
							(end 0.1778 -0.2794)
						)
					)
					(width 0)
					(fill yes)
				)
			)
		)
	)
	(footprint ""
		(layer "F.Cu")
		(at 303.149 -159.131)
		(property "Reference" "TP158"
			(at 0 0 0)
			(layer "F.SilkS")
			(hide yes)
			(effects
				(font
					(size 1.27 1.27)
				)
			)
		)
		(property "Value" "TPAD28"
			(at 0.0127 -1.8034 0)
			(unlocked yes)
			(layer "F.Fab")
			(hide yes)
			(effects
				(font
					(size 1.016 1.016)
					(thickness 0.1524)
				)
			)
		)
		(property "Device Type" "TPAD28"
			(at 0.0127 -3.3274 0)
			(unlocked yes)
			(layer "F.Fab")
			(hide yes)
			(effects
				(font
					(size 1.016 1.016)
					(thickness 0.1524)
				)
			)
		)
		(duplicate_pad_numbers_are_jumpers no)
		(fp_poly
			(pts
				(arc
					(start 0.3556 0)
					(mid -0.3556 0)
					(end 0.3556 0)
				)
			)
			(stroke
				(width 0)
				(type default)
			)
			(fill no)
			(layer "F.CrtYd")
		)
		(fp_poly
			(pts
				(arc
					(start 0.6096 0)
					(mid -0.6096 0)
					(end 0.6096 0)
				)
			)
			(stroke
				(width 0)
				(type default)
			)
			(fill no)
			(layer "F.Fab")
		)
		(pad "1" smd circle
			(at 0 0)
			(size 0.7112 0.7112)
			(layers "F.Cu" "F.Mask" "F.Paste")
			(net "TP_BMC_GPIOV3")
		)
	)
	(footprint ""
		(layer "F.Cu")
		(at 195.834 -116.205)
		(property "Reference" "PC240"
			(at 0 0 0)
			(layer "F.SilkS")
			(hide yes)
			(effects
				(font
					(size 1.27 1.27)
				)
			)
		)
		(property "Value" "SC1U10V2KX-1GP"
			(at 1.1811 -2.7051 0)
			(unlocked yes)
			(layer "F.Fab")
			(hide yes)
			(effects
				(font
					(size 1.016 1.016)
					(thickness 0.1524)
				)
			)
		)
		(property "Device Type" "C402H22"
			(at 1.1811 -4.2291 0)
			(unlocked yes)
			(layer "F.Fab")
			(hide yes)
			(effects
				(font
					(size 1.016 1.016)
					(thickness 0.1524)
				)
			)
		)
		(duplicate_pad_numbers_are_jumpers no)
		(fp_rect
			(start -0.4318 0.9525)
			(end 0.4318 -0.9525)
			(stroke
				(width 0)
				(type default)
			)
			(fill no)
			(layer "F.CrtYd")
		)
		(fp_rect
			(start -0.4318 0.9525)
			(end 0.4318 -0.9525)
			(stroke
				(width 0)
				(type default)
			)
			(fill no)
			(layer "F.Fab")
		)
		(pad "1" smd custom
			(at 0 -0.4445)
			(size 0.1524 0.1524)
			(layers "F.Cu" "F.Mask" "F.Paste")
			(net "GND")
			(options
				(clearance outline)
				(anchor circle)
			)
			(primitives
				(gr_poly
					(pts
						(arc
							(start 0.3048 -0.2032)
							(mid 0.275042 -0.275042)
							(end 0.2032 -0.3048)
						)
						(arc
							(start -0.2032 -0.3048)
							(mid -0.275042 -0.275042)
							(end -0.3048 -0.2032)
						)
						(arc
							(start -0.3048 0.2032)
							(mid -0.275042 0.275042)
							(end -0.2032 0.3048)
						)
						(arc
							(start 0.2032 0.3048)
							(mid 0.275042 0.275042)
							(end 0.3048 0.2032)
						)
					)
					(width 0)
					(fill yes)
				)
			)
		)
		(pad "2" smd custom
			(at 0 0.4445)
			(size 0.1524 0.1524)
			(layers "F.Cu" "F.Mask" "F.Paste")
			(net "P1V5_E_EN_R")
			(options
				(clearance outline)
				(anchor circle)
			)
			(primitives
				(gr_poly
					(pts
						(arc
							(start 0.3048 -0.2032)
							(mid 0.275042 -0.275042)
							(end 0.2032 -0.3048)
						)
						(arc
							(start -0.2032 -0.3048)
							(mid -0.275042 -0.275042)
							(end -0.3048 -0.2032)
						)
						(arc
							(start -0.3048 0.2032)
							(mid -0.275042 0.275042)
							(end -0.2032 0.3048)
						)
						(arc
							(start 0.2032 0.3048)
							(mid 0.275042 0.275042)
							(end 0.3048 0.2032)
						)
					)
					(width 0)
					(fill yes)
				)
			)
		)
	)
	(footprint ""
		(layer "F.Cu")
		(at 25.985216 -225.73488)
		(property "Reference" "R635"
			(at 0 0 0)
			(layer "F.SilkS")
			(hide yes)
			(effects
				(font
					(size 1.27 1.27)
				)
			)
		)
		(property "Value" "4K7R2F-GP"
			(at 0.064008 -3.993896 0)
			(unlocked yes)
			(layer "F.Fab")
			(hide yes)
			(effects
				(font
					(size 1.016 1.016)
					(thickness 0.1524)
				)
			)
		)
		(property "Device Type" "R402H16"
			(at 0.064008 -5.517896 0)
			(unlocked yes)
			(layer "F.Fab")
			(hide yes)
			(effects
				(font
					(size 1.016 1.016)
					(thickness 0.1524)
				)
			)
		)
		(duplicate_pad_numbers_are_jumpers no)
		(fp_line
			(start -0.508 -0.9398)
			(end -0.508 0.9398)
			(stroke
				(width 0.1524)
				(type default)
			)
			(layer "F.SilkS")
		)
		(fp_line
			(start 0.508 -0.9398)
			(end -0.508 -0.9398)
			(stroke
				(width 0.1524)
				(type default)
			)
			(layer "F.SilkS")
		)
		(fp_rect
			(start -0.508 0.9398)
			(end 0.508 -0.9398)
			(stroke
				(width 0)
				(type default)
			)
			(fill no)
			(layer "F.CrtYd")
		)
		(fp_rect
			(start -0.508 0.9398)
			(end 0.508 -0.9398)
			(stroke
				(width 0)
				(type default)
			)
			(fill no)
			(layer "F.Fab")
		)
		(pad "1" smd custom
			(at 0 -0.4445)
			(size 0.1397 0.1397)
			(layers "F.Cu" "F.Mask" "F.Paste")
			(net "P3V3_STBY")
			(options
				(clearance outline)
				(anchor circle)
			)
			(primitives
				(gr_poly
					(pts
						(arc
							(start -0.1778 -0.2794)
							(mid -0.249642 -0.249642)
							(end -0.2794 -0.1778)
						)
						(arc
							(start -0.2794 0.1778)
							(mid -0.249642 0.249642)
							(end -0.1778 0.2794)
						)
						(arc
							(start 0.1778 0.2794)
							(mid 0.249642 0.249642)
							(end 0.2794 0.1778)
						)
						(arc
							(start 0.2794 -0.1778)
							(mid 0.249642 -0.249642)
							(end 0.1778 -0.2794)
						)
					)
					(width 0)
					(fill yes)
				)
			)
		)
		(pad "2" smd custom
			(at 0 0.4445)
			(size 0.1397 0.1397)
			(layers "F.Cu" "F.Mask" "F.Paste")
			(net "IO_EXP_HDD_PWR_A2")
			(options
				(clearance outline)
				(anchor circle)
			)
			(primitives
				(gr_poly
					(pts
						(arc
							(start -0.1778 -0.2794)
							(mid -0.249642 -0.249642)
							(end -0.2794 -0.1778)
						)
						(arc
							(start -0.2794 0.1778)
							(mid -0.249642 0.249642)
							(end -0.1778 0.2794)
						)
						(arc
							(start 0.1778 0.2794)
							(mid 0.249642 0.249642)
							(end 0.2794 0.1778)
						)
						(arc
							(start 0.2794 -0.1778)
							(mid 0.249642 -0.249642)
							(end 0.1778 -0.2794)
						)
					)
					(width 0)
					(fill yes)
				)
			)
		)
	)
	(footprint ""
		(layer "F.Cu")
		(at 94.215966 -69.342 180)
		(property "Reference" "SC1005"
			(at 0 0 180)
			(layer "F.SilkS")
			(hide yes)
			(effects
				(font
					(size 1.27 1.27)
				)
			)
		)
		(property "Value" "SCD1U16V2KX-3GP"
			(at 1.1811 -2.7051 180)
			(unlocked yes)
			(layer "F.Fab")
			(hide yes)
			(effects
				(font
					(size 1.016 1.016)
					(thickness 0.1524)
				)
			)
		)
		(property "Device Type" "C402H22"
			(at 1.1811 -4.2291 180)
			(unlocked yes)
			(layer "F.Fab")
			(hide yes)
			(effects
				(font
					(size 1.016 1.016)
					(thickness 0.1524)
				)
			)
		)
		(duplicate_pad_numbers_are_jumpers no)
		(fp_rect
			(start -0.4318 0.9525)
			(end 0.4318 -0.9525)
			(stroke
				(width 0)
				(type default)
			)
			(fill no)
			(layer "F.CrtYd")
		)
		(fp_rect
			(start -0.4318 0.9525)
			(end 0.4318 -0.9525)
			(stroke
				(width 0)
				(type default)
			)
			(fill no)
			(layer "F.Fab")
		)
		(pad "1" smd custom
			(at 0 -0.4445 180)
			(size 0.1524 0.1524)
			(layers "F.Cu" "F.Mask" "F.Paste")
			(net "P1V8_C")
			(options
				(clearance outline)
				(anchor circle)
			)
			(primitives
				(gr_poly
					(pts
						(arc
							(start 0.3048 -0.2032)
							(mid 0.275042 -0.275042)
							(end 0.2032 -0.3048)
						)
						(arc
							(start -0.2032 -0.3048)
							(mid -0.275042 -0.275042)
							(end -0.3048 -0.2032)
						)
						(arc
							(start -0.3048 0.2032)
							(mid -0.275042 0.275042)
							(end -0.2032 0.3048)
						)
						(arc
							(start 0.2032 0.3048)
							(mid 0.275042 0.275042)
							(end 0.3048 0.2032)
						)
					)
					(width 0)
					(fill yes)
				)
			)
		)
		(pad "2" smd custom
			(at 0 0.4445 180)
			(size 0.1524 0.1524)
			(layers "F.Cu" "F.Mask" "F.Paste")
			(net "GND")
			(options
				(clearance outline)
				(anchor circle)
			)
			(primitives
				(gr_poly
					(pts
						(arc
							(start 0.3048 -0.2032)
							(mid 0.275042 -0.275042)
							(end 0.2032 -0.3048)
						)
						(arc
							(start -0.2032 -0.3048)
							(mid -0.275042 -0.275042)
							(end -0.3048 -0.2032)
						)
						(arc
							(start -0.3048 0.2032)
							(mid -0.275042 0.275042)
							(end -0.2032 0.3048)
						)
						(arc
							(start 0.2032 0.3048)
							(mid 0.275042 0.275042)
							(end 0.3048 0.2032)
						)
					)
					(width 0)
					(fill yes)
				)
			)
		)
	)
	(footprint ""
		(layer "F.Cu")
		(at 182.372 -219.456 -90)
		(property "Reference" "C81"
			(at 0 0 270)
			(layer "F.SilkS")
			(hide yes)
			(effects
				(font
					(size 1.27 1.27)
				)
			)
		)
		(property "Value" "SCD1U16V2KX-3GP"
			(at 1.1811 -2.7051 270)
			(unlocked yes)
			(layer "F.Fab")
			(hide yes)
			(effects
				(font
					(size 1.016 1.016)
					(thickness 0.1524)
				)
			)
		)
		(property "Device Type" "C402H22"
			(at 1.1811 -4.2291 270)
			(unlocked yes)
			(layer "F.Fab")
			(hide yes)
			(effects
				(font
					(size 1.016 1.016)
					(thickness 0.1524)
				)
			)
		)
		(duplicate_pad_numbers_are_jumpers no)
		(fp_rect
			(start -0.4318 0.9525)
			(end 0.4318 -0.9525)
			(stroke
				(width 0)
				(type default)
			)
			(fill no)
			(layer "F.CrtYd")
		)
		(fp_rect
			(start -0.4318 0.9525)
			(end 0.4318 -0.9525)
			(stroke
				(width 0)
				(type default)
			)
			(fill no)
			(layer "F.Fab")
		)
		(pad "1" smd custom
			(at 0 -0.4445 270)
			(size 0.1524 0.1524)
			(layers "F.Cu" "F.Mask" "F.Paste")
			(net "P3V3_STBY")
			(options
				(clearance outline)
				(anchor circle)
			)
			(primitives
				(gr_poly
					(pts
						(arc
							(start 0.3048 -0.2032)
							(mid 0.275042 -0.275042)
							(end 0.2032 -0.3048)
						)
						(arc
							(start -0.2032 -0.3048)
							(mid -0.275042 -0.275042)
							(end -0.3048 -0.2032)
						)
						(arc
							(start -0.3048 0.2032)
							(mid -0.275042 0.275042)
							(end -0.2032 0.3048)
						)
						(arc
							(start 0.2032 0.3048)
							(mid 0.275042 0.275042)
							(end 0.3048 0.2032)
						)
					)
					(width 0)
					(fill yes)
				)
			)
		)
		(pad "2" smd custom
			(at 0 0.4445 270)
			(size 0.1524 0.1524)
			(layers "F.Cu" "F.Mask" "F.Paste")
			(net "GND")
			(options
				(clearance outline)
				(anchor circle)
			)
			(primitives
				(gr_poly
					(pts
						(arc
							(start 0.3048 -0.2032)
							(mid 0.275042 -0.275042)
							(end 0.2032 -0.3048)
						)
						(arc
							(start -0.2032 -0.3048)
							(mid -0.275042 -0.275042)
							(end -0.3048 -0.2032)
						)
						(arc
							(start -0.3048 0.2032)
							(mid -0.275042 0.275042)
							(end -0.2032 0.3048)
						)
						(arc
							(start 0.2032 0.3048)
							(mid 0.275042 0.275042)
							(end 0.3048 0.2032)
						)
					)
					(width 0)
					(fill yes)
				)
			)
		)
	)
	(footprint ""
		(layer "F.Cu")
		(at 86.976966 -88.011 180)
		(property "Reference" "SC1148"
			(at 0 0 180)
			(layer "F.SilkS")
			(hide yes)
			(effects
				(font
					(size 1.27 1.27)
				)
			)
		)
		(property "Value" "SC1U6D3V1MX-GP"
			(at 1.9177 2.0193 180)
			(unlocked yes)
			(layer "F.Fab")
			(hide yes)
			(effects
				(font
					(size 1.016 1.016)
					(thickness 0.1524)
				)
			)
		)
		(property "Device Type" "C0201H14"
			(at 1.9177 0.4953 180)
			(unlocked yes)
			(layer "F.Fab")
			(hide yes)
			(effects
				(font
					(size 1.016 1.016)
					(thickness 0.1524)
				)
			)
		)
		(duplicate_pad_numbers_are_jumpers no)
		(fp_rect
			(start -0.1524 0.3048)
			(end 0.1524 -0.3048)
			(stroke
				(width 0)
				(type default)
			)
			(fill no)
			(layer "F.CrtYd")
		)
		(fp_poly
			(pts
				(xy -0.2794 0.6477) (xy -0.2794 -0.6477) (xy 0.2794 -0.6477) (xy 0.2794 -0.1905) (xy 0.1524 -0.1905)
				(xy 0.1524 -0.3048) (xy -0.1524 -0.3048) (xy -0.1524 0.3048) (xy 0.1524 0.3048) (xy 0.1524 -0.1778)
				(xy 0.2794 -0.1778) (xy 0.2794 0.6477)
			)
			(stroke
				(width 0)
				(type default)
			)
			(fill no)
			(layer "F.CrtYd")
		)
		(fp_rect
			(start -0.2794 0.6477)
			(end 0.2794 -0.6477)
			(stroke
				(width 0)
				(type default)
			)
			(fill no)
			(layer "F.Fab")
		)
		(pad "1" smd custom
			(at 0 -0.2794 180)
			(size 0.0762 0.0762)
			(layers "F.Cu" "F.Mask" "F.Paste")
			(net "SYSPLL_VDDA18")
			(options
				(clearance outline)
				(anchor circle)
			)
			(primitives
				(gr_poly
					(pts
						(arc
							(start 0.1524 -0.127)
							(mid 0.137521 -0.162921)
							(end 0.1016 -0.1778)
						)
						(arc
							(start -0.1016 -0.1778)
							(mid -0.137521 -0.162921)
							(end -0.1524 -0.127)
						)
						(arc
							(start -0.1524 0.127)
							(mid -0.137521 0.162921)
							(end -0.1016 0.1778)
						)
						(arc
							(start 0.1016 0.1778)
							(mid 0.137521 0.162921)
							(end 0.1524 0.127)
						)
					)
					(width 0)
					(fill yes)
				)
			)
		)
		(pad "2" smd custom
			(at 0 0.2794 180)
			(size 0.0762 0.0762)
			(layers "F.Cu" "F.Mask" "F.Paste")
			(net "GND")
			(options
				(clearance outline)
				(anchor circle)
			)
			(primitives
				(gr_poly
					(pts
						(arc
							(start 0.1524 -0.127)
							(mid 0.137521 -0.162921)
							(end 0.1016 -0.1778)
						)
						(arc
							(start -0.1016 -0.1778)
							(mid -0.137521 -0.162921)
							(end -0.1524 -0.127)
						)
						(arc
							(start -0.1524 0.127)
							(mid -0.137521 0.162921)
							(end -0.1016 0.1778)
						)
						(arc
							(start 0.1016 0.1778)
							(mid 0.137521 0.162921)
							(end 0.1524 0.127)
						)
					)
					(width 0)
					(fill yes)
				)
			)
		)
	)
	(footprint ""
		(layer "F.Cu")
		(at 110.50397 -73.8124 90)
		(property "Reference" "SLED27"
			(at 0 0 90)
			(layer "F.SilkS")
			(hide yes)
			(effects
				(font
					(size 1.27 1.27)
				)
			)
		)
		(property "Value" "LED-YG-51-GP"
			(at -2.6924 -1.4224 90)
			(unlocked yes)
			(layer "F.Fab")
			(hide yes)
			(effects
				(font
					(size 1.016 1.016)
					(thickness 0.1524)
				)
			)
		)
		(property "Device Type" "LED1608AKH40"
			(at -2.6924 -2.9464 90)
			(unlocked yes)
			(layer "F.Fab")
			(hide yes)
			(effects
				(font
					(size 1.016 1.016)
					(thickness 0.1524)
				)
			)
		)
		(duplicate_pad_numbers_are_jumpers no)
		(fp_line
			(start 0.6604 -1.3716)
			(end 0.6604 1.3716)
			(stroke
				(width 0.1524)
				(type default)
			)
			(layer "F.SilkS")
		)
		(fp_line
			(start -0.6604 -1.3716)
			(end 0.6604 -1.3716)
			(stroke
				(width 0.1524)
				(type default)
			)
			(layer "F.SilkS")
		)
		(fp_line
			(start 0.6604 1.3716)
			(end -0.6604 1.3716)
			(stroke
				(width 0.1524)
				(type default)
			)
			(layer "F.SilkS")
		)
		(fp_line
			(start -0.6604 1.3716)
			(end -0.6604 -1.3716)
			(stroke
				(width 0.1524)
				(type default)
			)
			(layer "F.SilkS")
		)
		(fp_line
			(start -0.5969 1.5494)
			(end 0.5842 1.5494)
			(stroke
				(width 0.508)
				(type default)
			)
			(layer "F.SilkS")
		)
		(fp_line
			(start 0.7493 1.651)
			(end 0.7493 1.1811)
			(stroke
				(width 0.3302)
				(type default)
			)
			(layer "F.SilkS")
		)
		(fp_line
			(start -0.7493 1.651)
			(end -0.7493 1.1811)
			(stroke
				(width 0.3302)
				(type default)
			)
			(layer "F.SilkS")
		)
		(fp_rect
			(start -0.6223 1.3335)
			(end 0.6223 -1.3335)
			(stroke
				(width 0)
				(type default)
			)
			(fill no)
			(layer "F.CrtYd")
		)
		(fp_rect
			(start -0.6223 1.3335)
			(end 0.6223 -1.3335)
			(stroke
				(width 0)
				(type default)
			)
			(fill no)
			(layer "F.Fab")
		)
		(pad "A" smd custom
			(at 0 -0.762 90)
			(size 0.2159 0.2159)
			(layers "F.Cu" "F.Mask" "F.Paste")
			(net "EXP_HW_LED_R")
			(options
				(clearance outline)
				(anchor circle)
			)
			(primitives
				(gr_poly
					(pts
						(arc
							(start -0.3302 -0.4318)
							(mid -0.402042 -0.402042)
							(end -0.4318 -0.3302)
						)
						(arc
							(start -0.4318 0.3302)
							(mid -0.402042 0.402042)
							(end -0.3302 0.4318)
						)
						(arc
							(start 0.3302 0.4318)
							(mid 0.402042 0.402042)
							(end 0.4318 0.3302)
						)
						(arc
							(start 0.4318 -0.3302)
							(mid 0.402042 -0.402042)
							(end 0.3302 -0.4318)
						)
					)
					(width 0)
					(fill yes)
				)
			)
		)
		(pad "K" smd custom
			(at 0 0.762 90)
			(size 0.2159 0.2159)
			(layers "F.Cu" "F.Mask" "F.Paste")
			(net "EXP_HW_LED_D")
			(options
				(clearance outline)
				(anchor circle)
			)
			(primitives
				(gr_poly
					(pts
						(arc
							(start -0.3302 -0.4318)
							(mid -0.402042 -0.402042)
							(end -0.4318 -0.3302)
						)
						(arc
							(start -0.4318 0.3302)
							(mid -0.402042 0.402042)
							(end -0.3302 0.4318)
						)
						(arc
							(start 0.3302 0.4318)
							(mid 0.402042 0.402042)
							(end 0.4318 0.3302)
						)
						(arc
							(start 0.4318 -0.3302)
							(mid 0.402042 -0.402042)
							(end 0.3302 -0.4318)
						)
					)
					(width 0)
					(fill yes)
				)
			)
		)
	)
	(footprint ""
		(layer "F.Cu")
		(at 255.016 -17.653 90)
		(property "Reference" "L7"
			(at 0 0 90)
			(layer "F.SilkS")
			(hide yes)
			(effects
				(font
					(size 1.27 1.27)
				)
			)
		)
		(property "Value" "BLM21PG300SN-2GP"
			(at 0.0254 -5.6896 90)
			(unlocked yes)
			(layer "F.Fab")
			(hide yes)
			(effects
				(font
					(size 1.016 1.016)
					(thickness 0.1524)
				)
			)
		)
		(property "Device Type" "L20125H42"
			(at 0.0254 -7.5946 90)
			(unlocked yes)
			(layer "F.Fab")
			(hide yes)
			(effects
				(font
					(size 1.016 1.016)
					(thickness 0.1524)
				)
			)
		)
		(duplicate_pad_numbers_are_jumpers no)
		(fp_line
			(start 0.9144 -1.7018)
			(end -0.9144 -1.7018)
			(stroke
				(width 0.1524)
				(type default)
			)
			(layer "F.SilkS")
		)
		(fp_line
			(start -0.9144 -1.7018)
			(end -0.9144 1.7018)
			(stroke
				(width 0.1524)
				(type default)
			)
			(layer "F.SilkS")
		)
		(fp_line
			(start 0.9144 1.7018)
			(end 0.9144 -1.7018)
			(stroke
				(width 0.1524)
				(type default)
			)
			(layer "F.SilkS")
		)
		(fp_line
			(start -0.9144 1.7018)
			(end 0.9144 1.7018)
			(stroke
				(width 0.1524)
				(type default)
			)
			(layer "F.SilkS")
		)
		(fp_rect
			(start -1.0033 1.778)
			(end 1.0033 -1.778)
			(stroke
				(width 0)
				(type default)
			)
			(fill no)
			(layer "F.CrtYd")
		)
		(fp_poly
			(pts
				(xy -1.0033 -1.778) (xy 1.0033 -1.778) (xy 1.0033 1.778) (xy -1.0033 1.778)
			)
			(stroke
				(width 0)
				(type default)
			)
			(fill no)
			(layer "F.Fab")
		)
		(pad "1" smd rect
			(at 0 -0.9652 90)
			(size 1.397 1.143)
			(layers "F.Cu" "F.Mask" "F.Paste")
			(net "P5V_STBY")
		)
		(pad "2" smd rect
			(at 0 0.9652 90)
			(size 1.397 1.143)
			(layers "F.Cu" "F.Mask" "F.Paste")
			(net "P5V_USB_BP1_F")
		)
	)
	(footprint ""
		(layer "F.Cu")
		(at 332.36154 -13.903198 -90)
		(property "Reference" "Q21"
			(at 0 0 270)
			(layer "F.SilkS")
			(hide yes)
			(effects
				(font
					(size 1.27 1.27)
				)
			)
		)
		(property "Value" "2N7002A-7-GP"
			(at 0.127 -8.9662 270)
			(unlocked yes)
			(layer "F.Fab")
			(hide yes)
			(effects
				(font
					(size 1.016 1.016)
					(thickness 0.1524)
				)
			)
		)
		(property "Device Type" "SOT23DGS2D4H48"
			(at 0.127 -10.4902 270)
			(unlocked yes)
			(layer "F.Fab")
			(hide yes)
			(effects
				(font
					(size 1.016 1.016)
					(thickness 0.1524)
				)
			)
		)
		(duplicate_pad_numbers_are_jumpers no)
		(fp_line
			(start -1.651 1.778)
			(end 1.651 1.778)
			(stroke
				(width 0.1524)
				(type default)
			)
			(layer "F.SilkS")
		)
		(fp_line
			(start 1.651 1.778)
			(end 1.651 -1.778)
			(stroke
				(width 0.1524)
				(type default)
			)
			(layer "F.SilkS")
		)
		(fp_line
			(start -1.651 -1.778)
			(end -1.651 1.778)
			(stroke
				(width 0.1524)
				(type default)
			)
			(layer "F.SilkS")
		)
		(fp_line
			(start 1.651 -1.778)
			(end -1.651 -1.778)
			(stroke
				(width 0.1524)
				(type default)
			)
			(layer "F.SilkS")
		)
		(fp_poly
			(pts
				(xy -1.778 1.8796) (xy -1.778 -1.8796) (xy 1.778 -1.8796) (xy 1.778 1.8796)
			)
			(stroke
				(width 0)
				(type default)
			)
			(fill no)
			(layer "F.CrtYd")
		)
		(fp_poly
			(pts
				(xy -1.778 1.8796) (xy -1.778 -1.8796) (xy 1.778 -1.8796) (xy 1.778 1.8796)
			)
			(stroke
				(width 0)
				(type default)
			)
			(fill no)
			(layer "F.Fab")
		)
		(pad "D" smd custom
			(at 0 -0.9525 270)
			(size 0.1905 0.1905)
			(layers "F.Cu" "F.Mask" "F.Paste")
			(net "EXP_BMC_HB_LED_D")
			(options
				(clearance outline)
				(anchor circle)
			)
			(primitives
				(gr_poly
					(pts
						(arc
							(start -0.1778 0.5715)
							(mid -0.321484 0.511984)
							(end -0.381 0.3683)
						)
						(arc
							(start -0.381 -0.3683)
							(mid -0.321484 -0.511984)
							(end -0.1778 -0.5715)
						)
						(arc
							(start 0.1778 -0.5715)
							(mid 0.321484 -0.511984)
							(end 0.381 -0.3683)
						)
						(arc
							(start 0.381 0.3683)
							(mid 0.321484 0.511984)
							(end 0.1778 0.5715)
						)
					)
					(width 0)
					(fill yes)
				)
			)
		)
		(pad "G" smd custom
			(at -0.98425 0.9525 270)
			(size 0.1905 0.1905)
			(layers "F.Cu" "F.Mask" "F.Paste")
			(net "HB_OUT")
			(options
				(clearance outline)
				(anchor circle)
			)
			(primitives
				(gr_poly
					(pts
						(arc
							(start -0.1778 0.5715)
							(mid -0.321484 0.511984)
							(end -0.381 0.3683)
						)
						(arc
							(start -0.381 -0.3683)
							(mid -0.321484 -0.511984)
							(end -0.1778 -0.5715)
						)
						(arc
							(start 0.1778 -0.5715)
							(mid 0.321484 -0.511984)
							(end 0.381 -0.3683)
						)
						(arc
							(start 0.381 0.3683)
							(mid 0.321484 0.511984)
							(end 0.1778 0.5715)
						)
					)
					(width 0)
					(fill yes)
				)
			)
		)
		(pad "S" smd custom
			(at 0.98425 0.9525 270)
			(size 0.1905 0.1905)
			(layers "F.Cu" "F.Mask" "F.Paste")
			(net "GND")
			(options
				(clearance outline)
				(anchor circle)
			)
			(primitives
				(gr_poly
					(pts
						(arc
							(start -0.1778 0.5715)
							(mid -0.321484 0.511984)
							(end -0.381 0.3683)
						)
						(arc
							(start -0.381 -0.3683)
							(mid -0.321484 -0.511984)
							(end -0.1778 -0.5715)
						)
						(arc
							(start 0.1778 -0.5715)
							(mid 0.321484 -0.511984)
							(end 0.381 -0.3683)
						)
						(arc
							(start 0.381 0.3683)
							(mid 0.321484 0.511984)
							(end 0.1778 0.5715)
						)
					)
					(width 0)
					(fill yes)
				)
			)
		)
	)
	(footprint ""
		(layer "F.Cu")
		(at 174.941992 -31.115 -90)
		(property "Reference" "C234"
			(at 0 0 270)
			(layer "F.SilkS")
			(hide yes)
			(effects
				(font
					(size 1.27 1.27)
				)
			)
		)
		(property "Value" "SC27P50V2JN-2DLGP"
			(at 1.1811 -2.7051 270)
			(unlocked yes)
			(layer "F.Fab")
			(hide yes)
			(effects
				(font
					(size 1.016 1.016)
					(thickness 0.1524)
				)
			)
		)
		(property "Device Type" "C402H22"
			(at 1.1811 -4.2291 270)
			(unlocked yes)
			(layer "F.Fab")
			(hide yes)
			(effects
				(font
					(size 1.016 1.016)
					(thickness 0.1524)
				)
			)
		)
		(duplicate_pad_numbers_are_jumpers no)
		(fp_rect
			(start -0.4318 0.9525)
			(end 0.4318 -0.9525)
			(stroke
				(width 0)
				(type default)
			)
			(fill no)
			(layer "F.CrtYd")
		)
		(fp_rect
			(start -0.4318 0.9525)
			(end 0.4318 -0.9525)
			(stroke
				(width 0)
				(type default)
			)
			(fill no)
			(layer "F.Fab")
		)
		(pad "1" smd custom
			(at 0 -0.4445 270)
			(size 0.1524 0.1524)
			(layers "F.Cu" "F.Mask" "F.Paste")
			(net "BCM5221_RX_C_DN")
			(options
				(clearance outline)
				(anchor circle)
			)
			(primitives
				(gr_poly
					(pts
						(arc
							(start 0.3048 -0.2032)
							(mid 0.275042 -0.275042)
							(end 0.2032 -0.3048)
						)
						(arc
							(start -0.2032 -0.3048)
							(mid -0.275042 -0.275042)
							(end -0.3048 -0.2032)
						)
						(arc
							(start -0.3048 0.2032)
							(mid -0.275042 0.275042)
							(end -0.2032 0.3048)
						)
						(arc
							(start 0.2032 0.3048)
							(mid 0.275042 0.275042)
							(end 0.3048 0.2032)
						)
					)
					(width 0)
					(fill yes)
				)
			)
		)
		(pad "2" smd custom
			(at 0 0.4445 270)
			(size 0.1524 0.1524)
			(layers "F.Cu" "F.Mask" "F.Paste")
			(net "BCM5221_RX_C_DP")
			(options
				(clearance outline)
				(anchor circle)
			)
			(primitives
				(gr_poly
					(pts
						(arc
							(start 0.3048 -0.2032)
							(mid 0.275042 -0.275042)
							(end 0.2032 -0.3048)
						)
						(arc
							(start -0.2032 -0.3048)
							(mid -0.275042 -0.275042)
							(end -0.3048 -0.2032)
						)
						(arc
							(start -0.3048 0.2032)
							(mid -0.275042 0.275042)
							(end -0.2032 0.3048)
						)
						(arc
							(start 0.2032 0.3048)
							(mid 0.275042 0.275042)
							(end 0.3048 0.2032)
						)
					)
					(width 0)
					(fill yes)
				)
			)
		)
	)
	(footprint ""
		(layer "F.Cu")
		(at 135.14197 -98.806 180)
		(property "Reference" "SC1268"
			(at 0 0 180)
			(layer "F.SilkS")
			(hide yes)
			(effects
				(font
					(size 1.27 1.27)
				)
			)
		)
		(property "Value" "SCD01U10V1KX-GP"
			(at -2.8321 -1.7399 180)
			(unlocked yes)
			(layer "F.Fab")
			(hide yes)
			(effects
				(font
					(size 1.016 1.016)
					(thickness 0.1524)
				)
			)
		)
		(property "Device Type" "C0201H13"
			(at -2.8321 -3.2639 180)
			(unlocked yes)
			(layer "F.Fab")
			(hide yes)
			(effects
				(font
					(size 1.016 1.016)
					(thickness 0.1524)
				)
			)
		)
		(duplicate_pad_numbers_are_jumpers no)
		(fp_rect
			(start -0.2794 0.6477)
			(end 0.2794 -0.6477)
			(stroke
				(width 0)
				(type default)
			)
			(fill no)
			(layer "F.CrtYd")
		)
		(fp_rect
			(start -0.2794 0.6477)
			(end 0.2794 -0.6477)
			(stroke
				(width 0)
				(type default)
			)
			(fill no)
			(layer "F.Fab")
		)
		(pad "1" smd custom
			(at 0 -0.2794 180)
			(size 0.0762 0.0762)
			(layers "F.Cu" "F.Mask" "F.Paste")
			(net "3X24_SAS_TX21_P")
			(options
				(clearance outline)
				(anchor circle)
			)
			(primitives
				(gr_poly
					(pts
						(arc
							(start 0.1524 -0.127)
							(mid 0.137521 -0.162921)
							(end 0.1016 -0.1778)
						)
						(arc
							(start -0.1016 -0.1778)
							(mid -0.137521 -0.162921)
							(end -0.1524 -0.127)
						)
						(arc
							(start -0.1524 0.127)
							(mid -0.137521 0.162921)
							(end -0.1016 0.1778)
						)
						(arc
							(start 0.1016 0.1778)
							(mid 0.137521 0.162921)
							(end 0.1524 0.127)
						)
					)
					(width 0)
					(fill yes)
				)
			)
		)
		(pad "2" smd custom
			(at 0 0.2794 180)
			(size 0.0762 0.0762)
			(layers "F.Cu" "F.Mask" "F.Paste")
			(net "SAS_EXP_GF_TX_DP1")
			(options
				(clearance outline)
				(anchor circle)
			)
			(primitives
				(gr_poly
					(pts
						(arc
							(start 0.1524 -0.127)
							(mid 0.137521 -0.162921)
							(end 0.1016 -0.1778)
						)
						(arc
							(start -0.1016 -0.1778)
							(mid -0.137521 -0.162921)
							(end -0.1524 -0.127)
						)
						(arc
							(start -0.1524 0.127)
							(mid -0.137521 0.162921)
							(end -0.1016 0.1778)
						)
						(arc
							(start 0.1016 0.1778)
							(mid 0.137521 0.162921)
							(end 0.1524 0.127)
						)
					)
					(width 0)
					(fill yes)
				)
			)
		)
	)
	(footprint ""
		(layer "F.Cu")
		(at 96.647 -4.191)
		(property "Reference" "SC1047"
			(at 0 0 0)
			(layer "F.SilkS")
			(hide yes)
			(effects
				(font
					(size 1.27 1.27)
				)
			)
		)
		(property "Value" "SCD1U16V2KX-3GP"
			(at 1.1811 -2.7051 0)
			(unlocked yes)
			(layer "F.Fab")
			(hide yes)
			(effects
				(font
					(size 1.016 1.016)
					(thickness 0.1524)
				)
			)
		)
		(property "Device Type" "C402H22"
			(at 1.1811 -4.2291 0)
			(unlocked yes)
			(layer "F.Fab")
			(hide yes)
			(effects
				(font
					(size 1.016 1.016)
					(thickness 0.1524)
				)
			)
		)
		(duplicate_pad_numbers_are_jumpers no)
		(fp_rect
			(start -0.4318 0.9525)
			(end 0.4318 -0.9525)
			(stroke
				(width 0)
				(type default)
			)
			(fill no)
			(layer "F.CrtYd")
		)
		(fp_rect
			(start -0.4318 0.9525)
			(end 0.4318 -0.9525)
			(stroke
				(width 0)
				(type default)
			)
			(fill no)
			(layer "F.Fab")
		)
		(pad "1" smd custom
			(at 0 -0.4445)
			(size 0.1524 0.1524)
			(layers "F.Cu" "F.Mask" "F.Paste")
			(net "P0V955_C")
			(options
				(clearance outline)
				(anchor circle)
			)
			(primitives
				(gr_poly
					(pts
						(arc
							(start 0.3048 -0.2032)
							(mid 0.275042 -0.275042)
							(end 0.2032 -0.3048)
						)
						(arc
							(start -0.2032 -0.3048)
							(mid -0.275042 -0.275042)
							(end -0.3048 -0.2032)
						)
						(arc
							(start -0.3048 0.2032)
							(mid -0.275042 0.275042)
							(end -0.2032 0.3048)
						)
						(arc
							(start 0.2032 0.3048)
							(mid 0.275042 0.275042)
							(end 0.3048 0.2032)
						)
					)
					(width 0)
					(fill yes)
				)
			)
		)
		(pad "2" smd custom
			(at 0 0.4445)
			(size 0.1524 0.1524)
			(layers "F.Cu" "F.Mask" "F.Paste")
			(net "GND")
			(options
				(clearance outline)
				(anchor circle)
			)
			(primitives
				(gr_poly
					(pts
						(arc
							(start 0.3048 -0.2032)
							(mid 0.275042 -0.275042)
							(end 0.2032 -0.3048)
						)
						(arc
							(start -0.2032 -0.3048)
							(mid -0.275042 -0.275042)
							(end -0.3048 -0.2032)
						)
						(arc
							(start -0.3048 0.2032)
							(mid -0.275042 0.275042)
							(end -0.2032 0.3048)
						)
						(arc
							(start 0.2032 0.3048)
							(mid 0.275042 0.275042)
							(end 0.3048 0.2032)
						)
					)
					(width 0)
					(fill yes)
				)
			)
		)
	)
	(footprint ""
		(layer "F.Cu")
		(at 105.93197 -114.3 180)
		(property "Reference" "SC1085"
			(at 0 0 180)
			(layer "F.SilkS")
			(hide yes)
			(effects
				(font
					(size 1.27 1.27)
				)
			)
		)
		(property "Value" "SCD01U10V1KX-GP"
			(at -2.8321 -1.7399 180)
			(unlocked yes)
			(layer "F.Fab")
			(hide yes)
			(effects
				(font
					(size 1.016 1.016)
					(thickness 0.1524)
				)
			)
		)
		(property "Device Type" "C0201H13"
			(at -2.8321 -3.2639 180)
			(unlocked yes)
			(layer "F.Fab")
			(hide yes)
			(effects
				(font
					(size 1.016 1.016)
					(thickness 0.1524)
				)
			)
		)
		(duplicate_pad_numbers_are_jumpers no)
		(fp_rect
			(start -0.2794 0.6477)
			(end 0.2794 -0.6477)
			(stroke
				(width 0)
				(type default)
			)
			(fill no)
			(layer "F.CrtYd")
		)
		(fp_rect
			(start -0.2794 0.6477)
			(end 0.2794 -0.6477)
			(stroke
				(width 0)
				(type default)
			)
			(fill no)
			(layer "F.Fab")
		)
		(pad "1" smd custom
			(at 0 -0.2794 180)
			(size 0.0762 0.0762)
			(layers "F.Cu" "F.Mask" "F.Paste")
			(net "SAS_HDD_TX9_P")
			(options
				(clearance outline)
				(anchor circle)
			)
			(primitives
				(gr_poly
					(pts
						(arc
							(start 0.1524 -0.127)
							(mid 0.137521 -0.162921)
							(end 0.1016 -0.1778)
						)
						(arc
							(start -0.1016 -0.1778)
							(mid -0.137521 -0.162921)
							(end -0.1524 -0.127)
						)
						(arc
							(start -0.1524 0.127)
							(mid -0.137521 0.162921)
							(end -0.1016 0.1778)
						)
						(arc
							(start 0.1016 0.1778)
							(mid 0.137521 0.162921)
							(end 0.1524 0.127)
						)
					)
					(width 0)
					(fill yes)
				)
			)
		)
		(pad "2" smd custom
			(at 0 0.2794 180)
			(size 0.0762 0.0762)
			(layers "F.Cu" "F.Mask" "F.Paste")
			(net "SAS_EXP_GF_TX_DP13")
			(options
				(clearance outline)
				(anchor circle)
			)
			(primitives
				(gr_poly
					(pts
						(arc
							(start 0.1524 -0.127)
							(mid 0.137521 -0.162921)
							(end 0.1016 -0.1778)
						)
						(arc
							(start -0.1016 -0.1778)
							(mid -0.137521 -0.162921)
							(end -0.1524 -0.127)
						)
						(arc
							(start -0.1524 0.127)
							(mid -0.137521 0.162921)
							(end -0.1016 0.1778)
						)
						(arc
							(start 0.1016 0.1778)
							(mid 0.137521 0.162921)
							(end 0.1524 0.127)
						)
					)
					(width 0)
					(fill yes)
				)
			)
		)
	)
	(footprint ""
		(layer "F.Cu")
		(at 94.107 -14.097 90)
		(property "Reference" "SC945"
			(at 0 0 90)
			(layer "F.SilkS")
			(hide yes)
			(effects
				(font
					(size 1.27 1.27)
				)
			)
		)
		(property "Value" "SC100U6D3V0MX-2GP"
			(at -0.00254 -4.78536 90)
			(unlocked yes)
			(layer "F.Fab")
			(hide yes)
			(effects
				(font
					(size 1.016 1.016)
					(thickness 0.1524)
				)
			)
		)
		(property "Device Type" "C1210H107"
			(at -0.00254 -6.38048 90)
			(unlocked yes)
			(layer "F.Fab")
			(hide yes)
			(effects
				(font
					(size 1.016 1.016)
					(thickness 0.1524)
				)
			)
		)
		(duplicate_pad_numbers_are_jumpers no)
		(fp_line
			(start 1.5748 -2.3368)
			(end -1.5748 -2.3368)
			(stroke
				(width 0.1524)
				(type default)
			)
			(layer "F.SilkS")
		)
		(fp_line
			(start -1.5748 -2.3368)
			(end -1.5748 -0.762)
			(stroke
				(width 0.1524)
				(type default)
			)
			(layer "F.SilkS")
		)
		(fp_line
			(start 1.5748 -0.762)
			(end 1.5748 -2.3368)
			(stroke
				(width 0.1524)
				(type default)
			)
			(layer "F.SilkS")
		)
		(fp_line
			(start -1.5748 0.762)
			(end -1.5748 2.3368)
			(stroke
				(width 0.1524)
				(type default)
			)
			(layer "F.SilkS")
		)
		(fp_line
			(start 1.5748 2.3368)
			(end 1.5748 0.762)
			(stroke
				(width 0.1524)
				(type default)
			)
			(layer "F.SilkS")
		)
		(fp_line
			(start -1.5748 2.3368)
			(end 1.5748 2.3368)
			(stroke
				(width 0.1524)
				(type default)
			)
			(layer "F.SilkS")
		)
		(fp_rect
			(start -1.651 2.413)
			(end 1.651 -2.413)
			(stroke
				(width 0)
				(type default)
			)
			(fill no)
			(layer "F.CrtYd")
		)
		(fp_poly
			(pts
				(xy 1.651 2.413) (xy 1.651 -2.413) (xy -1.651 -2.413) (xy -1.651 2.413)
			)
			(stroke
				(width 0)
				(type default)
			)
			(fill no)
			(layer "F.Fab")
		)
		(pad "1" smd rect
			(at 0 -1.4732 90)
			(size 2.794 1.397)
			(layers "F.Cu" "F.Mask" "F.Paste")
			(net "GND")
		)
		(pad "2" smd rect
			(at 0 1.4732 90)
			(size 2.794 1.397)
			(layers "F.Cu" "F.Mask" "F.Paste")
			(net "PCE_AVDD")
		)
	)
	(footprint ""
		(layer "F.Cu")
		(at 318.008 -169.418 -90)
		(property "Reference" "R461"
			(at 0 0 270)
			(layer "F.SilkS")
			(hide yes)
			(effects
				(font
					(size 1.27 1.27)
				)
			)
		)
		(property "Value" "0R2J-2-GP"
			(at 0.064008 -3.993896 270)
			(unlocked yes)
			(layer "F.Fab")
			(hide yes)
			(effects
				(font
					(size 1.016 1.016)
					(thickness 0.1524)
				)
			)
		)
		(property "Device Type" "R402H16"
			(at 0.064008 -5.517896 270)
			(unlocked yes)
			(layer "F.Fab")
			(hide yes)
			(effects
				(font
					(size 1.016 1.016)
					(thickness 0.1524)
				)
			)
		)
		(duplicate_pad_numbers_are_jumpers no)
		(fp_line
			(start -0.508 -0.9398)
			(end -0.508 0.9398)
			(stroke
				(width 0.1524)
				(type default)
			)
			(layer "F.SilkS")
		)
		(fp_line
			(start 0.508 -0.9398)
			(end -0.508 -0.9398)
			(stroke
				(width 0.1524)
				(type default)
			)
			(layer "F.SilkS")
		)
		(fp_rect
			(start -0.508 0.9398)
			(end 0.508 -0.9398)
			(stroke
				(width 0)
				(type default)
			)
			(fill no)
			(layer "F.CrtYd")
		)
		(fp_rect
			(start -0.508 0.9398)
			(end 0.508 -0.9398)
			(stroke
				(width 0)
				(type default)
			)
			(fill no)
			(layer "F.Fab")
		)
		(pad "1" smd custom
			(at 0 -0.4445 270)
			(size 0.1397 0.1397)
			(layers "F.Cu" "F.Mask" "F.Paste")
			(net "BMC_I2C_B_SCL")
			(options
				(clearance outline)
				(anchor circle)
			)
			(primitives
				(gr_poly
					(pts
						(arc
							(start -0.1778 -0.2794)
							(mid -0.249642 -0.249642)
							(end -0.2794 -0.1778)
						)
						(arc
							(start -0.2794 0.1778)
							(mid -0.249642 0.249642)
							(end -0.1778 0.2794)
						)
						(arc
							(start 0.1778 0.2794)
							(mid 0.249642 0.249642)
							(end 0.2794 0.1778)
						)
						(arc
							(start 0.2794 -0.1778)
							(mid 0.249642 -0.249642)
							(end 0.1778 -0.2794)
						)
					)
					(width 0)
					(fill yes)
				)
			)
		)
		(pad "2" smd custom
			(at 0 0.4445 270)
			(size 0.1397 0.1397)
			(layers "F.Cu" "F.Mask" "F.Paste")
			(net "BMC0_SMB7_CLK")
			(options
				(clearance outline)
				(anchor circle)
			)
			(primitives
				(gr_poly
					(pts
						(arc
							(start -0.1778 -0.2794)
							(mid -0.249642 -0.249642)
							(end -0.2794 -0.1778)
						)
						(arc
							(start -0.2794 0.1778)
							(mid -0.249642 0.249642)
							(end -0.1778 0.2794)
						)
						(arc
							(start 0.1778 0.2794)
							(mid 0.249642 0.249642)
							(end 0.2794 0.1778)
						)
						(arc
							(start 0.2794 -0.1778)
							(mid 0.249642 -0.249642)
							(end 0.1778 -0.2794)
						)
					)
					(width 0)
					(fill yes)
				)
			)
		)
	)
	(footprint ""
		(layer "F.Cu")
		(at 20.016216 -213.79688 180)
		(property "Reference" "SR263"
			(at 0 0 180)
			(layer "F.SilkS")
			(hide yes)
			(effects
				(font
					(size 1.27 1.27)
				)
			)
		)
		(property "Value" "4K7R2F-GP"
			(at 0.064008 -3.993896 180)
			(unlocked yes)
			(layer "F.Fab")
			(hide yes)
			(effects
				(font
					(size 1.016 1.016)
					(thickness 0.1524)
				)
			)
		)
		(property "Device Type" "R402H16"
			(at 0.064008 -5.517896 180)
			(unlocked yes)
			(layer "F.Fab")
			(hide yes)
			(effects
				(font
					(size 1.016 1.016)
					(thickness 0.1524)
				)
			)
		)
		(duplicate_pad_numbers_are_jumpers no)
		(fp_line
			(start 0.508 -0.9398)
			(end -0.508 -0.9398)
			(stroke
				(width 0.1524)
				(type default)
			)
			(layer "F.SilkS")
		)
		(fp_line
			(start -0.508 -0.9398)
			(end -0.508 0.9398)
			(stroke
				(width 0.1524)
				(type default)
			)
			(layer "F.SilkS")
		)
		(fp_rect
			(start -0.508 0.9398)
			(end 0.508 -0.9398)
			(stroke
				(width 0)
				(type default)
			)
			(fill no)
			(layer "F.CrtYd")
		)
		(fp_rect
			(start -0.508 0.9398)
			(end 0.508 -0.9398)
			(stroke
				(width 0)
				(type default)
			)
			(fill no)
			(layer "F.Fab")
		)
		(pad "1" smd custom
			(at 0 -0.4445 180)
			(size 0.1397 0.1397)
			(layers "F.Cu" "F.Mask" "F.Paste")
			(net "P3V3_STBY")
			(options
				(clearance outline)
				(anchor circle)
			)
			(primitives
				(gr_poly
					(pts
						(arc
							(start -0.1778 -0.2794)
							(mid -0.249642 -0.249642)
							(end -0.2794 -0.1778)
						)
						(arc
							(start -0.2794 0.1778)
							(mid -0.249642 0.249642)
							(end -0.1778 0.2794)
						)
						(arc
							(start 0.1778 0.2794)
							(mid 0.249642 0.249642)
							(end 0.2794 0.1778)
						)
						(arc
							(start 0.2794 -0.1778)
							(mid 0.249642 -0.249642)
							(end 0.1778 -0.2794)
						)
					)
					(width 0)
					(fill yes)
				)
			)
		)
		(pad "2" smd custom
			(at 0 0.4445 180)
			(size 0.1397 0.1397)
			(layers "F.Cu" "F.Mask" "F.Paste")
			(net "I2C_IO_EXP_RESET#_PWR")
			(options
				(clearance outline)
				(anchor circle)
			)
			(primitives
				(gr_poly
					(pts
						(arc
							(start -0.1778 -0.2794)
							(mid -0.249642 -0.249642)
							(end -0.2794 -0.1778)
						)
						(arc
							(start -0.2794 0.1778)
							(mid -0.249642 0.249642)
							(end -0.1778 0.2794)
						)
						(arc
							(start 0.1778 0.2794)
							(mid 0.249642 0.249642)
							(end 0.2794 0.1778)
						)
						(arc
							(start 0.2794 -0.1778)
							(mid 0.249642 -0.249642)
							(end 0.1778 -0.2794)
						)
					)
					(width 0)
					(fill yes)
				)
			)
		)
	)
	(footprint ""
		(layer "F.Cu")
		(at 92.21597 -97.79 -90)
		(property "Reference" "SR777"
			(at 0 0 270)
			(layer "F.SilkS")
			(hide yes)
			(effects
				(font
					(size 1.27 1.27)
				)
			)
		)
		(property "Value" "4K7R2F-GP"
			(at 0.064008 -3.993896 270)
			(unlocked yes)
			(layer "F.Fab")
			(hide yes)
			(effects
				(font
					(size 1.016 1.016)
					(thickness 0.1524)
				)
			)
		)
		(property "Device Type" "R402H16"
			(at 0.064008 -5.517896 270)
			(unlocked yes)
			(layer "F.Fab")
			(hide yes)
			(effects
				(font
					(size 1.016 1.016)
					(thickness 0.1524)
				)
			)
		)
		(duplicate_pad_numbers_are_jumpers no)
		(fp_line
			(start -0.508 -0.9398)
			(end -0.508 0.9398)
			(stroke
				(width 0.1524)
				(type default)
			)
			(layer "F.SilkS")
		)
		(fp_line
			(start 0.508 -0.9398)
			(end -0.508 -0.9398)
			(stroke
				(width 0.1524)
				(type default)
			)
			(layer "F.SilkS")
		)
		(fp_rect
			(start -0.508 0.9398)
			(end 0.508 -0.9398)
			(stroke
				(width 0)
				(type default)
			)
			(fill no)
			(layer "F.CrtYd")
		)
		(fp_rect
			(start -0.508 0.9398)
			(end 0.508 -0.9398)
			(stroke
				(width 0)
				(type default)
			)
			(fill no)
			(layer "F.Fab")
		)
		(pad "1" smd custom
			(at 0 -0.4445 270)
			(size 0.1397 0.1397)
			(layers "F.Cu" "F.Mask" "F.Paste")
			(net "EXP_XM_ADDR_16")
			(options
				(clearance outline)
				(anchor circle)
			)
			(primitives
				(gr_poly
					(pts
						(arc
							(start -0.1778 -0.2794)
							(mid -0.249642 -0.249642)
							(end -0.2794 -0.1778)
						)
						(arc
							(start -0.2794 0.1778)
							(mid -0.249642 0.249642)
							(end -0.1778 0.2794)
						)
						(arc
							(start 0.1778 0.2794)
							(mid 0.249642 0.249642)
							(end 0.2794 0.1778)
						)
						(arc
							(start 0.2794 -0.1778)
							(mid 0.249642 -0.249642)
							(end 0.1778 -0.2794)
						)
					)
					(width 0)
					(fill yes)
				)
			)
		)
		(pad "2" smd custom
			(at 0 0.4445 270)
			(size 0.1397 0.1397)
			(layers "F.Cu" "F.Mask" "F.Paste")
			(net "GND")
			(options
				(clearance outline)
				(anchor circle)
			)
			(primitives
				(gr_poly
					(pts
						(arc
							(start -0.1778 -0.2794)
							(mid -0.249642 -0.249642)
							(end -0.2794 -0.1778)
						)
						(arc
							(start -0.2794 0.1778)
							(mid -0.249642 0.249642)
							(end -0.1778 0.2794)
						)
						(arc
							(start 0.1778 0.2794)
							(mid 0.249642 0.249642)
							(end 0.2794 0.1778)
						)
						(arc
							(start 0.2794 -0.1778)
							(mid 0.249642 -0.249642)
							(end 0.1778 -0.2794)
						)
					)
					(width 0)
					(fill yes)
				)
			)
		)
	)
	(footprint ""
		(layer "F.Cu")
		(at 278.3586 -183.388)
		(property "Reference" "TP146"
			(at 0 0 0)
			(layer "F.SilkS")
			(hide yes)
			(effects
				(font
					(size 1.27 1.27)
				)
			)
		)
		(property "Value" "TPAD28"
			(at 0.0127 -1.8034 0)
			(unlocked yes)
			(layer "F.Fab")
			(hide yes)
			(effects
				(font
					(size 1.016 1.016)
					(thickness 0.1524)
				)
			)
		)
		(property "Device Type" "TPAD28"
			(at 0.0127 -3.3274 0)
			(unlocked yes)
			(layer "F.Fab")
			(hide yes)
			(effects
				(font
					(size 1.016 1.016)
					(thickness 0.1524)
				)
			)
		)
		(duplicate_pad_numbers_are_jumpers no)
		(fp_poly
			(pts
				(arc
					(start 0.3556 0)
					(mid -0.3556 0)
					(end 0.3556 0)
				)
			)
			(stroke
				(width 0)
				(type default)
			)
			(fill no)
			(layer "F.CrtYd")
		)
		(fp_poly
			(pts
				(arc
					(start 0.6096 0)
					(mid -0.6096 0)
					(end 0.6096 0)
				)
			)
			(stroke
				(width 0)
				(type default)
			)
			(fill no)
			(layer "F.Fab")
		)
		(pad "1" smd circle
			(at 0 0)
			(size 0.7112 0.7112)
			(layers "F.Cu" "F.Mask" "F.Paste")
			(net "TP_BMC_GPIOR4")
		)
	)
	(footprint ""
		(layer "F.Cu")
		(at 344.424 -114.808 -90)
		(property "Reference" "PC9"
			(at 0 0 270)
			(layer "F.SilkS")
			(hide yes)
			(effects
				(font
					(size 1.27 1.27)
				)
			)
		)
		(property "Value" "SC1U10V2KX-1GP"
			(at 1.1811 -2.7051 270)
			(unlocked yes)
			(layer "F.Fab")
			(hide yes)
			(effects
				(font
					(size 1.016 1.016)
					(thickness 0.1524)
				)
			)
		)
		(property "Device Type" "C402H22"
			(at 1.1811 -4.2291 270)
			(unlocked yes)
			(layer "F.Fab")
			(hide yes)
			(effects
				(font
					(size 1.016 1.016)
					(thickness 0.1524)
				)
			)
		)
		(duplicate_pad_numbers_are_jumpers no)
		(fp_rect
			(start -0.4318 0.9525)
			(end 0.4318 -0.9525)
			(stroke
				(width 0)
				(type default)
			)
			(fill no)
			(layer "F.CrtYd")
		)
		(fp_rect
			(start -0.4318 0.9525)
			(end 0.4318 -0.9525)
			(stroke
				(width 0)
				(type default)
			)
			(fill no)
			(layer "F.Fab")
		)
		(pad "1" smd custom
			(at 0 -0.4445 270)
			(size 0.1524 0.1524)
			(layers "F.Cu" "F.Mask" "F.Paste")
			(net "P5V_STBY_CC_R")
			(options
				(clearance outline)
				(anchor circle)
			)
			(primitives
				(gr_poly
					(pts
						(arc
							(start 0.3048 -0.2032)
							(mid 0.275042 -0.275042)
							(end 0.2032 -0.3048)
						)
						(arc
							(start -0.2032 -0.3048)
							(mid -0.275042 -0.275042)
							(end -0.3048 -0.2032)
						)
						(arc
							(start -0.3048 0.2032)
							(mid -0.275042 0.275042)
							(end -0.2032 0.3048)
						)
						(arc
							(start 0.2032 0.3048)
							(mid 0.275042 0.275042)
							(end 0.3048 0.2032)
						)
					)
					(width 0)
					(fill yes)
				)
			)
		)
		(pad "2" smd custom
			(at 0 0.4445 270)
			(size 0.1524 0.1524)
			(layers "F.Cu" "F.Mask" "F.Paste")
			(net "P5V_STBY_VFB")
			(options
				(clearance outline)
				(anchor circle)
			)
			(primitives
				(gr_poly
					(pts
						(arc
							(start 0.3048 -0.2032)
							(mid 0.275042 -0.275042)
							(end 0.2032 -0.3048)
						)
						(arc
							(start -0.2032 -0.3048)
							(mid -0.275042 -0.275042)
							(end -0.3048 -0.2032)
						)
						(arc
							(start -0.3048 0.2032)
							(mid -0.275042 0.275042)
							(end -0.2032 0.3048)
						)
						(arc
							(start 0.2032 0.3048)
							(mid 0.275042 0.275042)
							(end 0.3048 0.2032)
						)
					)
					(width 0)
					(fill yes)
				)
			)
		)
	)
	(footprint ""
		(layer "F.Cu")
		(at 48.768 -215.392 -90)
		(property "Reference" "C7273"
			(at 0 0 270)
			(layer "F.SilkS")
			(hide yes)
			(effects
				(font
					(size 1.27 1.27)
				)
			)
		)
		(property "Value" "SCD01U16V2KX-3GP"
			(at 1.1811 -2.7051 270)
			(unlocked yes)
			(layer "F.Fab")
			(hide yes)
			(effects
				(font
					(size 1.016 1.016)
					(thickness 0.1524)
				)
			)
		)
		(property "Device Type" "C402H22"
			(at 1.1811 -4.2291 270)
			(unlocked yes)
			(layer "F.Fab")
			(hide yes)
			(effects
				(font
					(size 1.016 1.016)
					(thickness 0.1524)
				)
			)
		)
		(duplicate_pad_numbers_are_jumpers no)
		(fp_rect
			(start -0.4318 0.9525)
			(end 0.4318 -0.9525)
			(stroke
				(width 0)
				(type default)
			)
			(fill no)
			(layer "F.CrtYd")
		)
		(fp_rect
			(start -0.4318 0.9525)
			(end 0.4318 -0.9525)
			(stroke
				(width 0)
				(type default)
			)
			(fill no)
			(layer "F.Fab")
		)
		(pad "1" smd custom
			(at 0 -0.4445 270)
			(size 0.1524 0.1524)
			(layers "F.Cu" "F.Mask" "F.Paste")
			(net "MB0_TIME_R")
			(options
				(clearance outline)
				(anchor circle)
			)
			(primitives
				(gr_poly
					(pts
						(arc
							(start 0.3048 -0.2032)
							(mid 0.275042 -0.275042)
							(end 0.2032 -0.3048)
						)
						(arc
							(start -0.2032 -0.3048)
							(mid -0.275042 -0.275042)
							(end -0.3048 -0.2032)
						)
						(arc
							(start -0.3048 0.2032)
							(mid -0.275042 0.275042)
							(end -0.2032 0.3048)
						)
						(arc
							(start 0.2032 0.3048)
							(mid 0.275042 0.275042)
							(end 0.3048 0.2032)
						)
					)
					(width 0)
					(fill yes)
				)
			)
		)
		(pad "2" smd custom
			(at 0 0.4445 270)
			(size 0.1524 0.1524)
			(layers "F.Cu" "F.Mask" "F.Paste")
			(net "AGND_CURRENT_MON")
			(options
				(clearance outline)
				(anchor circle)
			)
			(primitives
				(gr_poly
					(pts
						(arc
							(start 0.3048 -0.2032)
							(mid 0.275042 -0.275042)
							(end 0.2032 -0.3048)
						)
						(arc
							(start -0.2032 -0.3048)
							(mid -0.275042 -0.275042)
							(end -0.3048 -0.2032)
						)
						(arc
							(start -0.3048 0.2032)
							(mid -0.275042 0.275042)
							(end -0.2032 0.3048)
						)
						(arc
							(start 0.2032 0.3048)
							(mid 0.275042 0.275042)
							(end 0.3048 0.2032)
						)
					)
					(width 0)
					(fill yes)
				)
			)
		)
	)
	(footprint ""
		(layer "F.Cu")
		(at 275.336 -36.83 180)
		(property "Reference" "PR49"
			(at 0 0 180)
			(layer "F.SilkS")
			(hide yes)
			(effects
				(font
					(size 1.27 1.27)
				)
			)
		)
		(property "Value" "3D01R5F-GP"
			(at 0 -8.9535 180)
			(unlocked yes)
			(layer "F.Fab")
			(hide yes)
			(effects
				(font
					(size 1.27 1.016)
					(thickness 0.1524)
				)
			)
		)
		(property "Device Type" "R805H24"
			(at 0 -10.6299 180)
			(unlocked yes)
			(layer "F.Fab")
			(hide yes)
			(effects
				(font
					(size 1.27 1.016)
					(thickness 0.1524)
				)
			)
		)
		(duplicate_pad_numbers_are_jumpers no)
		(fp_line
			(start 0.889 1.7018)
			(end 0.889 -0.508)
			(stroke
				(width 0.1524)
				(type default)
			)
			(layer "F.SilkS")
		)
		(fp_line
			(start 0.889 -1.7018)
			(end 0.889 -0.381)
			(stroke
				(width 0.1524)
				(type default)
			)
			(layer "F.SilkS")
		)
		(fp_line
			(start 0.889 -1.7018)
			(end -0.889 -1.7018)
			(stroke
				(width 0.1524)
				(type default)
			)
			(layer "F.SilkS")
		)
		(fp_line
			(start -0.889 1.7018)
			(end 0.889 1.7018)
			(stroke
				(width 0.1524)
				(type default)
			)
			(layer "F.SilkS")
		)
		(fp_line
			(start -0.889 0.0762)
			(end -0.889 1.7018)
			(stroke
				(width 0.1524)
				(type default)
			)
			(layer "F.SilkS")
		)
		(fp_line
			(start -0.889 -1.7018)
			(end -0.889 0.2794)
			(stroke
				(width 0.1524)
				(type default)
			)
			(layer "F.SilkS")
		)
		(fp_poly
			(pts
				(xy 0.9652 -1.778) (xy 0.9652 1.778) (xy -0.9652 1.778) (xy -0.9652 -1.778)
			)
			(stroke
				(width 0)
				(type default)
			)
			(fill no)
			(layer "F.CrtYd")
		)
		(fp_rect
			(start -0.9652 1.778)
			(end 0.9652 -1.778)
			(stroke
				(width 0)
				(type default)
			)
			(fill no)
			(layer "F.Fab")
		)
		(pad "1" smd rect
			(at 0 -0.9652 180)
			(size 1.397 1.143)
			(layers "F.Cu" "F.Mask" "F.Paste")
			(net "P1V8_STBY_SNB")
		)
		(pad "2" smd rect
			(at 0 0.9652 180)
			(size 1.397 1.143)
			(layers "F.Cu" "F.Mask" "F.Paste")
			(net "GND")
		)
	)
	(footprint ""
		(layer "F.Cu")
		(at 108.14177 -78.6892)
		(property "Reference" "STP156"
			(at 0 0 0)
			(layer "F.SilkS")
			(hide yes)
			(effects
				(font
					(size 1.27 1.27)
				)
			)
		)
		(property "Value" "TPAD28"
			(at 0.0127 -1.8034 0)
			(unlocked yes)
			(layer "F.Fab")
			(hide yes)
			(effects
				(font
					(size 1.016 1.016)
					(thickness 0.1524)
				)
			)
		)
		(property "Device Type" "TPAD28"
			(at 0.0127 -3.3274 0)
			(unlocked yes)
			(layer "F.Fab")
			(hide yes)
			(effects
				(font
					(size 1.016 1.016)
					(thickness 0.1524)
				)
			)
		)
		(duplicate_pad_numbers_are_jumpers no)
		(fp_poly
			(pts
				(arc
					(start 0.3556 0)
					(mid -0.3556 0)
					(end 0.3556 0)
				)
			)
			(stroke
				(width 0)
				(type default)
			)
			(fill no)
			(layer "F.CrtYd")
		)
		(fp_poly
			(pts
				(arc
					(start 0.6096 0)
					(mid -0.6096 0)
					(end 0.6096 0)
				)
			)
			(stroke
				(width 0)
				(type default)
			)
			(fill no)
			(layer "F.Fab")
		)
		(pad "1" smd circle
			(at 0 0)
			(size 0.7112 0.7112)
			(layers "F.Cu" "F.Mask" "F.Paste")
			(net "EXP_LED_15")
		)
	)
	(footprint ""
		(layer "F.Cu")
		(at 188.087 -20.574 180)
		(property "Reference" "R459"
			(at 0 0 180)
			(layer "F.SilkS")
			(hide yes)
			(effects
				(font
					(size 1.27 1.27)
				)
			)
		)
		(property "Value" "4K75R2F-1-GP"
			(at 0.064008 -3.993896 180)
			(unlocked yes)
			(layer "F.Fab")
			(hide yes)
			(effects
				(font
					(size 1.016 1.016)
					(thickness 0.1524)
				)
			)
		)
		(property "Device Type" "R402H16"
			(at 0.064008 -5.517896 180)
			(unlocked yes)
			(layer "F.Fab")
			(hide yes)
			(effects
				(font
					(size 1.016 1.016)
					(thickness 0.1524)
				)
			)
		)
		(duplicate_pad_numbers_are_jumpers no)
		(fp_line
			(start 0.508 -0.9398)
			(end -0.508 -0.9398)
			(stroke
				(width 0.1524)
				(type default)
			)
			(layer "F.SilkS")
		)
		(fp_line
			(start -0.508 -0.9398)
			(end -0.508 0.9398)
			(stroke
				(width 0.1524)
				(type default)
			)
			(layer "F.SilkS")
		)
		(fp_rect
			(start -0.508 0.9398)
			(end 0.508 -0.9398)
			(stroke
				(width 0)
				(type default)
			)
			(fill no)
			(layer "F.CrtYd")
		)
		(fp_rect
			(start -0.508 0.9398)
			(end 0.508 -0.9398)
			(stroke
				(width 0)
				(type default)
			)
			(fill no)
			(layer "F.Fab")
		)
		(pad "1" smd custom
			(at 0 -0.4445 180)
			(size 0.1397 0.1397)
			(layers "F.Cu" "F.Mask" "F.Paste")
			(net "P3V3_STBY")
			(options
				(clearance outline)
				(anchor circle)
			)
			(primitives
				(gr_poly
					(pts
						(arc
							(start -0.1778 -0.2794)
							(mid -0.249642 -0.249642)
							(end -0.2794 -0.1778)
						)
						(arc
							(start -0.2794 0.1778)
							(mid -0.249642 0.249642)
							(end -0.1778 0.2794)
						)
						(arc
							(start 0.1778 0.2794)
							(mid 0.249642 0.249642)
							(end 0.2794 0.1778)
						)
						(arc
							(start 0.2794 -0.1778)
							(mid 0.249642 -0.249642)
							(end 0.1778 -0.2794)
						)
					)
					(width 0)
					(fill yes)
				)
			)
		)
		(pad "2" smd custom
			(at 0 0.4445 180)
			(size 0.1397 0.1397)
			(layers "F.Cu" "F.Mask" "F.Paste")
			(net "RMII_BMC_MDIO_R")
			(options
				(clearance outline)
				(anchor circle)
			)
			(primitives
				(gr_poly
					(pts
						(arc
							(start -0.1778 -0.2794)
							(mid -0.249642 -0.249642)
							(end -0.2794 -0.1778)
						)
						(arc
							(start -0.2794 0.1778)
							(mid -0.249642 0.249642)
							(end -0.1778 0.2794)
						)
						(arc
							(start 0.1778 0.2794)
							(mid 0.249642 0.249642)
							(end 0.2794 0.1778)
						)
						(arc
							(start 0.2794 -0.1778)
							(mid 0.249642 -0.249642)
							(end 0.1778 -0.2794)
						)
					)
					(width 0)
					(fill yes)
				)
			)
		)
	)
	(footprint ""
		(layer "F.Cu")
		(at 273.499072 -55.936896 -90)
		(property "Reference" "PQ2"
			(at 0 0 270)
			(layer "F.SilkS")
			(hide yes)
			(effects
				(font
					(size 1.27 1.27)
				)
			)
		)
		(property "Value" "2N7002A-7-GP"
			(at 0.127 -8.9662 270)
			(unlocked yes)
			(layer "F.Fab")
			(hide yes)
			(effects
				(font
					(size 1.016 1.016)
					(thickness 0.1524)
				)
			)
		)
		(property "Device Type" "SOT23DGS2D4H48"
			(at 0.127 -10.4902 270)
			(unlocked yes)
			(layer "F.Fab")
			(hide yes)
			(effects
				(font
					(size 1.016 1.016)
					(thickness 0.1524)
				)
			)
		)
		(duplicate_pad_numbers_are_jumpers no)
		(fp_line
			(start -1.651 1.778)
			(end 1.651 1.778)
			(stroke
				(width 0.1524)
				(type default)
			)
			(layer "F.SilkS")
		)
		(fp_line
			(start 1.651 1.778)
			(end 1.651 -1.778)
			(stroke
				(width 0.1524)
				(type default)
			)
			(layer "F.SilkS")
		)
		(fp_line
			(start -1.651 -1.778)
			(end -1.651 1.778)
			(stroke
				(width 0.1524)
				(type default)
			)
			(layer "F.SilkS")
		)
		(fp_line
			(start 1.651 -1.778)
			(end -1.651 -1.778)
			(stroke
				(width 0.1524)
				(type default)
			)
			(layer "F.SilkS")
		)
		(fp_poly
			(pts
				(xy -1.778 1.8796) (xy -1.778 -1.8796) (xy 1.778 -1.8796) (xy 1.778 1.8796)
			)
			(stroke
				(width 0)
				(type default)
			)
			(fill no)
			(layer "F.CrtYd")
		)
		(fp_poly
			(pts
				(xy -1.778 1.8796) (xy -1.778 -1.8796) (xy 1.778 -1.8796) (xy 1.778 1.8796)
			)
			(stroke
				(width 0)
				(type default)
			)
			(fill no)
			(layer "F.Fab")
		)
		(pad "D" smd custom
			(at 0 -0.9525 270)
			(size 0.1905 0.1905)
			(layers "F.Cu" "F.Mask" "F.Paste")
			(net "P3V3_EN_LV")
			(options
				(clearance outline)
				(anchor circle)
			)
			(primitives
				(gr_poly
					(pts
						(arc
							(start -0.1778 0.5715)
							(mid -0.321484 0.511984)
							(end -0.381 0.3683)
						)
						(arc
							(start -0.381 -0.3683)
							(mid -0.321484 -0.511984)
							(end -0.1778 -0.5715)
						)
						(arc
							(start 0.1778 -0.5715)
							(mid 0.321484 -0.511984)
							(end 0.381 -0.3683)
						)
						(arc
							(start 0.381 0.3683)
							(mid 0.321484 0.511984)
							(end 0.1778 0.5715)
						)
					)
					(width 0)
					(fill yes)
				)
			)
		)
		(pad "G" smd custom
			(at -0.98425 0.9525 270)
			(size 0.1905 0.1905)
			(layers "F.Cu" "F.Mask" "F.Paste")
			(net "P3V3_EN_G")
			(options
				(clearance outline)
				(anchor circle)
			)
			(primitives
				(gr_poly
					(pts
						(arc
							(start -0.1778 0.5715)
							(mid -0.321484 0.511984)
							(end -0.381 0.3683)
						)
						(arc
							(start -0.381 -0.3683)
							(mid -0.321484 -0.511984)
							(end -0.1778 -0.5715)
						)
						(arc
							(start 0.1778 -0.5715)
							(mid 0.321484 -0.511984)
							(end 0.381 -0.3683)
						)
						(arc
							(start 0.381 0.3683)
							(mid 0.321484 0.511984)
							(end 0.1778 0.5715)
						)
					)
					(width 0)
					(fill yes)
				)
			)
		)
		(pad "S" smd custom
			(at 0.98425 0.9525 270)
			(size 0.1905 0.1905)
			(layers "F.Cu" "F.Mask" "F.Paste")
			(net "P3V3_EN_B")
			(options
				(clearance outline)
				(anchor circle)
			)
			(primitives
				(gr_poly
					(pts
						(arc
							(start -0.1778 0.5715)
							(mid -0.321484 0.511984)
							(end -0.381 0.3683)
						)
						(arc
							(start -0.381 -0.3683)
							(mid -0.321484 -0.511984)
							(end -0.1778 -0.5715)
						)
						(arc
							(start 0.1778 -0.5715)
							(mid 0.321484 -0.511984)
							(end 0.381 -0.3683)
						)
						(arc
							(start 0.381 0.3683)
							(mid 0.321484 0.511984)
							(end 0.1778 0.5715)
						)
					)
					(width 0)
					(fill yes)
				)
			)
		)
	)
	(footprint ""
		(layer "F.Cu")
		(at 328.549 -114.3)
		(property "Reference" "PC21"
			(at 0 0 0)
			(layer "F.SilkS")
			(hide yes)
			(effects
				(font
					(size 1.27 1.27)
				)
			)
		)
		(property "Value" "SC22U25V5MX-GP"
			(at -0.0762 -6.1214 0)
			(unlocked yes)
			(layer "F.Fab")
			(hide yes)
			(effects
				(font
					(size 1.016 1.016)
					(thickness 0.1524)
				)
			)
		)
		(property "Device Type" "C805H58"
			(at -0.0762 -8.1534 0)
			(unlocked yes)
			(layer "F.Fab")
			(hide yes)
			(effects
				(font
					(size 1.016 1.016)
					(thickness 0.1524)
				)
			)
		)
		(duplicate_pad_numbers_are_jumpers no)
		(fp_line
			(start 0.635 0)
			(end -0.635 0)
			(stroke
				(width 0.508)
				(type default)
			)
			(layer "F.SilkS")
		)
		(fp_rect
			(start -0.9652 1.778)
			(end 0.9652 -1.778)
			(stroke
				(width 0)
				(type default)
			)
			(fill no)
			(layer "F.CrtYd")
		)
		(fp_poly
			(pts
				(xy -0.9652 -1.778) (xy 0.9652 -1.778) (xy 0.9652 1.778) (xy -0.9652 1.778)
			)
			(stroke
				(width 0)
				(type default)
			)
			(fill no)
			(layer "F.Fab")
		)
		(pad "1" smd rect
			(at 0 -0.9652)
			(size 1.397 1.143)
			(layers "F.Cu" "F.Mask" "F.Paste")
			(net "P3V3_STBY_VIN")
		)
		(pad "2" smd rect
			(at 0 0.9652)
			(size 1.397 1.143)
			(layers "F.Cu" "F.Mask" "F.Paste")
			(net "GND")
		)
	)
	(footprint ""
		(layer "F.Cu")
		(at 131.135882 -81.147158)
		(property "Reference" "SC1091"
			(at 0 0 0)
			(layer "F.SilkS")
			(hide yes)
			(effects
				(font
					(size 1.27 1.27)
				)
			)
		)
		(property "Value" "SCD01U10V1KX-GP"
			(at -2.8321 -1.7399 0)
			(unlocked yes)
			(layer "F.Fab")
			(hide yes)
			(effects
				(font
					(size 1.016 1.016)
					(thickness 0.1524)
				)
			)
		)
		(property "Device Type" "C0201H13"
			(at -2.8321 -3.2639 0)
			(unlocked yes)
			(layer "F.Fab")
			(hide yes)
			(effects
				(font
					(size 1.016 1.016)
					(thickness 0.1524)
				)
			)
		)
		(duplicate_pad_numbers_are_jumpers no)
		(fp_rect
			(start -0.2794 0.6477)
			(end 0.2794 -0.6477)
			(stroke
				(width 0)
				(type default)
			)
			(fill no)
			(layer "F.CrtYd")
		)
		(fp_rect
			(start -0.2794 0.6477)
			(end 0.2794 -0.6477)
			(stroke
				(width 0)
				(type default)
			)
			(fill no)
			(layer "F.Fab")
		)
		(pad "1" smd custom
			(at 0 -0.2794)
			(size 0.0762 0.0762)
			(layers "F.Cu" "F.Mask" "F.Paste")
			(net "SAS_HDD_TX12_N")
			(options
				(clearance outline)
				(anchor circle)
			)
			(primitives
				(gr_poly
					(pts
						(arc
							(start 0.1524 -0.127)
							(mid 0.137521 -0.162921)
							(end 0.1016 -0.1778)
						)
						(arc
							(start -0.1016 -0.1778)
							(mid -0.137521 -0.162921)
							(end -0.1524 -0.127)
						)
						(arc
							(start -0.1524 0.127)
							(mid -0.137521 0.162921)
							(end -0.1016 0.1778)
						)
						(arc
							(start 0.1016 0.1778)
							(mid 0.137521 0.162921)
							(end 0.1524 0.127)
						)
					)
					(width 0)
					(fill yes)
				)
			)
		)
		(pad "2" smd custom
			(at 0 0.2794)
			(size 0.0762 0.0762)
			(layers "F.Cu" "F.Mask" "F.Paste")
			(net "3008_SAS_RX_N0")
			(options
				(clearance outline)
				(anchor circle)
			)
			(primitives
				(gr_poly
					(pts
						(arc
							(start 0.1524 -0.127)
							(mid 0.137521 -0.162921)
							(end 0.1016 -0.1778)
						)
						(arc
							(start -0.1016 -0.1778)
							(mid -0.137521 -0.162921)
							(end -0.1524 -0.127)
						)
						(arc
							(start -0.1524 0.127)
							(mid -0.137521 0.162921)
							(end -0.1016 0.1778)
						)
						(arc
							(start 0.1016 0.1778)
							(mid 0.137521 0.162921)
							(end 0.1524 0.127)
						)
					)
					(width 0)
					(fill yes)
				)
			)
		)
	)
	(footprint ""
		(layer "F.Cu")
		(at 284.607 -162.433)
		(property "Reference" "TP136"
			(at 0 0 0)
			(layer "F.SilkS")
			(hide yes)
			(effects
				(font
					(size 1.27 1.27)
				)
			)
		)
		(property "Value" "TPAD28"
			(at 0.0127 -1.8034 0)
			(unlocked yes)
			(layer "F.Fab")
			(hide yes)
			(effects
				(font
					(size 1.016 1.016)
					(thickness 0.1524)
				)
			)
		)
		(property "Device Type" "TPAD28"
			(at 0.0127 -3.3274 0)
			(unlocked yes)
			(layer "F.Fab")
			(hide yes)
			(effects
				(font
					(size 1.016 1.016)
					(thickness 0.1524)
				)
			)
		)
		(duplicate_pad_numbers_are_jumpers no)
		(fp_poly
			(pts
				(arc
					(start 0.3556 0)
					(mid -0.3556 0)
					(end 0.3556 0)
				)
			)
			(stroke
				(width 0)
				(type default)
			)
			(fill no)
			(layer "F.CrtYd")
		)
		(fp_poly
			(pts
				(arc
					(start 0.6096 0)
					(mid -0.6096 0)
					(end 0.6096 0)
				)
			)
			(stroke
				(width 0)
				(type default)
			)
			(fill no)
			(layer "F.Fab")
		)
		(pad "1" smd circle
			(at 0 0)
			(size 0.7112 0.7112)
			(layers "F.Cu" "F.Mask" "F.Paste")
			(net "TP_BMC_GPIOF5")
		)
	)
	(footprint ""
		(layer "F.Cu")
		(at 343.183718 -142.852648 90)
		(property "Reference" "C8090"
			(at 0 0 90)
			(layer "F.SilkS")
			(hide yes)
			(effects
				(font
					(size 1.27 1.27)
				)
			)
		)
		(property "Value" "SC18P50V3JN-1-GP"
			(at 0 -2.8194 90)
			(unlocked yes)
			(layer "F.Fab")
			(hide yes)
			(effects
				(font
					(size 1.016 1.016)
					(thickness 0.1524)
				)
			)
		)
		(property "Device Type" "C603"
			(at 0 -4.3434 90)
			(unlocked yes)
			(layer "F.Fab")
			(hide yes)
			(effects
				(font
					(size 1.016 1.016)
					(thickness 0.1524)
				)
			)
		)
		(duplicate_pad_numbers_are_jumpers no)
		(fp_line
			(start 0.508 0)
			(end -0.508 0)
			(stroke
				(width 0.2032)
				(type default)
			)
			(layer "F.SilkS")
		)
		(fp_rect
			(start -0.5842 1.3335)
			(end 0.5842 -1.3335)
			(stroke
				(width 0)
				(type default)
			)
			(fill no)
			(layer "F.CrtYd")
		)
		(fp_rect
			(start -0.5842 1.3335)
			(end 0.5842 -1.3335)
			(stroke
				(width 0)
				(type default)
			)
			(fill no)
			(layer "F.Fab")
		)
		(pad "1" smd custom
			(at 0 -0.762 90)
			(size 0.2159 0.2159)
			(layers "F.Cu" "F.Mask" "F.Paste")
			(net "USB_HUB_XTAL_IN")
			(options
				(clearance outline)
				(anchor circle)
			)
			(primitives
				(gr_poly
					(pts
						(arc
							(start -0.3302 -0.4318)
							(mid -0.402042 -0.402042)
							(end -0.4318 -0.3302)
						)
						(arc
							(start -0.4318 0.3302)
							(mid -0.402042 0.402042)
							(end -0.3302 0.4318)
						)
						(arc
							(start 0.3302 0.4318)
							(mid 0.402042 0.402042)
							(end 0.4318 0.3302)
						)
						(arc
							(start 0.4318 -0.3302)
							(mid 0.402042 -0.402042)
							(end 0.3302 -0.4318)
						)
					)
					(width 0)
					(fill yes)
				)
			)
		)
		(pad "2" smd custom
			(at 0 0.762 90)
			(size 0.2159 0.2159)
			(layers "F.Cu" "F.Mask" "F.Paste")
			(net "GND")
			(options
				(clearance outline)
				(anchor circle)
			)
			(primitives
				(gr_poly
					(pts
						(arc
							(start -0.3302 -0.4318)
							(mid -0.402042 -0.402042)
							(end -0.4318 -0.3302)
						)
						(arc
							(start -0.4318 0.3302)
							(mid -0.402042 0.402042)
							(end -0.3302 0.4318)
						)
						(arc
							(start 0.3302 0.4318)
							(mid 0.402042 0.402042)
							(end 0.4318 0.3302)
						)
						(arc
							(start 0.4318 -0.3302)
							(mid 0.402042 -0.402042)
							(end 0.3302 -0.4318)
						)
					)
					(width 0)
					(fill yes)
				)
			)
		)
	)
	(footprint ""
		(layer "F.Cu")
		(at 320.294 -197.866 90)
		(property "Reference" "R561"
			(at 0 0 90)
			(layer "F.SilkS")
			(hide yes)
			(effects
				(font
					(size 1.27 1.27)
				)
			)
		)
		(property "Value" "10KR2F-2-GP"
			(at 0.064008 -3.993896 90)
			(unlocked yes)
			(layer "F.Fab")
			(hide yes)
			(effects
				(font
					(size 1.016 1.016)
					(thickness 0.1524)
				)
			)
		)
		(property "Device Type" "R402H16"
			(at 0.064008 -5.517896 90)
			(unlocked yes)
			(layer "F.Fab")
			(hide yes)
			(effects
				(font
					(size 1.016 1.016)
					(thickness 0.1524)
				)
			)
		)
		(duplicate_pad_numbers_are_jumpers no)
		(fp_line
			(start 0.508 -0.9398)
			(end -0.508 -0.9398)
			(stroke
				(width 0.1524)
				(type default)
			)
			(layer "F.SilkS")
		)
		(fp_line
			(start -0.508 -0.9398)
			(end -0.508 0.9398)
			(stroke
				(width 0.1524)
				(type default)
			)
			(layer "F.SilkS")
		)
		(fp_rect
			(start -0.508 0.9398)
			(end 0.508 -0.9398)
			(stroke
				(width 0)
				(type default)
			)
			(fill no)
			(layer "F.CrtYd")
		)
		(fp_rect
			(start -0.508 0.9398)
			(end 0.508 -0.9398)
			(stroke
				(width 0)
				(type default)
			)
			(fill no)
			(layer "F.Fab")
		)
		(pad "1" smd custom
			(at 0 -0.4445 90)
			(size 0.1397 0.1397)
			(layers "F.Cu" "F.Mask" "F.Paste")
			(net "BMC_JTAG_L_EN")
			(options
				(clearance outline)
				(anchor circle)
			)
			(primitives
				(gr_poly
					(pts
						(arc
							(start -0.1778 -0.2794)
							(mid -0.249642 -0.249642)
							(end -0.2794 -0.1778)
						)
						(arc
							(start -0.2794 0.1778)
							(mid -0.249642 0.249642)
							(end -0.1778 0.2794)
						)
						(arc
							(start 0.1778 0.2794)
							(mid 0.249642 0.249642)
							(end 0.2794 0.1778)
						)
						(arc
							(start 0.2794 -0.1778)
							(mid 0.249642 -0.249642)
							(end 0.1778 -0.2794)
						)
					)
					(width 0)
					(fill yes)
				)
			)
		)
		(pad "2" smd custom
			(at 0 0.4445 90)
			(size 0.1397 0.1397)
			(layers "F.Cu" "F.Mask" "F.Paste")
			(net "GND")
			(options
				(clearance outline)
				(anchor circle)
			)
			(primitives
				(gr_poly
					(pts
						(arc
							(start -0.1778 -0.2794)
							(mid -0.249642 -0.249642)
							(end -0.2794 -0.1778)
						)
						(arc
							(start -0.2794 0.1778)
							(mid -0.249642 0.249642)
							(end -0.1778 0.2794)
						)
						(arc
							(start 0.1778 0.2794)
							(mid 0.249642 0.249642)
							(end 0.2794 0.1778)
						)
						(arc
							(start 0.2794 -0.1778)
							(mid 0.249642 -0.249642)
							(end 0.1778 -0.2794)
						)
					)
					(width 0)
					(fill yes)
				)
			)
		)
	)
	(footprint ""
		(layer "F.Cu")
		(at 89.643966 -61.468)
		(property "Reference" "STP31"
			(at 0 0 0)
			(layer "F.SilkS")
			(hide yes)
			(effects
				(font
					(size 1.27 1.27)
				)
			)
		)
		(property "Value" "TPAD28"
			(at 0.0127 -1.8034 0)
			(unlocked yes)
			(layer "F.Fab")
			(hide yes)
			(effects
				(font
					(size 1.016 1.016)
					(thickness 0.1524)
				)
			)
		)
		(property "Device Type" "TPAD28"
			(at 0.0127 -3.3274 0)
			(unlocked yes)
			(layer "F.Fab")
			(hide yes)
			(effects
				(font
					(size 1.016 1.016)
					(thickness 0.1524)
				)
			)
		)
		(duplicate_pad_numbers_are_jumpers no)
		(fp_poly
			(pts
				(arc
					(start 0.3556 0)
					(mid -0.3556 0)
					(end 0.3556 0)
				)
			)
			(stroke
				(width 0)
				(type default)
			)
			(fill no)
			(layer "F.CrtYd")
		)
		(fp_poly
			(pts
				(arc
					(start 0.6096 0)
					(mid -0.6096 0)
					(end 0.6096 0)
				)
			)
			(stroke
				(width 0)
				(type default)
			)
			(fill no)
			(layer "F.Fab")
		)
		(pad "1" smd circle
			(at 0 0)
			(size 0.7112 0.7112)
			(layers "F.Cu" "F.Mask" "F.Paste")
			(net "ICE0_TMS")
		)
	)
	(footprint ""
		(layer "F.Cu")
		(at 279.654 -108.712 -90)
		(property "Reference" "PR175"
			(at 0 0 270)
			(layer "F.SilkS")
			(hide yes)
			(effects
				(font
					(size 1.27 1.27)
				)
			)
		)
		(property "Value" "20KR2F-L-GP"
			(at 0.064008 -3.993896 270)
			(unlocked yes)
			(layer "F.Fab")
			(hide yes)
			(effects
				(font
					(size 1.016 1.016)
					(thickness 0.1524)
				)
			)
		)
		(property "Device Type" "R402H16"
			(at 0.064008 -5.517896 270)
			(unlocked yes)
			(layer "F.Fab")
			(hide yes)
			(effects
				(font
					(size 1.016 1.016)
					(thickness 0.1524)
				)
			)
		)
		(duplicate_pad_numbers_are_jumpers no)
		(fp_line
			(start -0.508 -0.9398)
			(end -0.508 0.9398)
			(stroke
				(width 0.1524)
				(type default)
			)
			(layer "F.SilkS")
		)
		(fp_line
			(start 0.508 -0.9398)
			(end -0.508 -0.9398)
			(stroke
				(width 0.1524)
				(type default)
			)
			(layer "F.SilkS")
		)
		(fp_rect
			(start -0.508 0.9398)
			(end 0.508 -0.9398)
			(stroke
				(width 0)
				(type default)
			)
			(fill no)
			(layer "F.CrtYd")
		)
		(fp_rect
			(start -0.508 0.9398)
			(end 0.508 -0.9398)
			(stroke
				(width 0)
				(type default)
			)
			(fill no)
			(layer "F.Fab")
		)
		(pad "1" smd custom
			(at 0 -0.4445 270)
			(size 0.1397 0.1397)
			(layers "F.Cu" "F.Mask" "F.Paste")
			(net "P12V")
			(options
				(clearance outline)
				(anchor circle)
			)
			(primitives
				(gr_poly
					(pts
						(arc
							(start -0.1778 -0.2794)
							(mid -0.249642 -0.249642)
							(end -0.2794 -0.1778)
						)
						(arc
							(start -0.2794 0.1778)
							(mid -0.249642 0.249642)
							(end -0.1778 0.2794)
						)
						(arc
							(start 0.1778 0.2794)
							(mid 0.249642 0.249642)
							(end 0.2794 0.1778)
						)
						(arc
							(start 0.2794 -0.1778)
							(mid 0.249642 -0.249642)
							(end 0.1778 -0.2794)
						)
					)
					(width 0)
					(fill yes)
				)
			)
		)
		(pad "2" smd custom
			(at 0 0.4445 270)
			(size 0.1397 0.1397)
			(layers "F.Cu" "F.Mask" "F.Paste")
			(net "P1V8_C_EN_LV")
			(options
				(clearance outline)
				(anchor circle)
			)
			(primitives
				(gr_poly
					(pts
						(arc
							(start -0.1778 -0.2794)
							(mid -0.249642 -0.249642)
							(end -0.2794 -0.1778)
						)
						(arc
							(start -0.2794 0.1778)
							(mid -0.249642 0.249642)
							(end -0.1778 0.2794)
						)
						(arc
							(start 0.1778 0.2794)
							(mid 0.249642 0.249642)
							(end 0.2794 0.1778)
						)
						(arc
							(start 0.2794 -0.1778)
							(mid 0.249642 -0.249642)
							(end 0.1778 -0.2794)
						)
					)
					(width 0)
					(fill yes)
				)
			)
		)
	)
	(footprint ""
		(layer "F.Cu")
		(at 345.985084 -6.500114 180)
		(property "Reference" "CN3"
			(at 0 0 180)
			(layer "F.SilkS")
			(hide yes)
			(effects
				(font
					(size 1.27 1.27)
				)
			)
		)
		(property "Value" "JWT-CONN14A-1-GP"
			(at -9.8298 -4.064 180)
			(unlocked yes)
			(layer "F.Fab")
			(hide yes)
			(effects
				(font
					(size 1.016 1.016)
					(thickness 0.1524)
				)
			)
		)
		(property "Device Type" "A2005WR0-2CX7P-6T"
			(at -9.8298 -5.588 180)
			(unlocked yes)
			(layer "F.Fab")
			(hide yes)
			(effects
				(font
					(size 1.016 1.016)
					(thickness 0.1524)
				)
			)
		)
		(duplicate_pad_numbers_are_jumpers no)
		(fp_line
			(start 8.5852 -0.7366)
			(end 6.8834 -0.7366)
			(stroke
				(width 0.1524)
				(type default)
			)
			(layer "F.SilkS")
		)
		(fp_line
			(start 8.5852 -7.6454)
			(end 8.5852 -0.7366)
			(stroke
				(width 0.1524)
				(type default)
			)
			(layer "F.SilkS")
		)
		(fp_line
			(start 6.8834 1.8796)
			(end -6.8834 1.8796)
			(stroke
				(width 0.1524)
				(type default)
			)
			(layer "F.SilkS")
		)
		(fp_line
			(start 6.8834 -0.7366)
			(end 6.8834 1.8796)
			(stroke
				(width 0.1524)
				(type default)
			)
			(layer "F.SilkS")
		)
		(fp_line
			(start 1.1938 -7.6454)
			(end 1.1938 -7.1374)
			(stroke
				(width 0.1524)
				(type default)
			)
			(layer "F.SilkS")
		)
		(fp_line
			(start -1.1938 -7.1374)
			(end 1.1938 -7.1374)
			(stroke
				(width 0.1524)
				(type default)
			)
			(layer "F.SilkS")
		)
		(fp_line
			(start -1.1938 -7.6454)
			(end -1.1938 -7.1374)
			(stroke
				(width 0.1524)
				(type default)
			)
			(layer "F.SilkS")
		)
		(fp_line
			(start -5.1689 2.0574)
			(end -7.0739 2.0574)
			(stroke
				(width 0.508)
				(type default)
			)
			(layer "F.SilkS")
		)
		(fp_line
			(start -6.8834 1.8796)
			(end -6.8834 -0.7366)
			(stroke
				(width 0.1524)
				(type default)
			)
			(layer "F.SilkS")
		)
		(fp_line
			(start -6.8834 -0.7366)
			(end -8.5852 -0.7366)
			(stroke
				(width 0.1524)
				(type default)
			)
			(layer "F.SilkS")
		)
		(fp_line
			(start -7.0739 2.0574)
			(end -7.0739 0.1524)
			(stroke
				(width 0.508)
				(type default)
			)
			(layer "F.SilkS")
		)
		(fp_line
			(start -8.5852 -0.7366)
			(end -8.5852 -7.6454)
			(stroke
				(width 0.1524)
				(type default)
			)
			(layer "F.SilkS")
		)
		(fp_line
			(start -8.5852 -7.6454)
			(end 8.5852 -7.6454)
			(stroke
				(width 0.1524)
				(type default)
			)
			(layer "F.SilkS")
		)
		(fp_circle
			(center 5.99948 0.99949)
			(end 5.00888 0.99949)
			(stroke
				(width 0.3048)
				(type default)
			)
			(fill no)
			(layer "F.SilkS")
		)
		(fp_circle
			(center 5.99948 -0.99949)
			(end 5.00888 -0.99949)
			(stroke
				(width 0.3048)
				(type default)
			)
			(fill no)
			(layer "F.SilkS")
		)
		(fp_circle
			(center 4.0005 0.99949)
			(end 3.0099 0.99949)
			(stroke
				(width 0.3048)
				(type default)
			)
			(fill no)
			(layer "F.SilkS")
		)
		(fp_circle
			(center 4.0005 -0.99949)
			(end 3.0099 -0.99949)
			(stroke
				(width 0.3048)
				(type default)
			)
			(fill no)
			(layer "F.SilkS")
		)
		(fp_circle
			(center 2.00025 0.99949)
			(end 1.00965 0.99949)
			(stroke
				(width 0.3048)
				(type default)
			)
			(fill no)
			(layer "F.SilkS")
		)
		(fp_circle
			(center 2.00025 -0.99949)
			(end 1.00965 -0.99949)
			(stroke
				(width 0.3048)
				(type default)
			)
			(fill no)
			(layer "F.SilkS")
		)
		(fp_circle
			(center 0 0.99949)
			(end -0.9906 0.99949)
			(stroke
				(width 0.3048)
				(type default)
			)
			(fill no)
			(layer "F.SilkS")
		)
		(fp_circle
			(center 0 -0.99949)
			(end -0.9906 -0.99949)
			(stroke
				(width 0.3048)
				(type default)
			)
			(fill no)
			(layer "F.SilkS")
		)
		(fp_circle
			(center -2.00025 0.99949)
			(end -2.99085 0.99949)
			(stroke
				(width 0.3048)
				(type default)
			)
			(fill no)
			(layer "F.SilkS")
		)
		(fp_circle
			(center -2.00025 -0.99949)
			(end -2.99085 -0.99949)
			(stroke
				(width 0.3048)
				(type default)
			)
			(fill no)
			(layer "F.SilkS")
		)
		(fp_circle
			(center -4.0005 0.99949)
			(end -4.9911 0.99949)
			(stroke
				(width 0.3048)
				(type default)
			)
			(fill no)
			(layer "F.SilkS")
		)
		(fp_circle
			(center -4.0005 -0.99949)
			(end -4.9911 -0.99949)
			(stroke
				(width 0.3048)
				(type default)
			)
			(fill no)
			(layer "F.SilkS")
		)
		(fp_circle
			(center -5.99948 0.99949)
			(end -6.99008 0.99949)
			(stroke
				(width 0.3048)
				(type default)
			)
			(fill no)
			(layer "F.SilkS")
		)
		(fp_circle
			(center -5.99948 -0.99949)
			(end -6.99008 -0.99949)
			(stroke
				(width 0.3048)
				(type default)
			)
			(fill no)
			(layer "F.SilkS")
		)
		(fp_poly
			(pts
				(xy -6.2484 1.2446) (xy 6.2484 1.2446) (xy 6.2484 -0.9906) (xy 8.3312 -0.9906) (xy 8.3312 -7.3914)
				(xy -8.3312 -7.3914) (xy -8.3312 -0.9906) (xy -6.2484 -0.9906)
			)
			(stroke
				(width 0)
				(type default)
			)
			(fill no)
			(layer "F.CrtYd")
		)
		(fp_poly
			(pts
				(xy -7.1374 2.1336) (xy -7.1374 -0.4826) (xy -8.8392 -0.4826) (xy -8.8392 -7.8994) (xy 8.8392 -7.8994)
				(xy 8.8392 -0.4826) (xy 7.1374 -0.4826) (xy 7.1374 -0.00635) (xy 6.2484 -0.00635) (xy 6.2484 -0.9906)
				(xy 8.3312 -0.9906) (xy 8.3312 -7.3914) (xy -8.3312 -7.3914) (xy -8.3312 -0.9906) (xy -6.2484 -0.9906)
				(xy -6.2484 1.2446) (xy 6.2484 1.2446) (xy 6.2484 0.00635) (xy 7.1374 0.00635) (xy 7.1374 2.1336)
			)
			(stroke
				(width 0)
				(type default)
			)
			(fill no)
			(layer "F.CrtYd")
		)
		(fp_poly
			(pts
				(xy -7.1374 2.1336) (xy -7.1374 -0.4826) (xy -8.8392 -0.4826) (xy -8.8392 -7.8994) (xy 8.8392 -7.8994)
				(xy 8.8392 -0.4826) (xy 7.1374 -0.4826) (xy 7.1374 2.1336)
			)
			(stroke
				(width 0)
				(type default)
			)
			(fill no)
			(layer "F.Fab")
		)
		(pad "1" thru_hole circle
			(at -5.99948 0.99949 180)
			(size 1.27 1.27)
			(drill 0.889)
			(layers "*.Cu" "*.Mask")
			(remove_unused_layers no)
			(net "LOW_HEX_0")
			(clearance 0.1651)
			(thermal_gap 0.1651)
		)
		(pad "2" thru_hole circle
			(at -5.99948 -0.99949 180)
			(size 1.27 1.27)
			(drill 0.889)
			(layers "*.Cu" "*.Mask")
			(remove_unused_layers no)
			(net "LOW_HEX_1")
			(clearance 0.1651)
			(thermal_gap 0.1651)
		)
		(pad "3" thru_hole circle
			(at -4.0005 0.99949 180)
			(size 1.27 1.27)
			(drill 0.889)
			(layers "*.Cu" "*.Mask")
			(remove_unused_layers no)
			(net "LOW_HEX_2")
			(clearance 0.1651)
			(thermal_gap 0.1651)
		)
		(pad "4" thru_hole circle
			(at -4.0005 -0.99949 180)
			(size 1.27 1.27)
			(drill 0.889)
			(layers "*.Cu" "*.Mask")
			(remove_unused_layers no)
			(net "LOW_HEX_3")
			(clearance 0.1651)
			(thermal_gap 0.1651)
		)
		(pad "5" thru_hole circle
			(at -2.00025 0.99949 180)
			(size 1.27 1.27)
			(drill 0.889)
			(layers "*.Cu" "*.Mask")
			(remove_unused_layers no)
			(net "HIGH_HEX_0")
			(clearance 0.1651)
			(thermal_gap 0.1651)
		)
		(pad "6" thru_hole circle
			(at -2.00025 -0.99949 180)
			(size 1.27 1.27)
			(drill 0.889)
			(layers "*.Cu" "*.Mask")
			(remove_unused_layers no)
			(net "HIGH_HEX_1")
			(clearance 0.1651)
			(thermal_gap 0.1651)
		)
		(pad "7" thru_hole circle
			(at 0 0.99949 180)
			(size 1.27 1.27)
			(drill 0.889)
			(layers "*.Cu" "*.Mask")
			(remove_unused_layers no)
			(net "HIGH_HEX_2")
			(clearance 0.1651)
			(thermal_gap 0.1651)
		)
		(pad "8" thru_hole circle
			(at 0 -0.99949 180)
			(size 1.27 1.27)
			(drill 0.889)
			(layers "*.Cu" "*.Mask")
			(remove_unused_layers no)
			(net "HIGH_HEX_3")
			(clearance 0.1651)
			(thermal_gap 0.1651)
		)
		(pad "9" thru_hole circle
			(at 2.00025 0.99949 180)
			(size 1.27 1.27)
			(drill 0.889)
			(layers "*.Cu" "*.Mask")
			(remove_unused_layers no)
			(net "DEBUG_CARD_TX")
			(clearance 0.1651)
			(thermal_gap 0.1651)
		)
		(pad "10" thru_hole circle
			(at 2.00025 -0.99949 180)
			(size 1.27 1.27)
			(drill 0.889)
			(layers "*.Cu" "*.Mask")
			(remove_unused_layers no)
			(net "DEBUG_CARD_RX")
			(clearance 0.1651)
			(thermal_gap 0.1651)
		)
		(pad "11" thru_hole circle
			(at 4.0005 0.99949 180)
			(size 1.27 1.27)
			(drill 0.889)
			(layers "*.Cu" "*.Mask")
			(remove_unused_layers no)
			(net "DP_RST_N")
			(clearance 0.1651)
			(thermal_gap 0.1651)
		)
		(pad "12" thru_hole circle
			(at 4.0005 -0.99949 180)
			(size 1.27 1.27)
			(drill 0.889)
			(layers "*.Cu" "*.Mask")
			(remove_unused_layers no)
			(net "UART COUNT")
			(clearance 0.1651)
			(thermal_gap 0.1651)
		)
		(pad "13" thru_hole circle
			(at 5.99948 0.99949 180)
			(size 1.27 1.27)
			(drill 0.889)
			(layers "*.Cu" "*.Mask")
			(remove_unused_layers no)
			(net "GND")
			(clearance 0.1651)
			(thermal_gap 0.1651)
		)
		(pad "14" thru_hole circle
			(at 5.99948 -0.99949 180)
			(size 1.27 1.27)
			(drill 0.889)
			(layers "*.Cu" "*.Mask")
			(remove_unused_layers no)
			(net "P5V_STBY")
			(clearance 0.1651)
			(thermal_gap 0.1651)
		)
	)
	(footprint ""
		(layer "F.Cu")
		(at 346.858336 -76.538328)
		(property "Reference" "SKT3"
			(at 0 0 0)
			(layer "F.SilkS")
			(hide yes)
			(effects
				(font
					(size 1.27 1.27)
				)
			)
		)
		(property "Value" "SKT-SPI16P-GP-U"
			(at -8.9916 4.641596 0)
			(unlocked yes)
			(layer "F.Fab")
			(hide yes)
			(effects
				(font
					(size 1.016 1.016)
					(thickness 0.1524)
				)
			)
		)
		(property "Device Type" "SKT-SOIC16-153139H258"
			(at -8.9916 3.117596 0)
			(unlocked yes)
			(layer "F.Fab")
			(hide yes)
			(effects
				(font
					(size 1.016 1.016)
					(thickness 0.1524)
				)
			)
		)
		(duplicate_pad_numbers_are_jumpers no)
		(fp_line
			(start -7.8994 -6.4008)
			(end -7.8994 6.4008)
			(stroke
				(width 0.1524)
				(type default)
			)
			(layer "F.SilkS")
		)
		(fp_line
			(start -7.8994 6.4008)
			(end 7.8994 6.4008)
			(stroke
				(width 0.1524)
				(type default)
			)
			(layer "F.SilkS")
		)
		(fp_line
			(start 6.7183 0.0762)
			(end 7.8994 1.2573)
			(stroke
				(width 0.1524)
				(type default)
			)
			(layer "F.SilkS")
		)
		(fp_line
			(start 7.7216 -6.223)
			(end 7.7216 -3.6576)
			(stroke
				(width 0.508)
				(type default)
			)
			(layer "F.SilkS")
		)
		(fp_line
			(start 7.8867 -1.0922)
			(end 6.7183 0.0762)
			(stroke
				(width 0.1524)
				(type default)
			)
			(layer "F.SilkS")
		)
		(fp_line
			(start 7.8994 -6.4008)
			(end -7.8994 -6.4008)
			(stroke
				(width 0.1524)
				(type default)
			)
			(layer "F.SilkS")
		)
		(fp_line
			(start 7.8994 6.4008)
			(end 7.8994 -6.4008)
			(stroke
				(width 0.1524)
				(type default)
			)
			(layer "F.SilkS")
		)
		(fp_poly
			(pts
				(xy -4.699 -3.855466) (xy -4.699 3.855466) (xy 4.699 3.855466) (xy 4.699 -3.855466)
			)
			(stroke
				(width 0)
				(type default)
			)
			(fill yes)
			(layer "F.SilkS")
		)
		(fp_rect
			(start -8.1534 -6.4008)
			(end 8.1534 -12.5222)
			(stroke
				(width 0)
				(type default)
			)
			(fill no)
			(layer "F.CrtYd")
		)
		(fp_rect
			(start -8.1534 11.6078)
			(end 8.1534 6.4008)
			(stroke
				(width 0)
				(type default)
			)
			(fill no)
			(layer "F.CrtYd")
		)
		(fp_poly
			(pts
				(xy -8.1534 6.4008) (xy -8.1534 -6.4008) (xy -6.2484 -6.4008) (xy -6.2484 -2.6416) (xy -7.6454 -2.6416)
				(xy -7.6454 2.6416) (xy -6.2484 2.6416) (xy -6.2484 6.4008)
			)
			(stroke
				(width 0)
				(type default)
			)
			(fill no)
			(layer "F.CrtYd")
		)
		(fp_poly
			(pts
				(xy 6.2484 -6.4008) (xy 8.1534 -6.4008) (xy 8.1534 6.4008) (xy 6.2484 6.4008) (xy 6.2484 2.6416)
				(xy 7.6454 2.6416) (xy 7.6454 -2.6416) (xy 6.2484 -2.6416)
			)
			(stroke
				(width 0)
				(type default)
			)
			(fill no)
			(layer "F.CrtYd")
		)
		(fp_poly
			(pts
				(xy 6.2484 -6.4008) (xy -6.2484 -6.4008) (xy -6.2484 -2.6416) (xy -7.6454 -2.6416) (xy -7.6454 2.6416)
				(xy -6.2484 2.6416) (xy -6.2484 6.4008) (xy 6.2484 6.4008) (xy 6.2484 2.6416) (xy 7.6454 2.6416)
				(xy 7.6454 -2.6416) (xy 6.2484 -2.6416)
			)
			(stroke
				(width 0)
				(type default)
			)
			(fill no)
			(layer "F.CrtYd")
		)
		(fp_rect
			(start -8.1534 11.6078)
			(end 8.1534 -12.5222)
			(stroke
				(width 0)
				(type default)
			)
			(fill no)
			(layer "F.Fab")
		)
		(pad "1" smd rect
			(at 4.445 -4.896866)
			(size 0.508 1.6764)
			(layers "F.Cu" "F.Mask" "F.Paste")
			(net "PU_IBMC_BT_HOLD_N")
		)
		(pad "2" smd rect
			(at 3.175 -4.896866)
			(size 0.508 1.6764)
			(layers "F.Cu" "F.Mask" "F.Paste")
			(net "P3V3_STBY")
		)
		(pad "3" smd rect
			(at 1.905 -4.896866)
			(size 0.508 1.6764)
			(layers "F.Cu" "F.Mask" "F.Paste")
			(net "Net_2087")
		)
		(pad "4" smd rect
			(at 0.635 -4.896866)
			(size 0.508 1.6764)
			(layers "F.Cu" "F.Mask" "F.Paste")
			(net "Net_2086")
		)
		(pad "5" smd rect
			(at -0.635 -4.896866)
			(size 0.508 1.6764)
			(layers "F.Cu" "F.Mask" "F.Paste")
			(net "Net_2085")
		)
		(pad "6" smd rect
			(at -1.905 -4.896866)
			(size 0.508 1.6764)
			(layers "F.Cu" "F.Mask" "F.Paste")
			(net "Net_2084")
		)
		(pad "7" smd rect
			(at -3.175 -4.896866)
			(size 0.508 1.6764)
			(layers "F.Cu" "F.Mask" "F.Paste")
			(net "FLA_CS_R")
		)
		(pad "8" smd rect
			(at -4.445 -4.896866)
			(size 0.508 1.6764)
			(layers "F.Cu" "F.Mask" "F.Paste")
			(net "ROMD2_R")
		)
		(pad "9" smd rect
			(at -4.445 4.896866)
			(size 0.508 1.6764)
			(layers "F.Cu" "F.Mask" "F.Paste")
			(net "FLA_WPN")
		)
		(pad "10" smd rect
			(at -3.175 4.896866)
			(size 0.508 1.6764)
			(layers "F.Cu" "F.Mask" "F.Paste")
			(net "GND")
		)
		(pad "11" smd rect
			(at -1.905 4.896866)
			(size 0.508 1.6764)
			(layers "F.Cu" "F.Mask" "F.Paste")
			(net "Net_2091")
		)
		(pad "12" smd rect
			(at -0.635 4.896866)
			(size 0.508 1.6764)
			(layers "F.Cu" "F.Mask" "F.Paste")
			(net "Net_2090")
		)
		(pad "13" smd rect
			(at 0.635 4.896866)
			(size 0.508 1.6764)
			(layers "F.Cu" "F.Mask" "F.Paste")
			(net "Net_2089")
		)
		(pad "14" smd rect
			(at 1.905 4.896866)
			(size 0.508 1.6764)
			(layers "F.Cu" "F.Mask" "F.Paste")
			(net "Net_2088")
		)
		(pad "15" smd rect
			(at 3.175 4.896866)
			(size 0.508 1.6764)
			(layers "F.Cu" "F.Mask" "F.Paste")
			(net "ROMD1_R")
		)
		(pad "16" smd rect
			(at 4.445 4.896866)
			(size 0.508 1.6764)
			(layers "F.Cu" "F.Mask" "F.Paste")
			(net "ROMD0_R")
		)
	)
	(footprint ""
		(layer "F.Cu")
		(at 199.263 -138.811 90)
		(property "Reference" "SR765"
			(at 0 0 90)
			(layer "F.SilkS")
			(hide yes)
			(effects
				(font
					(size 1.27 1.27)
				)
			)
		)
		(property "Value" "4K7R2F-GP"
			(at 0.064008 -3.993896 90)
			(unlocked yes)
			(layer "F.Fab")
			(hide yes)
			(effects
				(font
					(size 1.016 1.016)
					(thickness 0.1524)
				)
			)
		)
		(property "Device Type" "R402H16"
			(at 0.064008 -5.517896 90)
			(unlocked yes)
			(layer "F.Fab")
			(hide yes)
			(effects
				(font
					(size 1.016 1.016)
					(thickness 0.1524)
				)
			)
		)
		(duplicate_pad_numbers_are_jumpers no)
		(fp_line
			(start 0.508 -0.9398)
			(end -0.508 -0.9398)
			(stroke
				(width 0.1524)
				(type default)
			)
			(layer "F.SilkS")
		)
		(fp_line
			(start -0.508 -0.9398)
			(end -0.508 0.9398)
			(stroke
				(width 0.1524)
				(type default)
			)
			(layer "F.SilkS")
		)
		(fp_rect
			(start -0.508 0.9398)
			(end 0.508 -0.9398)
			(stroke
				(width 0)
				(type default)
			)
			(fill no)
			(layer "F.CrtYd")
		)
		(fp_rect
			(start -0.508 0.9398)
			(end 0.508 -0.9398)
			(stroke
				(width 0)
				(type default)
			)
			(fill no)
			(layer "F.Fab")
		)
		(pad "1" smd custom
			(at 0 -0.4445 90)
			(size 0.1397 0.1397)
			(layers "F.Cu" "F.Mask" "F.Paste")
			(net "EXP_EEPROM_A0")
			(options
				(clearance outline)
				(anchor circle)
			)
			(primitives
				(gr_poly
					(pts
						(arc
							(start -0.1778 -0.2794)
							(mid -0.249642 -0.249642)
							(end -0.2794 -0.1778)
						)
						(arc
							(start -0.2794 0.1778)
							(mid -0.249642 0.249642)
							(end -0.1778 0.2794)
						)
						(arc
							(start 0.1778 0.2794)
							(mid 0.249642 0.249642)
							(end 0.2794 0.1778)
						)
						(arc
							(start 0.2794 -0.1778)
							(mid 0.249642 -0.249642)
							(end 0.1778 -0.2794)
						)
					)
					(width 0)
					(fill yes)
				)
			)
		)
		(pad "2" smd custom
			(at 0 0.4445 90)
			(size 0.1397 0.1397)
			(layers "F.Cu" "F.Mask" "F.Paste")
			(net "GND")
			(options
				(clearance outline)
				(anchor circle)
			)
			(primitives
				(gr_poly
					(pts
						(arc
							(start -0.1778 -0.2794)
							(mid -0.249642 -0.249642)
							(end -0.2794 -0.1778)
						)
						(arc
							(start -0.2794 0.1778)
							(mid -0.249642 0.249642)
							(end -0.1778 0.2794)
						)
						(arc
							(start 0.1778 0.2794)
							(mid 0.249642 0.249642)
							(end 0.2794 0.1778)
						)
						(arc
							(start 0.2794 -0.1778)
							(mid 0.249642 -0.249642)
							(end 0.1778 -0.2794)
						)
					)
					(width 0)
					(fill yes)
				)
			)
		)
	)
	(footprint ""
		(layer "F.Cu")
		(at 58.293 -225.806)
		(property "Reference" "R2122"
			(at 0 0 0)
			(layer "F.SilkS")
			(hide yes)
			(effects
				(font
					(size 1.27 1.27)
				)
			)
		)
		(property "Value" "10R2F-L-GP"
			(at 0.064008 -3.993896 0)
			(unlocked yes)
			(layer "F.Fab")
			(hide yes)
			(effects
				(font
					(size 1.016 1.016)
					(thickness 0.1524)
				)
			)
		)
		(property "Device Type" "R402H14"
			(at 0.064008 -5.517896 0)
			(unlocked yes)
			(layer "F.Fab")
			(hide yes)
			(effects
				(font
					(size 1.016 1.016)
					(thickness 0.1524)
				)
			)
		)
		(duplicate_pad_numbers_are_jumpers no)
		(fp_line
			(start -0.508 -0.9398)
			(end -0.508 0.9398)
			(stroke
				(width 0.1524)
				(type default)
			)
			(layer "F.SilkS")
		)
		(fp_line
			(start 0.508 -0.9398)
			(end -0.508 -0.9398)
			(stroke
				(width 0.1524)
				(type default)
			)
			(layer "F.SilkS")
		)
		(fp_rect
			(start -0.508 0.9398)
			(end 0.508 -0.9398)
			(stroke
				(width 0)
				(type default)
			)
			(fill no)
			(layer "F.CrtYd")
		)
		(fp_rect
			(start -0.508 0.9398)
			(end 0.508 -0.9398)
			(stroke
				(width 0)
				(type default)
			)
			(fill no)
			(layer "F.Fab")
		)
		(pad "1" smd custom
			(at 0 -0.4445)
			(size 0.1397 0.1397)
			(layers "F.Cu" "F.Mask" "F.Paste")
			(net "MB0_CM_SENSE_R1_N")
			(options
				(clearance outline)
				(anchor circle)
			)
			(primitives
				(gr_poly
					(pts
						(arc
							(start -0.1778 -0.2794)
							(mid -0.249642 -0.249642)
							(end -0.2794 -0.1778)
						)
						(arc
							(start -0.2794 0.1778)
							(mid -0.249642 0.249642)
							(end -0.1778 0.2794)
						)
						(arc
							(start 0.1778 0.2794)
							(mid 0.249642 0.249642)
							(end 0.2794 0.1778)
						)
						(arc
							(start 0.2794 -0.1778)
							(mid 0.249642 -0.249642)
							(end 0.1778 -0.2794)
						)
					)
					(width 0)
					(fill yes)
				)
			)
		)
		(pad "2" smd custom
			(at 0 0.4445)
			(size 0.1397 0.1397)
			(layers "F.Cu" "F.Mask" "F.Paste")
			(net "MB0_CM_SENSE_N")
			(options
				(clearance outline)
				(anchor circle)
			)
			(primitives
				(gr_poly
					(pts
						(arc
							(start -0.1778 -0.2794)
							(mid -0.249642 -0.249642)
							(end -0.2794 -0.1778)
						)
						(arc
							(start -0.2794 0.1778)
							(mid -0.249642 0.249642)
							(end -0.1778 0.2794)
						)
						(arc
							(start 0.1778 0.2794)
							(mid 0.249642 0.249642)
							(end 0.2794 0.1778)
						)
						(arc
							(start 0.2794 -0.1778)
							(mid 0.249642 -0.249642)
							(end 0.1778 -0.2794)
						)
					)
					(width 0)
					(fill yes)
				)
			)
		)
	)
	(footprint ""
		(layer "F.Cu")
		(at 222.25 -112.395 180)
		(property "Reference" "R605"
			(at 0 0 180)
			(layer "F.SilkS")
			(hide yes)
			(effects
				(font
					(size 1.27 1.27)
				)
			)
		)
		(property "Value" "0R2J-2-GP"
			(at 0.064008 -3.993896 180)
			(unlocked yes)
			(layer "F.Fab")
			(hide yes)
			(effects
				(font
					(size 1.016 1.016)
					(thickness 0.1524)
				)
			)
		)
		(property "Device Type" "R402H16"
			(at 0.064008 -5.517896 180)
			(unlocked yes)
			(layer "F.Fab")
			(hide yes)
			(effects
				(font
					(size 1.016 1.016)
					(thickness 0.1524)
				)
			)
		)
		(duplicate_pad_numbers_are_jumpers no)
		(fp_line
			(start 0.508 -0.9398)
			(end -0.508 -0.9398)
			(stroke
				(width 0.1524)
				(type default)
			)
			(layer "F.SilkS")
		)
		(fp_line
			(start -0.508 -0.9398)
			(end -0.508 0.9398)
			(stroke
				(width 0.1524)
				(type default)
			)
			(layer "F.SilkS")
		)
		(fp_rect
			(start -0.508 0.9398)
			(end 0.508 -0.9398)
			(stroke
				(width 0)
				(type default)
			)
			(fill no)
			(layer "F.CrtYd")
		)
		(fp_rect
			(start -0.508 0.9398)
			(end 0.508 -0.9398)
			(stroke
				(width 0)
				(type default)
			)
			(fill no)
			(layer "F.Fab")
		)
		(pad "1" smd custom
			(at 0 -0.4445 180)
			(size 0.1397 0.1397)
			(layers "F.Cu" "F.Mask" "F.Paste")
			(net "P1V8_C_PG")
			(options
				(clearance outline)
				(anchor circle)
			)
			(primitives
				(gr_poly
					(pts
						(arc
							(start -0.1778 -0.2794)
							(mid -0.249642 -0.249642)
							(end -0.2794 -0.1778)
						)
						(arc
							(start -0.2794 0.1778)
							(mid -0.249642 0.249642)
							(end -0.1778 0.2794)
						)
						(arc
							(start 0.1778 0.2794)
							(mid 0.249642 0.249642)
							(end 0.2794 0.1778)
						)
						(arc
							(start 0.2794 -0.1778)
							(mid 0.249642 -0.249642)
							(end 0.1778 -0.2794)
						)
					)
					(width 0)
					(fill yes)
				)
			)
		)
		(pad "2" smd custom
			(at 0 0.4445 180)
			(size 0.1397 0.1397)
			(layers "F.Cu" "F.Mask" "F.Paste")
			(net "P1V8_PG_R_2")
			(options
				(clearance outline)
				(anchor circle)
			)
			(primitives
				(gr_poly
					(pts
						(arc
							(start -0.1778 -0.2794)
							(mid -0.249642 -0.249642)
							(end -0.2794 -0.1778)
						)
						(arc
							(start -0.2794 0.1778)
							(mid -0.249642 0.249642)
							(end -0.1778 0.2794)
						)
						(arc
							(start 0.1778 0.2794)
							(mid 0.249642 0.249642)
							(end 0.2794 0.1778)
						)
						(arc
							(start 0.2794 -0.1778)
							(mid 0.249642 -0.249642)
							(end 0.1778 -0.2794)
						)
					)
					(width 0)
					(fill yes)
				)
			)
		)
	)
	(footprint ""
		(layer "F.Cu")
		(at 55.89397 -142.24 90)
		(property "Reference" "SR1273"
			(at 0 0 90)
			(layer "F.SilkS")
			(hide yes)
			(effects
				(font
					(size 1.27 1.27)
				)
			)
		)
		(property "Value" "0R2J-2-GP"
			(at 0.064008 -3.993896 90)
			(unlocked yes)
			(layer "F.Fab")
			(hide yes)
			(effects
				(font
					(size 1.016 1.016)
					(thickness 0.1524)
				)
			)
		)
		(property "Device Type" "R402H16"
			(at 0.064008 -5.517896 90)
			(unlocked yes)
			(layer "F.Fab")
			(hide yes)
			(effects
				(font
					(size 1.016 1.016)
					(thickness 0.1524)
				)
			)
		)
		(duplicate_pad_numbers_are_jumpers no)
		(fp_line
			(start 0.508 -0.9398)
			(end -0.508 -0.9398)
			(stroke
				(width 0.1524)
				(type default)
			)
			(layer "F.SilkS")
		)
		(fp_line
			(start -0.508 -0.9398)
			(end -0.508 0.9398)
			(stroke
				(width 0.1524)
				(type default)
			)
			(layer "F.SilkS")
		)
		(fp_rect
			(start -0.508 0.9398)
			(end 0.508 -0.9398)
			(stroke
				(width 0)
				(type default)
			)
			(fill no)
			(layer "F.CrtYd")
		)
		(fp_rect
			(start -0.508 0.9398)
			(end 0.508 -0.9398)
			(stroke
				(width 0)
				(type default)
			)
			(fill no)
			(layer "F.Fab")
		)
		(pad "1" smd custom
			(at 0 -0.4445 90)
			(size 0.1397 0.1397)
			(layers "F.Cu" "F.Mask" "F.Paste")
			(net "RST_BTN_N")
			(options
				(clearance outline)
				(anchor circle)
			)
			(primitives
				(gr_poly
					(pts
						(arc
							(start -0.1778 -0.2794)
							(mid -0.249642 -0.249642)
							(end -0.2794 -0.1778)
						)
						(arc
							(start -0.2794 0.1778)
							(mid -0.249642 0.249642)
							(end -0.1778 0.2794)
						)
						(arc
							(start 0.1778 0.2794)
							(mid 0.249642 0.249642)
							(end 0.2794 0.1778)
						)
						(arc
							(start 0.2794 -0.1778)
							(mid 0.249642 -0.249642)
							(end 0.1778 -0.2794)
						)
					)
					(width 0)
					(fill yes)
				)
			)
		)
		(pad "2" smd custom
			(at 0 0.4445 90)
			(size 0.1397 0.1397)
			(layers "F.Cu" "F.Mask" "F.Paste")
			(net "RST_BTN_R")
			(options
				(clearance outline)
				(anchor circle)
			)
			(primitives
				(gr_poly
					(pts
						(arc
							(start -0.1778 -0.2794)
							(mid -0.249642 -0.249642)
							(end -0.2794 -0.1778)
						)
						(arc
							(start -0.2794 0.1778)
							(mid -0.249642 0.249642)
							(end -0.1778 0.2794)
						)
						(arc
							(start 0.1778 0.2794)
							(mid 0.249642 0.249642)
							(end 0.2794 0.1778)
						)
						(arc
							(start 0.2794 -0.1778)
							(mid 0.249642 -0.249642)
							(end 0.1778 -0.2794)
						)
					)
					(width 0)
					(fill yes)
				)
			)
		)
	)
	(footprint ""
		(layer "F.Cu")
		(at 329.184 -82.423 -90)
		(property "Reference" "JP1"
			(at 0 0 270)
			(layer "F.SilkS")
			(hide yes)
			(effects
				(font
					(size 1.27 1.27)
				)
			)
		)
		(property "Value" "FCI-CON2-S-GP"
			(at 0 -4.2672 270)
			(unlocked yes)
			(layer "F.Fab")
			(hide yes)
			(effects
				(font
					(size 1.016 1.016)
					(thickness 0.1524)
				)
			)
		)
		(property "Device Type" "680001-202HLF"
			(at 0 -5.7912 270)
			(unlocked yes)
			(layer "F.Fab")
			(hide yes)
			(effects
				(font
					(size 1.016 1.016)
					(thickness 0.1524)
				)
			)
		)
		(duplicate_pad_numbers_are_jumpers no)
		(fp_line
			(start -2.794 1.4732)
			(end -2.794 -1.4478)
			(stroke
				(width 0.1524)
				(type default)
			)
			(layer "F.SilkS")
		)
		(fp_line
			(start 2.794 1.4732)
			(end -2.794 1.4732)
			(stroke
				(width 0.1524)
				(type default)
			)
			(layer "F.SilkS")
		)
		(fp_line
			(start -3.0734 -0.7112)
			(end -3.0734 -1.7272)
			(stroke
				(width 0.4064)
				(type default)
			)
			(layer "F.SilkS")
		)
		(fp_line
			(start -2.794 -1.4478)
			(end 2.794 -1.4478)
			(stroke
				(width 0.1524)
				(type default)
			)
			(layer "F.SilkS")
		)
		(fp_line
			(start 2.794 -1.4478)
			(end 2.794 1.4732)
			(stroke
				(width 0.1524)
				(type default)
			)
			(layer "F.SilkS")
		)
		(fp_line
			(start -3.0734 -1.7272)
			(end -2.0574 -1.7272)
			(stroke
				(width 0.4064)
				(type default)
			)
			(layer "F.SilkS")
		)
		(fp_circle
			(center -1.27 0)
			(end -1.27 -1.0668)
			(stroke
				(width 0.3048)
				(type default)
			)
			(fill no)
			(layer "F.SilkS")
		)
		(fp_circle
			(center 1.27 0)
			(end 1.27 -1.0668)
			(stroke
				(width 0.3048)
				(type default)
			)
			(fill no)
			(layer "F.SilkS")
		)
		(fp_rect
			(start -2.54 1.2192)
			(end 2.54 -1.1938)
			(stroke
				(width 0)
				(type default)
			)
			(fill no)
			(layer "F.CrtYd")
		)
		(fp_poly
			(pts
				(xy -3.048 1.7272) (xy -3.048 0.01524) (xy -2.54 0.01524) (xy -2.54 1.2192) (xy 2.54 1.2192) (xy 2.54 -1.1938)
				(xy -2.54 -1.1938) (xy -2.54 0.01016) (xy -3.048 0.01016) (xy -3.048 -1.7018) (xy 3.048 -1.7018)
				(xy 3.048 1.7272)
			)
			(stroke
				(width 0)
				(type default)
			)
			(fill no)
			(layer "F.CrtYd")
		)
		(fp_rect
			(start -3.048 1.7272)
			(end 3.048 -1.7018)
			(stroke
				(width 0)
				(type default)
			)
			(fill no)
			(layer "F.Fab")
		)
		(pad "1" thru_hole circle
			(at -1.27 0 270)
			(size 1.4224 1.4224)
			(drill 1.016)
			(layers "*.Cu" "*.Mask")
			(remove_unused_layers no)
			(net "ROMA0")
			(clearance 0.1524)
			(thermal_gap 0.1524)
		)
		(pad "2" thru_hole circle
			(at 1.27 0 270)
			(size 1.4224 1.4224)
			(drill 1.016)
			(layers "*.Cu" "*.Mask")
			(remove_unused_layers no)
			(net "AS_ROMA0_R")
			(clearance 0.1524)
			(thermal_gap 0.1524)
		)
	)
	(footprint ""
		(layer "F.Cu")
		(at 269.748 -54.61 90)
		(property "Reference" "PR131"
			(at 0 0 90)
			(layer "F.SilkS")
			(hide yes)
			(effects
				(font
					(size 1.27 1.27)
				)
			)
		)
		(property "Value" "0R2J-2-GP"
			(at 0.064008 -3.993896 90)
			(unlocked yes)
			(layer "F.Fab")
			(hide yes)
			(effects
				(font
					(size 1.016 1.016)
					(thickness 0.1524)
				)
			)
		)
		(property "Device Type" "R402H16"
			(at 0.064008 -5.517896 90)
			(unlocked yes)
			(layer "F.Fab")
			(hide yes)
			(effects
				(font
					(size 1.016 1.016)
					(thickness 0.1524)
				)
			)
		)
		(duplicate_pad_numbers_are_jumpers no)
		(fp_line
			(start 0.508 -0.9398)
			(end -0.508 -0.9398)
			(stroke
				(width 0.1524)
				(type default)
			)
			(layer "F.SilkS")
		)
		(fp_line
			(start -0.508 -0.9398)
			(end -0.508 0.9398)
			(stroke
				(width 0.1524)
				(type default)
			)
			(layer "F.SilkS")
		)
		(fp_rect
			(start -0.508 0.9398)
			(end 0.508 -0.9398)
			(stroke
				(width 0)
				(type default)
			)
			(fill no)
			(layer "F.CrtYd")
		)
		(fp_rect
			(start -0.508 0.9398)
			(end 0.508 -0.9398)
			(stroke
				(width 0)
				(type default)
			)
			(fill no)
			(layer "F.Fab")
		)
		(pad "1" smd custom
			(at 0 -0.4445 90)
			(size 0.1397 0.1397)
			(layers "F.Cu" "F.Mask" "F.Paste")
			(net "BMC_EN_P3V3")
			(options
				(clearance outline)
				(anchor circle)
			)
			(primitives
				(gr_poly
					(pts
						(arc
							(start -0.1778 -0.2794)
							(mid -0.249642 -0.249642)
							(end -0.2794 -0.1778)
						)
						(arc
							(start -0.2794 0.1778)
							(mid -0.249642 0.249642)
							(end -0.1778 0.2794)
						)
						(arc
							(start 0.1778 0.2794)
							(mid 0.249642 0.249642)
							(end 0.2794 0.1778)
						)
						(arc
							(start 0.2794 -0.1778)
							(mid 0.249642 -0.249642)
							(end 0.1778 -0.2794)
						)
					)
					(width 0)
					(fill yes)
				)
			)
		)
		(pad "2" smd custom
			(at 0 0.4445 90)
			(size 0.1397 0.1397)
			(layers "F.Cu" "F.Mask" "F.Paste")
			(net "P3V3_EN_B")
			(options
				(clearance outline)
				(anchor circle)
			)
			(primitives
				(gr_poly
					(pts
						(arc
							(start -0.1778 -0.2794)
							(mid -0.249642 -0.249642)
							(end -0.2794 -0.1778)
						)
						(arc
							(start -0.2794 0.1778)
							(mid -0.249642 0.249642)
							(end -0.1778 0.2794)
						)
						(arc
							(start 0.1778 0.2794)
							(mid 0.249642 0.249642)
							(end 0.2794 0.1778)
						)
						(arc
							(start 0.2794 -0.1778)
							(mid 0.249642 -0.249642)
							(end 0.1778 -0.2794)
						)
					)
					(width 0)
					(fill yes)
				)
			)
		)
	)
	(footprint ""
		(layer "F.Cu")
		(at 215.773 -110.363)
		(property "Reference" "PC147"
			(at 0 0 0)
			(layer "F.SilkS")
			(hide yes)
			(effects
				(font
					(size 1.27 1.27)
				)
			)
		)
		(property "Value" "SC470P50V2KX-3GP"
			(at 1.1811 -2.7051 0)
			(unlocked yes)
			(layer "F.Fab")
			(hide yes)
			(effects
				(font
					(size 1.016 1.016)
					(thickness 0.1524)
				)
			)
		)
		(property "Device Type" "C402H22"
			(at 1.1811 -4.2291 0)
			(unlocked yes)
			(layer "F.Fab")
			(hide yes)
			(effects
				(font
					(size 1.016 1.016)
					(thickness 0.1524)
				)
			)
		)
		(duplicate_pad_numbers_are_jumpers no)
		(fp_rect
			(start -0.4318 0.9525)
			(end 0.4318 -0.9525)
			(stroke
				(width 0)
				(type default)
			)
			(fill no)
			(layer "F.CrtYd")
		)
		(fp_rect
			(start -0.4318 0.9525)
			(end 0.4318 -0.9525)
			(stroke
				(width 0)
				(type default)
			)
			(fill no)
			(layer "F.Fab")
		)
		(pad "1" smd custom
			(at 0 -0.4445)
			(size 0.1524 0.1524)
			(layers "F.Cu" "F.Mask" "F.Paste")
			(net "GND")
			(options
				(clearance outline)
				(anchor circle)
			)
			(primitives
				(gr_poly
					(pts
						(arc
							(start 0.3048 -0.2032)
							(mid 0.275042 -0.275042)
							(end 0.2032 -0.3048)
						)
						(arc
							(start -0.2032 -0.3048)
							(mid -0.275042 -0.275042)
							(end -0.3048 -0.2032)
						)
						(arc
							(start -0.3048 0.2032)
							(mid -0.275042 0.275042)
							(end -0.2032 0.3048)
						)
						(arc
							(start 0.2032 0.3048)
							(mid 0.275042 0.275042)
							(end 0.3048 0.2032)
						)
					)
					(width 0)
					(fill yes)
				)
			)
		)
		(pad "2" smd custom
			(at 0 0.4445)
			(size 0.1524 0.1524)
			(layers "F.Cu" "F.Mask" "F.Paste")
			(net "TPS74801_1V5_C_SS")
			(options
				(clearance outline)
				(anchor circle)
			)
			(primitives
				(gr_poly
					(pts
						(arc
							(start 0.3048 -0.2032)
							(mid 0.275042 -0.275042)
							(end 0.2032 -0.3048)
						)
						(arc
							(start -0.2032 -0.3048)
							(mid -0.275042 -0.275042)
							(end -0.3048 -0.2032)
						)
						(arc
							(start -0.3048 0.2032)
							(mid -0.275042 0.275042)
							(end -0.2032 0.3048)
						)
						(arc
							(start 0.2032 0.3048)
							(mid 0.275042 0.275042)
							(end 0.3048 0.2032)
						)
					)
					(width 0)
					(fill yes)
				)
			)
		)
	)
	(footprint ""
		(layer "F.Cu")
		(at 87.122 -17.907)
		(property "Reference" "PC193"
			(at 0 0 0)
			(layer "F.SilkS")
			(hide yes)
			(effects
				(font
					(size 1.27 1.27)
				)
			)
		)
		(property "Value" "SC1U50V3KX-GP"
			(at 0 -2.8194 0)
			(unlocked yes)
			(layer "F.Fab")
			(hide yes)
			(effects
				(font
					(size 1.016 1.016)
					(thickness 0.1524)
				)
			)
		)
		(property "Device Type" "C603H32"
			(at 0 -4.3434 0)
			(unlocked yes)
			(layer "F.Fab")
			(hide yes)
			(effects
				(font
					(size 1.016 1.016)
					(thickness 0.1524)
				)
			)
		)
		(duplicate_pad_numbers_are_jumpers no)
		(fp_line
			(start 0.508 0)
			(end -0.508 0)
			(stroke
				(width 0.2032)
				(type default)
			)
			(layer "F.SilkS")
		)
		(fp_rect
			(start -0.5842 1.3335)
			(end 0.5842 -1.3335)
			(stroke
				(width 0)
				(type default)
			)
			(fill no)
			(layer "F.CrtYd")
		)
		(fp_rect
			(start -0.5842 1.3335)
			(end 0.5842 -1.3335)
			(stroke
				(width 0)
				(type default)
			)
			(fill no)
			(layer "F.Fab")
		)
		(pad "1" smd custom
			(at 0 -0.762)
			(size 0.2159 0.2159)
			(layers "F.Cu" "F.Mask" "F.Paste")
			(net "VT235_BST")
			(options
				(clearance outline)
				(anchor circle)
			)
			(primitives
				(gr_poly
					(pts
						(arc
							(start -0.3302 -0.4318)
							(mid -0.402042 -0.402042)
							(end -0.4318 -0.3302)
						)
						(arc
							(start -0.4318 0.3302)
							(mid -0.402042 0.402042)
							(end -0.3302 0.4318)
						)
						(arc
							(start 0.3302 0.4318)
							(mid 0.402042 0.402042)
							(end 0.4318 0.3302)
						)
						(arc
							(start 0.4318 -0.3302)
							(mid 0.402042 -0.402042)
							(end 0.3302 -0.4318)
						)
					)
					(width 0)
					(fill yes)
				)
			)
		)
		(pad "2" smd custom
			(at 0 0.762)
			(size 0.2159 0.2159)
			(layers "F.Cu" "F.Mask" "F.Paste")
			(net "VT235_VX")
			(options
				(clearance outline)
				(anchor circle)
			)
			(primitives
				(gr_poly
					(pts
						(arc
							(start -0.3302 -0.4318)
							(mid -0.402042 -0.402042)
							(end -0.4318 -0.3302)
						)
						(arc
							(start -0.4318 0.3302)
							(mid -0.402042 0.402042)
							(end -0.3302 0.4318)
						)
						(arc
							(start 0.3302 0.4318)
							(mid 0.402042 0.402042)
							(end 0.4318 0.3302)
						)
						(arc
							(start 0.4318 -0.3302)
							(mid 0.402042 -0.402042)
							(end 0.3302 -0.4318)
						)
					)
					(width 0)
					(fill yes)
				)
			)
		)
	)
	(footprint ""
		(layer "F.Cu")
		(at 204.089 -218.567 90)
		(property "Reference" "C82"
			(at 0 0 90)
			(layer "F.SilkS")
			(hide yes)
			(effects
				(font
					(size 1.27 1.27)
				)
			)
		)
		(property "Value" "SCD1U16V2KX-3GP"
			(at 1.1811 -2.7051 90)
			(unlocked yes)
			(layer "F.Fab")
			(hide yes)
			(effects
				(font
					(size 1.016 1.016)
					(thickness 0.1524)
				)
			)
		)
		(property "Device Type" "C402H22"
			(at 1.1811 -4.2291 90)
			(unlocked yes)
			(layer "F.Fab")
			(hide yes)
			(effects
				(font
					(size 1.016 1.016)
					(thickness 0.1524)
				)
			)
		)
		(duplicate_pad_numbers_are_jumpers no)
		(fp_rect
			(start -0.4318 0.9525)
			(end 0.4318 -0.9525)
			(stroke
				(width 0)
				(type default)
			)
			(fill no)
			(layer "F.CrtYd")
		)
		(fp_rect
			(start -0.4318 0.9525)
			(end 0.4318 -0.9525)
			(stroke
				(width 0)
				(type default)
			)
			(fill no)
			(layer "F.Fab")
		)
		(pad "1" smd custom
			(at 0 -0.4445 90)
			(size 0.1524 0.1524)
			(layers "F.Cu" "F.Mask" "F.Paste")
			(net "P3V3_STBY")
			(options
				(clearance outline)
				(anchor circle)
			)
			(primitives
				(gr_poly
					(pts
						(arc
							(start 0.3048 -0.2032)
							(mid 0.275042 -0.275042)
							(end 0.2032 -0.3048)
						)
						(arc
							(start -0.2032 -0.3048)
							(mid -0.275042 -0.275042)
							(end -0.3048 -0.2032)
						)
						(arc
							(start -0.3048 0.2032)
							(mid -0.275042 0.275042)
							(end -0.2032 0.3048)
						)
						(arc
							(start 0.2032 0.3048)
							(mid 0.275042 0.275042)
							(end 0.3048 0.2032)
						)
					)
					(width 0)
					(fill yes)
				)
			)
		)
		(pad "2" smd custom
			(at 0 0.4445 90)
			(size 0.1524 0.1524)
			(layers "F.Cu" "F.Mask" "F.Paste")
			(net "GND")
			(options
				(clearance outline)
				(anchor circle)
			)
			(primitives
				(gr_poly
					(pts
						(arc
							(start 0.3048 -0.2032)
							(mid 0.275042 -0.275042)
							(end 0.2032 -0.3048)
						)
						(arc
							(start -0.2032 -0.3048)
							(mid -0.275042 -0.275042)
							(end -0.3048 -0.2032)
						)
						(arc
							(start -0.3048 0.2032)
							(mid -0.275042 0.275042)
							(end -0.2032 0.3048)
						)
						(arc
							(start 0.2032 0.3048)
							(mid 0.275042 0.275042)
							(end 0.3048 0.2032)
						)
					)
					(width 0)
					(fill yes)
				)
			)
		)
	)
	(footprint ""
		(layer "F.Cu")
		(at 170.561 -133.096 -90)
		(property "Reference" "PL8"
			(at 0 0 270)
			(layer "F.SilkS")
			(hide yes)
			(effects
				(font
					(size 1.27 1.27)
				)
			)
		)
		(property "Value" "BLM41PG600-GP"
			(at -3.690874 -7.441184 270)
			(unlocked yes)
			(layer "F.Fab")
			(hide yes)
			(effects
				(font
					(size 1.016 1.016)
					(thickness 0.1524)
				)
			)
		)
		(property "Device Type" "L451616H71"
			(at -3.690874 -5.917184 270)
			(unlocked yes)
			(layer "F.Fab")
			(hide yes)
			(effects
				(font
					(size 1.016 1.016)
					(thickness 0.1524)
				)
			)
		)
		(duplicate_pad_numbers_are_jumpers no)
		(fp_line
			(start -2.8702 1.2954)
			(end 2.8702 1.2954)
			(stroke
				(width 0.1524)
				(type default)
			)
			(layer "F.SilkS")
		)
		(fp_line
			(start -2.8702 1.2954)
			(end 2.8702 1.2954)
			(stroke
				(width 0.1524)
				(type default)
			)
			(layer "F.SilkS")
		)
		(fp_line
			(start 2.8702 1.2954)
			(end 2.8702 -1.2954)
			(stroke
				(width 0.1524)
				(type default)
			)
			(layer "F.SilkS")
		)
		(fp_line
			(start 2.8702 1.2954)
			(end 2.8702 -1.2954)
			(stroke
				(width 0.1524)
				(type default)
			)
			(layer "F.SilkS")
		)
		(fp_line
			(start -2.8702 -1.2954)
			(end -2.8702 1.2954)
			(stroke
				(width 0.1524)
				(type default)
			)
			(layer "F.SilkS")
		)
		(fp_line
			(start -2.8702 -1.2954)
			(end -2.8702 1.2954)
			(stroke
				(width 0.1524)
				(type default)
			)
			(layer "F.SilkS")
		)
		(fp_line
			(start 2.8702 -1.2954)
			(end -2.8702 -1.2954)
			(stroke
				(width 0.1524)
				(type default)
			)
			(layer "F.SilkS")
		)
		(fp_line
			(start 2.8702 -1.2954)
			(end -2.8702 -1.2954)
			(stroke
				(width 0.1524)
				(type default)
			)
			(layer "F.SilkS")
		)
		(fp_poly
			(pts
				(xy -2.8702 1.2954) (xy 2.8702 1.2954) (xy 2.8702 -1.2954) (xy -2.8702 -1.2954)
			)
			(stroke
				(width 0)
				(type default)
			)
			(fill no)
			(layer "F.CrtYd")
		)
		(fp_poly
			(pts
				(xy -2.8702 1.2954) (xy 2.8702 1.2954) (xy 2.8702 -1.2954) (xy -2.8702 -1.2954)
			)
			(stroke
				(width 0)
				(type default)
			)
			(fill no)
			(layer "F.Fab")
		)
		(pad "1" smd rect
			(at -1.9685 0 270)
			(size 1.3716 1.8796)
			(layers "F.Cu" "F.Mask" "F.Paste")
			(net "P12V")
		)
		(pad "2" smd rect
			(at 1.9685 0 270)
			(size 1.3716 1.8796)
			(layers "F.Cu" "F.Mask" "F.Paste")
			(net "P0V9_E_VIN")
		)
	)
	(footprint ""
		(layer "F.Cu")
		(at 293.234872 -175.840136 180)
		(property "Reference" "U40"
			(at 0 0 180)
			(layer "F.SilkS")
			(hide yes)
			(effects
				(font
					(size 1.27 1.27)
				)
			)
		)
		(property "Value" "AST1250A1-GP"
			(at -17.7292 -6.184392 180)
			(unlocked yes)
			(layer "F.Fab")
			(hide yes)
			(effects
				(font
					(size 1.016 1.016)
					(thickness 0.1524)
				)
			)
		)
		(property "Device Type" "BGA408D19H52"
			(at -17.7292 -7.708392 180)
			(unlocked yes)
			(layer "F.Fab")
			(hide yes)
			(effects
				(font
					(size 1.016 1.016)
					(thickness 0.1524)
				)
			)
		)
		(duplicate_pad_numbers_are_jumpers no)
		(fp_line
			(start 9.500108 9.500108)
			(end 9.500108 -9.500108)
			(stroke
				(width 0.1524)
				(type default)
			)
			(layer "F.SilkS")
		)
		(fp_line
			(start 9.500108 -9.500108)
			(end -9.500108 -9.500108)
			(stroke
				(width 0.1524)
				(type default)
			)
			(layer "F.SilkS")
		)
		(fp_line
			(start -9.500108 9.500108)
			(end 9.500108 9.500108)
			(stroke
				(width 0.1524)
				(type default)
			)
			(layer "F.SilkS")
		)
		(fp_line
			(start -9.500108 -9.500108)
			(end -9.500108 9.500108)
			(stroke
				(width 0.1524)
				(type default)
			)
			(layer "F.SilkS")
		)
		(fp_line
			(start -9.830308 -8.230108)
			(end -9.830308 -9.830308)
			(stroke
				(width 0.508)
				(type default)
			)
			(layer "F.SilkS")
		)
		(fp_line
			(start -9.830308 -9.830308)
			(end -8.230108 -9.830308)
			(stroke
				(width 0.508)
				(type default)
			)
			(layer "F.SilkS")
		)
		(fp_rect
			(start -9.500108 9.500108)
			(end 9.500108 -9.500108)
			(stroke
				(width 0)
				(type default)
			)
			(fill no)
			(layer "F.CrtYd")
		)
		(fp_poly
			(pts
				(xy 10.500106 -9.500108) (xy -9.500108 -9.500108) (xy -9.500108 9.500108) (xy 9.500108 9.500108)
				(xy 9.500108 -9.487408) (xy 10.500106 -9.487408) (xy 10.500106 10.500106) (xy -10.500106 10.500106)
				(xy -10.500106 -10.500106) (xy 10.500106 -10.500106)
			)
			(stroke
				(width 0)
				(type default)
			)
			(fill no)
			(layer "F.CrtYd")
		)
		(fp_rect
			(start -11.500104 11.500104)
			(end 11.500104 -11.500104)
			(stroke
				(width 0)
				(type default)
			)
			(fill no)
			(layer "F.Fab")
		)
		(pad "A1" smd circle
			(at -8.400034 -8.400034 180)
			(size 0.4064 0.4064)
			(layers "F.Cu" "F.Mask" "F.Paste")
			(net "PU_BMC0_SDA13")
		)
		(pad "A2" smd circle
			(at -7.599934 -8.400034 180)
			(size 0.4064 0.4064)
			(layers "F.Cu" "F.Mask" "F.Paste")
			(net "PU_BMC0_SCL11")
		)
		(pad "A3" smd circle
			(at -6.800088 -8.400034 180)
			(size 0.4064 0.4064)
			(layers "F.Cu" "F.Mask" "F.Paste")
			(net "TP_BMC_GPIOA6")
		)
		(pad "A4" smd circle
			(at -5.999988 -8.400034 180)
			(size 0.3556 0.3556)
			(layers "F.Cu" "F.Mask" "F.Paste")
			(net "DP_BMC_CPU_RST_N_R")
		)
		(pad "A5" smd circle
			(at -5.199888 -8.400034 180)
			(size 0.3556 0.3556)
			(layers "F.Cu" "F.Mask" "F.Paste")
			(net "RMII_BMC_MDIO")
		)
		(pad "A6" smd circle
			(at -4.400042 -8.400034 180)
			(size 0.3556 0.3556)
			(layers "F.Cu" "F.Mask" "F.Paste")
			(net "TP_GPIOH6")
		)
		(pad "A7" smd circle
			(at -3.599942 -8.400034 180)
			(size 0.3556 0.3556)
			(layers "F.Cu" "F.Mask" "F.Paste")
			(net "TP_GPIOH3")
		)
		(pad "A8" smd circle
			(at -2.800096 -8.400034 180)
			(size 0.3556 0.3556)
			(layers "F.Cu" "F.Mask" "F.Paste")
			(net "Net_1333")
		)
		(pad "A9" smd circle
			(at -1.999996 -8.400034 180)
			(size 0.3556 0.3556)
			(layers "F.Cu" "F.Mask" "F.Paste")
			(net "NCSI_10G_RXD0")
		)
		(pad "A10" smd circle
			(at -1.199896 -8.400034 180)
			(size 0.3556 0.3556)
			(layers "F.Cu" "F.Mask" "F.Paste")
			(net "NCSI_10G_TXD0")
		)
		(pad "A11" smd circle
			(at -0.40005 -8.400034 180)
			(size 0.3556 0.3556)
			(layers "F.Cu" "F.Mask" "F.Paste")
			(net "RMII0_BMC_C_CRS_DV")
		)
		(pad "A12" smd circle
			(at 0.40005 -8.400034 180)
			(size 0.3556 0.3556)
			(layers "F.Cu" "F.Mask" "F.Paste")
			(net "RMII0_BMC_C_TX_EN")
		)
		(pad "A13" smd circle
			(at 1.199896 -8.400034 180)
			(size 0.3556 0.3556)
			(layers "F.Cu" "F.Mask" "F.Paste")
			(net "GND")
		)
		(pad "A14" smd circle
			(at 1.999996 -8.400034 180)
			(size 0.3556 0.3556)
			(layers "F.Cu" "F.Mask" "F.Paste")
			(net "HIGH_HEX_0")
		)
		(pad "A15" smd circle
			(at 2.800096 -8.400034 180)
			(size 0.3556 0.3556)
			(layers "F.Cu" "F.Mask" "F.Paste")
			(net "TP_BMC_GPIOE3")
		)
		(pad "A16" smd circle
			(at 3.599942 -8.400034 180)
			(size 0.3556 0.3556)
			(layers "F.Cu" "F.Mask" "F.Paste")
			(net "BMC_LSI_BOARD")
		)
		(pad "A17" smd circle
			(at 4.400042 -8.400034 180)
			(size 0.3556 0.3556)
			(layers "F.Cu" "F.Mask" "F.Paste")
			(net "BMC_PWRBTN_N_R")
		)
		(pad "A18" smd circle
			(at 5.199888 -8.400034 180)
			(size 0.3556 0.3556)
			(layers "F.Cu" "F.Mask" "F.Paste")
			(net "SYS_RSTBTN_N_R")
		)
		(pad "A19" smd circle
			(at 5.999988 -8.400034 180)
			(size 0.3556 0.3556)
			(layers "F.Cu" "F.Mask" "F.Paste")
			(net "TP_BMC_GPIOF5")
		)
		(pad "A20" smd circle
			(at 6.800088 -8.400034 180)
			(size 0.4064 0.4064)
			(layers "F.Cu" "F.Mask" "F.Paste")
			(net "TP_BMC_GPIOF2")
		)
		(pad "A21" smd circle
			(at 7.599934 -8.400034 180)
			(size 0.4064 0.4064)
			(layers "F.Cu" "F.Mask" "F.Paste")
			(net "TP_LPC_CPU_FRAME_N")
		)
		(pad "A22" smd circle
			(at 8.400034 -8.400034 180)
			(size 0.4064 0.4064)
			(layers "F.Cu" "F.Mask" "F.Paste")
			(net "TP_BMC0_LPC_LAD1")
		)
		(pad "AA1" smd circle
			(at -8.400034 7.599934 180)
			(size 0.4064 0.4064)
			(layers "F.Cu" "F.Mask" "F.Paste")
			(net "TP_BMC_GPIOM6")
		)
		(pad "AA2" smd circle
			(at -7.599934 7.599934 180)
			(size 0.4064 0.4064)
			(layers "F.Cu" "F.Mask" "F.Paste")
			(net "BMC0_LED_DR_R_LED1")
		)
		(pad "AA3" smd circle
			(at -6.800088 7.599934 180)
			(size 0.4064 0.4064)
			(layers "F.Cu" "F.Mask" "F.Paste")
			(net "BMC_FW_DET_BOARD_VER_1")
		)
		(pad "AA4" smd circle
			(at -5.999988 7.599934 180)
			(size 0.3556 0.3556)
			(layers "F.Cu" "F.Mask" "F.Paste")
			(net "HB0_R_IN2")
		)
		(pad "AA5" smd circle
			(at -5.199888 7.599934 180)
			(size 0.3556 0.3556)
			(layers "F.Cu" "F.Mask" "F.Paste")
			(net "CONN_10G_PRSNT2_N")
		)
		(pad "AA6" smd circle
			(at -4.400042 7.599934 180)
			(size 0.3556 0.3556)
			(layers "F.Cu" "F.Mask" "F.Paste")
			(net "BMC0_TACH11")
		)
		(pad "AA7" smd circle
			(at -3.599942 7.599934 180)
			(size 0.3556 0.3556)
			(layers "F.Cu" "F.Mask" "F.Paste")
			(net "BMC0_TACH14")
		)
		(pad "AA8" smd circle
			(at -2.800096 7.599934 180)
			(size 0.3556 0.3556)
			(layers "F.Cu" "F.Mask" "F.Paste")
			(net "MEMDQS_P1")
		)
		(pad "AA9" smd circle
			(at -1.999996 7.599934 180)
			(size 0.3556 0.3556)
			(layers "F.Cu" "F.Mask" "F.Paste")
			(net "MEMDQ_10")
		)
		(pad "AA10" smd circle
			(at -1.199896 7.599934 180)
			(size 0.3556 0.3556)
			(layers "F.Cu" "F.Mask" "F.Paste")
			(net "MEMDQS_N0")
		)
		(pad "AA11" smd circle
			(at -0.40005 7.599934 180)
			(size 0.3556 0.3556)
			(layers "F.Cu" "F.Mask" "F.Paste")
			(net "MEMDQ_3")
		)
		(pad "AA12" smd circle
			(at 0.40005 7.599934 180)
			(size 0.3556 0.3556)
			(layers "F.Cu" "F.Mask" "F.Paste")
			(net "MEMCK_N")
		)
		(pad "AA13" smd circle
			(at 1.199896 7.599934 180)
			(size 0.3556 0.3556)
			(layers "F.Cu" "F.Mask" "F.Paste")
			(net "MEMCSN")
		)
		(pad "AA14" smd circle
			(at 1.999996 7.599934 180)
			(size 0.3556 0.3556)
			(layers "F.Cu" "F.Mask" "F.Paste")
			(net "MEMBA_1")
		)
		(pad "AA15" smd circle
			(at 2.800096 7.599934 180)
			(size 0.3556 0.3556)
			(layers "F.Cu" "F.Mask" "F.Paste")
			(net "MEMA_6")
		)
		(pad "AA16" smd circle
			(at 3.599942 7.599934 180)
			(size 0.3556 0.3556)
			(layers "F.Cu" "F.Mask" "F.Paste")
			(net "MEMA_11")
		)
		(pad "AA17" smd circle
			(at 4.400042 7.599934 180)
			(size 0.3556 0.3556)
			(layers "F.Cu" "F.Mask" "F.Paste")
			(net "MEMA_9")
		)
		(pad "AA18" smd circle
			(at 5.199888 7.599934 180)
			(size 0.3556 0.3556)
			(layers "F.Cu" "F.Mask" "F.Paste")
			(net "GND")
		)
		(pad "AA19" smd circle
			(at 5.999988 7.599934 180)
			(size 0.3556 0.3556)
			(layers "F.Cu" "F.Mask" "F.Paste")
			(net "GND")
		)
		(pad "AA20" smd circle
			(at 6.800088 7.599934 180)
			(size 0.4064 0.4064)
			(layers "F.Cu" "F.Mask" "F.Paste")
			(net "PD_USB2VRES")
		)
		(pad "AA21" smd circle
			(at 7.599934 7.599934 180)
			(size 0.4064 0.4064)
			(layers "F.Cu" "F.Mask" "F.Paste")
			(net "PECI0_R")
		)
		(pad "AA22" smd circle
			(at 8.400034 7.599934 180)
			(size 0.4064 0.4064)
			(layers "F.Cu" "F.Mask" "F.Paste")
			(net "DP_RST_N_R")
		)
		(pad "AB1" smd circle
			(at -8.400034 8.400034 180)
			(size 0.4064 0.4064)
			(layers "F.Cu" "F.Mask" "F.Paste")
			(net "BMC0_LED_DR_R_LED0")
		)
		(pad "AB2" smd circle
			(at -7.599934 8.400034 180)
			(size 0.4064 0.4064)
			(layers "F.Cu" "F.Mask" "F.Paste")
			(net "BMC_FW_DET_BOARD_VER_2")
		)
		(pad "AB3" smd circle
			(at -6.800088 8.400034 180)
			(size 0.4064 0.4064)
			(layers "F.Cu" "F.Mask" "F.Paste")
			(net "HB_OUT_BMC")
		)
		(pad "AB4" smd circle
			(at -5.999988 8.400034 180)
			(size 0.3556 0.3556)
			(layers "F.Cu" "F.Mask" "F.Paste")
			(net "BMC_EN_CPU_RESET_CONTROL")
		)
		(pad "AB5" smd circle
			(at -5.199888 8.400034 180)
			(size 0.3556 0.3556)
			(layers "F.Cu" "F.Mask" "F.Paste")
			(net "BMC0_TACH9")
		)
		(pad "AB6" smd circle
			(at -4.400042 8.400034 180)
			(size 0.3556 0.3556)
			(layers "F.Cu" "F.Mask" "F.Paste")
			(net "BMC0_TACH12")
		)
		(pad "AB7" smd circle
			(at -3.599942 8.400034 180)
			(size 0.3556 0.3556)
			(layers "F.Cu" "F.Mask" "F.Paste")
			(net "BMC0_TACH15")
		)
		(pad "AB8" smd circle
			(at -2.800096 8.400034 180)
			(size 0.3556 0.3556)
			(layers "F.Cu" "F.Mask" "F.Paste")
			(net "MEMDQS_N1")
		)
		(pad "AB9" smd circle
			(at -1.999996 8.400034 180)
			(size 0.3556 0.3556)
			(layers "F.Cu" "F.Mask" "F.Paste")
			(net "MEMDQ_9")
		)
		(pad "AB10" smd circle
			(at -1.199896 8.400034 180)
			(size 0.3556 0.3556)
			(layers "F.Cu" "F.Mask" "F.Paste")
			(net "MEMDQS_P0")
		)
		(pad "AB11" smd circle
			(at -0.40005 8.400034 180)
			(size 0.3556 0.3556)
			(layers "F.Cu" "F.Mask" "F.Paste")
			(net "MEMDQ_2")
		)
		(pad "AB12" smd circle
			(at 0.40005 8.400034 180)
			(size 0.3556 0.3556)
			(layers "F.Cu" "F.Mask" "F.Paste")
			(net "MEMCK_P")
		)
		(pad "AB13" smd circle
			(at 1.199896 8.400034 180)
			(size 0.3556 0.3556)
			(layers "F.Cu" "F.Mask" "F.Paste")
			(net "MEMCASN")
		)
		(pad "AB14" smd circle
			(at 1.999996 8.400034 180)
			(size 0.3556 0.3556)
			(layers "F.Cu" "F.Mask" "F.Paste")
			(net "MEMA_0")
		)
		(pad "AB15" smd circle
			(at 2.800096 8.400034 180)
			(size 0.3556 0.3556)
			(layers "F.Cu" "F.Mask" "F.Paste")
			(net "MEMA_4")
		)
		(pad "AB16" smd circle
			(at 3.599942 8.400034 180)
			(size 0.3556 0.3556)
			(layers "F.Cu" "F.Mask" "F.Paste")
			(net "MEMA_8")
		)
		(pad "AB17" smd circle
			(at 4.400042 8.400034 180)
			(size 0.3556 0.3556)
			(layers "F.Cu" "F.Mask" "F.Paste")
			(net "MEMA_14")
		)
		(pad "AB18" smd circle
			(at 5.199888 8.400034 180)
			(size 0.3556 0.3556)
			(layers "F.Cu" "F.Mask" "F.Paste")
			(net "MEMA_7")
		)
		(pad "AB19" smd circle
			(at 5.999988 8.400034 180)
			(size 0.3556 0.3556)
			(layers "F.Cu" "F.Mask" "F.Paste")
			(net "MPLLAV33")
		)
		(pad "AB20" smd circle
			(at 6.800088 8.400034 180)
			(size 0.4064 0.4064)
			(layers "F.Cu" "F.Mask" "F.Paste")
			(net "BMC_USB2_HDN")
		)
		(pad "AB21" smd circle
			(at 7.599934 8.400034 180)
			(size 0.4064 0.4064)
			(layers "F.Cu" "F.Mask" "F.Paste")
			(net "BMC_USB2_HDP")
		)
		(pad "AB22" smd circle
			(at 8.400034 8.400034 180)
			(size 0.4064 0.4064)
			(layers "F.Cu" "F.Mask" "F.Paste")
			(net "OSC0_AS_CLKIN")
		)
		(pad "B1" smd circle
			(at -8.400034 -7.599934 180)
			(size 0.4064 0.4064)
			(layers "F.Cu" "F.Mask" "F.Paste")
			(net "BMC0_SMB4_CLK")
		)
		(pad "B2" smd circle
			(at -7.599934 -7.599934 180)
			(size 0.4064 0.4064)
			(layers "F.Cu" "F.Mask" "F.Paste")
			(net "PU_BMC0_SCL13")
		)
		(pad "B3" smd circle
			(at -6.800088 -7.599934 180)
			(size 0.4064 0.4064)
			(layers "F.Cu" "F.Mask" "F.Paste")
			(net "BMC0_SMB10_DAT")
		)
		(pad "B4" smd circle
			(at -5.999988 -7.599934 180)
			(size 0.3556 0.3556)
			(layers "F.Cu" "F.Mask" "F.Paste")
			(net "BMC0_SMB9_DAT")
		)
		(pad "B5" smd circle
			(at -5.199888 -7.599934 180)
			(size 0.3556 0.3556)
			(layers "F.Cu" "F.Mask" "F.Paste")
			(net "BMC_JTAG_L_EN_R")
		)
		(pad "B6" smd circle
			(at -4.400042 -7.599934 180)
			(size 0.3556 0.3556)
			(layers "F.Cu" "F.Mask" "F.Paste")
			(net "TP_GPIOH5")
		)
		(pad "B7" smd circle
			(at -3.599942 -7.599934 180)
			(size 0.3556 0.3556)
			(layers "F.Cu" "F.Mask" "F.Paste")
			(net "TP_GPIOH2")
		)
		(pad "B8" smd circle
			(at -2.800096 -7.599934 180)
			(size 0.3556 0.3556)
			(layers "F.Cu" "F.Mask" "F.Paste")
			(net "BMC_MAC2_RGMIICK")
		)
		(pad "B9" smd circle
			(at -1.999996 -7.599934 180)
			(size 0.3556 0.3556)
			(layers "F.Cu" "F.Mask" "F.Paste")
			(net "TP_BMC_GPIOV3")
		)
		(pad "B10" smd circle
			(at -1.199896 -7.599934 180)
			(size 0.3556 0.3556)
			(layers "F.Cu" "F.Mask" "F.Paste")
			(net "NCSI_10G_TXD1")
		)
		(pad "B11" smd circle
			(at -0.40005 -7.599934 180)
			(size 0.3556 0.3556)
			(layers "F.Cu" "F.Mask" "F.Paste")
			(net "RMII0_PHY_BMC_C_RXD1")
		)
		(pad "B12" smd circle
			(at 0.40005 -7.599934 180)
			(size 0.3556 0.3556)
			(layers "F.Cu" "F.Mask" "F.Paste")
			(net "GND")
		)
		(pad "B13" smd circle
			(at 1.199896 -7.599934 180)
			(size 0.3556 0.3556)
			(layers "F.Cu" "F.Mask" "F.Paste")
			(net "HDD_PRE_INT_R")
		)
		(pad "B14" smd circle
			(at 1.999996 -7.599934 180)
			(size 0.3556 0.3556)
			(layers "F.Cu" "F.Mask" "F.Paste")
			(net "BMC_RXD1")
		)
		(pad "B15" smd circle
			(at 2.800096 -7.599934 180)
			(size 0.3556 0.3556)
			(layers "F.Cu" "F.Mask" "F.Paste")
			(net "TP_BMC_GPIOE2")
		)
		(pad "B16" smd circle
			(at 3.599942 -7.599934 180)
			(size 0.3556 0.3556)
			(layers "F.Cu" "F.Mask" "F.Paste")
			(net "FM_BMC_READY_N_R")
		)
		(pad "B17" smd circle
			(at 4.400042 -7.599934 180)
			(size 0.3556 0.3556)
			(layers "F.Cu" "F.Mask" "F.Paste")
			(net "SYS_PWRBTN_N_R")
		)
		(pad "B18" smd circle
			(at 5.199888 -7.599934 180)
			(size 0.3556 0.3556)
			(layers "F.Cu" "F.Mask" "F.Paste")
			(net "TP_BMC_GPIOF4")
		)
		(pad "B19" smd circle
			(at 5.999988 -7.599934 180)
			(size 0.3556 0.3556)
			(layers "F.Cu" "F.Mask" "F.Paste")
			(net "TP_BMC_GPIOF1")
		)
		(pad "B20" smd circle
			(at 6.800088 -7.599934 180)
			(size 0.4064 0.4064)
			(layers "F.Cu" "F.Mask" "F.Paste")
			(net "TP_LPC_CPU_CLKOUT0")
		)
		(pad "B21" smd circle
			(at 7.599934 -7.599934 180)
			(size 0.4064 0.4064)
			(layers "F.Cu" "F.Mask" "F.Paste")
			(net "TP_BMC0_LPC_LAD0")
		)
		(pad "B22" smd circle
			(at 8.400034 -7.599934 180)
			(size 0.4064 0.4064)
			(layers "F.Cu" "F.Mask" "F.Paste")
			(net "BMC_EN_P3V3_R")
		)
		(pad "C1" smd circle
			(at -8.400034 -6.800088 180)
			(size 0.4064 0.4064)
			(layers "F.Cu" "F.Mask" "F.Paste")
			(net "BMC0_SMB6_CLK")
		)
		(pad "C2" smd circle
			(at -7.599934 -6.800088 180)
			(size 0.4064 0.4064)
			(layers "F.Cu" "F.Mask" "F.Paste")
			(net "BMC0_SMB3_DAT")
		)
		(pad "C3" smd circle
			(at -6.800088 -6.800088 180)
			(size 0.4064 0.4064)
			(layers "F.Cu" "F.Mask" "F.Paste")
			(net "PU_BMC0_SDA12")
		)
		(pad "C4" smd circle
			(at -5.999988 -6.800088 180)
			(size 0.3556 0.3556)
			(layers "F.Cu" "F.Mask" "F.Paste")
			(net "BMC0_SMB10_CLK")
		)
		(pad "C5" smd circle
			(at -5.199888 -6.800088 180)
			(size 0.3556 0.3556)
			(layers "F.Cu" "F.Mask" "F.Paste")
			(net "BMC0_SMB9_CLK")
		)
		(pad "C6" smd circle
			(at -4.400042 -6.800088 180)
			(size 0.3556 0.3556)
			(layers "F.Cu" "F.Mask" "F.Paste")
			(net "RMII_BMC_MDC")
		)
		(pad "C7" smd circle
			(at -3.599942 -6.800088 180)
			(size 0.3556 0.3556)
			(layers "F.Cu" "F.Mask" "F.Paste")
			(net "BMC_ID_LED")
		)
		(pad "C8" smd circle
			(at -2.800096 -6.800088 180)
			(size 0.3556 0.3556)
			(layers "F.Cu" "F.Mask" "F.Paste")
			(net "NCSI_10G_RX_ER")
		)
		(pad "C9" smd circle
			(at -1.999996 -6.800088 180)
			(size 0.3556 0.3556)
			(layers "F.Cu" "F.Mask" "F.Paste")
			(net "CLK_50M_BMC_NCSI_R")
		)
		(pad "C10" smd circle
			(at -1.199896 -6.800088 180)
			(size 0.3556 0.3556)
			(layers "F.Cu" "F.Mask" "F.Paste")
			(net "TP_BMC_GPIOU2")
		)
		(pad "C11" smd circle
			(at -0.40005 -6.800088 180)
			(size 0.3556 0.3556)
			(layers "F.Cu" "F.Mask" "F.Paste")
			(net "RMII0_PHY_BMC_C_RXD0")
		)
		(pad "C12" smd circle
			(at 0.40005 -6.800088 180)
			(size 0.3556 0.3556)
			(layers "F.Cu" "F.Mask" "F.Paste")
			(net "RMII0_BMC_C_PHY_TXD0")
		)
		(pad "C13" smd circle
			(at 1.199896 -6.800088 180)
			(size 0.3556 0.3556)
			(layers "F.Cu" "F.Mask" "F.Paste")
			(net "HIGH_HEX_3")
		)
		(pad "C14" smd circle
			(at 1.999996 -6.800088 180)
			(size 0.3556 0.3556)
			(layers "F.Cu" "F.Mask" "F.Paste")
			(net "BMC_TXD1")
		)
		(pad "C15" smd circle
			(at 2.800096 -6.800088 180)
			(size 0.3556 0.3556)
			(layers "F.Cu" "F.Mask" "F.Paste")
			(net "TP_BMC_GPIOE1")
		)
		(pad "C16" smd circle
			(at 3.599942 -6.800088 180)
			(size 0.3556 0.3556)
			(layers "F.Cu" "F.Mask" "F.Paste")
			(net "BMC0_PMU_PLTRST_N_BMC")
		)
		(pad "C17" smd circle
			(at 4.400042 -6.800088 180)
			(size 0.3556 0.3556)
			(layers "F.Cu" "F.Mask" "F.Paste")
			(net "TP_BMC_GPIOF7")
		)
		(pad "C18" smd circle
			(at 5.199888 -6.800088 180)
			(size 0.3556 0.3556)
			(layers "F.Cu" "F.Mask" "F.Paste")
			(net "BMC_EN_0V955_R")
		)
		(pad "C19" smd circle
			(at 5.999988 -6.800088 180)
			(size 0.3556 0.3556)
			(layers "F.Cu" "F.Mask" "F.Paste")
			(net "TP_BMC0_LPC_LAD3")
		)
		(pad "C20" smd circle
			(at 6.800088 -6.800088 180)
			(size 0.4064 0.4064)
			(layers "F.Cu" "F.Mask" "F.Paste")
			(net "PWGD_P0V9_E_PG_R")
		)
		(pad "C21" smd circle
			(at 7.599934 -6.800088 180)
			(size 0.4064 0.4064)
			(layers "F.Cu" "F.Mask" "F.Paste")
			(net "PRSNT_CONTROL_BMC")
		)
		(pad "C22" smd circle
			(at 8.400034 -6.800088 180)
			(size 0.4064 0.4064)
			(layers "F.Cu" "F.Mask" "F.Paste")
			(net "TP_BMC_GPIOI0")
		)
		(pad "D1" smd circle
			(at -8.400034 -5.999988 180)
			(size 0.3556 0.3556)
			(layers "F.Cu" "F.Mask" "F.Paste")
			(net "BMC0_SMB7_DAT")
		)
		(pad "D2" smd circle
			(at -7.599934 -5.999988 180)
			(size 0.3556 0.3556)
			(layers "F.Cu" "F.Mask" "F.Paste")
			(net "BMC0_SMB5_DAT")
		)
		(pad "D3" smd circle
			(at -6.800088 -5.999988 180)
			(size 0.3556 0.3556)
			(layers "F.Cu" "F.Mask" "F.Paste")
			(net "BMC0_SMB3_CLK")
		)
		(pad "D4" smd circle
			(at -5.999988 -5.999988 180)
			(size 0.3556 0.3556)
			(layers "F.Cu" "F.Mask" "F.Paste")
			(net "PU_BMC0_SCL12")
		)
		(pad "D5" smd circle
			(at -5.199888 -5.999988 180)
			(size 0.3556 0.3556)
			(layers "F.Cu" "F.Mask" "F.Paste")
			(net "TP_BMC_GPIOA7")
		)
		(pad "D6" smd circle
			(at -4.400042 -5.999988 180)
			(size 0.3556 0.3556)
			(layers "F.Cu" "F.Mask" "F.Paste")
			(net "PEER_TRAY_BMC")
		)
		(pad "D7" smd circle
			(at -3.599942 -5.999988 180)
			(size 0.3556 0.3556)
			(layers "F.Cu" "F.Mask" "F.Paste")
			(net "TP_GPIOH4")
		)
		(pad "D8" smd circle
			(at -2.800096 -5.999988 180)
			(size 0.3556 0.3556)
			(layers "F.Cu" "F.Mask" "F.Paste")
			(net "NCSI_10G_RCSDV")
		)
		(pad "D9" smd circle
			(at -1.999996 -5.999988 180)
			(size 0.3556 0.3556)
			(layers "F.Cu" "F.Mask" "F.Paste")
			(net "NCSI_10G_TXEN")
		)
		(pad "D10" smd circle
			(at -1.199896 -5.999988 180)
			(size 0.3556 0.3556)
			(layers "F.Cu" "F.Mask" "F.Paste")
			(net "TP_BMC_GPIOU3")
		)
		(pad "D11" smd circle
			(at -0.40005 -5.999988 180)
			(size 0.3556 0.3556)
			(layers "F.Cu" "F.Mask" "F.Paste")
			(net "GND")
		)
		(pad "D12" smd circle
			(at 0.40005 -5.999988 180)
			(size 0.3556 0.3556)
			(layers "F.Cu" "F.Mask" "F.Paste")
			(net "RMII0_BMC_C_PHY_TXD1")
		)
		(pad "D13" smd circle
			(at 1.199896 -5.999988 180)
			(size 0.3556 0.3556)
			(layers "F.Cu" "F.Mask" "F.Paste")
			(net "HIGH_HEX_2")
		)
		(pad "D14" smd circle
			(at 1.999996 -5.999988 180)
			(size 0.3556 0.3556)
			(layers "F.Cu" "F.Mask" "F.Paste")
			(net "TP_BMC_GPIOE5")
		)
		(pad "D15" smd circle
			(at 2.800096 -5.999988 180)
			(size 0.3556 0.3556)
			(layers "F.Cu" "F.Mask" "F.Paste")
			(net "TP_BMC_GPIOE0")
		)
		(pad "D16" smd circle
			(at 3.599942 -5.999988 180)
			(size 0.3556 0.3556)
			(layers "F.Cu" "F.Mask" "F.Paste")
			(net "BMC_RSTBTN_N_R")
		)
		(pad "D17" smd circle
			(at 4.400042 -5.999988 180)
			(size 0.3556 0.3556)
			(layers "F.Cu" "F.Mask" "F.Paste")
			(net "TP_BMC_GPIOF3")
		)
		(pad "D18" smd circle
			(at 5.199888 -5.999988 180)
			(size 0.3556 0.3556)
			(layers "F.Cu" "F.Mask" "F.Paste")
			(net "TP_BMC_GPIOF0")
		)
		(pad "D19" smd circle
			(at 5.999988 -5.999988 180)
			(size 0.3556 0.3556)
			(layers "F.Cu" "F.Mask" "F.Paste")
			(net "BMC_RST_EXPANDER")
		)
		(pad "D20" smd circle
			(at 6.800088 -5.999988 180)
			(size 0.3556 0.3556)
			(layers "F.Cu" "F.Mask" "F.Paste")
			(net "Net_1409")
		)
		(pad "D21" smd circle
			(at 7.599934 -5.999988 180)
			(size 0.3556 0.3556)
			(layers "F.Cu" "F.Mask" "F.Paste")
			(net "GND")
		)
		(pad "D22" smd circle
			(at 8.400034 -5.999988 180)
			(size 0.3556 0.3556)
			(layers "F.Cu" "F.Mask" "F.Paste")
			(net "GND")
		)
		(pad "E1" smd circle
			(at -8.400034 -5.199888 180)
			(size 0.3556 0.3556)
			(layers "F.Cu" "F.Mask" "F.Paste")
			(net "JTAG_BMC_TRST_N")
		)
		(pad "E2" smd circle
			(at -7.599934 -5.199888 180)
			(size 0.3556 0.3556)
			(layers "F.Cu" "F.Mask" "F.Paste")
			(net "BMC0_SMB7_CLK")
		)
		(pad "E3" smd circle
			(at -6.800088 -5.199888 180)
			(size 0.3556 0.3556)
			(layers "F.Cu" "F.Mask" "F.Paste")
			(net "BMC0_SMB5_CLK")
		)
		(pad "E4" smd circle
			(at -5.999988 -5.199888 180)
			(size 0.3556 0.3556)
			(layers "F.Cu" "F.Mask" "F.Paste")
			(net "BMC0_ENTEST1")
		)
		(pad "E5" smd circle
			(at -5.199888 -5.199888 180)
			(size 0.3556 0.3556)
			(layers "F.Cu" "F.Mask" "F.Paste")
			(net "PU_BMC0_SDA11")
		)
		(pad "E6" smd circle
			(at -4.400042 -5.199888 180)
			(size 0.3556 0.3556)
			(layers "F.Cu" "F.Mask" "F.Paste")
			(net "EXP_ID_BMC")
		)
		(pad "E7" smd circle
			(at -3.599942 -5.199888 180)
			(size 0.3556 0.3556)
			(layers "F.Cu" "F.Mask" "F.Paste")
			(net "TP_GPIOH7")
		)
		(pad "E8" smd circle
			(at -2.800096 -5.199888 180)
			(size 0.3556 0.3556)
			(layers "F.Cu" "F.Mask" "F.Paste")
			(net "NCSI_10G_RXD1")
		)
		(pad "E9" smd circle
			(at -1.999996 -5.199888 180)
			(size 0.3556 0.3556)
			(layers "F.Cu" "F.Mask" "F.Paste")
			(net "TP_BMC_GPIOT7")
		)
		(pad "E10" smd circle
			(at -1.199896 -5.199888 180)
			(size 0.3556 0.3556)
			(layers "F.Cu" "F.Mask" "F.Paste")
			(net "RMII0_BMC_C_RX_ER")
		)
		(pad "E11" smd circle
			(at -0.40005 -5.199888 180)
			(size 0.3556 0.3556)
			(layers "F.Cu" "F.Mask" "F.Paste")
			(net "BMC_RXCK_R")
		)
		(pad "E12" smd circle
			(at 0.40005 -5.199888 180)
			(size 0.3556 0.3556)
			(layers "F.Cu" "F.Mask" "F.Paste")
			(net "GND")
		)
		(pad "E13" smd circle
			(at 1.199896 -5.199888 180)
			(size 0.3556 0.3556)
			(layers "F.Cu" "F.Mask" "F.Paste")
			(net "HIGH_HEX_1")
		)
		(pad "E14" smd circle
			(at 1.999996 -5.199888 180)
			(size 0.3556 0.3556)
			(layers "F.Cu" "F.Mask" "F.Paste")
			(net "TP_BMC_GPIOE4")
		)
		(pad "E15" smd circle
			(at 2.800096 -5.199888 180)
			(size 0.3556 0.3556)
			(layers "F.Cu" "F.Mask" "F.Paste")
			(net "BMC0_TP15")
		)
		(pad "E16" smd circle
			(at 3.599942 -5.199888 180)
			(size 0.3556 0.3556)
			(layers "F.Cu" "F.Mask" "F.Paste")
			(net "TP_BMC_GPIOF6")
		)
		(pad "E17" smd circle
			(at 4.400042 -5.199888 180)
			(size 0.3556 0.3556)
			(layers "F.Cu" "F.Mask" "F.Paste")
			(net "TP_IRQ_CPU_SERIAL")
		)
		(pad "E18" smd circle
			(at 5.199888 -5.199888 180)
			(size 0.3556 0.3556)
			(layers "F.Cu" "F.Mask" "F.Paste")
			(net "TP_BMC_GPIOB7")
		)
		(pad "E19" smd circle
			(at 5.999988 -5.199888 180)
			(size 0.3556 0.3556)
			(layers "F.Cu" "F.Mask" "F.Paste")
			(net "LPCRST0_N")
		)
		(pad "E20" smd circle
			(at 6.800088 -5.199888 180)
			(size 0.3556 0.3556)
			(layers "F.Cu" "F.Mask" "F.Paste")
			(net "PWGD_P0V955_C_PG_R")
		)
		(pad "E21" smd circle
			(at 7.599934 -5.199888 180)
			(size 0.3556 0.3556)
			(layers "F.Cu" "F.Mask" "F.Paste")
			(net "Net_1408")
		)
		(pad "E22" smd circle
			(at 8.400034 -5.199888 180)
			(size 0.3556 0.3556)
			(layers "F.Cu" "F.Mask" "F.Paste")
			(net "Net_1407")
		)
		(pad "F1" smd circle
			(at -8.400034 -4.400042 180)
			(size 0.3556 0.3556)
			(layers "F.Cu" "F.Mask" "F.Paste")
			(net "JTAG_BMC_TDI")
		)
		(pad "F2" smd circle
			(at -7.599934 -4.400042 180)
			(size 0.3556 0.3556)
			(layers "F.Cu" "F.Mask" "F.Paste")
			(net "JTAG_BMC_TCK")
		)
		(pad "F3" smd circle
			(at -6.800088 -4.400042 180)
			(size 0.3556 0.3556)
			(layers "F.Cu" "F.Mask" "F.Paste")
			(net "BMC0_SMB8_DAT")
		)
		(pad "F4" smd circle
			(at -5.999988 -4.400042 180)
			(size 0.3556 0.3556)
			(layers "F.Cu" "F.Mask" "F.Paste")
			(net "BMC0_SMB6_DAT")
		)
		(pad "F5" smd circle
			(at -5.199888 -4.400042 180)
			(size 0.3556 0.3556)
			(layers "F.Cu" "F.Mask" "F.Paste")
			(net "BMC0_SMB4_DAT")
		)
		(pad "F8" smd circle
			(at -2.800096 -4.400042 180)
			(size 0.3556 0.3556)
			(layers "F.Cu" "F.Mask" "F.Paste")
			(net "P3V3_STBY")
		)
		(pad "F9" smd circle
			(at -1.999996 -4.400042 180)
			(size 0.3556 0.3556)
			(layers "F.Cu" "F.Mask" "F.Paste")
			(net "P3V3_STBY")
		)
		(pad "F10" smd circle
			(at -1.199896 -4.400042 180)
			(size 0.3556 0.3556)
			(layers "F.Cu" "F.Mask" "F.Paste")
			(net "P3V3_STBY")
		)
		(pad "F11" smd circle
			(at -0.40005 -4.400042 180)
			(size 0.3556 0.3556)
			(layers "F.Cu" "F.Mask" "F.Paste")
			(net "P3V3_STBY")
		)
		(pad "F12" smd circle
			(at 0.40005 -4.400042 180)
			(size 0.3556 0.3556)
			(layers "F.Cu" "F.Mask" "F.Paste")
			(net "P3V3_STBY")
		)
		(pad "F13" smd circle
			(at 1.199896 -4.400042 180)
			(size 0.3556 0.3556)
			(layers "F.Cu" "F.Mask" "F.Paste")
			(net "P3V3_STBY")
		)
		(pad "F14" smd circle
			(at 1.999996 -4.400042 180)
			(size 0.3556 0.3556)
			(layers "F.Cu" "F.Mask" "F.Paste")
			(net "P1V26_STBY")
		)
		(pad "F15" smd circle
			(at 2.800096 -4.400042 180)
			(size 0.3556 0.3556)
			(layers "F.Cu" "F.Mask" "F.Paste")
			(net "P1V26_STBY")
		)
		(pad "F18" smd circle
			(at 5.199888 -4.400042 180)
			(size 0.3556 0.3556)
			(layers "F.Cu" "F.Mask" "F.Paste")
			(net "BMC_SALT4")
		)
		(pad "F19" smd circle
			(at 5.999988 -4.400042 180)
			(size 0.3556 0.3556)
			(layers "F.Cu" "F.Mask" "F.Paste")
			(net "TP_BMC0_LPC_LAD2")
		)
		(pad "F20" smd circle
			(at 6.800088 -4.400042 180)
			(size 0.3556 0.3556)
			(layers "F.Cu" "F.Mask" "F.Paste")
			(net "FCB_HW_REVISION")
		)
		(pad "F21" smd circle
			(at 7.599934 -4.400042 180)
			(size 0.3556 0.3556)
			(layers "F.Cu" "F.Mask" "F.Paste")
			(net "GND")
		)
		(pad "F22" smd circle
			(at 8.400034 -4.400042 180)
			(size 0.3556 0.3556)
			(layers "F.Cu" "F.Mask" "F.Paste")
			(net "GND")
		)
		(pad "G1" smd circle
			(at -8.400034 -3.599942 180)
			(size 0.3556 0.3556)
			(layers "F.Cu" "F.Mask" "F.Paste")
			(net "BMC_RXD5_R")
		)
		(pad "G2" smd circle
			(at -7.599934 -3.599942 180)
			(size 0.3556 0.3556)
			(layers "F.Cu" "F.Mask" "F.Paste")
			(net "JTAG_BMC_TMS")
		)
		(pad "G3" smd circle
			(at -6.800088 -3.599942 180)
			(size 0.3556 0.3556)
			(layers "F.Cu" "F.Mask" "F.Paste")
			(net "JTAG_BMC_TDO")
		)
		(pad "G4" smd circle
			(at -5.999988 -3.599942 180)
			(size 0.3556 0.3556)
			(layers "F.Cu" "F.Mask" "F.Paste")
			(net "BMC0_JTAG_RTCK")
		)
		(pad "G5" smd circle
			(at -5.199888 -3.599942 180)
			(size 0.3556 0.3556)
			(layers "F.Cu" "F.Mask" "F.Paste")
			(net "BMC0_SMB8_CLK")
		)
		(pad "G18" smd circle
			(at 5.199888 -3.599942 180)
			(size 0.3556 0.3556)
			(layers "F.Cu" "F.Mask" "F.Paste")
			(net "PMU_WAKE_N")
		)
		(pad "G19" smd circle
			(at 5.999988 -3.599942 180)
			(size 0.3556 0.3556)
			(layers "F.Cu" "F.Mask" "F.Paste")
			(net "BMC_1V8_C_EN_R")
		)
		(pad "G20" smd circle
			(at 6.800088 -3.599942 180)
			(size 0.3556 0.3556)
			(layers "F.Cu" "F.Mask" "F.Paste")
			(net "DPB_HW_REVISION")
		)
		(pad "G21" smd circle
			(at 7.599934 -3.599942 180)
			(size 0.3556 0.3556)
			(layers "F.Cu" "F.Mask" "F.Paste")
			(net "GND")
		)
		(pad "G22" smd circle
			(at 8.400034 -3.599942 180)
			(size 0.3556 0.3556)
			(layers "F.Cu" "F.Mask" "F.Paste")
			(net "GND")
		)
		(pad "H1" smd circle
			(at -8.400034 -2.800096 180)
			(size 0.3556 0.3556)
			(layers "F.Cu" "F.Mask" "F.Paste")
			(net "BMC_JTAG_L_R")
		)
		(pad "H2" smd circle
			(at -7.599934 -2.800096 180)
			(size 0.3556 0.3556)
			(layers "F.Cu" "F.Mask" "F.Paste")
			(net "TP_BMC_GPIOQ6")
		)
		(pad "H3" smd circle
			(at -6.800088 -2.800096 180)
			(size 0.3556 0.3556)
			(layers "F.Cu" "F.Mask" "F.Paste")
			(net "BMC0_SMB14_SDA")
		)
		(pad "H4" smd circle
			(at -5.999988 -2.800096 180)
			(size 0.3556 0.3556)
			(layers "F.Cu" "F.Mask" "F.Paste")
			(net "BMC0_SMB14_CLK")
		)
		(pad "H5" smd circle
			(at -5.199888 -2.800096 180)
			(size 0.3556 0.3556)
			(layers "F.Cu" "F.Mask" "F.Paste")
			(net "BMC_TXD5_R")
		)
		(pad "H6" smd circle
			(at -4.400042 -2.800096 180)
			(size 0.3556 0.3556)
			(layers "F.Cu" "F.Mask" "F.Paste")
			(net "P3V3_STBY")
		)
		(pad "H17" smd circle
			(at 4.400042 -2.800096 180)
			(size 0.3556 0.3556)
			(layers "F.Cu" "F.Mask" "F.Paste")
			(net "P3V3_STBY")
		)
		(pad "H18" smd circle
			(at 5.199888 -2.800096 180)
			(size 0.3556 0.3556)
			(layers "F.Cu" "F.Mask" "F.Paste")
			(net "BMC_SALT3")
		)
		(pad "H19" smd circle
			(at 5.999988 -2.800096 180)
			(size 0.3556 0.3556)
			(layers "F.Cu" "F.Mask" "F.Paste")
			(net "DEBUG_LED_SW")
		)
		(pad "H20" smd circle
			(at 6.800088 -2.800096 180)
			(size 0.3556 0.3556)
			(layers "F.Cu" "F.Mask" "F.Paste")
			(net "HSC_MSB_ALERT_N")
		)
		(pad "H21" smd circle
			(at 7.599934 -2.800096 180)
			(size 0.3556 0.3556)
			(layers "F.Cu" "F.Mask" "F.Paste")
			(net "Net_1406")
		)
		(pad "H22" smd circle
			(at 8.400034 -2.800096 180)
			(size 0.3556 0.3556)
			(layers "F.Cu" "F.Mask" "F.Paste")
			(net "Net_1405")
		)
		(pad "J1" smd circle
			(at -8.400034 -1.999996 180)
			(size 0.3556 0.3556)
			(layers "F.Cu" "F.Mask" "F.Paste")
			(net "BMC_USB1_HDP")
		)
		(pad "J2" smd circle
			(at -7.599934 -1.999996 180)
			(size 0.3556 0.3556)
			(layers "F.Cu" "F.Mask" "F.Paste")
			(net "BMC_USB1_HDN")
		)
		(pad "J3" smd circle
			(at -6.800088 -1.999996 180)
			(size 0.3556 0.3556)
			(layers "F.Cu" "F.Mask" "F.Paste")
			(net "LOW_HEX_3")
		)
		(pad "J4" smd circle
			(at -5.999988 -1.999996 180)
			(size 0.3556 0.3556)
			(layers "F.Cu" "F.Mask" "F.Paste")
			(net "LOW_HEX_1")
		)
		(pad "J5" smd circle
			(at -5.199888 -1.999996 180)
			(size 0.3556 0.3556)
			(layers "F.Cu" "F.Mask" "F.Paste")
			(net "LOW_HEX_0")
		)
		(pad "J6" smd circle
			(at -4.400042 -1.999996 180)
			(size 0.3556 0.3556)
			(layers "F.Cu" "F.Mask" "F.Paste")
			(net "P3V3_STBY")
		)
		(pad "J9" smd circle
			(at -1.999996 -1.999996 180)
			(size 0.3556 0.3556)
			(layers "F.Cu" "F.Mask" "F.Paste")
			(net "GND")
		)
		(pad "J10" smd circle
			(at -1.199896 -1.999996 180)
			(size 0.3556 0.3556)
			(layers "F.Cu" "F.Mask" "F.Paste")
			(net "GND")
		)
		(pad "J11" smd circle
			(at -0.40005 -1.999996 180)
			(size 0.3556 0.3556)
			(layers "F.Cu" "F.Mask" "F.Paste")
			(net "GND")
		)
		(pad "J12" smd circle
			(at 0.40005 -1.999996 180)
			(size 0.3556 0.3556)
			(layers "F.Cu" "F.Mask" "F.Paste")
			(net "GND")
		)
		(pad "J13" smd circle
			(at 1.199896 -1.999996 180)
			(size 0.3556 0.3556)
			(layers "F.Cu" "F.Mask" "F.Paste")
			(net "GND")
		)
		(pad "J14" smd circle
			(at 1.999996 -1.999996 180)
			(size 0.3556 0.3556)
			(layers "F.Cu" "F.Mask" "F.Paste")
			(net "GND")
		)
		(pad "J17" smd circle
			(at 4.400042 -1.999996 180)
			(size 0.3556 0.3556)
			(layers "F.Cu" "F.Mask" "F.Paste")
			(net "P3V3_STBY")
		)
		(pad "J18" smd circle
			(at 5.199888 -1.999996 180)
			(size 0.3556 0.3556)
			(layers "F.Cu" "F.Mask" "F.Paste")
			(net "BMC0_SMB2_DAT")
		)
		(pad "J19" smd circle
			(at 5.999988 -1.999996 180)
			(size 0.3556 0.3556)
			(layers "F.Cu" "F.Mask" "F.Paste")
			(net "BMC0_SMB2_CLK")
		)
		(pad "J20" smd circle
			(at 6.800088 -1.999996 180)
			(size 0.3556 0.3556)
			(layers "F.Cu" "F.Mask" "F.Paste")
			(net "I2C_BMC_10G_ALERT#")
		)
		(pad "J21" smd circle
			(at 7.599934 -1.999996 180)
			(size 0.3556 0.3556)
			(layers "F.Cu" "F.Mask" "F.Paste")
			(net "BMC_MSB_I2C_E_ALERT_#")
		)
		(pad "J22" smd circle
			(at 8.400034 -1.999996 180)
			(size 0.3556 0.3556)
			(layers "F.Cu" "F.Mask" "F.Paste")
			(net "GND")
		)
		(pad "K1" smd circle
			(at -8.400034 -1.199896 180)
			(size 0.3556 0.3556)
			(layers "F.Cu" "F.Mask" "F.Paste")
			(net "ADCVREFFP")
		)
		(pad "K2" smd circle
			(at -7.599934 -1.199896 180)
			(size 0.3556 0.3556)
			(layers "F.Cu" "F.Mask" "F.Paste")
			(net "ADCVREFFN")
		)
		(pad "K3" smd circle
			(at -6.800088 -1.199896 180)
			(size 0.3556 0.3556)
			(layers "F.Cu" "F.Mask" "F.Paste")
			(net "BMC_USB1_HDN2")
		)
		(pad "K4" smd circle
			(at -5.999988 -1.199896 180)
			(size 0.3556 0.3556)
			(layers "F.Cu" "F.Mask" "F.Paste")
			(net "BMC_USB1_HDP2")
		)
		(pad "K5" smd circle
			(at -5.199888 -1.199896 180)
			(size 0.3556 0.3556)
			(layers "F.Cu" "F.Mask" "F.Paste")
			(net "LOW_HEX_2")
		)
		(pad "K6" smd circle
			(at -4.400042 -1.199896 180)
			(size 0.3556 0.3556)
			(layers "F.Cu" "F.Mask" "F.Paste")
			(net "P1V26_STBY")
		)
		(pad "K9" smd circle
			(at -1.999996 -1.199896 180)
			(size 0.3556 0.3556)
			(layers "F.Cu" "F.Mask" "F.Paste")
			(net "GND")
		)
		(pad "K10" smd circle
			(at -1.199896 -1.199896 180)
			(size 0.3556 0.3556)
			(layers "F.Cu" "F.Mask" "F.Paste")
			(net "GND")
		)
		(pad "K11" smd circle
			(at -0.40005 -1.199896 180)
			(size 0.3556 0.3556)
			(layers "F.Cu" "F.Mask" "F.Paste")
			(net "GND")
		)
		(pad "K12" smd circle
			(at 0.40005 -1.199896 180)
			(size 0.3556 0.3556)
			(layers "F.Cu" "F.Mask" "F.Paste")
			(net "GND")
		)
		(pad "K13" smd circle
			(at 1.199896 -1.199896 180)
			(size 0.3556 0.3556)
			(layers "F.Cu" "F.Mask" "F.Paste")
			(net "GND")
		)
		(pad "K14" smd circle
			(at 1.999996 -1.199896 180)
			(size 0.3556 0.3556)
			(layers "F.Cu" "F.Mask" "F.Paste")
			(net "GND")
		)
		(pad "K17" smd circle
			(at 4.400042 -1.199896 180)
			(size 0.3556 0.3556)
			(layers "F.Cu" "F.Mask" "F.Paste")
			(net "P1V26_STBY")
		)
		(pad "K18" smd circle
			(at 5.199888 -1.199896 180)
			(size 0.3556 0.3556)
			(layers "F.Cu" "F.Mask" "F.Paste")
			(net "ROMA23")
		)
		(pad "K19" smd circle
			(at 5.999988 -1.199896 180)
			(size 0.3556 0.3556)
			(layers "F.Cu" "F.Mask" "F.Paste")
			(net "PD_PERST_N")
		)
		(pad "K20" smd circle
			(at 6.800088 -1.199896 180)
			(size 0.3556 0.3556)
			(layers "F.Cu" "F.Mask" "F.Paste")
			(net "MB0_PRESNET#")
		)
		(pad "K21" smd circle
			(at 7.599934 -1.199896 180)
			(size 0.3556 0.3556)
			(layers "F.Cu" "F.Mask" "F.Paste")
			(net "BMC0_SMB1_CLK")
		)
		(pad "K22" smd circle
			(at 8.400034 -1.199896 180)
			(size 0.3556 0.3556)
			(layers "F.Cu" "F.Mask" "F.Paste")
			(net "BMC0_SMB1_DAT")
		)
		(pad "L1" smd circle
			(at -8.400034 -0.40005 180)
			(size 0.3556 0.3556)
			(layers "F.Cu" "F.Mask" "F.Paste")
			(net "ADC_P1V5_C_BMC")
		)
		(pad "L2" smd circle
			(at -7.599934 -0.40005 180)
			(size 0.3556 0.3556)
			(layers "F.Cu" "F.Mask" "F.Paste")
			(net "ADC_P1V8_STBY_BMC")
		)
		(pad "L3" smd circle
			(at -6.800088 -0.40005 180)
			(size 0.3556 0.3556)
			(layers "F.Cu" "F.Mask" "F.Paste")
			(net "ADC_P3V3_STBY_BMC")
		)
		(pad "L4" smd circle
			(at -5.999988 -0.40005 180)
			(size 0.3556 0.3556)
			(layers "F.Cu" "F.Mask" "F.Paste")
			(net "ADC_P5V_STBY_BMC")
		)
		(pad "L5" smd circle
			(at -5.199888 -0.40005 180)
			(size 0.3556 0.3556)
			(layers "F.Cu" "F.Mask" "F.Paste")
			(net "ADC0_12V_BMC")
		)
		(pad "L6" smd circle
			(at -4.400042 -0.40005 180)
			(size 0.3556 0.3556)
			(layers "F.Cu" "F.Mask" "F.Paste")
			(net "P1V26_STBY")
		)
		(pad "L9" smd circle
			(at -1.999996 -0.40005 180)
			(size 0.3556 0.3556)
			(layers "F.Cu" "F.Mask" "F.Paste")
			(net "GND")
		)
		(pad "L10" smd circle
			(at -1.199896 -0.40005 180)
			(size 0.3556 0.3556)
			(layers "F.Cu" "F.Mask" "F.Paste")
			(net "GND")
		)
		(pad "L11" smd circle
			(at -0.40005 -0.40005 180)
			(size 0.3556 0.3556)
			(layers "F.Cu" "F.Mask" "F.Paste")
			(net "GND")
		)
		(pad "L12" smd circle
			(at 0.40005 -0.40005 180)
			(size 0.3556 0.3556)
			(layers "F.Cu" "F.Mask" "F.Paste")
			(net "GND")
		)
		(pad "L13" smd circle
			(at 1.199896 -0.40005 180)
			(size 0.3556 0.3556)
			(layers "F.Cu" "F.Mask" "F.Paste")
			(net "GND")
		)
		(pad "L14" smd circle
			(at 1.999996 -0.40005 180)
			(size 0.3556 0.3556)
			(layers "F.Cu" "F.Mask" "F.Paste")
			(net "GND")
		)
		(pad "L17" smd circle
			(at 4.400042 -0.40005 180)
			(size 0.3556 0.3556)
			(layers "F.Cu" "F.Mask" "F.Paste")
			(net "P1V26_STBY")
		)
		(pad "L18" smd circle
			(at 5.199888 -0.40005 180)
			(size 0.3556 0.3556)
			(layers "F.Cu" "F.Mask" "F.Paste")
			(net "ROMA12")
		)
		(pad "L19" smd circle
			(at 5.999988 -0.40005 180)
			(size 0.3556 0.3556)
			(layers "F.Cu" "F.Mask" "F.Paste")
			(net "ROMA13")
		)
		(pad "L20" smd circle
			(at 6.800088 -0.40005 180)
			(size 0.3556 0.3556)
			(layers "F.Cu" "F.Mask" "F.Paste")
			(net "ROMA14")
		)
		(pad "L21" smd circle
			(at 7.599934 -0.40005 180)
			(size 0.3556 0.3556)
			(layers "F.Cu" "F.Mask" "F.Paste")
			(net "ROMA15")
		)
		(pad "L22" smd circle
			(at 8.400034 -0.40005 180)
			(size 0.3556 0.3556)
			(layers "F.Cu" "F.Mask" "F.Paste")
			(net "ROMA22")
		)
		(pad "M1" smd circle
			(at -8.400034 0.40005 180)
			(size 0.3556 0.3556)
			(layers "F.Cu" "F.Mask" "F.Paste")
			(net "GND")
		)
		(pad "M2" smd circle
			(at -7.599934 0.40005 180)
			(size 0.3556 0.3556)
			(layers "F.Cu" "F.Mask" "F.Paste")
			(net "GND")
		)
		(pad "M3" smd circle
			(at -6.800088 0.40005 180)
			(size 0.3556 0.3556)
			(layers "F.Cu" "F.Mask" "F.Paste")
			(net "ADC_P1V5_E_BMC")
		)
		(pad "M4" smd circle
			(at -5.999988 0.40005 180)
			(size 0.3556 0.3556)
			(layers "F.Cu" "F.Mask" "F.Paste")
			(net "ADC_P0V9_E_BMC")
		)
		(pad "M5" smd circle
			(at -5.199888 0.40005 180)
			(size 0.3556 0.3556)
			(layers "F.Cu" "F.Mask" "F.Paste")
			(net "ADC_P0V955_C_BMC")
		)
		(pad "M6" smd circle
			(at -4.400042 0.40005 180)
			(size 0.3556 0.3556)
			(layers "F.Cu" "F.Mask" "F.Paste")
			(net "P3V3_STBY")
		)
		(pad "M9" smd circle
			(at -1.999996 0.40005 180)
			(size 0.3556 0.3556)
			(layers "F.Cu" "F.Mask" "F.Paste")
			(net "GND")
		)
		(pad "M10" smd circle
			(at -1.199896 0.40005 180)
			(size 0.3556 0.3556)
			(layers "F.Cu" "F.Mask" "F.Paste")
			(net "GND")
		)
		(pad "M11" smd circle
			(at -0.40005 0.40005 180)
			(size 0.3556 0.3556)
			(layers "F.Cu" "F.Mask" "F.Paste")
			(net "GND")
		)
		(pad "M12" smd circle
			(at 0.40005 0.40005 180)
			(size 0.3556 0.3556)
			(layers "F.Cu" "F.Mask" "F.Paste")
			(net "GND")
		)
		(pad "M13" smd circle
			(at 1.199896 0.40005 180)
			(size 0.3556 0.3556)
			(layers "F.Cu" "F.Mask" "F.Paste")
			(net "GND")
		)
		(pad "M14" smd circle
			(at 1.999996 0.40005 180)
			(size 0.3556 0.3556)
			(layers "F.Cu" "F.Mask" "F.Paste")
			(net "GND")
		)
		(pad "M17" smd circle
			(at 4.400042 0.40005 180)
			(size 0.3556 0.3556)
			(layers "F.Cu" "F.Mask" "F.Paste")
			(net "P3V3_STBY")
		)
		(pad "M18" smd circle
			(at 5.199888 0.40005 180)
			(size 0.3556 0.3556)
			(layers "F.Cu" "F.Mask" "F.Paste")
			(net "ROMA19")
		)
		(pad "M19" smd circle
			(at 5.999988 0.40005 180)
			(size 0.3556 0.3556)
			(layers "F.Cu" "F.Mask" "F.Paste")
			(net "ROMA8")
		)
		(pad "M20" smd circle
			(at 6.800088 0.40005 180)
			(size 0.3556 0.3556)
			(layers "F.Cu" "F.Mask" "F.Paste")
			(net "ROMA9")
		)
		(pad "M21" smd circle
			(at 7.599934 0.40005 180)
			(size 0.3556 0.3556)
			(layers "F.Cu" "F.Mask" "F.Paste")
			(net "ROMA10")
		)
		(pad "M22" smd circle
			(at 8.400034 0.40005 180)
			(size 0.3556 0.3556)
			(layers "F.Cu" "F.Mask" "F.Paste")
			(net "ROMA11")
		)
		(pad "N1" smd circle
			(at -8.400034 1.199896 180)
			(size 0.3556 0.3556)
			(layers "F.Cu" "F.Mask" "F.Paste")
			(net "GND")
		)
		(pad "N2" smd circle
			(at -7.599934 1.199896 180)
			(size 0.3556 0.3556)
			(layers "F.Cu" "F.Mask" "F.Paste")
			(net "GND")
		)
		(pad "N3" smd circle
			(at -6.800088 1.199896 180)
			(size 0.3556 0.3556)
			(layers "F.Cu" "F.Mask" "F.Paste")
			(net "GND")
		)
		(pad "N4" smd circle
			(at -5.999988 1.199896 180)
			(size 0.3556 0.3556)
			(layers "F.Cu" "F.Mask" "F.Paste")
			(net "GND")
		)
		(pad "N5" smd circle
			(at -5.199888 1.199896 180)
			(size 0.3556 0.3556)
			(layers "F.Cu" "F.Mask" "F.Paste")
			(net "GND")
		)
		(pad "N6" smd circle
			(at -4.400042 1.199896 180)
			(size 0.3556 0.3556)
			(layers "F.Cu" "F.Mask" "F.Paste")
			(net "P3V3_STBY")
		)
		(pad "N9" smd circle
			(at -1.999996 1.199896 180)
			(size 0.3556 0.3556)
			(layers "F.Cu" "F.Mask" "F.Paste")
			(net "GND")
		)
		(pad "N10" smd circle
			(at -1.199896 1.199896 180)
			(size 0.3556 0.3556)
			(layers "F.Cu" "F.Mask" "F.Paste")
			(net "GND")
		)
		(pad "N11" smd circle
			(at -0.40005 1.199896 180)
			(size 0.3556 0.3556)
			(layers "F.Cu" "F.Mask" "F.Paste")
			(net "GND")
		)
		(pad "N12" smd circle
			(at 0.40005 1.199896 180)
			(size 0.3556 0.3556)
			(layers "F.Cu" "F.Mask" "F.Paste")
			(net "GND")
		)
		(pad "N13" smd circle
			(at 1.199896 1.199896 180)
			(size 0.3556 0.3556)
			(layers "F.Cu" "F.Mask" "F.Paste")
			(net "GND")
		)
		(pad "N14" smd circle
			(at 1.999996 1.199896 180)
			(size 0.3556 0.3556)
			(layers "F.Cu" "F.Mask" "F.Paste")
			(net "GND")
		)
		(pad "N17" smd circle
			(at 4.400042 1.199896 180)
			(size 0.3556 0.3556)
			(layers "F.Cu" "F.Mask" "F.Paste")
			(net "P3V3_STBY")
		)
		(pad "N18" smd circle
			(at 5.199888 1.199896 180)
			(size 0.3556 0.3556)
			(layers "F.Cu" "F.Mask" "F.Paste")
			(net "ROMA17")
		)
		(pad "N19" smd circle
			(at 5.999988 1.199896 180)
			(size 0.3556 0.3556)
			(layers "F.Cu" "F.Mask" "F.Paste")
			(net "ROMA18")
		)
		(pad "N20" smd circle
			(at 6.800088 1.199896 180)
			(size 0.3556 0.3556)
			(layers "F.Cu" "F.Mask" "F.Paste")
			(net "ROMA21")
		)
		(pad "N21" smd circle
			(at 7.599934 1.199896 180)
			(size 0.3556 0.3556)
			(layers "F.Cu" "F.Mask" "F.Paste")
			(net "TP_BMC_GPIOR5")
		)
		(pad "N22" smd circle
			(at 8.400034 1.199896 180)
			(size 0.3556 0.3556)
			(layers "F.Cu" "F.Mask" "F.Paste")
			(net "ROMA20")
		)
		(pad "P1" smd circle
			(at -8.400034 1.999996 180)
			(size 0.3556 0.3556)
			(layers "F.Cu" "F.Mask" "F.Paste")
			(net "P3V3_STBY")
		)
		(pad "P2" smd circle
			(at -7.599934 1.999996 180)
			(size 0.3556 0.3556)
			(layers "F.Cu" "F.Mask" "F.Paste")
			(net "ADCVREXT")
		)
		(pad "P3" smd circle
			(at -6.800088 1.999996 180)
			(size 0.3556 0.3556)
			(layers "F.Cu" "F.Mask" "F.Paste")
			(net "ADCAV33")
		)
		(pad "P4" smd circle
			(at -5.999988 1.999996 180)
			(size 0.3556 0.3556)
			(layers "F.Cu" "F.Mask" "F.Paste")
			(net "GND")
		)
		(pad "P5" smd circle
			(at -5.199888 1.999996 180)
			(size 0.3556 0.3556)
			(layers "F.Cu" "F.Mask" "F.Paste")
			(net "GND")
		)
		(pad "P6" smd circle
			(at -4.400042 1.999996 180)
			(size 0.3556 0.3556)
			(layers "F.Cu" "F.Mask" "F.Paste")
			(net "P1V26_STBY")
		)
		(pad "P9" smd circle
			(at -1.999996 1.999996 180)
			(size 0.3556 0.3556)
			(layers "F.Cu" "F.Mask" "F.Paste")
			(net "GND")
		)
		(pad "P10" smd circle
			(at -1.199896 1.999996 180)
			(size 0.3556 0.3556)
			(layers "F.Cu" "F.Mask" "F.Paste")
			(net "GND")
		)
		(pad "P11" smd circle
			(at -0.40005 1.999996 180)
			(size 0.3556 0.3556)
			(layers "F.Cu" "F.Mask" "F.Paste")
			(net "GND")
		)
		(pad "P12" smd circle
			(at 0.40005 1.999996 180)
			(size 0.3556 0.3556)
			(layers "F.Cu" "F.Mask" "F.Paste")
			(net "GND")
		)
		(pad "P13" smd circle
			(at 1.199896 1.999996 180)
			(size 0.3556 0.3556)
			(layers "F.Cu" "F.Mask" "F.Paste")
			(net "GND")
		)
		(pad "P14" smd circle
			(at 1.999996 1.999996 180)
			(size 0.3556 0.3556)
			(layers "F.Cu" "F.Mask" "F.Paste")
			(net "GND")
		)
		(pad "P17" smd circle
			(at 4.400042 1.999996 180)
			(size 0.3556 0.3556)
			(layers "F.Cu" "F.Mask" "F.Paste")
			(net "P1V26_STBY")
		)
		(pad "P18" smd circle
			(at 5.199888 1.999996 180)
			(size 0.3556 0.3556)
			(layers "F.Cu" "F.Mask" "F.Paste")
			(net "ROMA3")
		)
		(pad "P19" smd circle
			(at 5.999988 1.999996 180)
			(size 0.3556 0.3556)
			(layers "F.Cu" "F.Mask" "F.Paste")
			(net "ROMA4")
		)
		(pad "P20" smd circle
			(at 6.800088 1.999996 180)
			(size 0.3556 0.3556)
			(layers "F.Cu" "F.Mask" "F.Paste")
			(net "ROMA5")
		)
		(pad "P21" smd circle
			(at 7.599934 1.999996 180)
			(size 0.3556 0.3556)
			(layers "F.Cu" "F.Mask" "F.Paste")
			(net "ROMA6")
		)
		(pad "P22" smd circle
			(at 8.400034 1.999996 180)
			(size 0.3556 0.3556)
			(layers "F.Cu" "F.Mask" "F.Paste")
			(net "ROMA7")
		)
		(pad "R1" smd circle
			(at -8.400034 2.800096 180)
			(size 0.3556 0.3556)
			(layers "F.Cu" "F.Mask" "F.Paste")
			(net "DACRSET")
		)
		(pad "R2" smd circle
			(at -7.599934 2.800096 180)
			(size 0.3556 0.3556)
			(layers "F.Cu" "F.Mask" "F.Paste")
			(net "Net_1413")
		)
		(pad "R3" smd circle
			(at -6.800088 2.800096 180)
			(size 0.3556 0.3556)
			(layers "F.Cu" "F.Mask" "F.Paste")
			(net "Net_1412")
		)
		(pad "R4" smd circle
			(at -5.999988 2.800096 180)
			(size 0.3556 0.3556)
			(layers "F.Cu" "F.Mask" "F.Paste")
			(net "Net_1411")
		)
		(pad "R5" smd circle
			(at -5.199888 2.800096 180)
			(size 0.3556 0.3556)
			(layers "F.Cu" "F.Mask" "F.Paste")
			(net "GND")
		)
		(pad "R6" smd circle
			(at -4.400042 2.800096 180)
			(size 0.3556 0.3556)
			(layers "F.Cu" "F.Mask" "F.Paste")
			(net "P1V26_STBY")
		)
		(pad "R17" smd circle
			(at 4.400042 2.800096 180)
			(size 0.3556 0.3556)
			(layers "F.Cu" "F.Mask" "F.Paste")
			(net "P1V26_STBY")
		)
		(pad "R18" smd circle
			(at 5.199888 2.800096 180)
			(size 0.3556 0.3556)
			(layers "F.Cu" "F.Mask" "F.Paste")
			(net "TP_BMC_GPIOR4")
		)
		(pad "R19" smd circle
			(at 5.999988 2.800096 180)
			(size 0.3556 0.3556)
			(layers "F.Cu" "F.Mask" "F.Paste")
			(net "FLA_CS")
		)
		(pad "R20" smd circle
			(at 6.800088 2.800096 180)
			(size 0.3556 0.3556)
			(layers "F.Cu" "F.Mask" "F.Paste")
			(net "ROMA0")
		)
		(pad "R21" smd circle
			(at 7.599934 2.800096 180)
			(size 0.3556 0.3556)
			(layers "F.Cu" "F.Mask" "F.Paste")
			(net "ROMA1")
		)
		(pad "R22" smd circle
			(at 8.400034 2.800096 180)
			(size 0.3556 0.3556)
			(layers "F.Cu" "F.Mask" "F.Paste")
			(net "ROMA2")
		)
		(pad "T1" smd circle
			(at -8.400034 3.599942 180)
			(size 0.3556 0.3556)
			(layers "F.Cu" "F.Mask" "F.Paste")
			(net "TP_BMC_GPIOJ7")
		)
		(pad "T2" smd circle
			(at -7.599934 3.599942 180)
			(size 0.3556 0.3556)
			(layers "F.Cu" "F.Mask" "F.Paste")
			(net "TP_BMC_GPIOJ6")
		)
		(pad "T3" smd circle
			(at -6.800088 3.599942 180)
			(size 0.3556 0.3556)
			(layers "F.Cu" "F.Mask" "F.Paste")
			(net "P3V3_STBY")
		)
		(pad "T4" smd circle
			(at -5.999988 3.599942 180)
			(size 0.3556 0.3556)
			(layers "F.Cu" "F.Mask" "F.Paste")
			(net "TP_BMC_GPIOJ4")
		)
		(pad "T5" smd circle
			(at -5.199888 3.599942 180)
			(size 0.3556 0.3556)
			(layers "F.Cu" "F.Mask" "F.Paste")
			(net "TP_BMC_GPIOL1")
		)
		(pad "T18" smd circle
			(at 5.199888 3.599942 180)
			(size 0.3556 0.3556)
			(layers "F.Cu" "F.Mask" "F.Paste")
			(net "ROMA16")
		)
		(pad "T19" smd circle
			(at 5.999988 3.599942 180)
			(size 0.3556 0.3556)
			(layers "F.Cu" "F.Mask" "F.Paste")
			(net "ROMD5")
		)
		(pad "T20" smd circle
			(at 6.800088 3.599942 180)
			(size 0.3556 0.3556)
			(layers "F.Cu" "F.Mask" "F.Paste")
			(net "ROMD2")
		)
		(pad "T21" smd circle
			(at 7.599934 3.599942 180)
			(size 0.3556 0.3556)
			(layers "F.Cu" "F.Mask" "F.Paste")
			(net "ROMD1")
		)
		(pad "T22" smd circle
			(at 8.400034 3.599942 180)
			(size 0.3556 0.3556)
			(layers "F.Cu" "F.Mask" "F.Paste")
			(net "ROMD0")
		)
		(pad "U1" smd circle
			(at -8.400034 4.400042 180)
			(size 0.3556 0.3556)
			(layers "F.Cu" "F.Mask" "F.Paste")
			(net "TP_BMC_GPIOL0")
		)
		(pad "U2" smd circle
			(at -7.599934 4.400042 180)
			(size 0.3556 0.3556)
			(layers "F.Cu" "F.Mask" "F.Paste")
			(net "TP_BMC_GPIOJ5")
		)
		(pad "U3" smd circle
			(at -6.800088 4.400042 180)
			(size 0.3556 0.3556)
			(layers "F.Cu" "F.Mask" "F.Paste")
			(net "TP_BMC_GPIOL2")
		)
		(pad "U4" smd circle
			(at -5.999988 4.400042 180)
			(size 0.3556 0.3556)
			(layers "F.Cu" "F.Mask" "F.Paste")
			(net "TP_BMC_GPIOL4")
		)
		(pad "U5" smd circle
			(at -5.199888 4.400042 180)
			(size 0.3556 0.3556)
			(layers "F.Cu" "F.Mask" "F.Paste")
			(net "TP_BMC_GPIOL7")
		)
		(pad "U8" smd circle
			(at -2.800096 4.400042 180)
			(size 0.3556 0.3556)
			(layers "F.Cu" "F.Mask" "F.Paste")
			(net "P3V3_STBY")
		)
		(pad "U9" smd circle
			(at -1.999996 4.400042 180)
			(size 0.3556 0.3556)
			(layers "F.Cu" "F.Mask" "F.Paste")
			(net "P3V3_STBY")
		)
		(pad "U10" smd circle
			(at -1.199896 4.400042 180)
			(size 0.3556 0.3556)
			(layers "F.Cu" "F.Mask" "F.Paste")
			(net "P1V53_STBY")
		)
		(pad "U11" smd circle
			(at -0.40005 4.400042 180)
			(size 0.3556 0.3556)
			(layers "F.Cu" "F.Mask" "F.Paste")
			(net "P1V53_STBY")
		)
		(pad "U12" smd circle
			(at 0.40005 4.400042 180)
			(size 0.3556 0.3556)
			(layers "F.Cu" "F.Mask" "F.Paste")
			(net "P1V26_STBY")
		)
		(pad "U13" smd circle
			(at 1.199896 4.400042 180)
			(size 0.3556 0.3556)
			(layers "F.Cu" "F.Mask" "F.Paste")
			(net "P1V26_STBY")
		)
		(pad "U14" smd circle
			(at 1.999996 4.400042 180)
			(size 0.3556 0.3556)
			(layers "F.Cu" "F.Mask" "F.Paste")
			(net "P1V53_STBY")
		)
		(pad "U15" smd circle
			(at 2.800096 4.400042 180)
			(size 0.3556 0.3556)
			(layers "F.Cu" "F.Mask" "F.Paste")
			(net "P1V53_STBY")
		)
		(pad "U18" smd circle
			(at 5.199888 4.400042 180)
			(size 0.3556 0.3556)
			(layers "F.Cu" "F.Mask" "F.Paste")
			(net "EXP_TRAY_ID_BMC")
		)
		(pad "U19" smd circle
			(at 5.999988 4.400042 180)
			(size 0.3556 0.3556)
			(layers "F.Cu" "F.Mask" "F.Paste")
			(net "TP_BMC_GPIOR3")
		)
		(pad "U20" smd circle
			(at 6.800088 4.400042 180)
			(size 0.3556 0.3556)
			(layers "F.Cu" "F.Mask" "F.Paste")
			(net "ROMD7")
		)
		(pad "U21" smd circle
			(at 7.599934 4.400042 180)
			(size 0.3556 0.3556)
			(layers "F.Cu" "F.Mask" "F.Paste")
			(net "ROMD4")
		)
		(pad "U22" smd circle
			(at 8.400034 4.400042 180)
			(size 0.3556 0.3556)
			(layers "F.Cu" "F.Mask" "F.Paste")
			(net "ROMD3")
		)
		(pad "V1" smd circle
			(at -8.400034 5.199888 180)
			(size 0.3556 0.3556)
			(layers "F.Cu" "F.Mask" "F.Paste")
			(net "TP_BMC_GPIOL3")
		)
		(pad "V2" smd circle
			(at -7.599934 5.199888 180)
			(size 0.3556 0.3556)
			(layers "F.Cu" "F.Mask" "F.Paste")
			(net "TP_BMC_GPIOL5")
		)
		(pad "V3" smd circle
			(at -6.800088 5.199888 180)
			(size 0.3556 0.3556)
			(layers "F.Cu" "F.Mask" "F.Paste")
			(net "TP_BMC_GPIOM0")
		)
		(pad "V4" smd circle
			(at -5.999988 5.199888 180)
			(size 0.3556 0.3556)
			(layers "F.Cu" "F.Mask" "F.Paste")
			(net "TP_BMC_GPIOM3")
		)
		(pad "V5" smd circle
			(at -5.199888 5.199888 180)
			(size 0.3556 0.3556)
			(layers "F.Cu" "F.Mask" "F.Paste")
			(net "TP_BMC_GPIOM7")
		)
		(pad "V6" smd circle
			(at -4.400042 5.199888 180)
			(size 0.3556 0.3556)
			(layers "F.Cu" "F.Mask" "F.Paste")
			(net "HB0_R_IN0")
		)
		(pad "V7" smd circle
			(at -3.599942 5.199888 180)
			(size 0.3556 0.3556)
			(layers "F.Cu" "F.Mask" "F.Paste")
			(net "TP_BMC_GPIOO7")
		)
		(pad "V8" smd circle
			(at -2.800096 5.199888 180)
			(size 0.3556 0.3556)
			(layers "F.Cu" "F.Mask" "F.Paste")
			(net "MEMDM_1")
		)
		(pad "V9" smd circle
			(at -1.999996 5.199888 180)
			(size 0.3556 0.3556)
			(layers "F.Cu" "F.Mask" "F.Paste")
			(net "MEMDQ_13")
		)
		(pad "V10" smd circle
			(at -1.199896 5.199888 180)
			(size 0.3556 0.3556)
			(layers "F.Cu" "F.Mask" "F.Paste")
			(net "MEMDQ_8")
		)
		(pad "V11" smd circle
			(at -0.40005 5.199888 180)
			(size 0.3556 0.3556)
			(layers "F.Cu" "F.Mask" "F.Paste")
			(net "MEMDQ_6")
		)
		(pad "V12" smd circle
			(at 0.40005 5.199888 180)
			(size 0.3556 0.3556)
			(layers "F.Cu" "F.Mask" "F.Paste")
			(net "MEMDQ_1")
		)
		(pad "V13" smd circle
			(at 1.199896 5.199888 180)
			(size 0.3556 0.3556)
			(layers "F.Cu" "F.Mask" "F.Paste")
			(net "DDR_VREF")
		)
		(pad "V14" smd circle
			(at 1.999996 5.199888 180)
			(size 0.3556 0.3556)
			(layers "F.Cu" "F.Mask" "F.Paste")
			(net "MEMODT")
		)
		(pad "V15" smd circle
			(at 2.800096 5.199888 180)
			(size 0.3556 0.3556)
			(layers "F.Cu" "F.Mask" "F.Paste")
			(net "MEMA_2")
		)
		(pad "V16" smd circle
			(at 3.599942 5.199888 180)
			(size 0.3556 0.3556)
			(layers "F.Cu" "F.Mask" "F.Paste")
			(net "Net_1410")
		)
		(pad "V17" smd circle
			(at 4.400042 5.199888 180)
			(size 0.3556 0.3556)
			(layers "F.Cu" "F.Mask" "F.Paste")
			(net "MPLLAV33")
		)
		(pad "V18" smd circle
			(at 5.199888 5.199888 180)
			(size 0.3556 0.3556)
			(layers "F.Cu" "F.Mask" "F.Paste")
			(net "GND")
		)
		(pad "V19" smd circle
			(at 5.999988 5.199888 180)
			(size 0.3556 0.3556)
			(layers "F.Cu" "F.Mask" "F.Paste")
			(net "P1V26_STBY")
		)
		(pad "V20" smd circle
			(at 6.800088 5.199888 180)
			(size 0.3556 0.3556)
			(layers "F.Cu" "F.Mask" "F.Paste")
			(net "FLA_CS_1_R")
		)
		(pad "V21" smd circle
			(at 7.599934 5.199888 180)
			(size 0.3556 0.3556)
			(layers "F.Cu" "F.Mask" "F.Paste")
			(net "TP_BMC_GPIOR4")
		)
		(pad "V22" smd circle
			(at 8.400034 5.199888 180)
			(size 0.3556 0.3556)
			(layers "F.Cu" "F.Mask" "F.Paste")
			(net "ROMD6")
		)
		(pad "W1" smd circle
			(at -8.400034 5.999988 180)
			(size 0.3556 0.3556)
			(layers "F.Cu" "F.Mask" "F.Paste")
			(net "TP_BMC_GPIOL6")
		)
		(pad "W2" smd circle
			(at -7.599934 5.999988 180)
			(size 0.3556 0.3556)
			(layers "F.Cu" "F.Mask" "F.Paste")
			(net "TP_BMC_GPIOM1")
		)
		(pad "W3" smd circle
			(at -6.800088 5.999988 180)
			(size 0.3556 0.3556)
			(layers "F.Cu" "F.Mask" "F.Paste")
			(net "TP_BMC_GPIOM4")
		)
		(pad "W4" smd circle
			(at -5.999988 5.999988 180)
			(size 0.3556 0.3556)
			(layers "F.Cu" "F.Mask" "F.Paste")
			(net "FAN_PWM_PCIE_BMC")
		)
		(pad "W5" smd circle
			(at -5.199888 5.999988 180)
			(size 0.3556 0.3556)
			(layers "F.Cu" "F.Mask" "F.Paste")
			(net "BMC_SELF_TRAY")
		)
		(pad "W6" smd circle
			(at -4.400042 5.999988 180)
			(size 0.3556 0.3556)
			(layers "F.Cu" "F.Mask" "F.Paste")
			(net "HB_EXP_TO_BMC")
		)
		(pad "W7" smd circle
			(at -3.599942 5.999988 180)
			(size 0.3556 0.3556)
			(layers "F.Cu" "F.Mask" "F.Paste")
			(net "BMC0_TACH10")
		)
		(pad "W8" smd circle
			(at -2.800096 5.999988 180)
			(size 0.3556 0.3556)
			(layers "F.Cu" "F.Mask" "F.Paste")
			(net "MEMDQ_15")
		)
		(pad "W9" smd circle
			(at -1.999996 5.999988 180)
			(size 0.3556 0.3556)
			(layers "F.Cu" "F.Mask" "F.Paste")
			(net "MEMDQ_12")
		)
		(pad "W10" smd circle
			(at -1.199896 5.999988 180)
			(size 0.3556 0.3556)
			(layers "F.Cu" "F.Mask" "F.Paste")
			(net "MEMDM_0")
		)
		(pad "W11" smd circle
			(at -0.40005 5.999988 180)
			(size 0.3556 0.3556)
			(layers "F.Cu" "F.Mask" "F.Paste")
			(net "MEMDQ_5")
		)
		(pad "W12" smd circle
			(at 0.40005 5.999988 180)
			(size 0.3556 0.3556)
			(layers "F.Cu" "F.Mask" "F.Paste")
			(net "MEMDQ_0")
		)
		(pad "W13" smd circle
			(at 1.199896 5.999988 180)
			(size 0.3556 0.3556)
			(layers "F.Cu" "F.Mask" "F.Paste")
			(net "MEMRASN")
		)
		(pad "W14" smd circle
			(at 1.999996 5.999988 180)
			(size 0.3556 0.3556)
			(layers "F.Cu" "F.Mask" "F.Paste")
			(net "MEMBA_0")
		)
		(pad "W15" smd circle
			(at 2.800096 5.999988 180)
			(size 0.3556 0.3556)
			(layers "F.Cu" "F.Mask" "F.Paste")
			(net "MEMA_1")
		)
		(pad "W16" smd circle
			(at 3.599942 5.999988 180)
			(size 0.3556 0.3556)
			(layers "F.Cu" "F.Mask" "F.Paste")
			(net "MEMA_5")
		)
		(pad "W17" smd circle
			(at 4.400042 5.999988 180)
			(size 0.3556 0.3556)
			(layers "F.Cu" "F.Mask" "F.Paste")
			(net "MEMA_12")
		)
		(pad "W18" smd circle
			(at 5.199888 5.999988 180)
			(size 0.3556 0.3556)
			(layers "F.Cu" "F.Mask" "F.Paste")
			(net "P3V3_STBY")
		)
		(pad "W19" smd circle
			(at 5.999988 5.999988 180)
			(size 0.3556 0.3556)
			(layers "F.Cu" "F.Mask" "F.Paste")
			(net "V1PLLAV12")
		)
		(pad "W20" smd circle
			(at 6.800088 5.999988 180)
			(size 0.3556 0.3556)
			(layers "F.Cu" "F.Mask" "F.Paste")
			(net "BMC0_SRST_N")
		)
		(pad "W21" smd circle
			(at 7.599934 5.999988 180)
			(size 0.3556 0.3556)
			(layers "F.Cu" "F.Mask" "F.Paste")
			(net "TP_BMC_GPIOR1")
		)
		(pad "W22" smd circle
			(at 8.400034 5.999988 180)
			(size 0.3556 0.3556)
			(layers "F.Cu" "F.Mask" "F.Paste")
			(net "TP_BMC_GPIOR5")
		)
		(pad "Y1" smd circle
			(at -8.400034 6.800088 180)
			(size 0.4064 0.4064)
			(layers "F.Cu" "F.Mask" "F.Paste")
			(net "TP_BMC_GPIOM2")
		)
		(pad "Y2" smd circle
			(at -7.599934 6.800088 180)
			(size 0.4064 0.4064)
			(layers "F.Cu" "F.Mask" "F.Paste")
			(net "TP_BMC_GPIOM5")
		)
		(pad "Y3" smd circle
			(at -6.800088 6.800088 180)
			(size 0.4064 0.4064)
			(layers "F.Cu" "F.Mask" "F.Paste")
			(net "BMC_FW_DET_BOARD_VER_0")
		)
		(pad "Y4" smd circle
			(at -5.999988 6.800088 180)
			(size 0.3556 0.3556)
			(layers "F.Cu" "F.Mask" "F.Paste")
			(net "BMC0_I2C_IO_EXP_RESET#")
		)
		(pad "Y5" smd circle
			(at -5.199888 6.800088 180)
			(size 0.3556 0.3556)
			(layers "F.Cu" "F.Mask" "F.Paste")
			(net "HB0_R_IN1")
		)
		(pad "Y6" smd circle
			(at -4.400042 6.800088 180)
			(size 0.3556 0.3556)
			(layers "F.Cu" "F.Mask" "F.Paste")
			(net "TP_BMC0_TACH8")
		)
		(pad "Y7" smd circle
			(at -3.599942 6.800088 180)
			(size 0.3556 0.3556)
			(layers "F.Cu" "F.Mask" "F.Paste")
			(net "BMC0_TACH13")
		)
		(pad "Y8" smd circle
			(at -2.800096 6.800088 180)
			(size 0.3556 0.3556)
			(layers "F.Cu" "F.Mask" "F.Paste")
			(net "MEMDQ_14")
		)
		(pad "Y9" smd circle
			(at -1.999996 6.800088 180)
			(size 0.3556 0.3556)
			(layers "F.Cu" "F.Mask" "F.Paste")
			(net "MEMDQ_11")
		)
		(pad "Y10" smd circle
			(at -1.199896 6.800088 180)
			(size 0.3556 0.3556)
			(layers "F.Cu" "F.Mask" "F.Paste")
			(net "MEMDQ_7")
		)
		(pad "Y11" smd circle
			(at -0.40005 6.800088 180)
			(size 0.3556 0.3556)
			(layers "F.Cu" "F.Mask" "F.Paste")
			(net "MEMDQ_4")
		)
		(pad "Y12" smd circle
			(at 0.40005 6.800088 180)
			(size 0.3556 0.3556)
			(layers "F.Cu" "F.Mask" "F.Paste")
			(net "MEMCKE")
		)
		(pad "Y13" smd circle
			(at 1.199896 6.800088 180)
			(size 0.3556 0.3556)
			(layers "F.Cu" "F.Mask" "F.Paste")
			(net "MEMWEN")
		)
		(pad "Y14" smd circle
			(at 1.999996 6.800088 180)
			(size 0.3556 0.3556)
			(layers "F.Cu" "F.Mask" "F.Paste")
			(net "MEMBA_2")
		)
		(pad "Y15" smd circle
			(at 2.800096 6.800088 180)
			(size 0.3556 0.3556)
			(layers "F.Cu" "F.Mask" "F.Paste")
			(net "MEMA_10")
		)
		(pad "Y16" smd circle
			(at 3.599942 6.800088 180)
			(size 0.3556 0.3556)
			(layers "F.Cu" "F.Mask" "F.Paste")
			(net "MEMA_3")
		)
		(pad "Y17" smd circle
			(at 4.400042 6.800088 180)
			(size 0.3556 0.3556)
			(layers "F.Cu" "F.Mask" "F.Paste")
			(net "MEMA_13")
		)
		(pad "Y18" smd circle
			(at 5.199888 6.800088 180)
			(size 0.3556 0.3556)
			(layers "F.Cu" "F.Mask" "F.Paste")
			(net "P1V26_STBY")
		)
		(pad "Y19" smd circle
			(at 5.999988 6.800088 180)
			(size 0.3556 0.3556)
			(layers "F.Cu" "F.Mask" "F.Paste")
			(net "GND")
		)
		(pad "Y20" smd circle
			(at 6.800088 6.800088 180)
			(size 0.4064 0.4064)
			(layers "F.Cu" "F.Mask" "F.Paste")
			(net "V1PLLAV12")
		)
		(pad "Y21" smd circle
			(at 7.599934 6.800088 180)
			(size 0.4064 0.4064)
			(layers "F.Cu" "F.Mask" "F.Paste")
			(net "DP_BMC_EXP_RST_N_R")
		)
		(pad "Y22" smd circle
			(at 8.400034 6.800088 180)
			(size 0.4064 0.4064)
			(layers "F.Cu" "F.Mask" "F.Paste")
			(net "TP_BMC_GPIOR2")
		)
	)
	(footprint ""
		(layer "F.Cu")
		(at 273.158966 -18.734532 -90)
		(property "Reference" "C240"
			(at 0 0 270)
			(layer "F.SilkS")
			(hide yes)
			(effects
				(font
					(size 1.27 1.27)
				)
			)
		)
		(property "Value" "SCD1U16V2JX-1-GP"
			(at 1.1811 -2.7051 270)
			(unlocked yes)
			(layer "F.Fab")
			(hide yes)
			(effects
				(font
					(size 1.016 1.016)
					(thickness 0.1524)
				)
			)
		)
		(property "Device Type" "C402H22"
			(at 1.1811 -4.2291 270)
			(unlocked yes)
			(layer "F.Fab")
			(hide yes)
			(effects
				(font
					(size 1.016 1.016)
					(thickness 0.1524)
				)
			)
		)
		(duplicate_pad_numbers_are_jumpers no)
		(fp_rect
			(start -0.4318 0.9525)
			(end 0.4318 -0.9525)
			(stroke
				(width 0)
				(type default)
			)
			(fill no)
			(layer "F.CrtYd")
		)
		(fp_rect
			(start -0.4318 0.9525)
			(end 0.4318 -0.9525)
			(stroke
				(width 0)
				(type default)
			)
			(fill no)
			(layer "F.Fab")
		)
		(pad "1" smd custom
			(at 0 -0.4445 270)
			(size 0.1524 0.1524)
			(layers "F.Cu" "F.Mask" "F.Paste")
			(net "P5V_USB")
			(options
				(clearance outline)
				(anchor circle)
			)
			(primitives
				(gr_poly
					(pts
						(arc
							(start 0.3048 -0.2032)
							(mid 0.275042 -0.275042)
							(end 0.2032 -0.3048)
						)
						(arc
							(start -0.2032 -0.3048)
							(mid -0.275042 -0.275042)
							(end -0.3048 -0.2032)
						)
						(arc
							(start -0.3048 0.2032)
							(mid -0.275042 0.275042)
							(end -0.2032 0.3048)
						)
						(arc
							(start 0.2032 0.3048)
							(mid 0.275042 0.275042)
							(end 0.3048 0.2032)
						)
					)
					(width 0)
					(fill yes)
				)
			)
		)
		(pad "2" smd custom
			(at 0 0.4445 270)
			(size 0.1524 0.1524)
			(layers "F.Cu" "F.Mask" "F.Paste")
			(net "GND")
			(options
				(clearance outline)
				(anchor circle)
			)
			(primitives
				(gr_poly
					(pts
						(arc
							(start 0.3048 -0.2032)
							(mid 0.275042 -0.275042)
							(end 0.2032 -0.3048)
						)
						(arc
							(start -0.2032 -0.3048)
							(mid -0.275042 -0.275042)
							(end -0.3048 -0.2032)
						)
						(arc
							(start -0.3048 0.2032)
							(mid -0.275042 0.275042)
							(end -0.2032 0.3048)
						)
						(arc
							(start 0.2032 0.3048)
							(mid 0.275042 0.275042)
							(end 0.3048 0.2032)
						)
					)
					(width 0)
					(fill yes)
				)
			)
		)
	)
	(footprint ""
		(layer "F.Cu")
		(at 212.86597 -69.088)
		(property "Reference" "R17"
			(at 0 0 0)
			(layer "F.SilkS")
			(hide yes)
			(effects
				(font
					(size 1.27 1.27)
				)
			)
		)
		(property "Value" "100R2F-L1-GP-U"
			(at 0.064008 -3.993896 0)
			(unlocked yes)
			(layer "F.Fab")
			(hide yes)
			(effects
				(font
					(size 1.016 1.016)
					(thickness 0.1524)
				)
			)
		)
		(property "Device Type" "R402H14"
			(at 0.064008 -5.517896 0)
			(unlocked yes)
			(layer "F.Fab")
			(hide yes)
			(effects
				(font
					(size 1.016 1.016)
					(thickness 0.1524)
				)
			)
		)
		(duplicate_pad_numbers_are_jumpers no)
		(fp_line
			(start -0.508 -0.9398)
			(end -0.508 0.9398)
			(stroke
				(width 0.1524)
				(type default)
			)
			(layer "F.SilkS")
		)
		(fp_line
			(start 0.508 -0.9398)
			(end -0.508 -0.9398)
			(stroke
				(width 0.1524)
				(type default)
			)
			(layer "F.SilkS")
		)
		(fp_rect
			(start -0.508 0.9398)
			(end 0.508 -0.9398)
			(stroke
				(width 0)
				(type default)
			)
			(fill no)
			(layer "F.CrtYd")
		)
		(fp_rect
			(start -0.508 0.9398)
			(end 0.508 -0.9398)
			(stroke
				(width 0)
				(type default)
			)
			(fill no)
			(layer "F.Fab")
		)
		(pad "1" smd custom
			(at 0 -0.4445)
			(size 0.1397 0.1397)
			(layers "F.Cu" "F.Mask" "F.Paste")
			(net "SVR_ID2")
			(options
				(clearance outline)
				(anchor circle)
			)
			(primitives
				(gr_poly
					(pts
						(arc
							(start -0.1778 -0.2794)
							(mid -0.249642 -0.249642)
							(end -0.2794 -0.1778)
						)
						(arc
							(start -0.2794 0.1778)
							(mid -0.249642 0.249642)
							(end -0.1778 0.2794)
						)
						(arc
							(start 0.1778 0.2794)
							(mid 0.249642 0.249642)
							(end 0.2794 0.1778)
						)
						(arc
							(start 0.2794 -0.1778)
							(mid 0.249642 -0.249642)
							(end 0.1778 -0.2794)
						)
					)
					(width 0)
					(fill yes)
				)
			)
		)
		(pad "2" smd custom
			(at 0 0.4445)
			(size 0.1397 0.1397)
			(layers "F.Cu" "F.Mask" "F.Paste")
			(net "GND")
			(options
				(clearance outline)
				(anchor circle)
			)
			(primitives
				(gr_poly
					(pts
						(arc
							(start -0.1778 -0.2794)
							(mid -0.249642 -0.249642)
							(end -0.2794 -0.1778)
						)
						(arc
							(start -0.2794 0.1778)
							(mid -0.249642 0.249642)
							(end -0.1778 0.2794)
						)
						(arc
							(start 0.1778 0.2794)
							(mid 0.249642 0.249642)
							(end 0.2794 0.1778)
						)
						(arc
							(start 0.2794 -0.1778)
							(mid 0.249642 -0.249642)
							(end 0.1778 -0.2794)
						)
					)
					(width 0)
					(fill yes)
				)
			)
		)
	)
	(footprint ""
		(layer "F.Cu")
		(at 218.948 -168.275 -90)
		(property "Reference" "U178"
			(at 0 0 270)
			(layer "F.SilkS")
			(hide yes)
			(effects
				(font
					(size 1.27 1.27)
				)
			)
		)
		(property "Value" "SNLVC1G126DCKR-GP"
			(at -2.3368 -8.6868 270)
			(unlocked yes)
			(layer "F.Fab")
			(hide yes)
			(effects
				(font
					(size 1.016 1.016)
					(thickness 0.1524)
				)
			)
		)
		(property "Device Type" "SC70-5H44"
			(at -2.3114 -10.414 270)
			(unlocked yes)
			(layer "F.Fab")
			(hide yes)
			(effects
				(font
					(size 1.016 1.016)
					(thickness 0.1524)
				)
			)
		)
		(duplicate_pad_numbers_are_jumpers no)
		(fp_line
			(start -1.27 1.7018)
			(end -1.27 -1.7018)
			(stroke
				(width 0.1524)
				(type default)
			)
			(layer "F.SilkS")
		)
		(fp_line
			(start 1.27 1.7018)
			(end -1.27 1.7018)
			(stroke
				(width 0.1524)
				(type default)
			)
			(layer "F.SilkS")
		)
		(fp_line
			(start -1.27 -1.7018)
			(end 1.27 -1.7018)
			(stroke
				(width 0.1524)
				(type default)
			)
			(layer "F.SilkS")
		)
		(fp_line
			(start 1.27 -1.7018)
			(end 1.27 1.7018)
			(stroke
				(width 0.1524)
				(type default)
			)
			(layer "F.SilkS")
		)
		(fp_line
			(start 0.6604 -1.8034)
			(end 1.3843 -1.8034)
			(stroke
				(width 0.3302)
				(type default)
			)
			(layer "F.SilkS")
		)
		(fp_line
			(start 1.3843 -1.8034)
			(end 1.3843 -1.1176)
			(stroke
				(width 0.3302)
				(type default)
			)
			(layer "F.SilkS")
		)
		(fp_rect
			(start -1.524 1.9558)
			(end 1.524 -1.9558)
			(stroke
				(width 0)
				(type default)
			)
			(fill no)
			(layer "F.CrtYd")
		)
		(fp_poly
			(pts
				(xy -1.524 -1.9558) (xy 1.524 -1.9558) (xy 1.524 1.9558) (xy -1.524 1.9558)
			)
			(stroke
				(width 0)
				(type default)
			)
			(fill no)
			(layer "F.Fab")
		)
		(pad "1" smd rect
			(at 0.65024 -0.8255 270)
			(size 0.4064 1.2192)
			(layers "F.Cu" "F.Mask" "F.Paste")
			(net "JTAG_DT")
		)
		(pad "2" smd rect
			(at 0 -0.8255 270)
			(size 0.4064 1.2192)
			(layers "F.Cu" "F.Mask" "F.Paste")
			(net "JTAG_IOC_TDO_L")
		)
		(pad "3" smd rect
			(at -0.65024 -0.8255 270)
			(size 0.4064 1.2192)
			(layers "F.Cu" "F.Mask" "F.Paste")
			(net "GND")
		)
		(pad "4" smd rect
			(at -0.65024 0.8255 270)
			(size 0.4064 1.2192)
			(layers "F.Cu" "F.Mask" "F.Paste")
			(net "JTAG_BMC_TDI")
		)
		(pad "5" smd rect
			(at 0.65024 0.8255 270)
			(size 0.4064 1.2192)
			(layers "F.Cu" "F.Mask" "F.Paste")
			(net "P3V3_STBY")
		)
	)
	(footprint ""
		(layer "F.Cu")
		(at 301.752 -92.329 -90)
		(property "Reference" "R5309"
			(at 0 0 270)
			(layer "F.SilkS")
			(hide yes)
			(effects
				(font
					(size 1.27 1.27)
				)
			)
		)
		(property "Value" "0R2J-2-GP"
			(at 0.064008 -3.993896 270)
			(unlocked yes)
			(layer "F.Fab")
			(hide yes)
			(effects
				(font
					(size 1.016 1.016)
					(thickness 0.1524)
				)
			)
		)
		(property "Device Type" "R402H16"
			(at 0.064008 -5.517896 270)
			(unlocked yes)
			(layer "F.Fab")
			(hide yes)
			(effects
				(font
					(size 1.016 1.016)
					(thickness 0.1524)
				)
			)
		)
		(duplicate_pad_numbers_are_jumpers no)
		(fp_line
			(start -0.508 -0.9398)
			(end -0.508 0.9398)
			(stroke
				(width 0.1524)
				(type default)
			)
			(layer "F.SilkS")
		)
		(fp_line
			(start 0.508 -0.9398)
			(end -0.508 -0.9398)
			(stroke
				(width 0.1524)
				(type default)
			)
			(layer "F.SilkS")
		)
		(fp_rect
			(start -0.508 0.9398)
			(end 0.508 -0.9398)
			(stroke
				(width 0)
				(type default)
			)
			(fill no)
			(layer "F.CrtYd")
		)
		(fp_rect
			(start -0.508 0.9398)
			(end 0.508 -0.9398)
			(stroke
				(width 0)
				(type default)
			)
			(fill no)
			(layer "F.Fab")
		)
		(pad "1" smd custom
			(at 0 -0.4445 270)
			(size 0.1397 0.1397)
			(layers "F.Cu" "F.Mask" "F.Paste")
			(net "BMC_I2C_SCL_10")
			(options
				(clearance outline)
				(anchor circle)
			)
			(primitives
				(gr_poly
					(pts
						(arc
							(start -0.1778 -0.2794)
							(mid -0.249642 -0.249642)
							(end -0.2794 -0.1778)
						)
						(arc
							(start -0.2794 0.1778)
							(mid -0.249642 0.249642)
							(end -0.1778 0.2794)
						)
						(arc
							(start 0.1778 0.2794)
							(mid 0.249642 0.249642)
							(end 0.2794 0.1778)
						)
						(arc
							(start 0.2794 -0.1778)
							(mid 0.249642 -0.249642)
							(end 0.1778 -0.2794)
						)
					)
					(width 0)
					(fill yes)
				)
			)
		)
		(pad "2" smd custom
			(at 0 0.4445 270)
			(size 0.1397 0.1397)
			(layers "F.Cu" "F.Mask" "F.Paste")
			(net "TEMP_2_SCL")
			(options
				(clearance outline)
				(anchor circle)
			)
			(primitives
				(gr_poly
					(pts
						(arc
							(start -0.1778 -0.2794)
							(mid -0.249642 -0.249642)
							(end -0.2794 -0.1778)
						)
						(arc
							(start -0.2794 0.1778)
							(mid -0.249642 0.249642)
							(end -0.1778 0.2794)
						)
						(arc
							(start 0.1778 0.2794)
							(mid 0.249642 0.249642)
							(end 0.2794 0.1778)
						)
						(arc
							(start 0.2794 -0.1778)
							(mid 0.249642 -0.249642)
							(end 0.1778 -0.2794)
						)
					)
					(width 0)
					(fill yes)
				)
			)
		)
	)
	(footprint ""
		(layer "F.Cu")
		(at 25.596088 -195.454016 180)
		(property "Reference" "SC546"
			(at 0 0 180)
			(layer "F.SilkS")
			(hide yes)
			(effects
				(font
					(size 1.27 1.27)
				)
			)
		)
		(property "Value" "SCD1U16V2KX-3GP"
			(at 1.1811 -2.7051 180)
			(unlocked yes)
			(layer "F.Fab")
			(hide yes)
			(effects
				(font
					(size 1.016 1.016)
					(thickness 0.1524)
				)
			)
		)
		(property "Device Type" "C402H22"
			(at 1.1811 -4.2291 180)
			(unlocked yes)
			(layer "F.Fab")
			(hide yes)
			(effects
				(font
					(size 1.016 1.016)
					(thickness 0.1524)
				)
			)
		)
		(duplicate_pad_numbers_are_jumpers no)
		(fp_rect
			(start -0.4318 0.9525)
			(end 0.4318 -0.9525)
			(stroke
				(width 0)
				(type default)
			)
			(fill no)
			(layer "F.CrtYd")
		)
		(fp_rect
			(start -0.4318 0.9525)
			(end 0.4318 -0.9525)
			(stroke
				(width 0)
				(type default)
			)
			(fill no)
			(layer "F.Fab")
		)
		(pad "1" smd custom
			(at 0 -0.4445 180)
			(size 0.1524 0.1524)
			(layers "F.Cu" "F.Mask" "F.Paste")
			(net "P1V8_E")
			(options
				(clearance outline)
				(anchor circle)
			)
			(primitives
				(gr_poly
					(pts
						(arc
							(start 0.3048 -0.2032)
							(mid 0.275042 -0.275042)
							(end 0.2032 -0.3048)
						)
						(arc
							(start -0.2032 -0.3048)
							(mid -0.275042 -0.275042)
							(end -0.3048 -0.2032)
						)
						(arc
							(start -0.3048 0.2032)
							(mid -0.275042 0.275042)
							(end -0.2032 0.3048)
						)
						(arc
							(start 0.2032 0.3048)
							(mid 0.275042 0.275042)
							(end 0.3048 0.2032)
						)
					)
					(width 0)
					(fill yes)
				)
			)
		)
		(pad "2" smd custom
			(at 0 0.4445 180)
			(size 0.1524 0.1524)
			(layers "F.Cu" "F.Mask" "F.Paste")
			(net "GND")
			(options
				(clearance outline)
				(anchor circle)
			)
			(primitives
				(gr_poly
					(pts
						(arc
							(start 0.3048 -0.2032)
							(mid 0.275042 -0.275042)
							(end 0.2032 -0.3048)
						)
						(arc
							(start -0.2032 -0.3048)
							(mid -0.275042 -0.275042)
							(end -0.3048 -0.2032)
						)
						(arc
							(start -0.3048 0.2032)
							(mid -0.275042 0.275042)
							(end -0.2032 0.3048)
						)
						(arc
							(start 0.2032 0.3048)
							(mid 0.275042 0.275042)
							(end 0.3048 0.2032)
						)
					)
					(width 0)
					(fill yes)
				)
			)
		)
	)
	(footprint ""
		(layer "F.Cu")
		(at 81.285842 -122.880882 -90)
		(property "Reference" "SC1106"
			(at 0 0 270)
			(layer "F.SilkS")
			(hide yes)
			(effects
				(font
					(size 1.27 1.27)
				)
			)
		)
		(property "Value" "SCD1U16V2KX-3GP"
			(at 1.1811 -2.7051 270)
			(unlocked yes)
			(layer "F.Fab")
			(hide yes)
			(effects
				(font
					(size 1.016 1.016)
					(thickness 0.1524)
				)
			)
		)
		(property "Device Type" "C402H22"
			(at 1.1811 -4.2291 270)
			(unlocked yes)
			(layer "F.Fab")
			(hide yes)
			(effects
				(font
					(size 1.016 1.016)
					(thickness 0.1524)
				)
			)
		)
		(duplicate_pad_numbers_are_jumpers no)
		(fp_rect
			(start -0.4318 0.9525)
			(end 0.4318 -0.9525)
			(stroke
				(width 0)
				(type default)
			)
			(fill no)
			(layer "F.CrtYd")
		)
		(fp_rect
			(start -0.4318 0.9525)
			(end 0.4318 -0.9525)
			(stroke
				(width 0)
				(type default)
			)
			(fill no)
			(layer "F.Fab")
		)
		(pad "1" smd custom
			(at 0 -0.4445 270)
			(size 0.1524 0.1524)
			(layers "F.Cu" "F.Mask" "F.Paste")
			(net "P1V8_E")
			(options
				(clearance outline)
				(anchor circle)
			)
			(primitives
				(gr_poly
					(pts
						(arc
							(start 0.3048 -0.2032)
							(mid 0.275042 -0.275042)
							(end 0.2032 -0.3048)
						)
						(arc
							(start -0.2032 -0.3048)
							(mid -0.275042 -0.275042)
							(end -0.3048 -0.2032)
						)
						(arc
							(start -0.3048 0.2032)
							(mid -0.275042 0.275042)
							(end -0.2032 0.3048)
						)
						(arc
							(start 0.2032 0.3048)
							(mid 0.275042 0.275042)
							(end 0.3048 0.2032)
						)
					)
					(width 0)
					(fill yes)
				)
			)
		)
		(pad "2" smd custom
			(at 0 0.4445 270)
			(size 0.1524 0.1524)
			(layers "F.Cu" "F.Mask" "F.Paste")
			(net "GND")
			(options
				(clearance outline)
				(anchor circle)
			)
			(primitives
				(gr_poly
					(pts
						(arc
							(start 0.3048 -0.2032)
							(mid 0.275042 -0.275042)
							(end 0.2032 -0.3048)
						)
						(arc
							(start -0.2032 -0.3048)
							(mid -0.275042 -0.275042)
							(end -0.3048 -0.2032)
						)
						(arc
							(start -0.3048 0.2032)
							(mid -0.275042 0.275042)
							(end -0.2032 0.3048)
						)
						(arc
							(start 0.2032 0.3048)
							(mid 0.275042 0.275042)
							(end 0.3048 0.2032)
						)
					)
					(width 0)
					(fill yes)
				)
			)
		)
	)
	(footprint ""
		(layer "F.Cu")
		(at 24.765 -237.236)
		(property "Reference" "SC426"
			(at 0 0 0)
			(layer "F.SilkS")
			(hide yes)
			(effects
				(font
					(size 1.27 1.27)
				)
			)
		)
		(property "Value" "SC1U10V3KX-4GP-U"
			(at 0 -2.8194 0)
			(unlocked yes)
			(layer "F.Fab")
			(hide yes)
			(effects
				(font
					(size 1.016 1.016)
					(thickness 0.1524)
				)
			)
		)
		(property "Device Type" "C603H36"
			(at 0 -4.3434 0)
			(unlocked yes)
			(layer "F.Fab")
			(hide yes)
			(effects
				(font
					(size 1.016 1.016)
					(thickness 0.1524)
				)
			)
		)
		(duplicate_pad_numbers_are_jumpers no)
		(fp_line
			(start 0.508 0)
			(end -0.508 0)
			(stroke
				(width 0.2032)
				(type default)
			)
			(layer "F.SilkS")
		)
		(fp_rect
			(start -0.5842 1.3335)
			(end 0.5842 -1.3335)
			(stroke
				(width 0)
				(type default)
			)
			(fill no)
			(layer "F.CrtYd")
		)
		(fp_rect
			(start -0.5842 1.3335)
			(end 0.5842 -1.3335)
			(stroke
				(width 0)
				(type default)
			)
			(fill no)
			(layer "F.Fab")
		)
		(pad "1" smd custom
			(at 0 -0.762)
			(size 0.2159 0.2159)
			(layers "F.Cu" "F.Mask" "F.Paste")
			(net "GND")
			(options
				(clearance outline)
				(anchor circle)
			)
			(primitives
				(gr_poly
					(pts
						(arc
							(start -0.3302 -0.4318)
							(mid -0.402042 -0.402042)
							(end -0.4318 -0.3302)
						)
						(arc
							(start -0.4318 0.3302)
							(mid -0.402042 0.402042)
							(end -0.3302 0.4318)
						)
						(arc
							(start 0.3302 0.4318)
							(mid 0.402042 0.402042)
							(end 0.4318 0.3302)
						)
						(arc
							(start 0.4318 -0.3302)
							(mid 0.402042 -0.402042)
							(end 0.3302 -0.4318)
						)
					)
					(width 0)
					(fill yes)
				)
			)
		)
		(pad "2" smd custom
			(at 0 0.762)
			(size 0.2159 0.2159)
			(layers "F.Cu" "F.Mask" "F.Paste")
			(net "P3V3_STBY")
			(options
				(clearance outline)
				(anchor circle)
			)
			(primitives
				(gr_poly
					(pts
						(arc
							(start -0.3302 -0.4318)
							(mid -0.402042 -0.402042)
							(end -0.4318 -0.3302)
						)
						(arc
							(start -0.4318 0.3302)
							(mid -0.402042 0.402042)
							(end -0.3302 0.4318)
						)
						(arc
							(start 0.3302 0.4318)
							(mid 0.402042 0.402042)
							(end 0.4318 0.3302)
						)
						(arc
							(start 0.4318 -0.3302)
							(mid 0.402042 -0.402042)
							(end 0.3302 -0.4318)
						)
					)
					(width 0)
					(fill yes)
				)
			)
		)
	)
	(footprint ""
		(layer "F.Cu")
		(at 174.51197 -67.183)
		(property "Reference" "C293"
			(at 0 0 0)
			(layer "F.SilkS")
			(hide yes)
			(effects
				(font
					(size 1.27 1.27)
				)
			)
		)
		(property "Value" "SCD1U25V2KX-2-GP"
			(at 1.1811 -2.7051 0)
			(unlocked yes)
			(layer "F.Fab")
			(hide yes)
			(effects
				(font
					(size 1.016 1.016)
					(thickness 0.1524)
				)
			)
		)
		(property "Device Type" "C402H22"
			(at 1.1811 -4.2291 0)
			(unlocked yes)
			(layer "F.Fab")
			(hide yes)
			(effects
				(font
					(size 1.016 1.016)
					(thickness 0.1524)
				)
			)
		)
		(duplicate_pad_numbers_are_jumpers no)
		(fp_rect
			(start -0.4318 0.9525)
			(end 0.4318 -0.9525)
			(stroke
				(width 0)
				(type default)
			)
			(fill no)
			(layer "F.CrtYd")
		)
		(fp_rect
			(start -0.4318 0.9525)
			(end 0.4318 -0.9525)
			(stroke
				(width 0)
				(type default)
			)
			(fill no)
			(layer "F.Fab")
		)
		(pad "1" smd custom
			(at 0 -0.4445)
			(size 0.1524 0.1524)
			(layers "F.Cu" "F.Mask" "F.Paste")
			(net "TP_MSB_A45_GBE_RX_P")
			(options
				(clearance outline)
				(anchor circle)
			)
			(primitives
				(gr_poly
					(pts
						(arc
							(start 0.3048 -0.2032)
							(mid 0.275042 -0.275042)
							(end 0.2032 -0.3048)
						)
						(arc
							(start -0.2032 -0.3048)
							(mid -0.275042 -0.275042)
							(end -0.3048 -0.2032)
						)
						(arc
							(start -0.3048 0.2032)
							(mid -0.275042 0.275042)
							(end -0.2032 0.3048)
						)
						(arc
							(start 0.2032 0.3048)
							(mid 0.275042 0.275042)
							(end 0.3048 0.2032)
						)
					)
					(width 0)
					(fill yes)
				)
			)
		)
		(pad "2" smd custom
			(at 0 0.4445)
			(size 0.1524 0.1524)
			(layers "F.Cu" "F.Mask" "F.Paste")
			(net "GND")
			(options
				(clearance outline)
				(anchor circle)
			)
			(primitives
				(gr_poly
					(pts
						(arc
							(start 0.3048 -0.2032)
							(mid 0.275042 -0.275042)
							(end 0.2032 -0.3048)
						)
						(arc
							(start -0.2032 -0.3048)
							(mid -0.275042 -0.275042)
							(end -0.3048 -0.2032)
						)
						(arc
							(start -0.3048 0.2032)
							(mid -0.275042 0.275042)
							(end -0.2032 0.3048)
						)
						(arc
							(start 0.2032 0.3048)
							(mid 0.275042 0.275042)
							(end 0.3048 0.2032)
						)
					)
					(width 0)
					(fill yes)
				)
			)
		)
	)
	(footprint ""
		(layer "F.Cu")
		(at 196.538596 -120.669812 -90)
		(property "Reference" "PC230"
			(at 0 0 270)
			(layer "F.SilkS")
			(hide yes)
			(effects
				(font
					(size 1.27 1.27)
				)
			)
		)
		(property "Value" "SC3300P50V2KX-1GP"
			(at 1.1811 -2.7051 270)
			(unlocked yes)
			(layer "F.Fab")
			(hide yes)
			(effects
				(font
					(size 1.016 1.016)
					(thickness 0.1524)
				)
			)
		)
		(property "Device Type" "C402H22"
			(at 1.1811 -4.2291 270)
			(unlocked yes)
			(layer "F.Fab")
			(hide yes)
			(effects
				(font
					(size 1.016 1.016)
					(thickness 0.1524)
				)
			)
		)
		(duplicate_pad_numbers_are_jumpers no)
		(fp_rect
			(start -0.4318 0.9525)
			(end 0.4318 -0.9525)
			(stroke
				(width 0)
				(type default)
			)
			(fill no)
			(layer "F.CrtYd")
		)
		(fp_rect
			(start -0.4318 0.9525)
			(end 0.4318 -0.9525)
			(stroke
				(width 0)
				(type default)
			)
			(fill no)
			(layer "F.Fab")
		)
		(pad "1" smd custom
			(at 0 -0.4445 270)
			(size 0.1524 0.1524)
			(layers "F.Cu" "F.Mask" "F.Paste")
			(net "P1V5_E_SS")
			(options
				(clearance outline)
				(anchor circle)
			)
			(primitives
				(gr_poly
					(pts
						(arc
							(start 0.3048 -0.2032)
							(mid 0.275042 -0.275042)
							(end 0.2032 -0.3048)
						)
						(arc
							(start -0.2032 -0.3048)
							(mid -0.275042 -0.275042)
							(end -0.3048 -0.2032)
						)
						(arc
							(start -0.3048 0.2032)
							(mid -0.275042 0.275042)
							(end -0.2032 0.3048)
						)
						(arc
							(start 0.2032 0.3048)
							(mid 0.275042 0.275042)
							(end 0.3048 0.2032)
						)
					)
					(width 0)
					(fill yes)
				)
			)
		)
		(pad "2" smd custom
			(at 0 0.4445 270)
			(size 0.1524 0.1524)
			(layers "F.Cu" "F.Mask" "F.Paste")
			(net "AGND_P1V5_E")
			(options
				(clearance outline)
				(anchor circle)
			)
			(primitives
				(gr_poly
					(pts
						(arc
							(start 0.3048 -0.2032)
							(mid 0.275042 -0.275042)
							(end 0.2032 -0.3048)
						)
						(arc
							(start -0.2032 -0.3048)
							(mid -0.275042 -0.275042)
							(end -0.3048 -0.2032)
						)
						(arc
							(start -0.3048 0.2032)
							(mid -0.275042 0.275042)
							(end -0.2032 0.3048)
						)
						(arc
							(start 0.2032 0.3048)
							(mid 0.275042 0.275042)
							(end 0.3048 0.2032)
						)
					)
					(width 0)
					(fill yes)
				)
			)
		)
	)
	(footprint ""
		(layer "F.Cu")
		(at 334.391 -211.455 180)
		(property "Reference" "R212"
			(at 0 0 180)
			(layer "F.SilkS")
			(hide yes)
			(effects
				(font
					(size 1.27 1.27)
				)
			)
		)
		(property "Value" "0R2J-2-GP"
			(at 0.064008 -3.993896 180)
			(unlocked yes)
			(layer "F.Fab")
			(hide yes)
			(effects
				(font
					(size 1.016 1.016)
					(thickness 0.1524)
				)
			)
		)
		(property "Device Type" "R402H16"
			(at 0.064008 -5.517896 180)
			(unlocked yes)
			(layer "F.Fab")
			(hide yes)
			(effects
				(font
					(size 1.016 1.016)
					(thickness 0.1524)
				)
			)
		)
		(duplicate_pad_numbers_are_jumpers no)
		(fp_line
			(start 0.508 -0.9398)
			(end -0.508 -0.9398)
			(stroke
				(width 0.1524)
				(type default)
			)
			(layer "F.SilkS")
		)
		(fp_line
			(start -0.508 -0.9398)
			(end -0.508 0.9398)
			(stroke
				(width 0.1524)
				(type default)
			)
			(layer "F.SilkS")
		)
		(fp_rect
			(start -0.508 0.9398)
			(end 0.508 -0.9398)
			(stroke
				(width 0)
				(type default)
			)
			(fill no)
			(layer "F.CrtYd")
		)
		(fp_rect
			(start -0.508 0.9398)
			(end 0.508 -0.9398)
			(stroke
				(width 0)
				(type default)
			)
			(fill no)
			(layer "F.Fab")
		)
		(pad "1" smd custom
			(at 0 -0.4445 180)
			(size 0.1397 0.1397)
			(layers "F.Cu" "F.Mask" "F.Paste")
			(net "EEPROM_SDA")
			(options
				(clearance outline)
				(anchor circle)
			)
			(primitives
				(gr_poly
					(pts
						(arc
							(start -0.1778 -0.2794)
							(mid -0.249642 -0.249642)
							(end -0.2794 -0.1778)
						)
						(arc
							(start -0.2794 0.1778)
							(mid -0.249642 0.249642)
							(end -0.1778 0.2794)
						)
						(arc
							(start 0.1778 0.2794)
							(mid 0.249642 0.249642)
							(end 0.2794 0.1778)
						)
						(arc
							(start 0.2794 -0.1778)
							(mid 0.249642 -0.249642)
							(end 0.1778 -0.2794)
						)
					)
					(width 0)
					(fill yes)
				)
			)
		)
		(pad "2" smd custom
			(at 0 0.4445 180)
			(size 0.1397 0.1397)
			(layers "F.Cu" "F.Mask" "F.Paste")
			(net "BMC_I2C_A_SDA")
			(options
				(clearance outline)
				(anchor circle)
			)
			(primitives
				(gr_poly
					(pts
						(arc
							(start -0.1778 -0.2794)
							(mid -0.249642 -0.249642)
							(end -0.2794 -0.1778)
						)
						(arc
							(start -0.2794 0.1778)
							(mid -0.249642 0.249642)
							(end -0.1778 0.2794)
						)
						(arc
							(start 0.1778 0.2794)
							(mid 0.249642 0.249642)
							(end 0.2794 0.1778)
						)
						(arc
							(start 0.2794 -0.1778)
							(mid 0.249642 -0.249642)
							(end 0.1778 -0.2794)
						)
					)
					(width 0)
					(fill yes)
				)
			)
		)
	)
	(footprint ""
		(layer "F.Cu")
		(at 92.21597 -95.504 -90)
		(property "Reference" "SR779"
			(at 0 0 270)
			(layer "F.SilkS")
			(hide yes)
			(effects
				(font
					(size 1.27 1.27)
				)
			)
		)
		(property "Value" "4K7R2F-GP"
			(at 0.064008 -3.993896 270)
			(unlocked yes)
			(layer "F.Fab")
			(hide yes)
			(effects
				(font
					(size 1.016 1.016)
					(thickness 0.1524)
				)
			)
		)
		(property "Device Type" "R402H16"
			(at 0.064008 -5.517896 270)
			(unlocked yes)
			(layer "F.Fab")
			(hide yes)
			(effects
				(font
					(size 1.016 1.016)
					(thickness 0.1524)
				)
			)
		)
		(duplicate_pad_numbers_are_jumpers no)
		(fp_line
			(start -0.508 -0.9398)
			(end -0.508 0.9398)
			(stroke
				(width 0.1524)
				(type default)
			)
			(layer "F.SilkS")
		)
		(fp_line
			(start 0.508 -0.9398)
			(end -0.508 -0.9398)
			(stroke
				(width 0.1524)
				(type default)
			)
			(layer "F.SilkS")
		)
		(fp_rect
			(start -0.508 0.9398)
			(end 0.508 -0.9398)
			(stroke
				(width 0)
				(type default)
			)
			(fill no)
			(layer "F.CrtYd")
		)
		(fp_rect
			(start -0.508 0.9398)
			(end 0.508 -0.9398)
			(stroke
				(width 0)
				(type default)
			)
			(fill no)
			(layer "F.Fab")
		)
		(pad "1" smd custom
			(at 0 -0.4445 270)
			(size 0.1397 0.1397)
			(layers "F.Cu" "F.Mask" "F.Paste")
			(net "EXP_XM_ADDR_18")
			(options
				(clearance outline)
				(anchor circle)
			)
			(primitives
				(gr_poly
					(pts
						(arc
							(start -0.1778 -0.2794)
							(mid -0.249642 -0.249642)
							(end -0.2794 -0.1778)
						)
						(arc
							(start -0.2794 0.1778)
							(mid -0.249642 0.249642)
							(end -0.1778 0.2794)
						)
						(arc
							(start 0.1778 0.2794)
							(mid 0.249642 0.249642)
							(end 0.2794 0.1778)
						)
						(arc
							(start 0.2794 -0.1778)
							(mid 0.249642 -0.249642)
							(end 0.1778 -0.2794)
						)
					)
					(width 0)
					(fill yes)
				)
			)
		)
		(pad "2" smd custom
			(at 0 0.4445 270)
			(size 0.1397 0.1397)
			(layers "F.Cu" "F.Mask" "F.Paste")
			(net "GND")
			(options
				(clearance outline)
				(anchor circle)
			)
			(primitives
				(gr_poly
					(pts
						(arc
							(start -0.1778 -0.2794)
							(mid -0.249642 -0.249642)
							(end -0.2794 -0.1778)
						)
						(arc
							(start -0.2794 0.1778)
							(mid -0.249642 0.249642)
							(end -0.1778 0.2794)
						)
						(arc
							(start 0.1778 0.2794)
							(mid 0.249642 0.249642)
							(end 0.2794 0.1778)
						)
						(arc
							(start 0.2794 -0.1778)
							(mid 0.249642 -0.249642)
							(end 0.1778 -0.2794)
						)
					)
					(width 0)
					(fill yes)
				)
			)
		)
	)
	(footprint ""
		(layer "F.Cu")
		(at 280.289 -197.231 -90)
		(property "Reference" "C195"
			(at 0 0 270)
			(layer "F.SilkS")
			(hide yes)
			(effects
				(font
					(size 1.27 1.27)
				)
			)
		)
		(property "Value" "SCD1U16V2KX-3GP"
			(at 1.1811 -2.7051 270)
			(unlocked yes)
			(layer "F.Fab")
			(hide yes)
			(effects
				(font
					(size 1.016 1.016)
					(thickness 0.1524)
				)
			)
		)
		(property "Device Type" "C402H22"
			(at 1.1811 -4.2291 270)
			(unlocked yes)
			(layer "F.Fab")
			(hide yes)
			(effects
				(font
					(size 1.016 1.016)
					(thickness 0.1524)
				)
			)
		)
		(duplicate_pad_numbers_are_jumpers no)
		(fp_rect
			(start -0.4318 0.9525)
			(end 0.4318 -0.9525)
			(stroke
				(width 0)
				(type default)
			)
			(fill no)
			(layer "F.CrtYd")
		)
		(fp_rect
			(start -0.4318 0.9525)
			(end 0.4318 -0.9525)
			(stroke
				(width 0)
				(type default)
			)
			(fill no)
			(layer "F.Fab")
		)
		(pad "1" smd custom
			(at 0 -0.4445 270)
			(size 0.1524 0.1524)
			(layers "F.Cu" "F.Mask" "F.Paste")
			(net "MPLLAV33")
			(options
				(clearance outline)
				(anchor circle)
			)
			(primitives
				(gr_poly
					(pts
						(arc
							(start 0.3048 -0.2032)
							(mid 0.275042 -0.275042)
							(end 0.2032 -0.3048)
						)
						(arc
							(start -0.2032 -0.3048)
							(mid -0.275042 -0.275042)
							(end -0.3048 -0.2032)
						)
						(arc
							(start -0.3048 0.2032)
							(mid -0.275042 0.275042)
							(end -0.2032 0.3048)
						)
						(arc
							(start 0.2032 0.3048)
							(mid 0.275042 0.275042)
							(end 0.3048 0.2032)
						)
					)
					(width 0)
					(fill yes)
				)
			)
		)
		(pad "2" smd custom
			(at 0 0.4445 270)
			(size 0.1524 0.1524)
			(layers "F.Cu" "F.Mask" "F.Paste")
			(net "GND")
			(options
				(clearance outline)
				(anchor circle)
			)
			(primitives
				(gr_poly
					(pts
						(arc
							(start 0.3048 -0.2032)
							(mid 0.275042 -0.275042)
							(end 0.2032 -0.3048)
						)
						(arc
							(start -0.2032 -0.3048)
							(mid -0.275042 -0.275042)
							(end -0.3048 -0.2032)
						)
						(arc
							(start -0.3048 0.2032)
							(mid -0.275042 0.275042)
							(end -0.2032 0.3048)
						)
						(arc
							(start 0.2032 0.3048)
							(mid 0.275042 0.275042)
							(end 0.3048 0.2032)
						)
					)
					(width 0)
					(fill yes)
				)
			)
		)
	)
	(footprint ""
		(layer "F.Cu")
		(at 185.42 -146.558 90)
		(property "Reference" "SU78"
			(at 0 0 90)
			(layer "F.SilkS")
			(hide yes)
			(effects
				(font
					(size 1.27 1.27)
				)
			)
		)
		(property "Value" "PCA9306DCTT-GP"
			(at 0 -11.6332 90)
			(unlocked yes)
			(layer "F.Fab")
			(hide yes)
			(effects
				(font
					(size 1.016 1.016)
					(thickness 0.1524)
				)
			)
		)
		(property "Device Type" "SSOIC8H52"
			(at 0 -13.1572 90)
			(unlocked yes)
			(layer "F.Fab")
			(hide yes)
			(effects
				(font
					(size 1.016 1.016)
					(thickness 0.1524)
				)
			)
		)
		(duplicate_pad_numbers_are_jumpers no)
		(fp_line
			(start 1.0668 -0.5842)
			(end 1.0668 0.5842)
			(stroke
				(width 0.1524)
				(type default)
			)
			(layer "F.SilkS")
		)
		(fp_line
			(start -1.7018 -0.5842)
			(end 1.0668 -0.5842)
			(stroke
				(width 0.1524)
				(type default)
			)
			(layer "F.SilkS")
		)
		(fp_line
			(start -1.7018 -0.5842)
			(end -1.7018 2.286)
			(stroke
				(width 0.1524)
				(type default)
			)
			(layer "F.SilkS")
		)
		(fp_line
			(start -1.397 0)
			(end -1.7018 -0.3048)
			(stroke
				(width 0.1524)
				(type default)
			)
			(layer "F.SilkS")
		)
		(fp_line
			(start -1.397 0)
			(end -1.7018 0.3048)
			(stroke
				(width 0.1524)
				(type default)
			)
			(layer "F.SilkS")
		)
		(fp_line
			(start 1.0668 0.5842)
			(end -1.524 0.5842)
			(stroke
				(width 0.1524)
				(type default)
			)
			(layer "F.SilkS")
		)
		(fp_line
			(start -1.524 0.5842)
			(end -1.524 2.286)
			(stroke
				(width 0.508)
				(type default)
			)
			(layer "F.SilkS")
		)
		(fp_poly
			(pts
				(xy -1.1684 -0.5842) (xy 1.0668 -0.5842) (xy 1.0668 0.5842) (xy -1.1684 0.5842)
			)
			(stroke
				(width 0)
				(type default)
			)
			(fill yes)
			(layer "F.SilkS")
		)
		(fp_poly
			(pts
				(xy -1.778 2.54) (xy 1.778 2.54) (xy 1.778 -2.54) (xy -1.778 -2.54)
			)
			(stroke
				(width 0)
				(type default)
			)
			(fill no)
			(layer "F.CrtYd")
		)
		(fp_poly
			(pts
				(xy -1.778 -2.54) (xy 1.778 -2.54) (xy 1.778 2.54) (xy -1.778 2.54)
			)
			(stroke
				(width 0)
				(type default)
			)
			(fill no)
			(layer "F.Fab")
		)
		(pad "1" smd rect
			(at -0.97536 1.6256 90)
			(size 0.3556 1.524)
			(layers "F.Cu" "F.Mask" "F.Paste")
			(net "GND")
		)
		(pad "2" smd rect
			(at -0.32512 1.6256 90)
			(size 0.3556 1.524)
			(layers "F.Cu" "F.Mask" "F.Paste")
			(net "P1V8_E")
		)
		(pad "3" smd rect
			(at 0.32512 1.6256 90)
			(size 0.3556 1.524)
			(layers "F.Cu" "F.Mask" "F.Paste")
			(net "EXP_I2C_SCL_4")
		)
		(pad "4" smd rect
			(at 0.97536 1.6256 90)
			(size 0.3556 1.524)
			(layers "F.Cu" "F.Mask" "F.Paste")
			(net "EXP_I2C_SDA_4")
		)
		(pad "5" smd rect
			(at 0.97536 -1.6256 90)
			(size 0.3556 1.524)
			(layers "F.Cu" "F.Mask" "F.Paste")
			(net "BMC_I2C_C_SDA")
		)
		(pad "6" smd rect
			(at 0.32512 -1.6256 90)
			(size 0.3556 1.524)
			(layers "F.Cu" "F.Mask" "F.Paste")
			(net "BMC_I2C_C_SCL")
		)
		(pad "7" smd rect
			(at -0.32512 -1.6256 90)
			(size 0.3556 1.524)
			(layers "F.Cu" "F.Mask" "F.Paste")
			(net "EXP_I2C_VREF_3")
		)
		(pad "8" smd rect
			(at -0.97536 -1.6256 90)
			(size 0.3556 1.524)
			(layers "F.Cu" "F.Mask" "F.Paste")
			(net "EXP_I2C_VREF_3")
		)
	)
	(footprint ""
		(layer "F.Cu")
		(at 332.105 -96.52 90)
		(property "Reference" "PC38"
			(at 0 0 90)
			(layer "F.SilkS")
			(hide yes)
			(effects
				(font
					(size 1.27 1.27)
				)
			)
		)
		(property "Value" "SC100U6D3V6MX-GP"
			(at -0.0762 -5.1308 90)
			(unlocked yes)
			(layer "F.Fab")
			(hide yes)
			(effects
				(font
					(size 1.016 1.016)
					(thickness 0.1524)
				)
			)
		)
		(property "Device Type" "C1206H71"
			(at -0.127 -6.6548 90)
			(unlocked yes)
			(layer "F.Fab")
			(hide yes)
			(effects
				(font
					(size 1.016 1.016)
					(thickness 0.1524)
				)
			)
		)
		(duplicate_pad_numbers_are_jumpers no)
		(fp_line
			(start 1.016 -2.2352)
			(end 1.016 -0.8382)
			(stroke
				(width 0.1524)
				(type default)
			)
			(layer "F.SilkS")
		)
		(fp_line
			(start -1.016 -2.2352)
			(end 1.016 -2.2352)
			(stroke
				(width 0.1524)
				(type default)
			)
			(layer "F.SilkS")
		)
		(fp_line
			(start -1.016 -0.8382)
			(end -1.016 -2.2352)
			(stroke
				(width 0.1524)
				(type default)
			)
			(layer "F.SilkS")
		)
		(fp_line
			(start 1.016 0.8382)
			(end 1.016 2.2352)
			(stroke
				(width 0.1524)
				(type default)
			)
			(layer "F.SilkS")
		)
		(fp_line
			(start 1.016 2.2352)
			(end -1.016 2.2352)
			(stroke
				(width 0.1524)
				(type default)
			)
			(layer "F.SilkS")
		)
		(fp_line
			(start -1.016 2.2352)
			(end -1.016 0.8382)
			(stroke
				(width 0.1524)
				(type default)
			)
			(layer "F.SilkS")
		)
		(fp_rect
			(start -1.0922 2.3114)
			(end 1.0922 -2.3114)
			(stroke
				(width 0)
				(type default)
			)
			(fill no)
			(layer "F.CrtYd")
		)
		(fp_poly
			(pts
				(xy 1.0922 -2.3114) (xy 1.0922 2.3114) (xy -1.0922 2.3114) (xy -1.0922 -2.3114)
			)
			(stroke
				(width 0)
				(type default)
			)
			(fill no)
			(layer "F.Fab")
		)
		(pad "1" smd rect
			(at 0 -1.397 90)
			(size 1.651 1.27)
			(layers "F.Cu" "F.Mask" "F.Paste")
			(net "P3V3_STBY")
		)
		(pad "2" smd rect
			(at 0 1.397 90)
			(size 1.651 1.27)
			(layers "F.Cu" "F.Mask" "F.Paste")
			(net "GND")
		)
	)
	(footprint ""
		(layer "F.Cu")
		(at 95.358966 -63.119)
		(property "Reference" "SR676"
			(at 0 0 0)
			(layer "F.SilkS")
			(hide yes)
			(effects
				(font
					(size 1.27 1.27)
				)
			)
		)
		(property "Value" "4K7R2F-GP"
			(at 0.064008 -3.993896 0)
			(unlocked yes)
			(layer "F.Fab")
			(hide yes)
			(effects
				(font
					(size 1.016 1.016)
					(thickness 0.1524)
				)
			)
		)
		(property "Device Type" "R402H16"
			(at 0.064008 -5.517896 0)
			(unlocked yes)
			(layer "F.Fab")
			(hide yes)
			(effects
				(font
					(size 1.016 1.016)
					(thickness 0.1524)
				)
			)
		)
		(duplicate_pad_numbers_are_jumpers no)
		(fp_line
			(start -0.508 -0.9398)
			(end -0.508 0.9398)
			(stroke
				(width 0.1524)
				(type default)
			)
			(layer "F.SilkS")
		)
		(fp_line
			(start 0.508 -0.9398)
			(end -0.508 -0.9398)
			(stroke
				(width 0.1524)
				(type default)
			)
			(layer "F.SilkS")
		)
		(fp_rect
			(start -0.508 0.9398)
			(end 0.508 -0.9398)
			(stroke
				(width 0)
				(type default)
			)
			(fill no)
			(layer "F.CrtYd")
		)
		(fp_rect
			(start -0.508 0.9398)
			(end 0.508 -0.9398)
			(stroke
				(width 0)
				(type default)
			)
			(fill no)
			(layer "F.Fab")
		)
		(pad "1" smd custom
			(at 0 -0.4445)
			(size 0.1397 0.1397)
			(layers "F.Cu" "F.Mask" "F.Paste")
			(net "P1V8_C")
			(options
				(clearance outline)
				(anchor circle)
			)
			(primitives
				(gr_poly
					(pts
						(arc
							(start -0.1778 -0.2794)
							(mid -0.249642 -0.249642)
							(end -0.2794 -0.1778)
						)
						(arc
							(start -0.2794 0.1778)
							(mid -0.249642 0.249642)
							(end -0.1778 0.2794)
						)
						(arc
							(start 0.1778 0.2794)
							(mid 0.249642 0.249642)
							(end 0.2794 0.1778)
						)
						(arc
							(start 0.2794 -0.1778)
							(mid 0.249642 -0.249642)
							(end 0.1778 -0.2794)
						)
					)
					(width 0)
					(fill yes)
				)
			)
		)
		(pad "2" smd custom
			(at 0 0.4445)
			(size 0.1397 0.1397)
			(layers "F.Cu" "F.Mask" "F.Paste")
			(net "ICE0_TRST#")
			(options
				(clearance outline)
				(anchor circle)
			)
			(primitives
				(gr_poly
					(pts
						(arc
							(start -0.1778 -0.2794)
							(mid -0.249642 -0.249642)
							(end -0.2794 -0.1778)
						)
						(arc
							(start -0.2794 0.1778)
							(mid -0.249642 0.249642)
							(end -0.1778 0.2794)
						)
						(arc
							(start 0.1778 0.2794)
							(mid 0.249642 0.249642)
							(end 0.2794 0.1778)
						)
						(arc
							(start 0.2794 -0.1778)
							(mid 0.249642 -0.249642)
							(end 0.1778 -0.2794)
						)
					)
					(width 0)
					(fill yes)
				)
			)
		)
	)
	(footprint ""
		(layer "F.Cu")
		(at 333.912718 -142.217648 90)
		(property "Reference" "R223"
			(at 0 0 90)
			(layer "F.SilkS")
			(hide yes)
			(effects
				(font
					(size 1.27 1.27)
				)
			)
		)
		(property "Value" "4K7R2F-GP"
			(at 0.064008 -3.993896 90)
			(unlocked yes)
			(layer "F.Fab")
			(hide yes)
			(effects
				(font
					(size 1.016 1.016)
					(thickness 0.1524)
				)
			)
		)
		(property "Device Type" "R402H16"
			(at 0.064008 -5.517896 90)
			(unlocked yes)
			(layer "F.Fab")
			(hide yes)
			(effects
				(font
					(size 1.016 1.016)
					(thickness 0.1524)
				)
			)
		)
		(duplicate_pad_numbers_are_jumpers no)
		(fp_line
			(start 0.508 -0.9398)
			(end -0.508 -0.9398)
			(stroke
				(width 0.1524)
				(type default)
			)
			(layer "F.SilkS")
		)
		(fp_line
			(start -0.508 -0.9398)
			(end -0.508 0.9398)
			(stroke
				(width 0.1524)
				(type default)
			)
			(layer "F.SilkS")
		)
		(fp_rect
			(start -0.508 0.9398)
			(end 0.508 -0.9398)
			(stroke
				(width 0)
				(type default)
			)
			(fill no)
			(layer "F.CrtYd")
		)
		(fp_rect
			(start -0.508 0.9398)
			(end 0.508 -0.9398)
			(stroke
				(width 0)
				(type default)
			)
			(fill no)
			(layer "F.Fab")
		)
		(pad "1" smd custom
			(at 0 -0.4445 90)
			(size 0.1397 0.1397)
			(layers "F.Cu" "F.Mask" "F.Paste")
			(net "P3V3_STBY")
			(options
				(clearance outline)
				(anchor circle)
			)
			(primitives
				(gr_poly
					(pts
						(arc
							(start -0.1778 -0.2794)
							(mid -0.249642 -0.249642)
							(end -0.2794 -0.1778)
						)
						(arc
							(start -0.2794 0.1778)
							(mid -0.249642 0.249642)
							(end -0.1778 0.2794)
						)
						(arc
							(start 0.1778 0.2794)
							(mid 0.249642 0.249642)
							(end 0.2794 0.1778)
						)
						(arc
							(start 0.2794 -0.1778)
							(mid 0.249642 -0.249642)
							(end 0.1778 -0.2794)
						)
					)
					(width 0)
					(fill yes)
				)
			)
		)
		(pad "2" smd custom
			(at 0 0.4445 90)
			(size 0.1397 0.1397)
			(layers "F.Cu" "F.Mask" "F.Paste")
			(net "USB_SUSP_IND")
			(options
				(clearance outline)
				(anchor circle)
			)
			(primitives
				(gr_poly
					(pts
						(arc
							(start -0.1778 -0.2794)
							(mid -0.249642 -0.249642)
							(end -0.2794 -0.1778)
						)
						(arc
							(start -0.2794 0.1778)
							(mid -0.249642 0.249642)
							(end -0.1778 0.2794)
						)
						(arc
							(start 0.1778 0.2794)
							(mid 0.249642 0.249642)
							(end 0.2794 0.1778)
						)
						(arc
							(start 0.2794 -0.1778)
							(mid 0.249642 -0.249642)
							(end 0.1778 -0.2794)
						)
					)
					(width 0)
					(fill yes)
				)
			)
		)
	)
	(footprint ""
		(layer "F.Cu")
		(at 54.991 -103.251 -90)
		(property "Reference" "SCN8"
			(at 0 0 270)
			(layer "F.SilkS")
			(hide yes)
			(effects
				(font
					(size 1.27 1.27)
				)
			)
		)
		(property "Value" "JWT-CON4-S24-GP"
			(at -7.3787 1.4351 270)
			(unlocked yes)
			(layer "F.Fab")
			(hide yes)
			(effects
				(font
					(size 1.016 1.016)
					(thickness 0.1524)
				)
			)
		)
		(property "Device Type" "A2541WV0-1QX4PA-6T"
			(at -7.3787 -0.0889 270)
			(unlocked yes)
			(layer "F.Fab")
			(hide yes)
			(effects
				(font
					(size 1.016 1.016)
					(thickness 0.1524)
				)
			)
		)
		(duplicate_pad_numbers_are_jumpers no)
		(fp_line
			(start -5.334 1.524)
			(end 5.334 1.524)
			(stroke
				(width 0.1524)
				(type default)
			)
			(layer "F.SilkS")
		)
		(fp_line
			(start 5.334 1.524)
			(end 5.334 -1.524)
			(stroke
				(width 0.1524)
				(type default)
			)
			(layer "F.SilkS")
		)
		(fp_line
			(start -5.334 -1.524)
			(end -5.334 1.524)
			(stroke
				(width 0.1524)
				(type default)
			)
			(layer "F.SilkS")
		)
		(fp_line
			(start 5.334 -1.524)
			(end -5.334 -1.524)
			(stroke
				(width 0.1524)
				(type default)
			)
			(layer "F.SilkS")
		)
		(fp_line
			(start -5.461 -1.651)
			(end -5.461 -0.381)
			(stroke
				(width 0.4064)
				(type default)
			)
			(layer "F.SilkS")
		)
		(fp_line
			(start -4.191 -1.651)
			(end -5.461 -1.651)
			(stroke
				(width 0.4064)
				(type default)
			)
			(layer "F.SilkS")
		)
		(fp_circle
			(center -3.81 0)
			(end -3.81 -1.0668)
			(stroke
				(width 0.3048)
				(type default)
			)
			(fill no)
			(layer "F.SilkS")
		)
		(fp_circle
			(center -1.27 0)
			(end -1.27 -1.0668)
			(stroke
				(width 0.3048)
				(type default)
			)
			(fill no)
			(layer "F.SilkS")
		)
		(fp_circle
			(center 1.27 0)
			(end 1.27 -1.0668)
			(stroke
				(width 0.3048)
				(type default)
			)
			(fill no)
			(layer "F.SilkS")
		)
		(fp_circle
			(center 3.81 0)
			(end 3.81 -1.0668)
			(stroke
				(width 0.3048)
				(type default)
			)
			(fill no)
			(layer "F.SilkS")
		)
		(fp_rect
			(start -5.08 1.27)
			(end 5.08 -1.27)
			(stroke
				(width 0)
				(type default)
			)
			(fill no)
			(layer "F.CrtYd")
		)
		(fp_poly
			(pts
				(xy -5.588 1.778) (xy -5.588 -1.778) (xy 5.588 -1.778) (xy 5.588 1.2573) (xy 5.08 1.2573) (xy 5.08 -1.27)
				(xy -5.08 -1.27) (xy -5.08 1.27) (xy 5.588 1.27) (xy 5.588 1.778)
			)
			(stroke
				(width 0)
				(type default)
			)
			(fill no)
			(layer "F.CrtYd")
		)
		(fp_rect
			(start -5.588 1.778)
			(end 5.588 -1.778)
			(stroke
				(width 0)
				(type default)
			)
			(fill no)
			(layer "F.Fab")
		)
		(pad "1" thru_hole circle
			(at -3.81 0 270)
			(size 1.4224 1.4224)
			(drill 1.016)
			(layers "*.Cu" "*.Mask")
			(remove_unused_layers no)
			(net "P5V_STBY")
			(clearance 0.1524)
			(thermal_gap 0.1524)
		)
		(pad "2" thru_hole circle
			(at -1.27 0 270)
			(size 1.4224 1.4224)
			(drill 1.016)
			(layers "*.Cu" "*.Mask")
			(remove_unused_layers no)
			(net "BMC_R_TXD5")
			(clearance 0.1524)
			(thermal_gap 0.1524)
		)
		(pad "3" thru_hole circle
			(at 1.27 0 270)
			(size 1.4224 1.4224)
			(drill 1.016)
			(layers "*.Cu" "*.Mask")
			(remove_unused_layers no)
			(net "BMC_R_RXD5")
			(clearance 0.1524)
			(thermal_gap 0.1524)
		)
		(pad "4" thru_hole circle
			(at 3.81 0 270)
			(size 1.4224 1.4224)
			(drill 1.016)
			(layers "*.Cu" "*.Mask")
			(remove_unused_layers no)
			(net "GND")
			(clearance 0.1524)
			(thermal_gap 0.1524)
		)
	)
	(footprint ""
		(layer "F.Cu")
		(at 187.442856 -143.138652 -90)
		(property "Reference" "R609"
			(at 0 0 270)
			(layer "F.SilkS")
			(hide yes)
			(effects
				(font
					(size 1.27 1.27)
				)
			)
		)
		(property "Value" "0R2J-2-GP"
			(at 0.064008 -3.993896 270)
			(unlocked yes)
			(layer "F.Fab")
			(hide yes)
			(effects
				(font
					(size 1.016 1.016)
					(thickness 0.1524)
				)
			)
		)
		(property "Device Type" "R402H16"
			(at 0.064008 -5.517896 270)
			(unlocked yes)
			(layer "F.Fab")
			(hide yes)
			(effects
				(font
					(size 1.016 1.016)
					(thickness 0.1524)
				)
			)
		)
		(duplicate_pad_numbers_are_jumpers no)
		(fp_line
			(start -0.508 -0.9398)
			(end -0.508 0.9398)
			(stroke
				(width 0.1524)
				(type default)
			)
			(layer "F.SilkS")
		)
		(fp_line
			(start 0.508 -0.9398)
			(end -0.508 -0.9398)
			(stroke
				(width 0.1524)
				(type default)
			)
			(layer "F.SilkS")
		)
		(fp_rect
			(start -0.508 0.9398)
			(end 0.508 -0.9398)
			(stroke
				(width 0)
				(type default)
			)
			(fill no)
			(layer "F.CrtYd")
		)
		(fp_rect
			(start -0.508 0.9398)
			(end 0.508 -0.9398)
			(stroke
				(width 0)
				(type default)
			)
			(fill no)
			(layer "F.Fab")
		)
		(pad "1" smd custom
			(at 0 -0.4445 270)
			(size 0.1397 0.1397)
			(layers "F.Cu" "F.Mask" "F.Paste")
			(net "EXP_EEPROM_SDA")
			(options
				(clearance outline)
				(anchor circle)
			)
			(primitives
				(gr_poly
					(pts
						(arc
							(start -0.1778 -0.2794)
							(mid -0.249642 -0.249642)
							(end -0.2794 -0.1778)
						)
						(arc
							(start -0.2794 0.1778)
							(mid -0.249642 0.249642)
							(end -0.1778 0.2794)
						)
						(arc
							(start 0.1778 0.2794)
							(mid 0.249642 0.249642)
							(end 0.2794 0.1778)
						)
						(arc
							(start 0.2794 -0.1778)
							(mid 0.249642 -0.249642)
							(end 0.1778 -0.2794)
						)
					)
					(width 0)
					(fill yes)
				)
			)
		)
		(pad "2" smd custom
			(at 0 0.4445 270)
			(size 0.1397 0.1397)
			(layers "F.Cu" "F.Mask" "F.Paste")
			(net "EXP_SDA_0")
			(options
				(clearance outline)
				(anchor circle)
			)
			(primitives
				(gr_poly
					(pts
						(arc
							(start -0.1778 -0.2794)
							(mid -0.249642 -0.249642)
							(end -0.2794 -0.1778)
						)
						(arc
							(start -0.2794 0.1778)
							(mid -0.249642 0.249642)
							(end -0.1778 0.2794)
						)
						(arc
							(start 0.1778 0.2794)
							(mid 0.249642 0.249642)
							(end 0.2794 0.1778)
						)
						(arc
							(start 0.2794 -0.1778)
							(mid 0.249642 -0.249642)
							(end 0.1778 -0.2794)
						)
					)
					(width 0)
					(fill yes)
				)
			)
		)
	)
	(footprint ""
		(layer "F.Cu")
		(at 305.562 -163.957)
		(property "Reference" "TP154"
			(at 0 0 0)
			(layer "F.SilkS")
			(hide yes)
			(effects
				(font
					(size 1.27 1.27)
				)
			)
		)
		(property "Value" "TPAD28"
			(at 0.0127 -1.8034 0)
			(unlocked yes)
			(layer "F.Fab")
			(hide yes)
			(effects
				(font
					(size 1.016 1.016)
					(thickness 0.1524)
				)
			)
		)
		(property "Device Type" "TPAD28"
			(at 0.0127 -3.3274 0)
			(unlocked yes)
			(layer "F.Fab")
			(hide yes)
			(effects
				(font
					(size 1.016 1.016)
					(thickness 0.1524)
				)
			)
		)
		(duplicate_pad_numbers_are_jumpers no)
		(fp_poly
			(pts
				(arc
					(start 0.3556 0)
					(mid -0.3556 0)
					(end 0.3556 0)
				)
			)
			(stroke
				(width 0)
				(type default)
			)
			(fill no)
			(layer "F.CrtYd")
		)
		(fp_poly
			(pts
				(arc
					(start 0.6096 0)
					(mid -0.6096 0)
					(end 0.6096 0)
				)
			)
			(stroke
				(width 0)
				(type default)
			)
			(fill no)
			(layer "F.Fab")
		)
		(pad "1" smd circle
			(at 0 0)
			(size 0.7112 0.7112)
			(layers "F.Cu" "F.Mask" "F.Paste")
			(net "TP_BMC_GPIOA6")
		)
	)
	(footprint ""
		(layer "F.Cu")
		(at 152.247092 -113.313464 -90)
		(property "Reference" "SR836"
			(at 0 0 270)
			(layer "F.SilkS")
			(hide yes)
			(effects
				(font
					(size 1.27 1.27)
				)
			)
		)
		(property "Value" "D51R3F-2-GP"
			(at -0.0254 -2.5146 270)
			(unlocked yes)
			(layer "F.Fab")
			(hide yes)
			(effects
				(font
					(size 1.016 1.016)
					(thickness 0.1524)
				)
			)
		)
		(property "Device Type" "R603H22"
			(at -0.0254 -4.0386 270)
			(unlocked yes)
			(layer "F.Fab")
			(hide yes)
			(effects
				(font
					(size 1.016 1.016)
					(thickness 0.1524)
				)
			)
		)
		(duplicate_pad_numbers_are_jumpers no)
		(fp_line
			(start -0.4826 0)
			(end -0.2032 0)
			(stroke
				(width 0.2032)
				(type default)
			)
			(layer "F.SilkS")
		)
		(fp_line
			(start 0.2032 0)
			(end 0.4826 0)
			(stroke
				(width 0.2032)
				(type default)
			)
			(layer "F.SilkS")
		)
		(fp_rect
			(start -0.5842 1.3335)
			(end 0.5842 -1.3335)
			(stroke
				(width 0)
				(type default)
			)
			(fill no)
			(layer "F.CrtYd")
		)
		(fp_rect
			(start -0.5842 1.3335)
			(end 0.5842 -1.3335)
			(stroke
				(width 0)
				(type default)
			)
			(fill no)
			(layer "F.Fab")
		)
		(pad "1" smd custom
			(at 0 -0.762 270)
			(size 0.2159 0.2159)
			(layers "F.Cu" "F.Mask" "F.Paste")
			(net "P0V9_E")
			(options
				(clearance outline)
				(anchor circle)
			)
			(primitives
				(gr_poly
					(pts
						(arc
							(start -0.3302 -0.4318)
							(mid -0.402042 -0.402042)
							(end -0.4318 -0.3302)
						)
						(arc
							(start -0.4318 0.3302)
							(mid -0.402042 0.402042)
							(end -0.3302 0.4318)
						)
						(arc
							(start 0.3302 0.4318)
							(mid 0.402042 0.402042)
							(end 0.4318 0.3302)
						)
						(arc
							(start 0.4318 -0.3302)
							(mid 0.402042 -0.402042)
							(end 0.3302 -0.4318)
						)
					)
					(width 0)
					(fill yes)
				)
			)
		)
		(pad "2" smd custom
			(at 0 0.762 270)
			(size 0.2159 0.2159)
			(layers "F.Cu" "F.Mask" "F.Paste")
			(net "GB_VDDA")
			(options
				(clearance outline)
				(anchor circle)
			)
			(primitives
				(gr_poly
					(pts
						(arc
							(start -0.3302 -0.4318)
							(mid -0.402042 -0.402042)
							(end -0.4318 -0.3302)
						)
						(arc
							(start -0.4318 0.3302)
							(mid -0.402042 0.402042)
							(end -0.3302 0.4318)
						)
						(arc
							(start 0.3302 0.4318)
							(mid 0.402042 0.402042)
							(end 0.4318 0.3302)
						)
						(arc
							(start 0.4318 -0.3302)
							(mid 0.402042 -0.402042)
							(end 0.3302 -0.4318)
						)
					)
					(width 0)
					(fill yes)
				)
			)
		)
	)
	(footprint ""
		(layer "F.Cu")
		(at 235.966 -15.113 -90)
		(property "Reference" "U38"
			(at 0 0 270)
			(layer "F.SilkS")
			(hide yes)
			(effects
				(font
					(size 1.27 1.27)
				)
			)
		)
		(property "Value" "SN74LVC1G08DCKR-GP"
			(at -2.3368 -8.6868 270)
			(unlocked yes)
			(layer "F.Fab")
			(hide yes)
			(effects
				(font
					(size 1.016 1.016)
					(thickness 0.1524)
				)
			)
		)
		(property "Device Type" "SC70-5H44"
			(at -2.3114 -10.414 270)
			(unlocked yes)
			(layer "F.Fab")
			(hide yes)
			(effects
				(font
					(size 1.016 1.016)
					(thickness 0.1524)
				)
			)
		)
		(duplicate_pad_numbers_are_jumpers no)
		(fp_line
			(start -1.27 1.7018)
			(end -1.27 -1.7018)
			(stroke
				(width 0.1524)
				(type default)
			)
			(layer "F.SilkS")
		)
		(fp_line
			(start 1.27 1.7018)
			(end -1.27 1.7018)
			(stroke
				(width 0.1524)
				(type default)
			)
			(layer "F.SilkS")
		)
		(fp_line
			(start -1.27 -1.7018)
			(end 1.27 -1.7018)
			(stroke
				(width 0.1524)
				(type default)
			)
			(layer "F.SilkS")
		)
		(fp_line
			(start 1.27 -1.7018)
			(end 1.27 1.7018)
			(stroke
				(width 0.1524)
				(type default)
			)
			(layer "F.SilkS")
		)
		(fp_line
			(start 0.6604 -1.8034)
			(end 1.3843 -1.8034)
			(stroke
				(width 0.3302)
				(type default)
			)
			(layer "F.SilkS")
		)
		(fp_line
			(start 1.3843 -1.8034)
			(end 1.3843 -1.1176)
			(stroke
				(width 0.3302)
				(type default)
			)
			(layer "F.SilkS")
		)
		(fp_rect
			(start -1.524 1.9558)
			(end 1.524 -1.9558)
			(stroke
				(width 0)
				(type default)
			)
			(fill no)
			(layer "F.CrtYd")
		)
		(fp_poly
			(pts
				(xy -1.524 -1.9558) (xy 1.524 -1.9558) (xy 1.524 1.9558) (xy -1.524 1.9558)
			)
			(stroke
				(width 0)
				(type default)
			)
			(fill no)
			(layer "F.Fab")
		)
		(pad "1" smd rect
			(at 0.65024 -0.8255 270)
			(size 0.4064 1.2192)
			(layers "F.Cu" "F.Mask" "F.Paste")
			(net "HB_OUT_R")
		)
		(pad "2" smd rect
			(at 0 -0.8255 270)
			(size 0.4064 1.2192)
			(layers "F.Cu" "F.Mask" "F.Paste")
			(net "BMC_ENCLOSURE_LED_R")
		)
		(pad "3" smd rect
			(at -0.65024 -0.8255 270)
			(size 0.4064 1.2192)
			(layers "F.Cu" "F.Mask" "F.Paste")
			(net "GND")
		)
		(pad "4" smd rect
			(at -0.65024 0.8255 270)
			(size 0.4064 1.2192)
			(layers "F.Cu" "F.Mask" "F.Paste")
			(net "ENCLO_LED_BLUE_OUT")
		)
		(pad "5" smd rect
			(at 0.65024 0.8255 270)
			(size 0.4064 1.2192)
			(layers "F.Cu" "F.Mask" "F.Paste")
			(net "P3V3_STBY")
		)
	)
	(footprint ""
		(layer "F.Cu")
		(at 300.482 -62.992 -90)
		(property "Reference" "R218"
			(at 0 0 270)
			(layer "F.SilkS")
			(hide yes)
			(effects
				(font
					(size 1.27 1.27)
				)
			)
		)
		(property "Value" "0R2J-2-GP"
			(at 0.064008 -3.993896 270)
			(unlocked yes)
			(layer "F.Fab")
			(hide yes)
			(effects
				(font
					(size 1.016 1.016)
					(thickness 0.1524)
				)
			)
		)
		(property "Device Type" "R402H16"
			(at 0.064008 -5.517896 270)
			(unlocked yes)
			(layer "F.Fab")
			(hide yes)
			(effects
				(font
					(size 1.016 1.016)
					(thickness 0.1524)
				)
			)
		)
		(duplicate_pad_numbers_are_jumpers no)
		(fp_line
			(start -0.508 -0.9398)
			(end -0.508 0.9398)
			(stroke
				(width 0.1524)
				(type default)
			)
			(layer "F.SilkS")
		)
		(fp_line
			(start 0.508 -0.9398)
			(end -0.508 -0.9398)
			(stroke
				(width 0.1524)
				(type default)
			)
			(layer "F.SilkS")
		)
		(fp_rect
			(start -0.508 0.9398)
			(end 0.508 -0.9398)
			(stroke
				(width 0)
				(type default)
			)
			(fill no)
			(layer "F.CrtYd")
		)
		(fp_rect
			(start -0.508 0.9398)
			(end 0.508 -0.9398)
			(stroke
				(width 0)
				(type default)
			)
			(fill no)
			(layer "F.Fab")
		)
		(pad "1" smd custom
			(at 0 -0.4445 270)
			(size 0.1397 0.1397)
			(layers "F.Cu" "F.Mask" "F.Paste")
			(net "NCSI_10G_TXD0_R")
			(options
				(clearance outline)
				(anchor circle)
			)
			(primitives
				(gr_poly
					(pts
						(arc
							(start -0.1778 -0.2794)
							(mid -0.249642 -0.249642)
							(end -0.2794 -0.1778)
						)
						(arc
							(start -0.2794 0.1778)
							(mid -0.249642 0.249642)
							(end -0.1778 0.2794)
						)
						(arc
							(start 0.1778 0.2794)
							(mid 0.249642 0.249642)
							(end 0.2794 0.1778)
						)
						(arc
							(start 0.2794 -0.1778)
							(mid 0.249642 -0.249642)
							(end 0.1778 -0.2794)
						)
					)
					(width 0)
					(fill yes)
				)
			)
		)
		(pad "2" smd custom
			(at 0 0.4445 270)
			(size 0.1397 0.1397)
			(layers "F.Cu" "F.Mask" "F.Paste")
			(net "NCSI_10G_TXD0")
			(options
				(clearance outline)
				(anchor circle)
			)
			(primitives
				(gr_poly
					(pts
						(arc
							(start -0.1778 -0.2794)
							(mid -0.249642 -0.249642)
							(end -0.2794 -0.1778)
						)
						(arc
							(start -0.2794 0.1778)
							(mid -0.249642 0.249642)
							(end -0.1778 0.2794)
						)
						(arc
							(start 0.1778 0.2794)
							(mid 0.249642 0.249642)
							(end 0.2794 0.1778)
						)
						(arc
							(start 0.2794 -0.1778)
							(mid 0.249642 -0.249642)
							(end 0.1778 -0.2794)
						)
					)
					(width 0)
					(fill yes)
				)
			)
		)
	)
	(footprint ""
		(layer "F.Cu")
		(at 333.366872 -229.307136 -90)
		(property "Reference" "TP84"
			(at 0 0 270)
			(layer "F.SilkS")
			(hide yes)
			(effects
				(font
					(size 1.27 1.27)
				)
			)
		)
		(property "Value" "TPAD32-GP"
			(at 0 -3.166364 270)
			(unlocked yes)
			(layer "F.Fab")
			(hide yes)
			(effects
				(font
					(size 1.016 1.016)
					(thickness 0.1524)
				)
			)
		)
		(property "Device Type" "TPAD32"
			(at 0 -4.690618 270)
			(unlocked yes)
			(layer "F.Fab")
			(hide yes)
			(effects
				(font
					(size 1.016 1.016)
					(thickness 0.1524)
				)
			)
		)
		(duplicate_pad_numbers_are_jumpers no)
		(fp_poly
			(pts
				(arc
					(start 0 -0.4064)
					(mid 0 0.4064)
					(end 0 -0.4064)
				)
			)
			(stroke
				(width 0)
				(type default)
			)
			(fill no)
			(layer "F.CrtYd")
		)
		(fp_poly
			(pts
				(arc
					(start 0 -0.7112)
					(mid 0 0.7112)
					(end 0 -0.7112)
				)
			)
			(stroke
				(width 0)
				(type default)
			)
			(fill no)
			(layer "F.Fab")
		)
		(pad "1" smd circle
			(at 0 0 270)
			(size 0.8128 0.8128)
			(layers "F.Cu" "F.Mask" "F.Paste")
			(net "VOL_SEN_ALERT")
		)
	)
	(footprint ""
		(layer "F.Cu")
		(at 184.776872 -204.796136 -90)
		(property "Reference" "R152"
			(at 0 0 270)
			(layer "F.SilkS")
			(hide yes)
			(effects
				(font
					(size 1.27 1.27)
				)
			)
		)
		(property "Value" "0R2J-2-GP"
			(at 0.064008 -3.993896 270)
			(unlocked yes)
			(layer "F.Fab")
			(hide yes)
			(effects
				(font
					(size 1.016 1.016)
					(thickness 0.1524)
				)
			)
		)
		(property "Device Type" "R402H16"
			(at 0.064008 -5.517896 270)
			(unlocked yes)
			(layer "F.Fab")
			(hide yes)
			(effects
				(font
					(size 1.016 1.016)
					(thickness 0.1524)
				)
			)
		)
		(duplicate_pad_numbers_are_jumpers no)
		(fp_line
			(start -0.508 -0.9398)
			(end -0.508 0.9398)
			(stroke
				(width 0.1524)
				(type default)
			)
			(layer "F.SilkS")
		)
		(fp_line
			(start 0.508 -0.9398)
			(end -0.508 -0.9398)
			(stroke
				(width 0.1524)
				(type default)
			)
			(layer "F.SilkS")
		)
		(fp_rect
			(start -0.508 0.9398)
			(end 0.508 -0.9398)
			(stroke
				(width 0)
				(type default)
			)
			(fill no)
			(layer "F.CrtYd")
		)
		(fp_rect
			(start -0.508 0.9398)
			(end 0.508 -0.9398)
			(stroke
				(width 0)
				(type default)
			)
			(fill no)
			(layer "F.Fab")
		)
		(pad "1" smd custom
			(at 0 -0.4445 270)
			(size 0.1397 0.1397)
			(layers "F.Cu" "F.Mask" "F.Paste")
			(net "SAS_I2C_B_BUF_SDA_R")
			(options
				(clearance outline)
				(anchor circle)
			)
			(primitives
				(gr_poly
					(pts
						(arc
							(start -0.1778 -0.2794)
							(mid -0.249642 -0.249642)
							(end -0.2794 -0.1778)
						)
						(arc
							(start -0.2794 0.1778)
							(mid -0.249642 0.249642)
							(end -0.1778 0.2794)
						)
						(arc
							(start 0.1778 0.2794)
							(mid 0.249642 0.249642)
							(end 0.2794 0.1778)
						)
						(arc
							(start 0.2794 -0.1778)
							(mid 0.249642 -0.249642)
							(end 0.1778 -0.2794)
						)
					)
					(width 0)
					(fill yes)
				)
			)
		)
		(pad "2" smd custom
			(at 0 0.4445 270)
			(size 0.1397 0.1397)
			(layers "F.Cu" "F.Mask" "F.Paste")
			(net "SAS_I2C_B_BUF_SDA")
			(options
				(clearance outline)
				(anchor circle)
			)
			(primitives
				(gr_poly
					(pts
						(arc
							(start -0.1778 -0.2794)
							(mid -0.249642 -0.249642)
							(end -0.2794 -0.1778)
						)
						(arc
							(start -0.2794 0.1778)
							(mid -0.249642 0.249642)
							(end -0.1778 0.2794)
						)
						(arc
							(start 0.1778 0.2794)
							(mid 0.249642 0.249642)
							(end 0.2794 0.1778)
						)
						(arc
							(start 0.2794 -0.1778)
							(mid 0.249642 -0.249642)
							(end 0.1778 -0.2794)
						)
					)
					(width 0)
					(fill yes)
				)
			)
		)
	)
	(footprint ""
		(layer "F.Cu")
		(at 298.45 -157.734 90)
		(property "Reference" "R672"
			(at 0 0 90)
			(layer "F.SilkS")
			(hide yes)
			(effects
				(font
					(size 1.27 1.27)
				)
			)
		)
		(property "Value" "0R2J-2-GP"
			(at 0.064008 -3.993896 90)
			(unlocked yes)
			(layer "F.Fab")
			(hide yes)
			(effects
				(font
					(size 1.016 1.016)
					(thickness 0.1524)
				)
			)
		)
		(property "Device Type" "R402H16"
			(at 0.064008 -5.517896 90)
			(unlocked yes)
			(layer "F.Fab")
			(hide yes)
			(effects
				(font
					(size 1.016 1.016)
					(thickness 0.1524)
				)
			)
		)
		(duplicate_pad_numbers_are_jumpers no)
		(fp_line
			(start 0.508 -0.9398)
			(end -0.508 -0.9398)
			(stroke
				(width 0.1524)
				(type default)
			)
			(layer "F.SilkS")
		)
		(fp_line
			(start -0.508 -0.9398)
			(end -0.508 0.9398)
			(stroke
				(width 0.1524)
				(type default)
			)
			(layer "F.SilkS")
		)
		(fp_rect
			(start -0.508 0.9398)
			(end 0.508 -0.9398)
			(stroke
				(width 0)
				(type default)
			)
			(fill no)
			(layer "F.CrtYd")
		)
		(fp_rect
			(start -0.508 0.9398)
			(end 0.508 -0.9398)
			(stroke
				(width 0)
				(type default)
			)
			(fill no)
			(layer "F.Fab")
		)
		(pad "1" smd custom
			(at 0 -0.4445 90)
			(size 0.1397 0.1397)
			(layers "F.Cu" "F.Mask" "F.Paste")
			(net "CLK_50M_BMC_NCSI")
			(options
				(clearance outline)
				(anchor circle)
			)
			(primitives
				(gr_poly
					(pts
						(arc
							(start -0.1778 -0.2794)
							(mid -0.249642 -0.249642)
							(end -0.2794 -0.1778)
						)
						(arc
							(start -0.2794 0.1778)
							(mid -0.249642 0.249642)
							(end -0.1778 0.2794)
						)
						(arc
							(start 0.1778 0.2794)
							(mid 0.249642 0.249642)
							(end 0.2794 0.1778)
						)
						(arc
							(start 0.2794 -0.1778)
							(mid 0.249642 -0.249642)
							(end 0.1778 -0.2794)
						)
					)
					(width 0)
					(fill yes)
				)
			)
		)
		(pad "2" smd custom
			(at 0 0.4445 90)
			(size 0.1397 0.1397)
			(layers "F.Cu" "F.Mask" "F.Paste")
			(net "CLK_50M_BMC_NCSI_R")
			(options
				(clearance outline)
				(anchor circle)
			)
			(primitives
				(gr_poly
					(pts
						(arc
							(start -0.1778 -0.2794)
							(mid -0.249642 -0.249642)
							(end -0.2794 -0.1778)
						)
						(arc
							(start -0.2794 0.1778)
							(mid -0.249642 0.249642)
							(end -0.1778 0.2794)
						)
						(arc
							(start 0.1778 0.2794)
							(mid 0.249642 0.249642)
							(end 0.2794 0.1778)
						)
						(arc
							(start 0.2794 -0.1778)
							(mid 0.249642 -0.249642)
							(end 0.1778 -0.2794)
						)
					)
					(width 0)
					(fill yes)
				)
			)
		)
	)
	(footprint ""
		(layer "F.Cu")
		(at 152.247092 -114.583464 -90)
		(property "Reference" "SR835"
			(at 0 0 270)
			(layer "F.SilkS")
			(hide yes)
			(effects
				(font
					(size 1.27 1.27)
				)
			)
		)
		(property "Value" "D51R3F-2-GP"
			(at -0.0254 -2.5146 270)
			(unlocked yes)
			(layer "F.Fab")
			(hide yes)
			(effects
				(font
					(size 1.016 1.016)
					(thickness 0.1524)
				)
			)
		)
		(property "Device Type" "R603H22"
			(at -0.0254 -4.0386 270)
			(unlocked yes)
			(layer "F.Fab")
			(hide yes)
			(effects
				(font
					(size 1.016 1.016)
					(thickness 0.1524)
				)
			)
		)
		(duplicate_pad_numbers_are_jumpers no)
		(fp_line
			(start -0.4826 0)
			(end -0.2032 0)
			(stroke
				(width 0.2032)
				(type default)
			)
			(layer "F.SilkS")
		)
		(fp_line
			(start 0.2032 0)
			(end 0.4826 0)
			(stroke
				(width 0.2032)
				(type default)
			)
			(layer "F.SilkS")
		)
		(fp_rect
			(start -0.5842 1.3335)
			(end 0.5842 -1.3335)
			(stroke
				(width 0)
				(type default)
			)
			(fill no)
			(layer "F.CrtYd")
		)
		(fp_rect
			(start -0.5842 1.3335)
			(end 0.5842 -1.3335)
			(stroke
				(width 0)
				(type default)
			)
			(fill no)
			(layer "F.Fab")
		)
		(pad "1" smd custom
			(at 0 -0.762 270)
			(size 0.2159 0.2159)
			(layers "F.Cu" "F.Mask" "F.Paste")
			(net "P0V9_E")
			(options
				(clearance outline)
				(anchor circle)
			)
			(primitives
				(gr_poly
					(pts
						(arc
							(start -0.3302 -0.4318)
							(mid -0.402042 -0.402042)
							(end -0.4318 -0.3302)
						)
						(arc
							(start -0.4318 0.3302)
							(mid -0.402042 0.402042)
							(end -0.3302 0.4318)
						)
						(arc
							(start 0.3302 0.4318)
							(mid 0.402042 0.402042)
							(end 0.4318 0.3302)
						)
						(arc
							(start 0.4318 -0.3302)
							(mid 0.402042 -0.402042)
							(end 0.3302 -0.4318)
						)
					)
					(width 0)
					(fill yes)
				)
			)
		)
		(pad "2" smd custom
			(at 0 0.762 270)
			(size 0.2159 0.2159)
			(layers "F.Cu" "F.Mask" "F.Paste")
			(net "GB_VDDA")
			(options
				(clearance outline)
				(anchor circle)
			)
			(primitives
				(gr_poly
					(pts
						(arc
							(start -0.3302 -0.4318)
							(mid -0.402042 -0.402042)
							(end -0.4318 -0.3302)
						)
						(arc
							(start -0.4318 0.3302)
							(mid -0.402042 0.402042)
							(end -0.3302 0.4318)
						)
						(arc
							(start 0.3302 0.4318)
							(mid 0.402042 0.402042)
							(end 0.4318 0.3302)
						)
						(arc
							(start 0.4318 -0.3302)
							(mid 0.402042 -0.402042)
							(end 0.3302 -0.4318)
						)
					)
					(width 0)
					(fill yes)
				)
			)
		)
	)
	(footprint ""
		(layer "F.Cu")
		(at 104.02697 -76.454)
		(property "Reference" "SR861"
			(at 0 0 0)
			(layer "F.SilkS")
			(hide yes)
			(effects
				(font
					(size 1.27 1.27)
				)
			)
		)
		(property "Value" "0R2J-2-GP"
			(at 0.064008 -3.993896 0)
			(unlocked yes)
			(layer "F.Fab")
			(hide yes)
			(effects
				(font
					(size 1.016 1.016)
					(thickness 0.1524)
				)
			)
		)
		(property "Device Type" "R402H16"
			(at 0.064008 -5.517896 0)
			(unlocked yes)
			(layer "F.Fab")
			(hide yes)
			(effects
				(font
					(size 1.016 1.016)
					(thickness 0.1524)
				)
			)
		)
		(duplicate_pad_numbers_are_jumpers no)
		(fp_line
			(start -0.508 -0.9398)
			(end -0.508 0.9398)
			(stroke
				(width 0.1524)
				(type default)
			)
			(layer "F.SilkS")
		)
		(fp_line
			(start 0.508 -0.9398)
			(end -0.508 -0.9398)
			(stroke
				(width 0.1524)
				(type default)
			)
			(layer "F.SilkS")
		)
		(fp_rect
			(start -0.508 0.9398)
			(end 0.508 -0.9398)
			(stroke
				(width 0)
				(type default)
			)
			(fill no)
			(layer "F.CrtYd")
		)
		(fp_rect
			(start -0.508 0.9398)
			(end 0.508 -0.9398)
			(stroke
				(width 0)
				(type default)
			)
			(fill no)
			(layer "F.Fab")
		)
		(pad "1" smd custom
			(at 0 -0.4445)
			(size 0.1397 0.1397)
			(layers "F.Cu" "F.Mask" "F.Paste")
			(net "JTAG_EXP_TMS")
			(options
				(clearance outline)
				(anchor circle)
			)
			(primitives
				(gr_poly
					(pts
						(arc
							(start -0.1778 -0.2794)
							(mid -0.249642 -0.249642)
							(end -0.2794 -0.1778)
						)
						(arc
							(start -0.2794 0.1778)
							(mid -0.249642 0.249642)
							(end -0.1778 0.2794)
						)
						(arc
							(start 0.1778 0.2794)
							(mid 0.249642 0.249642)
							(end 0.2794 0.1778)
						)
						(arc
							(start 0.2794 -0.1778)
							(mid 0.249642 -0.249642)
							(end 0.1778 -0.2794)
						)
					)
					(width 0)
					(fill yes)
				)
			)
		)
		(pad "2" smd custom
			(at 0 0.4445)
			(size 0.1397 0.1397)
			(layers "F.Cu" "F.Mask" "F.Paste")
			(net "JTAG_EXP_IOC_TMS")
			(options
				(clearance outline)
				(anchor circle)
			)
			(primitives
				(gr_poly
					(pts
						(arc
							(start -0.1778 -0.2794)
							(mid -0.249642 -0.249642)
							(end -0.2794 -0.1778)
						)
						(arc
							(start -0.2794 0.1778)
							(mid -0.249642 0.249642)
							(end -0.1778 0.2794)
						)
						(arc
							(start 0.1778 0.2794)
							(mid 0.249642 0.249642)
							(end 0.2794 0.1778)
						)
						(arc
							(start 0.2794 -0.1778)
							(mid 0.249642 -0.249642)
							(end 0.1778 -0.2794)
						)
					)
					(width 0)
					(fill yes)
				)
			)
		)
	)
	(footprint ""
		(layer "F.Cu")
		(at 19.381216 -224.97288 -90)
		(property "Reference" "R636"
			(at 0 0 270)
			(layer "F.SilkS")
			(hide yes)
			(effects
				(font
					(size 1.27 1.27)
				)
			)
		)
		(property "Value" "4K7R2F-GP"
			(at 0.064008 -3.993896 270)
			(unlocked yes)
			(layer "F.Fab")
			(hide yes)
			(effects
				(font
					(size 1.016 1.016)
					(thickness 0.1524)
				)
			)
		)
		(property "Device Type" "R402H16"
			(at 0.064008 -5.517896 270)
			(unlocked yes)
			(layer "F.Fab")
			(hide yes)
			(effects
				(font
					(size 1.016 1.016)
					(thickness 0.1524)
				)
			)
		)
		(duplicate_pad_numbers_are_jumpers no)
		(fp_line
			(start -0.508 -0.9398)
			(end -0.508 0.9398)
			(stroke
				(width 0.1524)
				(type default)
			)
			(layer "F.SilkS")
		)
		(fp_line
			(start 0.508 -0.9398)
			(end -0.508 -0.9398)
			(stroke
				(width 0.1524)
				(type default)
			)
			(layer "F.SilkS")
		)
		(fp_rect
			(start -0.508 0.9398)
			(end 0.508 -0.9398)
			(stroke
				(width 0)
				(type default)
			)
			(fill no)
			(layer "F.CrtYd")
		)
		(fp_rect
			(start -0.508 0.9398)
			(end 0.508 -0.9398)
			(stroke
				(width 0)
				(type default)
			)
			(fill no)
			(layer "F.Fab")
		)
		(pad "1" smd custom
			(at 0 -0.4445 270)
			(size 0.1397 0.1397)
			(layers "F.Cu" "F.Mask" "F.Paste")
			(net "P3V3_STBY")
			(options
				(clearance outline)
				(anchor circle)
			)
			(primitives
				(gr_poly
					(pts
						(arc
							(start -0.1778 -0.2794)
							(mid -0.249642 -0.249642)
							(end -0.2794 -0.1778)
						)
						(arc
							(start -0.2794 0.1778)
							(mid -0.249642 0.249642)
							(end -0.1778 0.2794)
						)
						(arc
							(start 0.1778 0.2794)
							(mid 0.249642 0.249642)
							(end 0.2794 0.1778)
						)
						(arc
							(start 0.2794 -0.1778)
							(mid 0.249642 -0.249642)
							(end 0.1778 -0.2794)
						)
					)
					(width 0)
					(fill yes)
				)
			)
		)
		(pad "2" smd custom
			(at 0 0.4445 270)
			(size 0.1397 0.1397)
			(layers "F.Cu" "F.Mask" "F.Paste")
			(net "IO_EXP_HDD_PWR_A3")
			(options
				(clearance outline)
				(anchor circle)
			)
			(primitives
				(gr_poly
					(pts
						(arc
							(start -0.1778 -0.2794)
							(mid -0.249642 -0.249642)
							(end -0.2794 -0.1778)
						)
						(arc
							(start -0.2794 0.1778)
							(mid -0.249642 0.249642)
							(end -0.1778 0.2794)
						)
						(arc
							(start 0.1778 0.2794)
							(mid 0.249642 0.249642)
							(end 0.2794 0.1778)
						)
						(arc
							(start 0.2794 -0.1778)
							(mid 0.249642 -0.249642)
							(end 0.1778 -0.2794)
						)
					)
					(width 0)
					(fill yes)
				)
			)
		)
	)
	(footprint ""
		(layer "F.Cu")
		(at 210.947 -103.886 180)
		(property "Reference" "PR123"
			(at 0 0 180)
			(layer "F.SilkS")
			(hide yes)
			(effects
				(font
					(size 1.27 1.27)
				)
			)
		)
		(property "Value" "4K75R2F-1-GP"
			(at 0.064008 -3.993896 180)
			(unlocked yes)
			(layer "F.Fab")
			(hide yes)
			(effects
				(font
					(size 1.016 1.016)
					(thickness 0.1524)
				)
			)
		)
		(property "Device Type" "R402H16"
			(at 0.064008 -5.517896 180)
			(unlocked yes)
			(layer "F.Fab")
			(hide yes)
			(effects
				(font
					(size 1.016 1.016)
					(thickness 0.1524)
				)
			)
		)
		(duplicate_pad_numbers_are_jumpers no)
		(fp_line
			(start 0.508 -0.9398)
			(end -0.508 -0.9398)
			(stroke
				(width 0.1524)
				(type default)
			)
			(layer "F.SilkS")
		)
		(fp_line
			(start -0.508 -0.9398)
			(end -0.508 0.9398)
			(stroke
				(width 0.1524)
				(type default)
			)
			(layer "F.SilkS")
		)
		(fp_rect
			(start -0.508 0.9398)
			(end 0.508 -0.9398)
			(stroke
				(width 0)
				(type default)
			)
			(fill no)
			(layer "F.CrtYd")
		)
		(fp_rect
			(start -0.508 0.9398)
			(end 0.508 -0.9398)
			(stroke
				(width 0)
				(type default)
			)
			(fill no)
			(layer "F.Fab")
		)
		(pad "1" smd custom
			(at 0 -0.4445 180)
			(size 0.1397 0.1397)
			(layers "F.Cu" "F.Mask" "F.Paste")
			(net "TPS74801_1V5_C_FB")
			(options
				(clearance outline)
				(anchor circle)
			)
			(primitives
				(gr_poly
					(pts
						(arc
							(start -0.1778 -0.2794)
							(mid -0.249642 -0.249642)
							(end -0.2794 -0.1778)
						)
						(arc
							(start -0.2794 0.1778)
							(mid -0.249642 0.249642)
							(end -0.1778 0.2794)
						)
						(arc
							(start 0.1778 0.2794)
							(mid 0.249642 0.249642)
							(end 0.2794 0.1778)
						)
						(arc
							(start 0.2794 -0.1778)
							(mid 0.249642 -0.249642)
							(end 0.1778 -0.2794)
						)
					)
					(width 0)
					(fill yes)
				)
			)
		)
		(pad "2" smd custom
			(at 0 0.4445 180)
			(size 0.1397 0.1397)
			(layers "F.Cu" "F.Mask" "F.Paste")
			(net "GND")
			(options
				(clearance outline)
				(anchor circle)
			)
			(primitives
				(gr_poly
					(pts
						(arc
							(start -0.1778 -0.2794)
							(mid -0.249642 -0.249642)
							(end -0.2794 -0.1778)
						)
						(arc
							(start -0.2794 0.1778)
							(mid -0.249642 0.249642)
							(end -0.1778 0.2794)
						)
						(arc
							(start 0.1778 0.2794)
							(mid 0.249642 0.249642)
							(end 0.2794 0.1778)
						)
						(arc
							(start 0.2794 -0.1778)
							(mid 0.249642 -0.249642)
							(end 0.1778 -0.2794)
						)
					)
					(width 0)
					(fill yes)
				)
			)
		)
	)
	(footprint ""
		(layer "F.Cu")
		(at 286.766 -161.544 180)
		(property "Reference" "R250"
			(at 0 0 180)
			(layer "F.SilkS")
			(hide yes)
			(effects
				(font
					(size 1.27 1.27)
				)
			)
		)
		(property "Value" "0R2J-2-GP"
			(at 0.064008 -3.993896 180)
			(unlocked yes)
			(layer "F.Fab")
			(hide yes)
			(effects
				(font
					(size 1.016 1.016)
					(thickness 0.1524)
				)
			)
		)
		(property "Device Type" "R402H16"
			(at 0.064008 -5.517896 180)
			(unlocked yes)
			(layer "F.Fab")
			(hide yes)
			(effects
				(font
					(size 1.016 1.016)
					(thickness 0.1524)
				)
			)
		)
		(duplicate_pad_numbers_are_jumpers no)
		(fp_line
			(start 0.508 -0.9398)
			(end -0.508 -0.9398)
			(stroke
				(width 0.1524)
				(type default)
			)
			(layer "F.SilkS")
		)
		(fp_line
			(start -0.508 -0.9398)
			(end -0.508 0.9398)
			(stroke
				(width 0.1524)
				(type default)
			)
			(layer "F.SilkS")
		)
		(fp_rect
			(start -0.508 0.9398)
			(end 0.508 -0.9398)
			(stroke
				(width 0)
				(type default)
			)
			(fill no)
			(layer "F.CrtYd")
		)
		(fp_rect
			(start -0.508 0.9398)
			(end 0.508 -0.9398)
			(stroke
				(width 0)
				(type default)
			)
			(fill no)
			(layer "F.Fab")
		)
		(pad "1" smd custom
			(at 0 -0.4445 180)
			(size 0.1397 0.1397)
			(layers "F.Cu" "F.Mask" "F.Paste")
			(net "SYS_PWRBTN_N")
			(options
				(clearance outline)
				(anchor circle)
			)
			(primitives
				(gr_poly
					(pts
						(arc
							(start -0.1778 -0.2794)
							(mid -0.249642 -0.249642)
							(end -0.2794 -0.1778)
						)
						(arc
							(start -0.2794 0.1778)
							(mid -0.249642 0.249642)
							(end -0.1778 0.2794)
						)
						(arc
							(start 0.1778 0.2794)
							(mid 0.249642 0.249642)
							(end 0.2794 0.1778)
						)
						(arc
							(start 0.2794 -0.1778)
							(mid 0.249642 -0.249642)
							(end 0.1778 -0.2794)
						)
					)
					(width 0)
					(fill yes)
				)
			)
		)
		(pad "2" smd custom
			(at 0 0.4445 180)
			(size 0.1397 0.1397)
			(layers "F.Cu" "F.Mask" "F.Paste")
			(net "SYS_PWRBTN_N_R")
			(options
				(clearance outline)
				(anchor circle)
			)
			(primitives
				(gr_poly
					(pts
						(arc
							(start -0.1778 -0.2794)
							(mid -0.249642 -0.249642)
							(end -0.2794 -0.1778)
						)
						(arc
							(start -0.2794 0.1778)
							(mid -0.249642 0.249642)
							(end -0.1778 0.2794)
						)
						(arc
							(start 0.1778 0.2794)
							(mid 0.249642 0.249642)
							(end 0.2794 0.1778)
						)
						(arc
							(start 0.2794 -0.1778)
							(mid 0.249642 -0.249642)
							(end 0.1778 -0.2794)
						)
					)
					(width 0)
					(fill yes)
				)
			)
		)
	)
	(footprint ""
		(layer "F.Cu")
		(at 268.351 -216.027 90)
		(property "Reference" "PC97"
			(at 0 0 90)
			(layer "F.SilkS")
			(hide yes)
			(effects
				(font
					(size 1.27 1.27)
				)
			)
		)
		(property "Value" "SC10U6D3V5KX-1GP"
			(at -0.0762 -6.1214 90)
			(unlocked yes)
			(layer "F.Fab")
			(hide yes)
			(effects
				(font
					(size 1.016 1.016)
					(thickness 0.1524)
				)
			)
		)
		(property "Device Type" "C805H54"
			(at -0.0762 -8.1534 90)
			(unlocked yes)
			(layer "F.Fab")
			(hide yes)
			(effects
				(font
					(size 1.016 1.016)
					(thickness 0.1524)
				)
			)
		)
		(duplicate_pad_numbers_are_jumpers no)
		(fp_line
			(start 0.635 0)
			(end -0.635 0)
			(stroke
				(width 0.508)
				(type default)
			)
			(layer "F.SilkS")
		)
		(fp_rect
			(start -0.9652 1.778)
			(end 0.9652 -1.778)
			(stroke
				(width 0)
				(type default)
			)
			(fill no)
			(layer "F.CrtYd")
		)
		(fp_poly
			(pts
				(xy -0.9652 -1.778) (xy 0.9652 -1.778) (xy 0.9652 1.778) (xy -0.9652 1.778)
			)
			(stroke
				(width 0)
				(type default)
			)
			(fill no)
			(layer "F.Fab")
		)
		(pad "1" smd rect
			(at 0 -0.9652 90)
			(size 1.397 1.143)
			(layers "F.Cu" "F.Mask" "F.Paste")
			(net "TPS74801_1V26_STBY_OUT")
		)
		(pad "2" smd rect
			(at 0 0.9652 90)
			(size 1.397 1.143)
			(layers "F.Cu" "F.Mask" "F.Paste")
			(net "GND")
		)
	)
	(footprint ""
		(layer "F.Cu")
		(at 96.540066 -2.029968 90)
		(property "Reference" "LED5"
			(at 0 0 90)
			(layer "F.SilkS")
			(hide yes)
			(effects
				(font
					(size 1.27 1.27)
				)
			)
		)
		(property "Value" "LED-B-77-GP-U3"
			(at -0.7112 -3.6068 90)
			(unlocked yes)
			(layer "F.Fab")
			(hide yes)
			(effects
				(font
					(size 1.016 1.016)
					(thickness 0.1524)
				)
			)
		)
		(property "Device Type" "LED3020AK-U2H44"
			(at -0.7112 -5.1308 90)
			(unlocked yes)
			(layer "F.Fab")
			(hide yes)
			(effects
				(font
					(size 1.016 1.016)
					(thickness 0.1524)
				)
			)
		)
		(duplicate_pad_numbers_are_jumpers no)
		(fp_line
			(start 0.8382 -2.4003)
			(end -0.8382 -2.4003)
			(stroke
				(width 0.1524)
				(type default)
			)
			(layer "F.SilkS")
		)
		(fp_line
			(start -0.8382 -2.4003)
			(end -0.8382 -1.31445)
			(stroke
				(width 0.1524)
				(type default)
			)
			(layer "F.SilkS")
		)
		(fp_line
			(start -0.8382 1.31445)
			(end -0.8382 2.4003)
			(stroke
				(width 0.1524)
				(type default)
			)
			(layer "F.SilkS")
		)
		(fp_line
			(start 0.8382 2.4003)
			(end 0.8382 -2.4003)
			(stroke
				(width 0.1524)
				(type default)
			)
			(layer "F.SilkS")
		)
		(fp_line
			(start -0.8382 2.4003)
			(end 0.8382 2.4003)
			(stroke
				(width 0.1524)
				(type default)
			)
			(layer "F.SilkS")
		)
		(fp_line
			(start 0.889 2.5273)
			(end -0.889 2.5273)
			(stroke
				(width 0.4064)
				(type default)
			)
			(layer "F.SilkS")
		)
		(fp_arc
			(start -0.8382 1.31445)
			(mid -1.85412 0)
			(end -0.8382 -1.31445)
			(stroke
				(width 0.1524)
				(type default)
			)
			(layer "F.SilkS")
		)
		(fp_poly
			(pts
				(xy -1.0922 2.6543) (xy -1.0922 1.49606) (xy -1.15189 1.4732) (xy -1.27254 1.41351) (xy -1.38557 1.34493)
				(xy -1.49098 1.26873) (xy -1.59258 1.18237) (xy -1.68656 1.08712) (xy -1.77165 0.98552) (xy -1.84785 0.87757)
				(xy -1.91516 0.76454) (xy -1.97358 0.64262) (xy -2.02057 0.5207) (xy -2.05867 0.3937) (xy -2.08534 0.26416)
				(xy -2.10185 0.13335) (xy -2.1082 0) (xy -2.10185 -0.13335) (xy -2.08534 -0.26416) (xy -2.05867 -0.3937)
				(xy -2.02057 -0.5207) (xy -1.97358 -0.64262) (xy -1.91516 -0.76454) (xy -1.84785 -0.87757) (xy -1.77165 -0.98552)
				(xy -1.68656 -1.08712) (xy -1.59258 -1.18237) (xy -1.49098 -1.26873) (xy -1.38557 -1.34493) (xy -1.27254 -1.41351)
				(xy -1.15189 -1.4732) (xy -1.0922 -1.49606) (xy -1.0922 -2.6543) (xy 1.0922 -2.6543) (xy 1.0922 2.6543)
			)
			(stroke
				(width 0)
				(type default)
			)
			(fill no)
			(layer "F.CrtYd")
		)
		(fp_poly
			(pts
				(xy -1.0922 2.6543) (xy -1.0922 1.49606) (xy -1.15189 1.4732) (xy -1.27254 1.41351) (xy -1.38557 1.34493)
				(xy -1.49098 1.26873) (xy -1.59258 1.18237) (xy -1.68656 1.08712) (xy -1.77165 0.98552) (xy -1.84785 0.87757)
				(xy -1.91516 0.76454) (xy -1.97358 0.64262) (xy -2.02057 0.5207) (xy -2.05867 0.3937) (xy -2.08534 0.26416)
				(xy -2.10185 0.13335) (xy -2.1082 0) (xy -2.10185 -0.13335) (xy -2.08534 -0.26416) (xy -2.05867 -0.3937)
				(xy -2.02057 -0.5207) (xy -1.97358 -0.64262) (xy -1.91516 -0.76454) (xy -1.84785 -0.87757) (xy -1.77165 -0.98552)
				(xy -1.68656 -1.08712) (xy -1.59258 -1.18237) (xy -1.49098 -1.26873) (xy -1.38557 -1.34493) (xy -1.27254 -1.41351)
				(xy -1.15189 -1.4732) (xy -1.0922 -1.49606) (xy -1.0922 -2.6543) (xy 1.0922 -2.6543) (xy 1.0922 2.6543)
			)
			(stroke
				(width 0)
				(type default)
			)
			(fill no)
			(layer "F.Fab")
		)
		(pad "A" smd rect
			(at 0 -1.57099 90)
			(size 1.143 1.143)
			(layers "F.Cu" "F.Mask" "F.Paste")
			(net "LED_PWR_N_R")
		)
		(pad "K" smd rect
			(at 0 1.57099 90)
			(size 1.143 1.143)
			(layers "F.Cu" "F.Mask" "F.Paste")
			(net "LED_PWR_N_ON")
		)
	)
	(footprint ""
		(layer "F.Cu")
		(at 220.68028 -91.02852)
		(property "Reference" "SR927"
			(at 0 0 0)
			(layer "F.SilkS")
			(hide yes)
			(effects
				(font
					(size 1.27 1.27)
				)
			)
		)
		(property "Value" "0R2J-2-GP"
			(at 0.064008 -3.993896 0)
			(unlocked yes)
			(layer "F.Fab")
			(hide yes)
			(effects
				(font
					(size 1.016 1.016)
					(thickness 0.1524)
				)
			)
		)
		(property "Device Type" "R402H16"
			(at 0.064008 -5.517896 0)
			(unlocked yes)
			(layer "F.Fab")
			(hide yes)
			(effects
				(font
					(size 1.016 1.016)
					(thickness 0.1524)
				)
			)
		)
		(duplicate_pad_numbers_are_jumpers no)
		(fp_line
			(start -0.508 -0.9398)
			(end -0.508 0.9398)
			(stroke
				(width 0.1524)
				(type default)
			)
			(layer "F.SilkS")
		)
		(fp_line
			(start 0.508 -0.9398)
			(end -0.508 -0.9398)
			(stroke
				(width 0.1524)
				(type default)
			)
			(layer "F.SilkS")
		)
		(fp_rect
			(start -0.508 0.9398)
			(end 0.508 -0.9398)
			(stroke
				(width 0)
				(type default)
			)
			(fill no)
			(layer "F.CrtYd")
		)
		(fp_rect
			(start -0.508 0.9398)
			(end 0.508 -0.9398)
			(stroke
				(width 0)
				(type default)
			)
			(fill no)
			(layer "F.Fab")
		)
		(pad "1" smd custom
			(at 0 -0.4445)
			(size 0.1397 0.1397)
			(layers "F.Cu" "F.Mask" "F.Paste")
			(net "IOC_UART_TX")
			(options
				(clearance outline)
				(anchor circle)
			)
			(primitives
				(gr_poly
					(pts
						(arc
							(start -0.1778 -0.2794)
							(mid -0.249642 -0.249642)
							(end -0.2794 -0.1778)
						)
						(arc
							(start -0.2794 0.1778)
							(mid -0.249642 0.249642)
							(end -0.1778 0.2794)
						)
						(arc
							(start 0.1778 0.2794)
							(mid 0.249642 0.249642)
							(end 0.2794 0.1778)
						)
						(arc
							(start 0.2794 -0.1778)
							(mid 0.249642 -0.249642)
							(end 0.1778 -0.2794)
						)
					)
					(width 0)
					(fill yes)
				)
			)
		)
		(pad "2" smd custom
			(at 0 0.4445)
			(size 0.1397 0.1397)
			(layers "F.Cu" "F.Mask" "F.Paste")
			(net "IOC_UART_R_TX")
			(options
				(clearance outline)
				(anchor circle)
			)
			(primitives
				(gr_poly
					(pts
						(arc
							(start -0.1778 -0.2794)
							(mid -0.249642 -0.249642)
							(end -0.2794 -0.1778)
						)
						(arc
							(start -0.2794 0.1778)
							(mid -0.249642 0.249642)
							(end -0.1778 0.2794)
						)
						(arc
							(start 0.1778 0.2794)
							(mid 0.249642 0.249642)
							(end 0.2794 0.1778)
						)
						(arc
							(start 0.2794 -0.1778)
							(mid 0.249642 -0.249642)
							(end 0.1778 -0.2794)
						)
					)
					(width 0)
					(fill yes)
				)
			)
		)
	)
	(footprint ""
		(layer "F.Cu")
		(at 159.766 -87.884)
		(property "Reference" "PTC6"
			(at 0 0 0)
			(layer "F.SilkS")
			(hide yes)
			(effects
				(font
					(size 1.27 1.27)
				)
			)
		)
		(property "Value" "SE470UF2VDM-GP"
			(at 0 -9.6012 0)
			(unlocked yes)
			(layer "F.Fab")
			(hide yes)
			(effects
				(font
					(size 1.016 1.016)
					(thickness 0.1524)
				)
			)
		)
		(property "Device Type" "CT7343H83"
			(at 0 -11.1252 0)
			(unlocked yes)
			(layer "F.Fab")
			(hide yes)
			(effects
				(font
					(size 1.016 1.016)
					(thickness 0.1524)
				)
			)
		)
		(duplicate_pad_numbers_are_jumpers no)
		(fp_line
			(start -2.286 -4.8768)
			(end -2.286 -2.032)
			(stroke
				(width 0.1524)
				(type default)
			)
			(layer "F.SilkS")
		)
		(fp_line
			(start -2.286 4.8768)
			(end -2.286 2.032)
			(stroke
				(width 0.1524)
				(type default)
			)
			(layer "F.SilkS")
		)
		(fp_line
			(start 2.1082 -4.699)
			(end -2.1082 -4.699)
			(stroke
				(width 0.508)
				(type default)
			)
			(layer "F.SilkS")
		)
		(fp_line
			(start 2.286 -4.8768)
			(end -2.286 -4.8768)
			(stroke
				(width 0.1524)
				(type default)
			)
			(layer "F.SilkS")
		)
		(fp_line
			(start 2.286 -2.032)
			(end 2.286 -4.8768)
			(stroke
				(width 0.1524)
				(type default)
			)
			(layer "F.SilkS")
		)
		(fp_line
			(start 2.286 2.032)
			(end 2.286 4.8768)
			(stroke
				(width 0.1524)
				(type default)
			)
			(layer "F.SilkS")
		)
		(fp_line
			(start 2.286 4.8768)
			(end -2.286 4.8768)
			(stroke
				(width 0.1524)
				(type default)
			)
			(layer "F.SilkS")
		)
		(fp_rect
			(start -2.1463 3.6449)
			(end 2.1463 -3.6449)
			(stroke
				(width 0)
				(type default)
			)
			(fill no)
			(layer "F.CrtYd")
		)
		(fp_poly
			(pts
				(xy -2.54 4.953) (xy -2.54 4.2926) (xy -3.81 4.2926) (xy -3.81 -4.2926) (xy -2.54 -4.2926) (xy -2.54 -4.953)
				(xy 2.54 -4.953) (xy 2.54 -4.2926) (xy 3.81 -4.2926) (xy 3.81 -1.6256) (xy 2.1463 -1.6256) (xy 2.1463 -3.6449)
				(xy -2.1463 -3.6449) (xy -2.1463 3.6449) (xy 2.1463 3.6449) (xy 2.1463 -1.6129) (xy 3.81 -1.6129)
				(xy 3.81 4.2926) (xy 2.54 4.2926) (xy 2.54 4.953)
			)
			(stroke
				(width 0)
				(type default)
			)
			(fill no)
			(layer "F.CrtYd")
		)
		(fp_rect
			(start -3.81 4.2926)
			(end -2.54 -4.2926)
			(stroke
				(width 0)
				(type default)
			)
			(fill no)
			(layer "F.Fab")
		)
		(fp_rect
			(start -2.54 4.953)
			(end 2.54 -4.953)
			(stroke
				(width 0)
				(type default)
			)
			(fill no)
			(layer "F.Fab")
		)
		(fp_rect
			(start 2.54 4.2926)
			(end 3.81 -4.2926)
			(stroke
				(width 0)
				(type default)
			)
			(fill no)
			(layer "F.Fab")
		)
		(pad "1" smd rect
			(at 0 -3.1496)
			(size 2.413 2.286)
			(layers "F.Cu" "F.Mask" "F.Paste")
			(net "P0V9_E")
		)
		(pad "2" smd rect
			(at 0 3.1496)
			(size 2.413 2.286)
			(layers "F.Cu" "F.Mask" "F.Paste")
			(net "GND")
		)
		(zone
			(layer "F.Cu")
			(hatch none 0.5)
			(connect_pads
				(clearance 0)
			)
			(min_thickness 0.25)
			(keepout
				(tracks allowed)
				(vias not_allowed)
				(pads allowed)
				(copperpour not_allowed)
				(footprints allowed)
			)
			(placement
				(enabled no)
				(sheetname "")
			)
			(fill
				(thermal_gap 0.5)
				(thermal_bridge_width 0.5)
				(island_removal_mode 0)
			)
			(polygon
				(pts
					(xy 158.2547 -83.2866) (xy 161.2773 -83.2866) (xy 161.2773 -86.1822) (xy 161.2773 -86.5124) (xy 158.2547 -86.5124)
					(xy 158.2547 -86.1822)
				)
			)
		)
		(zone
			(layer "F.Cu")
			(hatch none 0.5)
			(connect_pads
				(clearance 0)
			)
			(min_thickness 0.25)
			(keepout
				(tracks allowed)
				(vias not_allowed)
				(pads allowed)
				(copperpour not_allowed)
				(footprints allowed)
			)
			(placement
				(enabled no)
				(sheetname "")
			)
			(fill
				(thermal_gap 0.5)
				(thermal_bridge_width 0.5)
				(island_removal_mode 0)
			)
			(polygon
				(pts
					(xy 161.2773 -89.5731) (xy 161.2773 -92.4814) (xy 158.2547 -92.4814) (xy 158.2547 -89.5858) (xy 158.2547 -89.2556)
					(xy 161.2773 -89.2556)
				)
			)
		)
	)
	(footprint ""
		(layer "F.Cu")
		(at 160.02 -148.336 -90)
		(property "Reference" "SR726"
			(at 0 0 270)
			(layer "F.SilkS")
			(hide yes)
			(effects
				(font
					(size 1.27 1.27)
				)
			)
		)
		(property "Value" "4K7R2F-GP"
			(at 0.064008 -3.993896 270)
			(unlocked yes)
			(layer "F.Fab")
			(hide yes)
			(effects
				(font
					(size 1.016 1.016)
					(thickness 0.1524)
				)
			)
		)
		(property "Device Type" "R402H16"
			(at 0.064008 -5.517896 270)
			(unlocked yes)
			(layer "F.Fab")
			(hide yes)
			(effects
				(font
					(size 1.016 1.016)
					(thickness 0.1524)
				)
			)
		)
		(duplicate_pad_numbers_are_jumpers no)
		(fp_line
			(start -0.508 -0.9398)
			(end -0.508 0.9398)
			(stroke
				(width 0.1524)
				(type default)
			)
			(layer "F.SilkS")
		)
		(fp_line
			(start 0.508 -0.9398)
			(end -0.508 -0.9398)
			(stroke
				(width 0.1524)
				(type default)
			)
			(layer "F.SilkS")
		)
		(fp_rect
			(start -0.508 0.9398)
			(end 0.508 -0.9398)
			(stroke
				(width 0)
				(type default)
			)
			(fill no)
			(layer "F.CrtYd")
		)
		(fp_rect
			(start -0.508 0.9398)
			(end 0.508 -0.9398)
			(stroke
				(width 0)
				(type default)
			)
			(fill no)
			(layer "F.Fab")
		)
		(pad "1" smd custom
			(at 0 -0.4445 270)
			(size 0.1397 0.1397)
			(layers "F.Cu" "F.Mask" "F.Paste")
			(net "IOC_P3V3_SCL_14")
			(options
				(clearance outline)
				(anchor circle)
			)
			(primitives
				(gr_poly
					(pts
						(arc
							(start -0.1778 -0.2794)
							(mid -0.249642 -0.249642)
							(end -0.2794 -0.1778)
						)
						(arc
							(start -0.2794 0.1778)
							(mid -0.249642 0.249642)
							(end -0.1778 0.2794)
						)
						(arc
							(start 0.1778 0.2794)
							(mid 0.249642 0.249642)
							(end 0.2794 0.1778)
						)
						(arc
							(start 0.2794 -0.1778)
							(mid 0.249642 -0.249642)
							(end 0.1778 -0.2794)
						)
					)
					(width 0)
					(fill yes)
				)
			)
		)
		(pad "2" smd custom
			(at 0 0.4445 270)
			(size 0.1397 0.1397)
			(layers "F.Cu" "F.Mask" "F.Paste")
			(net "P3V3")
			(options
				(clearance outline)
				(anchor circle)
			)
			(primitives
				(gr_poly
					(pts
						(arc
							(start -0.1778 -0.2794)
							(mid -0.249642 -0.249642)
							(end -0.2794 -0.1778)
						)
						(arc
							(start -0.2794 0.1778)
							(mid -0.249642 0.249642)
							(end -0.1778 0.2794)
						)
						(arc
							(start 0.1778 0.2794)
							(mid 0.249642 0.249642)
							(end 0.2794 0.1778)
						)
						(arc
							(start 0.2794 -0.1778)
							(mid 0.249642 -0.249642)
							(end 0.1778 -0.2794)
						)
					)
					(width 0)
					(fill yes)
				)
			)
		)
	)
	(footprint ""
		(layer "F.Cu")
		(at 85.598 -24.384 180)
		(property "Reference" "PC217"
			(at 0 0 180)
			(layer "F.SilkS")
			(hide yes)
			(effects
				(font
					(size 1.27 1.27)
				)
			)
		)
		(property "Value" "SC220P50V2KX-3GP"
			(at 1.1811 -2.7051 180)
			(unlocked yes)
			(layer "F.Fab")
			(hide yes)
			(effects
				(font
					(size 1.016 1.016)
					(thickness 0.1524)
				)
			)
		)
		(property "Device Type" "C402H22"
			(at 1.1811 -4.2291 180)
			(unlocked yes)
			(layer "F.Fab")
			(hide yes)
			(effects
				(font
					(size 1.016 1.016)
					(thickness 0.1524)
				)
			)
		)
		(duplicate_pad_numbers_are_jumpers no)
		(fp_rect
			(start -0.4318 0.9525)
			(end 0.4318 -0.9525)
			(stroke
				(width 0)
				(type default)
			)
			(fill no)
			(layer "F.CrtYd")
		)
		(fp_rect
			(start -0.4318 0.9525)
			(end 0.4318 -0.9525)
			(stroke
				(width 0)
				(type default)
			)
			(fill no)
			(layer "F.Fab")
		)
		(pad "1" smd custom
			(at 0 -0.4445 180)
			(size 0.1524 0.1524)
			(layers "F.Cu" "F.Mask" "F.Paste")
			(net "VT235_PGIN")
			(options
				(clearance outline)
				(anchor circle)
			)
			(primitives
				(gr_poly
					(pts
						(arc
							(start 0.3048 -0.2032)
							(mid 0.275042 -0.275042)
							(end 0.2032 -0.3048)
						)
						(arc
							(start -0.2032 -0.3048)
							(mid -0.275042 -0.275042)
							(end -0.3048 -0.2032)
						)
						(arc
							(start -0.3048 0.2032)
							(mid -0.275042 0.275042)
							(end -0.2032 0.3048)
						)
						(arc
							(start 0.2032 0.3048)
							(mid 0.275042 0.275042)
							(end 0.3048 0.2032)
						)
					)
					(width 0)
					(fill yes)
				)
			)
		)
		(pad "2" smd custom
			(at 0 0.4445 180)
			(size 0.1524 0.1524)
			(layers "F.Cu" "F.Mask" "F.Paste")
			(net "VT235_VREF")
			(options
				(clearance outline)
				(anchor circle)
			)
			(primitives
				(gr_poly
					(pts
						(arc
							(start 0.3048 -0.2032)
							(mid 0.275042 -0.275042)
							(end 0.2032 -0.3048)
						)
						(arc
							(start -0.2032 -0.3048)
							(mid -0.275042 -0.275042)
							(end -0.3048 -0.2032)
						)
						(arc
							(start -0.3048 0.2032)
							(mid -0.275042 0.275042)
							(end -0.2032 0.3048)
						)
						(arc
							(start 0.2032 0.3048)
							(mid 0.275042 0.275042)
							(end 0.3048 0.2032)
						)
					)
					(width 0)
					(fill yes)
				)
			)
		)
	)
	(footprint ""
		(layer "F.Cu")
		(at 196.977 -179.832 180)
		(property "Reference" "R481"
			(at 0 0 180)
			(layer "F.SilkS")
			(hide yes)
			(effects
				(font
					(size 1.27 1.27)
				)
			)
		)
		(property "Value" "200R3F-GP"
			(at -0.0254 -2.5146 180)
			(unlocked yes)
			(layer "F.Fab")
			(hide yes)
			(effects
				(font
					(size 1.016 1.016)
					(thickness 0.1524)
				)
			)
		)
		(property "Device Type" "R603H22"
			(at -0.0254 -4.0386 180)
			(unlocked yes)
			(layer "F.Fab")
			(hide yes)
			(effects
				(font
					(size 1.016 1.016)
					(thickness 0.1524)
				)
			)
		)
		(duplicate_pad_numbers_are_jumpers no)
		(fp_line
			(start 0.2032 0)
			(end 0.4826 0)
			(stroke
				(width 0.2032)
				(type default)
			)
			(layer "F.SilkS")
		)
		(fp_line
			(start -0.4826 0)
			(end -0.2032 0)
			(stroke
				(width 0.2032)
				(type default)
			)
			(layer "F.SilkS")
		)
		(fp_rect
			(start -0.5842 1.3335)
			(end 0.5842 -1.3335)
			(stroke
				(width 0)
				(type default)
			)
			(fill no)
			(layer "F.CrtYd")
		)
		(fp_rect
			(start -0.5842 1.3335)
			(end 0.5842 -1.3335)
			(stroke
				(width 0)
				(type default)
			)
			(fill no)
			(layer "F.Fab")
		)
		(pad "1" smd custom
			(at 0 -0.762 180)
			(size 0.2159 0.2159)
			(layers "F.Cu" "F.Mask" "F.Paste")
			(net "P3V3_STBY")
			(options
				(clearance outline)
				(anchor circle)
			)
			(primitives
				(gr_poly
					(pts
						(arc
							(start -0.3302 -0.4318)
							(mid -0.402042 -0.402042)
							(end -0.4318 -0.3302)
						)
						(arc
							(start -0.4318 0.3302)
							(mid -0.402042 0.402042)
							(end -0.3302 0.4318)
						)
						(arc
							(start 0.3302 0.4318)
							(mid 0.402042 0.402042)
							(end 0.4318 0.3302)
						)
						(arc
							(start 0.4318 -0.3302)
							(mid 0.402042 -0.402042)
							(end 0.3302 -0.4318)
						)
					)
					(width 0)
					(fill yes)
				)
			)
		)
		(pad "2" smd custom
			(at 0 0.762 180)
			(size 0.2159 0.2159)
			(layers "F.Cu" "F.Mask" "F.Paste")
			(net "HB_A_OUT")
			(options
				(clearance outline)
				(anchor circle)
			)
			(primitives
				(gr_poly
					(pts
						(arc
							(start -0.3302 -0.4318)
							(mid -0.402042 -0.402042)
							(end -0.4318 -0.3302)
						)
						(arc
							(start -0.4318 0.3302)
							(mid -0.402042 0.402042)
							(end -0.3302 0.4318)
						)
						(arc
							(start 0.3302 0.4318)
							(mid 0.402042 0.402042)
							(end 0.4318 0.3302)
						)
						(arc
							(start 0.4318 -0.3302)
							(mid 0.402042 -0.402042)
							(end 0.3302 -0.4318)
						)
					)
					(width 0)
					(fill yes)
				)
			)
		)
	)
	(footprint ""
		(layer "F.Cu")
		(at 274.193 -164.592 90)
		(property "Reference" "R541"
			(at 0 0 90)
			(layer "F.SilkS")
			(hide yes)
			(effects
				(font
					(size 1.27 1.27)
				)
			)
		)
		(property "Value" "0R2J-2-GP"
			(at 0.064008 -3.993896 90)
			(unlocked yes)
			(layer "F.Fab")
			(hide yes)
			(effects
				(font
					(size 1.016 1.016)
					(thickness 0.1524)
				)
			)
		)
		(property "Device Type" "R402H16"
			(at 0.064008 -5.517896 90)
			(unlocked yes)
			(layer "F.Fab")
			(hide yes)
			(effects
				(font
					(size 1.016 1.016)
					(thickness 0.1524)
				)
			)
		)
		(duplicate_pad_numbers_are_jumpers no)
		(fp_line
			(start 0.508 -0.9398)
			(end -0.508 -0.9398)
			(stroke
				(width 0.1524)
				(type default)
			)
			(layer "F.SilkS")
		)
		(fp_line
			(start -0.508 -0.9398)
			(end -0.508 0.9398)
			(stroke
				(width 0.1524)
				(type default)
			)
			(layer "F.SilkS")
		)
		(fp_rect
			(start -0.508 0.9398)
			(end 0.508 -0.9398)
			(stroke
				(width 0)
				(type default)
			)
			(fill no)
			(layer "F.CrtYd")
		)
		(fp_rect
			(start -0.508 0.9398)
			(end 0.508 -0.9398)
			(stroke
				(width 0)
				(type default)
			)
			(fill no)
			(layer "F.Fab")
		)
		(pad "1" smd custom
			(at 0 -0.4445 90)
			(size 0.1397 0.1397)
			(layers "F.Cu" "F.Mask" "F.Paste")
			(net "P0V9_E_PG")
			(options
				(clearance outline)
				(anchor circle)
			)
			(primitives
				(gr_poly
					(pts
						(arc
							(start -0.1778 -0.2794)
							(mid -0.249642 -0.249642)
							(end -0.2794 -0.1778)
						)
						(arc
							(start -0.2794 0.1778)
							(mid -0.249642 0.249642)
							(end -0.1778 0.2794)
						)
						(arc
							(start 0.1778 0.2794)
							(mid 0.249642 0.249642)
							(end 0.2794 0.1778)
						)
						(arc
							(start 0.2794 -0.1778)
							(mid 0.249642 -0.249642)
							(end 0.1778 -0.2794)
						)
					)
					(width 0)
					(fill yes)
				)
			)
		)
		(pad "2" smd custom
			(at 0 0.4445 90)
			(size 0.1397 0.1397)
			(layers "F.Cu" "F.Mask" "F.Paste")
			(net "PWGD_P0V9_E_PG_R")
			(options
				(clearance outline)
				(anchor circle)
			)
			(primitives
				(gr_poly
					(pts
						(arc
							(start -0.1778 -0.2794)
							(mid -0.249642 -0.249642)
							(end -0.2794 -0.1778)
						)
						(arc
							(start -0.2794 0.1778)
							(mid -0.249642 0.249642)
							(end -0.1778 0.2794)
						)
						(arc
							(start 0.1778 0.2794)
							(mid 0.249642 0.249642)
							(end 0.2794 0.1778)
						)
						(arc
							(start 0.2794 -0.1778)
							(mid 0.249642 -0.249642)
							(end 0.1778 -0.2794)
						)
					)
					(width 0)
					(fill yes)
				)
			)
		)
	)
	(footprint ""
		(layer "F.Cu")
		(at 182.888128 -16.183864)
		(property "Reference" "R189"
			(at 0 0 0)
			(layer "F.SilkS")
			(hide yes)
			(effects
				(font
					(size 1.27 1.27)
				)
			)
		)
		(property "Value" "4K7R2F-GP"
			(at 0.064008 -3.993896 0)
			(unlocked yes)
			(layer "F.Fab")
			(hide yes)
			(effects
				(font
					(size 1.016 1.016)
					(thickness 0.1524)
				)
			)
		)
		(property "Device Type" "R402H16"
			(at 0.064008 -5.517896 0)
			(unlocked yes)
			(layer "F.Fab")
			(hide yes)
			(effects
				(font
					(size 1.016 1.016)
					(thickness 0.1524)
				)
			)
		)
		(duplicate_pad_numbers_are_jumpers no)
		(fp_line
			(start -0.508 -0.9398)
			(end -0.508 0.9398)
			(stroke
				(width 0.1524)
				(type default)
			)
			(layer "F.SilkS")
		)
		(fp_line
			(start 0.508 -0.9398)
			(end -0.508 -0.9398)
			(stroke
				(width 0.1524)
				(type default)
			)
			(layer "F.SilkS")
		)
		(fp_rect
			(start -0.508 0.9398)
			(end 0.508 -0.9398)
			(stroke
				(width 0)
				(type default)
			)
			(fill no)
			(layer "F.CrtYd")
		)
		(fp_rect
			(start -0.508 0.9398)
			(end 0.508 -0.9398)
			(stroke
				(width 0)
				(type default)
			)
			(fill no)
			(layer "F.Fab")
		)
		(pad "1" smd custom
			(at 0 -0.4445)
			(size 0.1397 0.1397)
			(layers "F.Cu" "F.Mask" "F.Paste")
			(net "P3V3_STBY")
			(options
				(clearance outline)
				(anchor circle)
			)
			(primitives
				(gr_poly
					(pts
						(arc
							(start -0.1778 -0.2794)
							(mid -0.249642 -0.249642)
							(end -0.2794 -0.1778)
						)
						(arc
							(start -0.2794 0.1778)
							(mid -0.249642 0.249642)
							(end -0.1778 0.2794)
						)
						(arc
							(start 0.1778 0.2794)
							(mid 0.249642 0.249642)
							(end 0.2794 0.1778)
						)
						(arc
							(start 0.2794 -0.1778)
							(mid 0.249642 -0.249642)
							(end 0.1778 -0.2794)
						)
					)
					(width 0)
					(fill yes)
				)
			)
		)
		(pad "2" smd custom
			(at 0 0.4445)
			(size 0.1397 0.1397)
			(layers "F.Cu" "F.Mask" "F.Paste")
			(net "TEMP_1_A1")
			(options
				(clearance outline)
				(anchor circle)
			)
			(primitives
				(gr_poly
					(pts
						(arc
							(start -0.1778 -0.2794)
							(mid -0.249642 -0.249642)
							(end -0.2794 -0.1778)
						)
						(arc
							(start -0.2794 0.1778)
							(mid -0.249642 0.249642)
							(end -0.1778 0.2794)
						)
						(arc
							(start 0.1778 0.2794)
							(mid 0.249642 0.249642)
							(end 0.2794 0.1778)
						)
						(arc
							(start 0.2794 -0.1778)
							(mid 0.249642 -0.249642)
							(end 0.1778 -0.2794)
						)
					)
					(width 0)
					(fill yes)
				)
			)
		)
	)
	(footprint ""
		(layer "F.Cu")
		(at 9.348216 -215.19388 90)
		(property "Reference" "U50"
			(at 0 0 90)
			(layer "F.SilkS")
			(hide yes)
			(effects
				(font
					(size 1.27 1.27)
				)
			)
		)
		(property "Value" "SN74LVC1G08DCKR-GP"
			(at -2.3368 -8.6868 90)
			(unlocked yes)
			(layer "F.Fab")
			(hide yes)
			(effects
				(font
					(size 1.016 1.016)
					(thickness 0.1524)
				)
			)
		)
		(property "Device Type" "SC70-5H44"
			(at -2.3114 -10.414 90)
			(unlocked yes)
			(layer "F.Fab")
			(hide yes)
			(effects
				(font
					(size 1.016 1.016)
					(thickness 0.1524)
				)
			)
		)
		(duplicate_pad_numbers_are_jumpers no)
		(fp_line
			(start 1.3843 -1.8034)
			(end 1.3843 -1.1176)
			(stroke
				(width 0.3302)
				(type default)
			)
			(layer "F.SilkS")
		)
		(fp_line
			(start 0.6604 -1.8034)
			(end 1.3843 -1.8034)
			(stroke
				(width 0.3302)
				(type default)
			)
			(layer "F.SilkS")
		)
		(fp_line
			(start 1.27 -1.7018)
			(end 1.27 1.7018)
			(stroke
				(width 0.1524)
				(type default)
			)
			(layer "F.SilkS")
		)
		(fp_line
			(start -1.27 -1.7018)
			(end 1.27 -1.7018)
			(stroke
				(width 0.1524)
				(type default)
			)
			(layer "F.SilkS")
		)
		(fp_line
			(start 1.27 1.7018)
			(end -1.27 1.7018)
			(stroke
				(width 0.1524)
				(type default)
			)
			(layer "F.SilkS")
		)
		(fp_line
			(start -1.27 1.7018)
			(end -1.27 -1.7018)
			(stroke
				(width 0.1524)
				(type default)
			)
			(layer "F.SilkS")
		)
		(fp_rect
			(start -1.524 1.9558)
			(end 1.524 -1.9558)
			(stroke
				(width 0)
				(type default)
			)
			(fill no)
			(layer "F.CrtYd")
		)
		(fp_poly
			(pts
				(xy -1.524 -1.9558) (xy 1.524 -1.9558) (xy 1.524 1.9558) (xy -1.524 1.9558)
			)
			(stroke
				(width 0)
				(type default)
			)
			(fill no)
			(layer "F.Fab")
		)
		(pad "1" smd rect
			(at 0.65024 -0.8255 90)
			(size 0.4064 1.2192)
			(layers "F.Cu" "F.Mask" "F.Paste")
			(net "PRSNT_AND_1")
		)
		(pad "2" smd rect
			(at 0 -0.8255 90)
			(size 0.4064 1.2192)
			(layers "F.Cu" "F.Mask" "F.Paste")
			(net "PRSNT_AND_3")
		)
		(pad "3" smd rect
			(at -0.65024 -0.8255 90)
			(size 0.4064 1.2192)
			(layers "F.Cu" "F.Mask" "F.Paste")
			(net "GND")
		)
		(pad "4" smd rect
			(at -0.65024 0.8255 90)
			(size 0.4064 1.2192)
			(layers "F.Cu" "F.Mask" "F.Paste")
			(net "MATED#")
		)
		(pad "5" smd rect
			(at 0.65024 0.8255 90)
			(size 0.4064 1.2192)
			(layers "F.Cu" "F.Mask" "F.Paste")
			(net "P3V3_STBY")
		)
	)
	(footprint ""
		(layer "F.Cu")
		(at 190.871856 -120.913652 90)
		(property "Reference" "R600"
			(at 0 0 90)
			(layer "F.SilkS")
			(hide yes)
			(effects
				(font
					(size 1.27 1.27)
				)
			)
		)
		(property "Value" "1KR2J-1-GP"
			(at 0.064008 -3.993896 90)
			(unlocked yes)
			(layer "F.Fab")
			(hide yes)
			(effects
				(font
					(size 1.016 1.016)
					(thickness 0.1524)
				)
			)
		)
		(property "Device Type" "R402H16"
			(at 0.064008 -5.517896 90)
			(unlocked yes)
			(layer "F.Fab")
			(hide yes)
			(effects
				(font
					(size 1.016 1.016)
					(thickness 0.1524)
				)
			)
		)
		(duplicate_pad_numbers_are_jumpers no)
		(fp_line
			(start 0.508 -0.9398)
			(end -0.508 -0.9398)
			(stroke
				(width 0.1524)
				(type default)
			)
			(layer "F.SilkS")
		)
		(fp_line
			(start -0.508 -0.9398)
			(end -0.508 0.9398)
			(stroke
				(width 0.1524)
				(type default)
			)
			(layer "F.SilkS")
		)
		(fp_rect
			(start -0.508 0.9398)
			(end 0.508 -0.9398)
			(stroke
				(width 0)
				(type default)
			)
			(fill no)
			(layer "F.CrtYd")
		)
		(fp_rect
			(start -0.508 0.9398)
			(end 0.508 -0.9398)
			(stroke
				(width 0)
				(type default)
			)
			(fill no)
			(layer "F.Fab")
		)
		(pad "1" smd custom
			(at 0 -0.4445 90)
			(size 0.1397 0.1397)
			(layers "F.Cu" "F.Mask" "F.Paste")
			(net "P3V3_STBY_R2")
			(options
				(clearance outline)
				(anchor circle)
			)
			(primitives
				(gr_poly
					(pts
						(arc
							(start -0.1778 -0.2794)
							(mid -0.249642 -0.249642)
							(end -0.2794 -0.1778)
						)
						(arc
							(start -0.2794 0.1778)
							(mid -0.249642 0.249642)
							(end -0.1778 0.2794)
						)
						(arc
							(start 0.1778 0.2794)
							(mid 0.249642 0.249642)
							(end 0.2794 0.1778)
						)
						(arc
							(start 0.2794 -0.1778)
							(mid 0.249642 -0.249642)
							(end 0.1778 -0.2794)
						)
					)
					(width 0)
					(fill yes)
				)
			)
		)
		(pad "2" smd custom
			(at 0 0.4445 90)
			(size 0.1397 0.1397)
			(layers "F.Cu" "F.Mask" "F.Paste")
			(net "P5V_STBY")
			(options
				(clearance outline)
				(anchor circle)
			)
			(primitives
				(gr_poly
					(pts
						(arc
							(start -0.1778 -0.2794)
							(mid -0.249642 -0.249642)
							(end -0.2794 -0.1778)
						)
						(arc
							(start -0.2794 0.1778)
							(mid -0.249642 0.249642)
							(end -0.1778 0.2794)
						)
						(arc
							(start 0.1778 0.2794)
							(mid 0.249642 0.249642)
							(end 0.2794 0.1778)
						)
						(arc
							(start 0.2794 -0.1778)
							(mid 0.249642 -0.249642)
							(end 0.1778 -0.2794)
						)
					)
					(width 0)
					(fill yes)
				)
			)
		)
	)
	(footprint ""
		(layer "F.Cu")
		(at 110.109 -60.452 180)
		(property "Reference" "SR695"
			(at 0 0 180)
			(layer "F.SilkS")
			(hide yes)
			(effects
				(font
					(size 1.27 1.27)
				)
			)
		)
		(property "Value" "10KR2F-2-GP"
			(at 0.064008 -3.993896 180)
			(unlocked yes)
			(layer "F.Fab")
			(hide yes)
			(effects
				(font
					(size 1.016 1.016)
					(thickness 0.1524)
				)
			)
		)
		(property "Device Type" "R402H16"
			(at 0.064008 -5.517896 180)
			(unlocked yes)
			(layer "F.Fab")
			(hide yes)
			(effects
				(font
					(size 1.016 1.016)
					(thickness 0.1524)
				)
			)
		)
		(duplicate_pad_numbers_are_jumpers no)
		(fp_line
			(start 0.508 -0.9398)
			(end -0.508 -0.9398)
			(stroke
				(width 0.1524)
				(type default)
			)
			(layer "F.SilkS")
		)
		(fp_line
			(start -0.508 -0.9398)
			(end -0.508 0.9398)
			(stroke
				(width 0.1524)
				(type default)
			)
			(layer "F.SilkS")
		)
		(fp_rect
			(start -0.508 0.9398)
			(end 0.508 -0.9398)
			(stroke
				(width 0)
				(type default)
			)
			(fill no)
			(layer "F.CrtYd")
		)
		(fp_rect
			(start -0.508 0.9398)
			(end 0.508 -0.9398)
			(stroke
				(width 0)
				(type default)
			)
			(fill no)
			(layer "F.Fab")
		)
		(pad "1" smd custom
			(at 0 -0.4445 180)
			(size 0.1397 0.1397)
			(layers "F.Cu" "F.Mask" "F.Paste")
			(net "XM_ADDR_0")
			(options
				(clearance outline)
				(anchor circle)
			)
			(primitives
				(gr_poly
					(pts
						(arc
							(start -0.1778 -0.2794)
							(mid -0.249642 -0.249642)
							(end -0.2794 -0.1778)
						)
						(arc
							(start -0.2794 0.1778)
							(mid -0.249642 0.249642)
							(end -0.1778 0.2794)
						)
						(arc
							(start 0.1778 0.2794)
							(mid 0.249642 0.249642)
							(end 0.2794 0.1778)
						)
						(arc
							(start 0.2794 -0.1778)
							(mid 0.249642 -0.249642)
							(end 0.1778 -0.2794)
						)
					)
					(width 0)
					(fill yes)
				)
			)
		)
		(pad "2" smd custom
			(at 0 0.4445 180)
			(size 0.1397 0.1397)
			(layers "F.Cu" "F.Mask" "F.Paste")
			(net "GND")
			(options
				(clearance outline)
				(anchor circle)
			)
			(primitives
				(gr_poly
					(pts
						(arc
							(start -0.1778 -0.2794)
							(mid -0.249642 -0.249642)
							(end -0.2794 -0.1778)
						)
						(arc
							(start -0.2794 0.1778)
							(mid -0.249642 0.249642)
							(end -0.1778 0.2794)
						)
						(arc
							(start 0.1778 0.2794)
							(mid 0.249642 0.249642)
							(end 0.2794 0.1778)
						)
						(arc
							(start 0.2794 -0.1778)
							(mid 0.249642 -0.249642)
							(end 0.1778 -0.2794)
						)
					)
					(width 0)
					(fill yes)
				)
			)
		)
	)
	(footprint ""
		(layer "F.Cu")
		(at 40.52697 -137.16 180)
		(property "Reference" "Q15"
			(at 0 0 180)
			(layer "F.SilkS")
			(hide yes)
			(effects
				(font
					(size 1.27 1.27)
				)
			)
		)
		(property "Value" "2N7002A-7-GP"
			(at 0.127 -8.9662 180)
			(unlocked yes)
			(layer "F.Fab")
			(hide yes)
			(effects
				(font
					(size 1.016 1.016)
					(thickness 0.1524)
				)
			)
		)
		(property "Device Type" "SOT23DGS2D4H48"
			(at 0.127 -10.4902 180)
			(unlocked yes)
			(layer "F.Fab")
			(hide yes)
			(effects
				(font
					(size 1.016 1.016)
					(thickness 0.1524)
				)
			)
		)
		(duplicate_pad_numbers_are_jumpers no)
		(fp_line
			(start 1.651 1.778)
			(end 1.651 -1.778)
			(stroke
				(width 0.1524)
				(type default)
			)
			(layer "F.SilkS")
		)
		(fp_line
			(start 1.651 -1.778)
			(end -1.651 -1.778)
			(stroke
				(width 0.1524)
				(type default)
			)
			(layer "F.SilkS")
		)
		(fp_line
			(start -1.651 1.778)
			(end 1.651 1.778)
			(stroke
				(width 0.1524)
				(type default)
			)
			(layer "F.SilkS")
		)
		(fp_line
			(start -1.651 -1.778)
			(end -1.651 1.778)
			(stroke
				(width 0.1524)
				(type default)
			)
			(layer "F.SilkS")
		)
		(fp_poly
			(pts
				(xy -1.778 1.8796) (xy -1.778 -1.8796) (xy 1.778 -1.8796) (xy 1.778 1.8796)
			)
			(stroke
				(width 0)
				(type default)
			)
			(fill no)
			(layer "F.CrtYd")
		)
		(fp_poly
			(pts
				(xy -1.778 1.8796) (xy -1.778 -1.8796) (xy 1.778 -1.8796) (xy 1.778 1.8796)
			)
			(stroke
				(width 0)
				(type default)
			)
			(fill no)
			(layer "F.Fab")
		)
		(pad "D" smd custom
			(at 0 -0.9525 180)
			(size 0.1905 0.1905)
			(layers "F.Cu" "F.Mask" "F.Paste")
			(net "P3V3_STBY_R5")
			(options
				(clearance outline)
				(anchor circle)
			)
			(primitives
				(gr_poly
					(pts
						(arc
							(start -0.1778 0.5715)
							(mid -0.321484 0.511984)
							(end -0.381 0.3683)
						)
						(arc
							(start -0.381 -0.3683)
							(mid -0.321484 -0.511984)
							(end -0.1778 -0.5715)
						)
						(arc
							(start 0.1778 -0.5715)
							(mid 0.321484 -0.511984)
							(end 0.381 -0.3683)
						)
						(arc
							(start 0.381 0.3683)
							(mid 0.321484 0.511984)
							(end 0.1778 0.5715)
						)
					)
					(width 0)
					(fill yes)
				)
			)
		)
		(pad "G" smd custom
			(at -0.98425 0.9525 180)
			(size 0.1905 0.1905)
			(layers "F.Cu" "F.Mask" "F.Paste")
			(net "BMC_RST_EXPANDER")
			(options
				(clearance outline)
				(anchor circle)
			)
			(primitives
				(gr_poly
					(pts
						(arc
							(start -0.1778 0.5715)
							(mid -0.321484 0.511984)
							(end -0.381 0.3683)
						)
						(arc
							(start -0.381 -0.3683)
							(mid -0.321484 -0.511984)
							(end -0.1778 -0.5715)
						)
						(arc
							(start 0.1778 -0.5715)
							(mid 0.321484 -0.511984)
							(end 0.381 -0.3683)
						)
						(arc
							(start 0.381 0.3683)
							(mid 0.321484 0.511984)
							(end 0.1778 0.5715)
						)
					)
					(width 0)
					(fill yes)
				)
			)
		)
		(pad "S" smd custom
			(at 0.98425 0.9525 180)
			(size 0.1905 0.1905)
			(layers "F.Cu" "F.Mask" "F.Paste")
			(net "GND")
			(options
				(clearance outline)
				(anchor circle)
			)
			(primitives
				(gr_poly
					(pts
						(arc
							(start -0.1778 0.5715)
							(mid -0.321484 0.511984)
							(end -0.381 0.3683)
						)
						(arc
							(start -0.381 -0.3683)
							(mid -0.321484 -0.511984)
							(end -0.1778 -0.5715)
						)
						(arc
							(start 0.1778 -0.5715)
							(mid 0.321484 -0.511984)
							(end 0.381 -0.3683)
						)
						(arc
							(start 0.381 0.3683)
							(mid 0.321484 0.511984)
							(end 0.1778 0.5715)
						)
					)
					(width 0)
					(fill yes)
				)
			)
		)
	)
	(footprint ""
		(layer "F.Cu")
		(at 111.322612 -205.867 180)
		(property "Reference" "SR883"
			(at 0 0 180)
			(layer "F.SilkS")
			(hide yes)
			(effects
				(font
					(size 1.27 1.27)
				)
			)
		)
		(property "Value" "0R2J-2-GP"
			(at 0.064008 -3.993896 180)
			(unlocked yes)
			(layer "F.Fab")
			(hide yes)
			(effects
				(font
					(size 1.016 1.016)
					(thickness 0.1524)
				)
			)
		)
		(property "Device Type" "R402H16"
			(at 0.064008 -5.517896 180)
			(unlocked yes)
			(layer "F.Fab")
			(hide yes)
			(effects
				(font
					(size 1.016 1.016)
					(thickness 0.1524)
				)
			)
		)
		(duplicate_pad_numbers_are_jumpers no)
		(fp_line
			(start 0.508 -0.9398)
			(end -0.508 -0.9398)
			(stroke
				(width 0.1524)
				(type default)
			)
			(layer "F.SilkS")
		)
		(fp_line
			(start -0.508 -0.9398)
			(end -0.508 0.9398)
			(stroke
				(width 0.1524)
				(type default)
			)
			(layer "F.SilkS")
		)
		(fp_rect
			(start -0.508 0.9398)
			(end 0.508 -0.9398)
			(stroke
				(width 0)
				(type default)
			)
			(fill no)
			(layer "F.CrtYd")
		)
		(fp_rect
			(start -0.508 0.9398)
			(end 0.508 -0.9398)
			(stroke
				(width 0)
				(type default)
			)
			(fill no)
			(layer "F.Fab")
		)
		(pad "1" smd custom
			(at 0 -0.4445 180)
			(size 0.1397 0.1397)
			(layers "F.Cu" "F.Mask" "F.Paste")
			(net "SAS_HDD_REDV_TX8_N")
			(options
				(clearance outline)
				(anchor circle)
			)
			(primitives
				(gr_poly
					(pts
						(arc
							(start -0.1778 -0.2794)
							(mid -0.249642 -0.249642)
							(end -0.2794 -0.1778)
						)
						(arc
							(start -0.2794 0.1778)
							(mid -0.249642 0.249642)
							(end -0.1778 0.2794)
						)
						(arc
							(start 0.1778 0.2794)
							(mid 0.249642 0.249642)
							(end 0.2794 0.1778)
						)
						(arc
							(start 0.2794 -0.1778)
							(mid 0.249642 -0.249642)
							(end 0.1778 -0.2794)
						)
					)
					(width 0)
					(fill yes)
				)
			)
		)
		(pad "2" smd custom
			(at 0 0.4445 180)
			(size 0.1397 0.1397)
			(layers "F.Cu" "F.Mask" "F.Paste")
			(net "REDV_TX8_N")
			(options
				(clearance outline)
				(anchor circle)
			)
			(primitives
				(gr_poly
					(pts
						(arc
							(start -0.1778 -0.2794)
							(mid -0.249642 -0.249642)
							(end -0.2794 -0.1778)
						)
						(arc
							(start -0.2794 0.1778)
							(mid -0.249642 0.249642)
							(end -0.1778 0.2794)
						)
						(arc
							(start 0.1778 0.2794)
							(mid 0.249642 0.249642)
							(end 0.2794 0.1778)
						)
						(arc
							(start 0.2794 -0.1778)
							(mid 0.249642 -0.249642)
							(end 0.1778 -0.2794)
						)
					)
					(width 0)
					(fill yes)
				)
			)
		)
	)
	(footprint ""
		(layer "F.Cu")
		(at 270.764 -188.341 -90)
		(property "Reference" "R174"
			(at 0 0 270)
			(layer "F.SilkS")
			(hide yes)
			(effects
				(font
					(size 1.27 1.27)
				)
			)
		)
		(property "Value" "4K7R2F-GP"
			(at 0.064008 -3.993896 270)
			(unlocked yes)
			(layer "F.Fab")
			(hide yes)
			(effects
				(font
					(size 1.016 1.016)
					(thickness 0.1524)
				)
			)
		)
		(property "Device Type" "R402H16"
			(at 0.064008 -5.517896 270)
			(unlocked yes)
			(layer "F.Fab")
			(hide yes)
			(effects
				(font
					(size 1.016 1.016)
					(thickness 0.1524)
				)
			)
		)
		(duplicate_pad_numbers_are_jumpers no)
		(fp_line
			(start -0.508 -0.9398)
			(end -0.508 0.9398)
			(stroke
				(width 0.1524)
				(type default)
			)
			(layer "F.SilkS")
		)
		(fp_line
			(start 0.508 -0.9398)
			(end -0.508 -0.9398)
			(stroke
				(width 0.1524)
				(type default)
			)
			(layer "F.SilkS")
		)
		(fp_rect
			(start -0.508 0.9398)
			(end 0.508 -0.9398)
			(stroke
				(width 0)
				(type default)
			)
			(fill no)
			(layer "F.CrtYd")
		)
		(fp_rect
			(start -0.508 0.9398)
			(end 0.508 -0.9398)
			(stroke
				(width 0)
				(type default)
			)
			(fill no)
			(layer "F.Fab")
		)
		(pad "1" smd custom
			(at 0 -0.4445 270)
			(size 0.1397 0.1397)
			(layers "F.Cu" "F.Mask" "F.Paste")
			(net "P3V3_STBY")
			(options
				(clearance outline)
				(anchor circle)
			)
			(primitives
				(gr_poly
					(pts
						(arc
							(start -0.1778 -0.2794)
							(mid -0.249642 -0.249642)
							(end -0.2794 -0.1778)
						)
						(arc
							(start -0.2794 0.1778)
							(mid -0.249642 0.249642)
							(end -0.1778 0.2794)
						)
						(arc
							(start 0.1778 0.2794)
							(mid 0.249642 0.249642)
							(end 0.2794 0.1778)
						)
						(arc
							(start 0.2794 -0.1778)
							(mid 0.249642 -0.249642)
							(end 0.1778 -0.2794)
						)
					)
					(width 0)
					(fill yes)
				)
			)
		)
		(pad "2" smd custom
			(at 0 0.4445 270)
			(size 0.1397 0.1397)
			(layers "F.Cu" "F.Mask" "F.Paste")
			(net "DP_RST_N")
			(options
				(clearance outline)
				(anchor circle)
			)
			(primitives
				(gr_poly
					(pts
						(arc
							(start -0.1778 -0.2794)
							(mid -0.249642 -0.249642)
							(end -0.2794 -0.1778)
						)
						(arc
							(start -0.2794 0.1778)
							(mid -0.249642 0.249642)
							(end -0.1778 0.2794)
						)
						(arc
							(start 0.1778 0.2794)
							(mid 0.249642 0.249642)
							(end 0.2794 0.1778)
						)
						(arc
							(start 0.2794 -0.1778)
							(mid 0.249642 -0.249642)
							(end 0.1778 -0.2794)
						)
					)
					(width 0)
					(fill yes)
				)
			)
		)
	)
	(footprint ""
		(layer "F.Cu")
		(at 95.89897 -87.376 90)
		(property "Reference" "SR775"
			(at 0 0 90)
			(layer "F.SilkS")
			(hide yes)
			(effects
				(font
					(size 1.27 1.27)
				)
			)
		)
		(property "Value" "4K75R2F-1-GP"
			(at 0.064008 -3.993896 90)
			(unlocked yes)
			(layer "F.Fab")
			(hide yes)
			(effects
				(font
					(size 1.016 1.016)
					(thickness 0.1524)
				)
			)
		)
		(property "Device Type" "R402H16"
			(at 0.064008 -5.517896 90)
			(unlocked yes)
			(layer "F.Fab")
			(hide yes)
			(effects
				(font
					(size 1.016 1.016)
					(thickness 0.1524)
				)
			)
		)
		(duplicate_pad_numbers_are_jumpers no)
		(fp_line
			(start 0.508 -0.9398)
			(end -0.508 -0.9398)
			(stroke
				(width 0.1524)
				(type default)
			)
			(layer "F.SilkS")
		)
		(fp_line
			(start -0.508 -0.9398)
			(end -0.508 0.9398)
			(stroke
				(width 0.1524)
				(type default)
			)
			(layer "F.SilkS")
		)
		(fp_rect
			(start -0.508 0.9398)
			(end 0.508 -0.9398)
			(stroke
				(width 0)
				(type default)
			)
			(fill no)
			(layer "F.CrtYd")
		)
		(fp_rect
			(start -0.508 0.9398)
			(end 0.508 -0.9398)
			(stroke
				(width 0)
				(type default)
			)
			(fill no)
			(layer "F.Fab")
		)
		(pad "1" smd custom
			(at 0 -0.4445 90)
			(size 0.1397 0.1397)
			(layers "F.Cu" "F.Mask" "F.Paste")
			(net "P1V8_E")
			(options
				(clearance outline)
				(anchor circle)
			)
			(primitives
				(gr_poly
					(pts
						(arc
							(start -0.1778 -0.2794)
							(mid -0.249642 -0.249642)
							(end -0.2794 -0.1778)
						)
						(arc
							(start -0.2794 0.1778)
							(mid -0.249642 0.249642)
							(end -0.1778 0.2794)
						)
						(arc
							(start 0.1778 0.2794)
							(mid 0.249642 0.249642)
							(end 0.2794 0.1778)
						)
						(arc
							(start 0.2794 -0.1778)
							(mid 0.249642 -0.249642)
							(end 0.1778 -0.2794)
						)
					)
					(width 0)
					(fill yes)
				)
			)
		)
		(pad "2" smd custom
			(at 0 0.4445 90)
			(size 0.1397 0.1397)
			(layers "F.Cu" "F.Mask" "F.Paste")
			(net "EXP_XM_WE_N")
			(options
				(clearance outline)
				(anchor circle)
			)
			(primitives
				(gr_poly
					(pts
						(arc
							(start -0.1778 -0.2794)
							(mid -0.249642 -0.249642)
							(end -0.2794 -0.1778)
						)
						(arc
							(start -0.2794 0.1778)
							(mid -0.249642 0.249642)
							(end -0.1778 0.2794)
						)
						(arc
							(start 0.1778 0.2794)
							(mid 0.249642 0.249642)
							(end 0.2794 0.1778)
						)
						(arc
							(start 0.2794 -0.1778)
							(mid 0.249642 -0.249642)
							(end 0.1778 -0.2794)
						)
					)
					(width 0)
					(fill yes)
				)
			)
		)
	)
	(footprint ""
		(layer "F.Cu")
		(at 333.701136 -197.366128 180)
		(property "Reference" "R194"
			(at 0 0 180)
			(layer "F.SilkS")
			(hide yes)
			(effects
				(font
					(size 1.27 1.27)
				)
			)
		)
		(property "Value" "8K2R2J-3-GP"
			(at 0.064008 -3.993896 180)
			(unlocked yes)
			(layer "F.Fab")
			(hide yes)
			(effects
				(font
					(size 1.016 1.016)
					(thickness 0.1524)
				)
			)
		)
		(property "Device Type" "R402H16"
			(at 0.064008 -5.517896 180)
			(unlocked yes)
			(layer "F.Fab")
			(hide yes)
			(effects
				(font
					(size 1.016 1.016)
					(thickness 0.1524)
				)
			)
		)
		(duplicate_pad_numbers_are_jumpers no)
		(fp_line
			(start 0.508 -0.9398)
			(end -0.508 -0.9398)
			(stroke
				(width 0.1524)
				(type default)
			)
			(layer "F.SilkS")
		)
		(fp_line
			(start -0.508 -0.9398)
			(end -0.508 0.9398)
			(stroke
				(width 0.1524)
				(type default)
			)
			(layer "F.SilkS")
		)
		(fp_rect
			(start -0.508 0.9398)
			(end 0.508 -0.9398)
			(stroke
				(width 0)
				(type default)
			)
			(fill no)
			(layer "F.CrtYd")
		)
		(fp_rect
			(start -0.508 0.9398)
			(end 0.508 -0.9398)
			(stroke
				(width 0)
				(type default)
			)
			(fill no)
			(layer "F.Fab")
		)
		(pad "1" smd custom
			(at 0 -0.4445 180)
			(size 0.1397 0.1397)
			(layers "F.Cu" "F.Mask" "F.Paste")
			(net "P3V3_STBY")
			(options
				(clearance outline)
				(anchor circle)
			)
			(primitives
				(gr_poly
					(pts
						(arc
							(start -0.1778 -0.2794)
							(mid -0.249642 -0.249642)
							(end -0.2794 -0.1778)
						)
						(arc
							(start -0.2794 0.1778)
							(mid -0.249642 0.249642)
							(end -0.1778 0.2794)
						)
						(arc
							(start 0.1778 0.2794)
							(mid 0.249642 0.249642)
							(end 0.2794 0.1778)
						)
						(arc
							(start 0.2794 -0.1778)
							(mid 0.249642 -0.249642)
							(end 0.1778 -0.2794)
						)
					)
					(width 0)
					(fill yes)
				)
			)
		)
		(pad "2" smd custom
			(at 0 0.4445 180)
			(size 0.1397 0.1397)
			(layers "F.Cu" "F.Mask" "F.Paste")
			(net "EEPROM_A2_R")
			(options
				(clearance outline)
				(anchor circle)
			)
			(primitives
				(gr_poly
					(pts
						(arc
							(start -0.1778 -0.2794)
							(mid -0.249642 -0.249642)
							(end -0.2794 -0.1778)
						)
						(arc
							(start -0.2794 0.1778)
							(mid -0.249642 0.249642)
							(end -0.1778 0.2794)
						)
						(arc
							(start 0.1778 0.2794)
							(mid 0.249642 0.249642)
							(end 0.2794 0.1778)
						)
						(arc
							(start 0.2794 -0.1778)
							(mid 0.249642 -0.249642)
							(end 0.1778 -0.2794)
						)
					)
					(width 0)
					(fill yes)
				)
			)
		)
	)
	(footprint ""
		(layer "F.Cu")
		(at 132.212842 -82.494882 90)
		(property "Reference" "SC1093"
			(at 0 0 90)
			(layer "F.SilkS")
			(hide yes)
			(effects
				(font
					(size 1.27 1.27)
				)
			)
		)
		(property "Value" "SCD01U10V1KX-GP"
			(at -2.8321 -1.7399 90)
			(unlocked yes)
			(layer "F.Fab")
			(hide yes)
			(effects
				(font
					(size 1.016 1.016)
					(thickness 0.1524)
				)
			)
		)
		(property "Device Type" "C0201H13"
			(at -2.8321 -3.2639 90)
			(unlocked yes)
			(layer "F.Fab")
			(hide yes)
			(effects
				(font
					(size 1.016 1.016)
					(thickness 0.1524)
				)
			)
		)
		(duplicate_pad_numbers_are_jumpers no)
		(fp_rect
			(start -0.2794 0.6477)
			(end 0.2794 -0.6477)
			(stroke
				(width 0)
				(type default)
			)
			(fill no)
			(layer "F.CrtYd")
		)
		(fp_rect
			(start -0.2794 0.6477)
			(end 0.2794 -0.6477)
			(stroke
				(width 0)
				(type default)
			)
			(fill no)
			(layer "F.Fab")
		)
		(pad "1" smd custom
			(at 0 -0.2794 90)
			(size 0.0762 0.0762)
			(layers "F.Cu" "F.Mask" "F.Paste")
			(net "SAS_HDD_TX13_N")
			(options
				(clearance outline)
				(anchor circle)
			)
			(primitives
				(gr_poly
					(pts
						(arc
							(start 0.1524 -0.127)
							(mid 0.137521 -0.162921)
							(end 0.1016 -0.1778)
						)
						(arc
							(start -0.1016 -0.1778)
							(mid -0.137521 -0.162921)
							(end -0.1524 -0.127)
						)
						(arc
							(start -0.1524 0.127)
							(mid -0.137521 0.162921)
							(end -0.1016 0.1778)
						)
						(arc
							(start 0.1016 0.1778)
							(mid 0.137521 0.162921)
							(end 0.1524 0.127)
						)
					)
					(width 0)
					(fill yes)
				)
			)
		)
		(pad "2" smd custom
			(at 0 0.2794 90)
			(size 0.0762 0.0762)
			(layers "F.Cu" "F.Mask" "F.Paste")
			(net "3008_SAS_RX_N1")
			(options
				(clearance outline)
				(anchor circle)
			)
			(primitives
				(gr_poly
					(pts
						(arc
							(start 0.1524 -0.127)
							(mid 0.137521 -0.162921)
							(end 0.1016 -0.1778)
						)
						(arc
							(start -0.1016 -0.1778)
							(mid -0.137521 -0.162921)
							(end -0.1524 -0.127)
						)
						(arc
							(start -0.1524 0.127)
							(mid -0.137521 0.162921)
							(end -0.1016 0.1778)
						)
						(arc
							(start 0.1016 0.1778)
							(mid 0.137521 0.162921)
							(end 0.1524 0.127)
						)
					)
					(width 0)
					(fill yes)
				)
			)
		)
	)
	(footprint ""
		(layer "F.Cu")
		(at 252.603 -136.779 180)
		(property "Reference" "SC1311"
			(at 0 0 180)
			(layer "F.SilkS")
			(hide yes)
			(effects
				(font
					(size 1.27 1.27)
				)
			)
		)
		(property "Value" "SCD1U16V2KX-3GP"
			(at 1.1811 -2.7051 180)
			(unlocked yes)
			(layer "F.Fab")
			(hide yes)
			(effects
				(font
					(size 1.016 1.016)
					(thickness 0.1524)
				)
			)
		)
		(property "Device Type" "C402H22"
			(at 1.1811 -4.2291 180)
			(unlocked yes)
			(layer "F.Fab")
			(hide yes)
			(effects
				(font
					(size 1.016 1.016)
					(thickness 0.1524)
				)
			)
		)
		(duplicate_pad_numbers_are_jumpers no)
		(fp_rect
			(start -0.4318 0.9525)
			(end 0.4318 -0.9525)
			(stroke
				(width 0)
				(type default)
			)
			(fill no)
			(layer "F.CrtYd")
		)
		(fp_rect
			(start -0.4318 0.9525)
			(end 0.4318 -0.9525)
			(stroke
				(width 0)
				(type default)
			)
			(fill no)
			(layer "F.Fab")
		)
		(pad "1" smd custom
			(at 0 -0.4445 180)
			(size 0.1524 0.1524)
			(layers "F.Cu" "F.Mask" "F.Paste")
			(net "P3V3_STBY")
			(options
				(clearance outline)
				(anchor circle)
			)
			(primitives
				(gr_poly
					(pts
						(arc
							(start 0.3048 -0.2032)
							(mid 0.275042 -0.275042)
							(end 0.2032 -0.3048)
						)
						(arc
							(start -0.2032 -0.3048)
							(mid -0.275042 -0.275042)
							(end -0.3048 -0.2032)
						)
						(arc
							(start -0.3048 0.2032)
							(mid -0.275042 0.275042)
							(end -0.2032 0.3048)
						)
						(arc
							(start 0.2032 0.3048)
							(mid 0.275042 0.275042)
							(end 0.3048 0.2032)
						)
					)
					(width 0)
					(fill yes)
				)
			)
		)
		(pad "2" smd custom
			(at 0 0.4445 180)
			(size 0.1524 0.1524)
			(layers "F.Cu" "F.Mask" "F.Paste")
			(net "GND")
			(options
				(clearance outline)
				(anchor circle)
			)
			(primitives
				(gr_poly
					(pts
						(arc
							(start 0.3048 -0.2032)
							(mid 0.275042 -0.275042)
							(end 0.2032 -0.3048)
						)
						(arc
							(start -0.2032 -0.3048)
							(mid -0.275042 -0.275042)
							(end -0.3048 -0.2032)
						)
						(arc
							(start -0.3048 0.2032)
							(mid -0.275042 0.275042)
							(end -0.2032 0.3048)
						)
						(arc
							(start 0.2032 0.3048)
							(mid 0.275042 0.275042)
							(end 0.3048 0.2032)
						)
					)
					(width 0)
					(fill yes)
				)
			)
		)
	)
	(footprint ""
		(layer "F.Cu")
		(at 114.84991 -94.84995 90)
		(property "Reference" "SU1"
			(at 0 0 90)
			(layer "F.SilkS")
			(hide yes)
			(effects
				(font
					(size 1.27 1.27)
				)
			)
		)
		(property "Value" "SAS3X24RLC1-DB-500021106-GP"
			(at -21.4503 -7.4168 90)
			(unlocked yes)
			(layer "F.Fab")
			(hide yes)
			(effects
				(font
					(size 1.016 1.016)
					(thickness 0.1524)
				)
			)
		)
		(property "Device Type" "BGA672C27H83"
			(at -21.4503 -8.9408 90)
			(unlocked yes)
			(layer "F.Fab")
			(hide yes)
			(effects
				(font
					(size 1.016 1.016)
					(thickness 0.1524)
				)
			)
		)
		(duplicate_pad_numbers_are_jumpers no)
		(fp_line
			(start 11.469878 -13.5001)
			(end 13.0302 -13.5001)
			(stroke
				(width 0.1524)
				(type default)
			)
			(layer "F.SilkS")
		)
		(fp_line
			(start -10.530078 -13.5001)
			(end 10.530078 -13.5001)
			(stroke
				(width 0.1524)
				(type default)
			)
			(layer "F.SilkS")
		)
		(fp_line
			(start -13.0302 -13.5001)
			(end -11.469878 -13.5001)
			(stroke
				(width 0.1524)
				(type default)
			)
			(layer "F.SilkS")
		)
		(fp_line
			(start 13.5001 -11.469878)
			(end 13.5001 -13.0302)
			(stroke
				(width 0.1524)
				(type default)
			)
			(layer "F.SilkS")
		)
		(fp_line
			(start -13.5001 -11.469878)
			(end -13.5001 -13.0302)
			(stroke
				(width 0.1524)
				(type default)
			)
			(layer "F.SilkS")
		)
		(fp_line
			(start 13.5001 -10.530078)
			(end 13.5001 10.530078)
			(stroke
				(width 0.1524)
				(type default)
			)
			(layer "F.SilkS")
		)
		(fp_line
			(start -13.5001 10.530078)
			(end -13.5001 -10.530078)
			(stroke
				(width 0.1524)
				(type default)
			)
			(layer "F.SilkS")
		)
		(fp_line
			(start 13.5001 11.469878)
			(end 13.5001 13.0302)
			(stroke
				(width 0.1524)
				(type default)
			)
			(layer "F.SilkS")
		)
		(fp_line
			(start -13.5001 11.469878)
			(end -13.5001 13.0302)
			(stroke
				(width 0.1524)
				(type default)
			)
			(layer "F.SilkS")
		)
		(fp_line
			(start 13.0302 13.5001)
			(end 11.469878 13.5001)
			(stroke
				(width 0.1524)
				(type default)
			)
			(layer "F.SilkS")
		)
		(fp_line
			(start 10.530078 13.5001)
			(end -10.530078 13.5001)
			(stroke
				(width 0.1524)
				(type default)
			)
			(layer "F.SilkS")
		)
		(fp_line
			(start -11.469878 13.5001)
			(end -13.0302 13.5001)
			(stroke
				(width 0.1524)
				(type default)
			)
			(layer "F.SilkS")
		)
		(fp_circle
			(center 13.5001 -13.5001)
			(end 13.5001 -13.0302)
			(stroke
				(width 0.1524)
				(type default)
			)
			(fill no)
			(layer "F.SilkS")
		)
		(fp_circle
			(center 10.999978 -13.5001)
			(end 10.999978 -13.0302)
			(stroke
				(width 0.1524)
				(type default)
			)
			(fill no)
			(layer "F.SilkS")
		)
		(fp_circle
			(center -10.999978 -13.5001)
			(end -10.999978 -13.0302)
			(stroke
				(width 0.1524)
				(type default)
			)
			(fill no)
			(layer "F.SilkS")
		)
		(fp_circle
			(center -13.5001 -13.5001)
			(end -13.5001 -13.0302)
			(stroke
				(width 0.1524)
				(type default)
			)
			(fill no)
			(layer "F.SilkS")
		)
		(fp_circle
			(center 13.5001 -10.999978)
			(end 13.5001 -10.530078)
			(stroke
				(width 0.1524)
				(type default)
			)
			(fill no)
			(layer "F.SilkS")
		)
		(fp_circle
			(center -13.5001 -10.999978)
			(end -13.5001 -10.530078)
			(stroke
				(width 0.1524)
				(type default)
			)
			(fill no)
			(layer "F.SilkS")
		)
		(fp_circle
			(center 13.5001 10.999978)
			(end 13.5001 11.469878)
			(stroke
				(width 0.1524)
				(type default)
			)
			(fill no)
			(layer "F.SilkS")
		)
		(fp_circle
			(center -13.5001 10.999978)
			(end -13.5001 11.469878)
			(stroke
				(width 0.1524)
				(type default)
			)
			(fill no)
			(layer "F.SilkS")
		)
		(fp_circle
			(center 13.5001 13.5001)
			(end 13.5001 13.97)
			(stroke
				(width 0.1524)
				(type default)
			)
			(fill no)
			(layer "F.SilkS")
		)
		(fp_circle
			(center 10.999978 13.5001)
			(end 10.999978 13.97)
			(stroke
				(width 0.1524)
				(type default)
			)
			(fill no)
			(layer "F.SilkS")
		)
		(fp_circle
			(center -10.999978 13.5001)
			(end -10.999978 13.97)
			(stroke
				(width 0.1524)
				(type default)
			)
			(fill no)
			(layer "F.SilkS")
		)
		(fp_circle
			(center -13.5001 13.5001)
			(end -13.5001 13.97)
			(stroke
				(width 0.1524)
				(type default)
			)
			(fill no)
			(layer "F.SilkS")
		)
		(fp_poly
			(pts
				(xy -15.870682 -13.885418) (xy -13.872718 -15.883382) (xy -13.872718 -13.885418)
			)
			(stroke
				(width 0)
				(type default)
			)
			(fill yes)
			(layer "F.SilkS")
		)
		(fp_poly
			(pts
				(xy -13.1064 13.1064)
				(arc
					(start -13.1064 11.256772)
					(mid -13.030054 10.999978)
					(end -13.1064 10.743184)
				)
				(arc
					(start -13.1064 -10.743184)
					(mid -13.030054 -10.999978)
					(end -13.1064 -11.256772)
				)
				(xy -13.1064 -13.1064)
				(arc
					(start -11.256772 -13.1064)
					(mid -10.999978 -13.030054)
					(end -10.743184 -13.1064)
				)
				(arc
					(start 10.743184 -13.1064)
					(mid 10.999978 -13.030054)
					(end 11.256772 -13.1064)
				)
				(xy 13.1064 -13.1064)
				(arc
					(start 13.1064 -11.256772)
					(mid 13.030054 -10.999978)
					(end 13.1064 -10.743184)
				)
				(arc
					(start 13.1064 10.743184)
					(mid 13.030054 10.999978)
					(end 13.1064 11.256772)
				)
				(xy 13.1064 13.1064)
				(arc
					(start 11.256772 13.1064)
					(mid 10.999978 13.030054)
					(end 10.743184 13.1064)
				)
				(arc
					(start -10.743184 13.1064)
					(mid -10.999978 13.030054)
					(end -11.256772 13.1064)
				)
			)
			(stroke
				(width 0)
				(type default)
			)
			(fill yes)
			(layer "F.SilkS")
		)
		(fp_rect
			(start -13.5001 13.5001)
			(end 13.5001 -13.5001)
			(stroke
				(width 0)
				(type default)
			)
			(fill no)
			(layer "F.CrtYd")
		)
		(fp_poly
			(pts
				(xy -14.5034 14.5034) (xy -14.5034 -14.5034) (xy -0.00254 -14.5034) (xy -0.00254 -13.5001) (xy -13.5001 -13.5001)
				(xy -13.5001 13.5001) (xy 13.5001 13.5001) (xy 13.5001 -13.5001) (xy 0.00254 -13.5001) (xy 0.00254 -14.5034)
				(xy 14.5034 -14.5034) (xy 14.5034 14.5034)
			)
			(stroke
				(width 0)
				(type default)
			)
			(fill no)
			(layer "F.CrtYd")
		)
		(fp_rect
			(start -15.500096 15.500096)
			(end 15.500096 -15.500096)
			(stroke
				(width 0)
				(type default)
			)
			(fill no)
			(layer "F.Fab")
		)
		(pad "A2" smd circle
			(at -11.500104 -12.500102 90)
			(size 0.508 0.508)
			(layers "F.Cu" "F.Mask" "F.Paste")
			(net "RESET_N")
		)
		(pad "A3" smd circle
			(at -10.500106 -12.500102 90)
			(size 0.508 0.508)
			(layers "F.Cu" "F.Mask" "F.Paste")
			(net "Net_1126")
		)
		(pad "A4" smd circle
			(at -9.500108 -12.500102 90)
			(size 0.4572 0.4572)
			(layers "F.Cu" "F.Mask" "F.Paste")
			(net "EXP_XM_OE_N")
		)
		(pad "A5" smd circle
			(at -8.50011 -12.500102 90)
			(size 0.4572 0.4572)
			(layers "F.Cu" "F.Mask" "F.Paste")
			(net "XM_DATA8")
		)
		(pad "A6" smd circle
			(at -7.500112 -12.500102 90)
			(size 0.4572 0.4572)
			(layers "F.Cu" "F.Mask" "F.Paste")
			(net "XM_DATA6")
		)
		(pad "A7" smd circle
			(at -6.500114 -12.500102 90)
			(size 0.4572 0.4572)
			(layers "F.Cu" "F.Mask" "F.Paste")
			(net "XM_DATA14")
		)
		(pad "A8" smd circle
			(at -5.500116 -12.500102 90)
			(size 0.4572 0.4572)
			(layers "F.Cu" "F.Mask" "F.Paste")
			(net "XM_DATA1")
		)
		(pad "A9" smd circle
			(at -4.500118 -12.500102 90)
			(size 0.4572 0.4572)
			(layers "F.Cu" "F.Mask" "F.Paste")
			(net "EXP_XM_BUSY_N")
		)
		(pad "A10" smd circle
			(at -3.50012 -12.500102 90)
			(size 0.4572 0.4572)
			(layers "F.Cu" "F.Mask" "F.Paste")
			(net "EXP_XM_ADDR_7")
		)
		(pad "A11" smd circle
			(at -2.500122 -12.500102 90)
			(size 0.4572 0.4572)
			(layers "F.Cu" "F.Mask" "F.Paste")
			(net "EXP_XM_ADDR_3")
		)
		(pad "A12" smd circle
			(at -1.500124 -12.500102 90)
			(size 0.4572 0.4572)
			(layers "F.Cu" "F.Mask" "F.Paste")
			(net "EXP_XM_ADDR_20")
		)
		(pad "A13" smd circle
			(at -0.500126 -12.500102 90)
			(size 0.4572 0.4572)
			(layers "F.Cu" "F.Mask" "F.Paste")
			(net "EXP_XM_ADDR_21")
		)
		(pad "A14" smd circle
			(at 0.500126 -12.500102 90)
			(size 0.4572 0.4572)
			(layers "F.Cu" "F.Mask" "F.Paste")
			(net "EXP_XM_ADDR_14")
		)
		(pad "A15" smd circle
			(at 1.500124 -12.500102 90)
			(size 0.4572 0.4572)
			(layers "F.Cu" "F.Mask" "F.Paste")
			(net "EXP_XM_ADDR_12")
		)
		(pad "A16" smd circle
			(at 2.500122 -12.500102 90)
			(size 0.4572 0.4572)
			(layers "F.Cu" "F.Mask" "F.Paste")
			(net "EXP_PWM_OUT1")
		)
		(pad "A17" smd circle
			(at 3.50012 -12.500102 90)
			(size 0.4572 0.4572)
			(layers "F.Cu" "F.Mask" "F.Paste")
			(net "EXP_FW_DET_BOARD_VER_2")
		)
		(pad "A18" smd circle
			(at 4.500118 -12.500102 90)
			(size 0.4572 0.4572)
			(layers "F.Cu" "F.Mask" "F.Paste")
			(net "EXP_FW_DET_BOARD_VER_0")
		)
		(pad "A19" smd circle
			(at 5.500116 -12.500102 90)
			(size 0.4572 0.4572)
			(layers "F.Cu" "F.Mask" "F.Paste")
			(net "EXP_GPIO_11")
		)
		(pad "A20" smd circle
			(at 6.500114 -12.500102 90)
			(size 0.4572 0.4572)
			(layers "F.Cu" "F.Mask" "F.Paste")
			(net "EXP_GPIO_6")
		)
		(pad "A21" smd circle
			(at 7.500112 -12.500102 90)
			(size 0.4572 0.4572)
			(layers "F.Cu" "F.Mask" "F.Paste")
			(net "EXP_GPIO_0")
		)
		(pad "A22" smd circle
			(at 8.50011 -12.500102 90)
			(size 0.4572 0.4572)
			(layers "F.Cu" "F.Mask" "F.Paste")
			(net "SDB_R_TX")
		)
		(pad "A23" smd circle
			(at 9.500108 -12.500102 90)
			(size 0.4572 0.4572)
			(layers "F.Cu" "F.Mask" "F.Paste")
			(net "UART_RTS")
		)
		(pad "A24" smd circle
			(at 10.500106 -12.500102 90)
			(size 0.508 0.508)
			(layers "F.Cu" "F.Mask" "F.Paste")
			(net "SIO_D_OUT")
		)
		(pad "A25" smd circle
			(at 11.500104 -12.500102 90)
			(size 0.508 0.508)
			(layers "F.Cu" "F.Mask" "F.Paste")
			(net "EXP_I2C_SCL_4")
		)
		(pad "AA1" smd circle
			(at -12.500102 7.500112 90)
			(size 0.4572 0.4572)
			(layers "F.Cu" "F.Mask" "F.Paste")
			(net "GND")
		)
		(pad "AA2" smd circle
			(at -11.500104 7.500112 90)
			(size 0.4572 0.4572)
			(layers "F.Cu" "F.Mask" "F.Paste")
			(net "SAS3008_RAID_TX_N1")
		)
		(pad "AA3" smd circle
			(at -10.500106 7.500112 90)
			(size 0.4572 0.4572)
			(layers "F.Cu" "F.Mask" "F.Paste")
			(net "SAS3008_RAID_TX_N2")
		)
		(pad "AA4" smd circle
			(at -9.500108 7.500112 90)
			(size 0.4572 0.4572)
			(layers "F.Cu" "F.Mask" "F.Paste")
			(net "SAS3008_RAID_TX_N3")
		)
		(pad "AA5" smd circle
			(at -8.50011 7.500112 90)
			(size 0.4572 0.4572)
			(layers "F.Cu" "F.Mask" "F.Paste")
			(net "SAS_EXP2CONN_RX_N_20")
		)
		(pad "AA6" smd circle
			(at -7.500112 7.500112 90)
			(size 0.4572 0.4572)
			(layers "F.Cu" "F.Mask" "F.Paste")
			(net "SAS_EXP2CONN_RX_N_21")
		)
		(pad "AA7" smd circle
			(at -6.500114 7.500112 90)
			(size 0.4572 0.4572)
			(layers "F.Cu" "F.Mask" "F.Paste")
			(net "SAS_EXP2CONN_RX_N_22")
		)
		(pad "AA8" smd circle
			(at -5.500116 7.500112 90)
			(size 0.4572 0.4572)
			(layers "F.Cu" "F.Mask" "F.Paste")
			(net "SAS_EXP2CONN_RX_N_23")
		)
		(pad "AA9" smd circle
			(at -4.500118 7.500112 90)
			(size 0.4572 0.4572)
			(layers "F.Cu" "F.Mask" "F.Paste")
			(net "SAS_GF_EXP_RX_DN0")
		)
		(pad "AA10" smd circle
			(at -3.50012 7.500112 90)
			(size 0.4572 0.4572)
			(layers "F.Cu" "F.Mask" "F.Paste")
			(net "SAS_GF_EXP_RX_DN1")
		)
		(pad "AA11" smd circle
			(at -2.500122 7.500112 90)
			(size 0.4572 0.4572)
			(layers "F.Cu" "F.Mask" "F.Paste")
			(net "SAS_GF_EXP_RX_DN2")
		)
		(pad "AA12" smd circle
			(at -1.500124 7.500112 90)
			(size 0.4572 0.4572)
			(layers "F.Cu" "F.Mask" "F.Paste")
			(net "SAS_GF_EXP_RX_DN3")
		)
		(pad "AA13" smd circle
			(at -0.500126 7.500112 90)
			(size 0.4572 0.4572)
			(layers "F.Cu" "F.Mask" "F.Paste")
			(net "Net_1125")
		)
		(pad "AA14" smd circle
			(at 0.500126 7.500112 90)
			(size 0.4572 0.4572)
			(layers "F.Cu" "F.Mask" "F.Paste")
			(net "Net_1124")
		)
		(pad "AA15" smd circle
			(at 1.500124 7.500112 90)
			(size 0.4572 0.4572)
			(layers "F.Cu" "F.Mask" "F.Paste")
			(net "Net_1123")
		)
		(pad "AA16" smd circle
			(at 2.500122 7.500112 90)
			(size 0.4572 0.4572)
			(layers "F.Cu" "F.Mask" "F.Paste")
			(net "Net_1122")
		)
		(pad "AA17" smd circle
			(at 3.50012 7.500112 90)
			(size 0.4572 0.4572)
			(layers "F.Cu" "F.Mask" "F.Paste")
			(net "Net_1121")
		)
		(pad "AA18" smd circle
			(at 4.500118 7.500112 90)
			(size 0.4572 0.4572)
			(layers "F.Cu" "F.Mask" "F.Paste")
			(net "Net_1104")
		)
		(pad "AA19" smd circle
			(at 5.500116 7.500112 90)
			(size 0.4572 0.4572)
			(layers "F.Cu" "F.Mask" "F.Paste")
			(net "Net_1103")
		)
		(pad "AA20" smd circle
			(at 6.500114 7.500112 90)
			(size 0.4572 0.4572)
			(layers "F.Cu" "F.Mask" "F.Paste")
			(net "Net_1102")
		)
		(pad "AA21" smd circle
			(at 7.500112 7.500112 90)
			(size 0.4572 0.4572)
			(layers "F.Cu" "F.Mask" "F.Paste")
			(net "GB_VDDA")
		)
		(pad "AA22" smd circle
			(at 8.50011 7.500112 90)
			(size 0.4572 0.4572)
			(layers "F.Cu" "F.Mask" "F.Paste")
			(net "GND")
		)
		(pad "AA23" smd circle
			(at 9.500108 7.500112 90)
			(size 0.4572 0.4572)
			(layers "F.Cu" "F.Mask" "F.Paste")
			(net "GB_VDDA")
		)
		(pad "AA24" smd circle
			(at 10.500106 7.500112 90)
			(size 0.4572 0.4572)
			(layers "F.Cu" "F.Mask" "F.Paste")
			(net "Net_1101")
		)
		(pad "AA25" smd circle
			(at 11.500104 7.500112 90)
			(size 0.4572 0.4572)
			(layers "F.Cu" "F.Mask" "F.Paste")
			(net "Net_1100")
		)
		(pad "AA26" smd circle
			(at 12.500102 7.500112 90)
			(size 0.4572 0.4572)
			(layers "F.Cu" "F.Mask" "F.Paste")
			(net "GND")
		)
		(pad "AB1" smd circle
			(at -12.500102 8.50011 90)
			(size 0.4572 0.4572)
			(layers "F.Cu" "F.Mask" "F.Paste")
			(net "SAS3008_RAID_TX_N0")
		)
		(pad "AB2" smd circle
			(at -11.500104 8.50011 90)
			(size 0.4572 0.4572)
			(layers "F.Cu" "F.Mask" "F.Paste")
			(net "SAS3008_RAID_TX_P1")
		)
		(pad "AB3" smd circle
			(at -10.500106 8.50011 90)
			(size 0.4572 0.4572)
			(layers "F.Cu" "F.Mask" "F.Paste")
			(net "SAS3008_RAID_TX_P2")
		)
		(pad "AB4" smd circle
			(at -9.500108 8.50011 90)
			(size 0.4572 0.4572)
			(layers "F.Cu" "F.Mask" "F.Paste")
			(net "SAS3008_RAID_TX_P3")
		)
		(pad "AB5" smd circle
			(at -8.50011 8.50011 90)
			(size 0.4572 0.4572)
			(layers "F.Cu" "F.Mask" "F.Paste")
			(net "SAS_EXP2CONN_RX_P_20")
		)
		(pad "AB6" smd circle
			(at -7.500112 8.50011 90)
			(size 0.4572 0.4572)
			(layers "F.Cu" "F.Mask" "F.Paste")
			(net "SAS_EXP2CONN_RX_P_21")
		)
		(pad "AB7" smd circle
			(at -6.500114 8.50011 90)
			(size 0.4572 0.4572)
			(layers "F.Cu" "F.Mask" "F.Paste")
			(net "SAS_EXP2CONN_RX_P_22")
		)
		(pad "AB8" smd circle
			(at -5.500116 8.50011 90)
			(size 0.4572 0.4572)
			(layers "F.Cu" "F.Mask" "F.Paste")
			(net "SAS_EXP2CONN_RX_P_23")
		)
		(pad "AB9" smd circle
			(at -4.500118 8.50011 90)
			(size 0.4572 0.4572)
			(layers "F.Cu" "F.Mask" "F.Paste")
			(net "SAS_GF_EXP_RX_DP0")
		)
		(pad "AB10" smd circle
			(at -3.50012 8.50011 90)
			(size 0.4572 0.4572)
			(layers "F.Cu" "F.Mask" "F.Paste")
			(net "SAS_GF_EXP_RX_DP1")
		)
		(pad "AB11" smd circle
			(at -2.500122 8.50011 90)
			(size 0.4572 0.4572)
			(layers "F.Cu" "F.Mask" "F.Paste")
			(net "SAS_GF_EXP_RX_DP2")
		)
		(pad "AB12" smd circle
			(at -1.500124 8.50011 90)
			(size 0.4572 0.4572)
			(layers "F.Cu" "F.Mask" "F.Paste")
			(net "SAS_GF_EXP_RX_DP3")
		)
		(pad "AB13" smd circle
			(at -0.500126 8.50011 90)
			(size 0.4572 0.4572)
			(layers "F.Cu" "F.Mask" "F.Paste")
			(net "Net_1120")
		)
		(pad "AB14" smd circle
			(at 0.500126 8.50011 90)
			(size 0.4572 0.4572)
			(layers "F.Cu" "F.Mask" "F.Paste")
			(net "Net_1119")
		)
		(pad "AB15" smd circle
			(at 1.500124 8.50011 90)
			(size 0.4572 0.4572)
			(layers "F.Cu" "F.Mask" "F.Paste")
			(net "Net_1118")
		)
		(pad "AB16" smd circle
			(at 2.500122 8.50011 90)
			(size 0.4572 0.4572)
			(layers "F.Cu" "F.Mask" "F.Paste")
			(net "Net_1117")
		)
		(pad "AB17" smd circle
			(at 3.50012 8.50011 90)
			(size 0.4572 0.4572)
			(layers "F.Cu" "F.Mask" "F.Paste")
			(net "Net_1116")
		)
		(pad "AB18" smd circle
			(at 4.500118 8.50011 90)
			(size 0.4572 0.4572)
			(layers "F.Cu" "F.Mask" "F.Paste")
			(net "Net_1099")
		)
		(pad "AB19" smd circle
			(at 5.500116 8.50011 90)
			(size 0.4572 0.4572)
			(layers "F.Cu" "F.Mask" "F.Paste")
			(net "Net_1098")
		)
		(pad "AB20" smd circle
			(at 6.500114 8.50011 90)
			(size 0.4572 0.4572)
			(layers "F.Cu" "F.Mask" "F.Paste")
			(net "Net_1097")
		)
		(pad "AB21" smd circle
			(at 7.500112 8.50011 90)
			(size 0.4572 0.4572)
			(layers "F.Cu" "F.Mask" "F.Paste")
			(net "GND")
		)
		(pad "AB22" smd circle
			(at 8.50011 8.50011 90)
			(size 0.4572 0.4572)
			(layers "F.Cu" "F.Mask" "F.Paste")
			(net "Net_1096")
		)
		(pad "AB23" smd circle
			(at 9.500108 8.50011 90)
			(size 0.4572 0.4572)
			(layers "F.Cu" "F.Mask" "F.Paste")
			(net "Net_1095")
		)
		(pad "AB24" smd circle
			(at 10.500106 8.50011 90)
			(size 0.4572 0.4572)
			(layers "F.Cu" "F.Mask" "F.Paste")
			(net "GND")
		)
		(pad "AB25" smd circle
			(at 11.500104 8.50011 90)
			(size 0.4572 0.4572)
			(layers "F.Cu" "F.Mask" "F.Paste")
			(net "GB_VDDA")
		)
		(pad "AB26" smd circle
			(at 12.500102 8.50011 90)
			(size 0.4572 0.4572)
			(layers "F.Cu" "F.Mask" "F.Paste")
			(net "GND")
		)
		(pad "AC1" smd circle
			(at -12.500102 9.500108 90)
			(size 0.4572 0.4572)
			(layers "F.Cu" "F.Mask" "F.Paste")
			(net "SAS3008_RAID_TX_P0")
		)
		(pad "AC2" smd circle
			(at -11.500104 9.500108 90)
			(size 0.4572 0.4572)
			(layers "F.Cu" "F.Mask" "F.Paste")
			(net "GND")
		)
		(pad "AC3" smd circle
			(at -10.500106 9.500108 90)
			(size 0.4572 0.4572)
			(layers "F.Cu" "F.Mask" "F.Paste")
			(net "GB_VDDA")
		)
		(pad "AC4" smd circle
			(at -9.500108 9.500108 90)
			(size 0.4572 0.4572)
			(layers "F.Cu" "F.Mask" "F.Paste")
			(net "GND")
		)
		(pad "AC5" smd circle
			(at -8.50011 9.500108 90)
			(size 0.4572 0.4572)
			(layers "F.Cu" "F.Mask" "F.Paste")
			(net "GB_VDDA")
		)
		(pad "AC6" smd circle
			(at -7.500112 9.500108 90)
			(size 0.4572 0.4572)
			(layers "F.Cu" "F.Mask" "F.Paste")
			(net "GND")
		)
		(pad "AC7" smd circle
			(at -6.500114 9.500108 90)
			(size 0.4572 0.4572)
			(layers "F.Cu" "F.Mask" "F.Paste")
			(net "GB_VDDA")
		)
		(pad "AC8" smd circle
			(at -5.500116 9.500108 90)
			(size 0.4572 0.4572)
			(layers "F.Cu" "F.Mask" "F.Paste")
			(net "GND")
		)
		(pad "AC9" smd circle
			(at -4.500118 9.500108 90)
			(size 0.4572 0.4572)
			(layers "F.Cu" "F.Mask" "F.Paste")
			(net "GB_VDDA")
		)
		(pad "AC10" smd circle
			(at -3.50012 9.500108 90)
			(size 0.4572 0.4572)
			(layers "F.Cu" "F.Mask" "F.Paste")
			(net "GND")
		)
		(pad "AC11" smd circle
			(at -2.500122 9.500108 90)
			(size 0.4572 0.4572)
			(layers "F.Cu" "F.Mask" "F.Paste")
			(net "GB_VDDA")
		)
		(pad "AC12" smd circle
			(at -1.500124 9.500108 90)
			(size 0.4572 0.4572)
			(layers "F.Cu" "F.Mask" "F.Paste")
			(net "GND")
		)
		(pad "AC13" smd circle
			(at -0.500126 9.500108 90)
			(size 0.4572 0.4572)
			(layers "F.Cu" "F.Mask" "F.Paste")
			(net "GB_VDDA")
		)
		(pad "AC14" smd circle
			(at 0.500126 9.500108 90)
			(size 0.4572 0.4572)
			(layers "F.Cu" "F.Mask" "F.Paste")
			(net "GND")
		)
		(pad "AC15" smd circle
			(at 1.500124 9.500108 90)
			(size 0.4572 0.4572)
			(layers "F.Cu" "F.Mask" "F.Paste")
			(net "GB_VDDA")
		)
		(pad "AC16" smd circle
			(at 2.500122 9.500108 90)
			(size 0.4572 0.4572)
			(layers "F.Cu" "F.Mask" "F.Paste")
			(net "GND")
		)
		(pad "AC17" smd circle
			(at 3.50012 9.500108 90)
			(size 0.4572 0.4572)
			(layers "F.Cu" "F.Mask" "F.Paste")
			(net "GB_VDDA")
		)
		(pad "AC18" smd circle
			(at 4.500118 9.500108 90)
			(size 0.4572 0.4572)
			(layers "F.Cu" "F.Mask" "F.Paste")
			(net "GND")
		)
		(pad "AC19" smd circle
			(at 5.500116 9.500108 90)
			(size 0.4572 0.4572)
			(layers "F.Cu" "F.Mask" "F.Paste")
			(net "GB_VDDA")
		)
		(pad "AC20" smd circle
			(at 6.500114 9.500108 90)
			(size 0.4572 0.4572)
			(layers "F.Cu" "F.Mask" "F.Paste")
			(net "GND")
		)
		(pad "AC21" smd circle
			(at 7.500112 9.500108 90)
			(size 0.4572 0.4572)
			(layers "F.Cu" "F.Mask" "F.Paste")
			(net "GB_VDDA")
		)
		(pad "AC22" smd circle
			(at 8.50011 9.500108 90)
			(size 0.4572 0.4572)
			(layers "F.Cu" "F.Mask" "F.Paste")
			(net "GND")
		)
		(pad "AC23" smd circle
			(at 9.500108 9.500108 90)
			(size 0.4572 0.4572)
			(layers "F.Cu" "F.Mask" "F.Paste")
			(net "GB_VDDA")
		)
		(pad "AC24" smd circle
			(at 10.500106 9.500108 90)
			(size 0.4572 0.4572)
			(layers "F.Cu" "F.Mask" "F.Paste")
			(net "GND")
		)
		(pad "AC25" smd circle
			(at 11.500104 9.500108 90)
			(size 0.4572 0.4572)
			(layers "F.Cu" "F.Mask" "F.Paste")
			(net "GND")
		)
		(pad "AC26" smd circle
			(at 12.500102 9.500108 90)
			(size 0.4572 0.4572)
			(layers "F.Cu" "F.Mask" "F.Paste")
			(net "GND")
		)
		(pad "AD1" smd circle
			(at -12.500102 10.500106 90)
			(size 0.508 0.508)
			(layers "F.Cu" "F.Mask" "F.Paste")
			(net "GND")
		)
		(pad "AD2" smd circle
			(at -11.500104 10.500106 90)
			(size 0.508 0.508)
			(layers "F.Cu" "F.Mask" "F.Paste")
			(net "GB_VDDA")
		)
		(pad "AD3" smd circle
			(at -10.500106 10.500106 90)
			(size 0.508 0.508)
			(layers "F.Cu" "F.Mask" "F.Paste")
			(net "SAS_HDD_TX13_N")
		)
		(pad "AD4" smd circle
			(at -9.500108 10.500106 90)
			(size 0.4572 0.4572)
			(layers "F.Cu" "F.Mask" "F.Paste")
			(net "GB_VDDA")
		)
		(pad "AD5" smd circle
			(at -8.50011 10.500106 90)
			(size 0.4572 0.4572)
			(layers "F.Cu" "F.Mask" "F.Paste")
			(net "SAS_HDD_TX15_N")
		)
		(pad "AD6" smd circle
			(at -7.500112 10.500106 90)
			(size 0.4572 0.4572)
			(layers "F.Cu" "F.Mask" "F.Paste")
			(net "GB_VDDA")
		)
		(pad "AD7" smd circle
			(at -6.500114 10.500106 90)
			(size 0.4572 0.4572)
			(layers "F.Cu" "F.Mask" "F.Paste")
			(net "3X24_SAS_TX17_N")
		)
		(pad "AD8" smd circle
			(at -5.500116 10.500106 90)
			(size 0.4572 0.4572)
			(layers "F.Cu" "F.Mask" "F.Paste")
			(net "GB_VDDA")
		)
		(pad "AD9" smd circle
			(at -4.500118 10.500106 90)
			(size 0.4572 0.4572)
			(layers "F.Cu" "F.Mask" "F.Paste")
			(net "3X24_SAS_TX19_N")
		)
		(pad "AD10" smd circle
			(at -3.50012 10.500106 90)
			(size 0.4572 0.4572)
			(layers "F.Cu" "F.Mask" "F.Paste")
			(net "GB_VDDA")
		)
		(pad "AD11" smd circle
			(at -2.500122 10.500106 90)
			(size 0.4572 0.4572)
			(layers "F.Cu" "F.Mask" "F.Paste")
			(net "3X24_SAS_TX21_N")
		)
		(pad "AD12" smd circle
			(at -1.500124 10.500106 90)
			(size 0.4572 0.4572)
			(layers "F.Cu" "F.Mask" "F.Paste")
			(net "GB_VDDA")
		)
		(pad "AD13" smd circle
			(at -0.500126 10.500106 90)
			(size 0.4572 0.4572)
			(layers "F.Cu" "F.Mask" "F.Paste")
			(net "3X24_SAS_TX23_N")
		)
		(pad "AD14" smd circle
			(at 0.500126 10.500106 90)
			(size 0.4572 0.4572)
			(layers "F.Cu" "F.Mask" "F.Paste")
			(net "GB_VDDA")
		)
		(pad "AD15" smd circle
			(at 1.500124 10.500106 90)
			(size 0.4572 0.4572)
			(layers "F.Cu" "F.Mask" "F.Paste")
			(net "Net_1115")
		)
		(pad "AD16" smd circle
			(at 2.500122 10.500106 90)
			(size 0.4572 0.4572)
			(layers "F.Cu" "F.Mask" "F.Paste")
			(net "GB_VDDA")
		)
		(pad "AD17" smd circle
			(at 3.50012 10.500106 90)
			(size 0.4572 0.4572)
			(layers "F.Cu" "F.Mask" "F.Paste")
			(net "Net_1114")
		)
		(pad "AD18" smd circle
			(at 4.500118 10.500106 90)
			(size 0.4572 0.4572)
			(layers "F.Cu" "F.Mask" "F.Paste")
			(net "GB_VDDA")
		)
		(pad "AD19" smd circle
			(at 5.500116 10.500106 90)
			(size 0.4572 0.4572)
			(layers "F.Cu" "F.Mask" "F.Paste")
			(net "Net_1094")
		)
		(pad "AD20" smd circle
			(at 6.500114 10.500106 90)
			(size 0.4572 0.4572)
			(layers "F.Cu" "F.Mask" "F.Paste")
			(net "GB_VDDA")
		)
		(pad "AD21" smd circle
			(at 7.500112 10.500106 90)
			(size 0.4572 0.4572)
			(layers "F.Cu" "F.Mask" "F.Paste")
			(net "Net_1093")
		)
		(pad "AD22" smd circle
			(at 8.50011 10.500106 90)
			(size 0.4572 0.4572)
			(layers "F.Cu" "F.Mask" "F.Paste")
			(net "GND")
		)
		(pad "AD23" smd circle
			(at 9.500108 10.500106 90)
			(size 0.4572 0.4572)
			(layers "F.Cu" "F.Mask" "F.Paste")
			(net "GND")
		)
		(pad "AD24" smd circle
			(at 10.500106 10.500106 90)
			(size 0.508 0.508)
			(layers "F.Cu" "F.Mask" "F.Paste")
			(net "GND")
		)
		(pad "AD25" smd circle
			(at 11.500104 10.500106 90)
			(size 0.508 0.508)
			(layers "F.Cu" "F.Mask" "F.Paste")
			(net "GND")
		)
		(pad "AD26" smd circle
			(at 12.500102 10.500106 90)
			(size 0.508 0.508)
			(layers "F.Cu" "F.Mask" "F.Paste")
			(net "GND")
		)
		(pad "AE1" smd circle
			(at -12.500102 11.500104 90)
			(size 0.508 0.508)
			(layers "F.Cu" "F.Mask" "F.Paste")
			(net "GND")
		)
		(pad "AE2" smd circle
			(at -11.500104 11.500104 90)
			(size 0.508 0.508)
			(layers "F.Cu" "F.Mask" "F.Paste")
			(net "SAS_HDD_TX12_N")
		)
		(pad "AE3" smd circle
			(at -10.500106 11.500104 90)
			(size 0.508 0.508)
			(layers "F.Cu" "F.Mask" "F.Paste")
			(net "SAS_HDD_TX13_P")
		)
		(pad "AE4" smd circle
			(at -9.500108 11.500104 90)
			(size 0.4572 0.4572)
			(layers "F.Cu" "F.Mask" "F.Paste")
			(net "SAS_HDD_TX14_N")
		)
		(pad "AE5" smd circle
			(at -8.50011 11.500104 90)
			(size 0.4572 0.4572)
			(layers "F.Cu" "F.Mask" "F.Paste")
			(net "SAS_HDD_TX15_P")
		)
		(pad "AE6" smd circle
			(at -7.500112 11.500104 90)
			(size 0.4572 0.4572)
			(layers "F.Cu" "F.Mask" "F.Paste")
			(net "3X24_SAS_TX16_N")
		)
		(pad "AE7" smd circle
			(at -6.500114 11.500104 90)
			(size 0.4572 0.4572)
			(layers "F.Cu" "F.Mask" "F.Paste")
			(net "3X24_SAS_TX17_P")
		)
		(pad "AE8" smd circle
			(at -5.500116 11.500104 90)
			(size 0.4572 0.4572)
			(layers "F.Cu" "F.Mask" "F.Paste")
			(net "3X24_SAS_TX18_N")
		)
		(pad "AE9" smd circle
			(at -4.500118 11.500104 90)
			(size 0.4572 0.4572)
			(layers "F.Cu" "F.Mask" "F.Paste")
			(net "3X24_SAS_TX19_P")
		)
		(pad "AE10" smd circle
			(at -3.50012 11.500104 90)
			(size 0.4572 0.4572)
			(layers "F.Cu" "F.Mask" "F.Paste")
			(net "3X24_SAS_TX20_N")
		)
		(pad "AE11" smd circle
			(at -2.500122 11.500104 90)
			(size 0.4572 0.4572)
			(layers "F.Cu" "F.Mask" "F.Paste")
			(net "3X24_SAS_TX21_P")
		)
		(pad "AE12" smd circle
			(at -1.500124 11.500104 90)
			(size 0.4572 0.4572)
			(layers "F.Cu" "F.Mask" "F.Paste")
			(net "3X24_SAS_TX22_N")
		)
		(pad "AE13" smd circle
			(at -0.500126 11.500104 90)
			(size 0.4572 0.4572)
			(layers "F.Cu" "F.Mask" "F.Paste")
			(net "3X24_SAS_TX23_P")
		)
		(pad "AE14" smd circle
			(at 0.500126 11.500104 90)
			(size 0.4572 0.4572)
			(layers "F.Cu" "F.Mask" "F.Paste")
			(net "Net_1113")
		)
		(pad "AE15" smd circle
			(at 1.500124 11.500104 90)
			(size 0.4572 0.4572)
			(layers "F.Cu" "F.Mask" "F.Paste")
			(net "Net_1112")
		)
		(pad "AE16" smd circle
			(at 2.500122 11.500104 90)
			(size 0.4572 0.4572)
			(layers "F.Cu" "F.Mask" "F.Paste")
			(net "Net_1111")
		)
		(pad "AE17" smd circle
			(at 3.50012 11.500104 90)
			(size 0.4572 0.4572)
			(layers "F.Cu" "F.Mask" "F.Paste")
			(net "Net_1110")
		)
		(pad "AE18" smd circle
			(at 4.500118 11.500104 90)
			(size 0.4572 0.4572)
			(layers "F.Cu" "F.Mask" "F.Paste")
			(net "Net_1092")
		)
		(pad "AE19" smd circle
			(at 5.500116 11.500104 90)
			(size 0.4572 0.4572)
			(layers "F.Cu" "F.Mask" "F.Paste")
			(net "Net_1091")
		)
		(pad "AE20" smd circle
			(at 6.500114 11.500104 90)
			(size 0.4572 0.4572)
			(layers "F.Cu" "F.Mask" "F.Paste")
			(net "Net_1090")
		)
		(pad "AE21" smd circle
			(at 7.500112 11.500104 90)
			(size 0.4572 0.4572)
			(layers "F.Cu" "F.Mask" "F.Paste")
			(net "Net_1089")
		)
		(pad "AE22" smd circle
			(at 8.50011 11.500104 90)
			(size 0.4572 0.4572)
			(layers "F.Cu" "F.Mask" "F.Paste")
			(net "GND")
		)
		(pad "AE23" smd circle
			(at 9.500108 11.500104 90)
			(size 0.4572 0.4572)
			(layers "F.Cu" "F.Mask" "F.Paste")
			(net "GND")
		)
		(pad "AE24" smd circle
			(at 10.500106 11.500104 90)
			(size 0.508 0.508)
			(layers "F.Cu" "F.Mask" "F.Paste")
			(net "GND")
		)
		(pad "AE25" smd circle
			(at 11.500104 11.500104 90)
			(size 0.508 0.508)
			(layers "F.Cu" "F.Mask" "F.Paste")
			(net "GND")
		)
		(pad "AE26" smd circle
			(at 12.500102 11.500104 90)
			(size 0.508 0.508)
			(layers "F.Cu" "F.Mask" "F.Paste")
			(net "GND")
		)
		(pad "AF2" smd circle
			(at -11.500104 12.500102 90)
			(size 0.508 0.508)
			(layers "F.Cu" "F.Mask" "F.Paste")
			(net "SAS_HDD_TX12_P")
		)
		(pad "AF3" smd circle
			(at -10.500106 12.500102 90)
			(size 0.508 0.508)
			(layers "F.Cu" "F.Mask" "F.Paste")
			(net "GND")
		)
		(pad "AF4" smd circle
			(at -9.500108 12.500102 90)
			(size 0.4572 0.4572)
			(layers "F.Cu" "F.Mask" "F.Paste")
			(net "SAS_HDD_TX14_P")
		)
		(pad "AF5" smd circle
			(at -8.50011 12.500102 90)
			(size 0.4572 0.4572)
			(layers "F.Cu" "F.Mask" "F.Paste")
			(net "GND")
		)
		(pad "AF6" smd circle
			(at -7.500112 12.500102 90)
			(size 0.4572 0.4572)
			(layers "F.Cu" "F.Mask" "F.Paste")
			(net "3X24_SAS_TX16_P")
		)
		(pad "AF7" smd circle
			(at -6.500114 12.500102 90)
			(size 0.4572 0.4572)
			(layers "F.Cu" "F.Mask" "F.Paste")
			(net "GND")
		)
		(pad "AF8" smd circle
			(at -5.500116 12.500102 90)
			(size 0.4572 0.4572)
			(layers "F.Cu" "F.Mask" "F.Paste")
			(net "3X24_SAS_TX18_P")
		)
		(pad "AF9" smd circle
			(at -4.500118 12.500102 90)
			(size 0.4572 0.4572)
			(layers "F.Cu" "F.Mask" "F.Paste")
			(net "GND")
		)
		(pad "AF10" smd circle
			(at -3.50012 12.500102 90)
			(size 0.4572 0.4572)
			(layers "F.Cu" "F.Mask" "F.Paste")
			(net "3X24_SAS_TX20_P")
		)
		(pad "AF11" smd circle
			(at -2.500122 12.500102 90)
			(size 0.4572 0.4572)
			(layers "F.Cu" "F.Mask" "F.Paste")
			(net "GND")
		)
		(pad "AF12" smd circle
			(at -1.500124 12.500102 90)
			(size 0.4572 0.4572)
			(layers "F.Cu" "F.Mask" "F.Paste")
			(net "3X24_SAS_TX22_P")
		)
		(pad "AF13" smd circle
			(at -0.500126 12.500102 90)
			(size 0.4572 0.4572)
			(layers "F.Cu" "F.Mask" "F.Paste")
			(net "GND")
		)
		(pad "AF14" smd circle
			(at 0.500126 12.500102 90)
			(size 0.4572 0.4572)
			(layers "F.Cu" "F.Mask" "F.Paste")
			(net "Net_1109")
		)
		(pad "AF15" smd circle
			(at 1.500124 12.500102 90)
			(size 0.4572 0.4572)
			(layers "F.Cu" "F.Mask" "F.Paste")
			(net "GND")
		)
		(pad "AF16" smd circle
			(at 2.500122 12.500102 90)
			(size 0.4572 0.4572)
			(layers "F.Cu" "F.Mask" "F.Paste")
			(net "Net_1108")
		)
		(pad "AF17" smd circle
			(at 3.50012 12.500102 90)
			(size 0.4572 0.4572)
			(layers "F.Cu" "F.Mask" "F.Paste")
			(net "GND")
		)
		(pad "AF18" smd circle
			(at 4.500118 12.500102 90)
			(size 0.4572 0.4572)
			(layers "F.Cu" "F.Mask" "F.Paste")
			(net "Net_1088")
		)
		(pad "AF19" smd circle
			(at 5.500116 12.500102 90)
			(size 0.4572 0.4572)
			(layers "F.Cu" "F.Mask" "F.Paste")
			(net "GND")
		)
		(pad "AF20" smd circle
			(at 6.500114 12.500102 90)
			(size 0.4572 0.4572)
			(layers "F.Cu" "F.Mask" "F.Paste")
			(net "Net_1087")
		)
		(pad "AF21" smd circle
			(at 7.500112 12.500102 90)
			(size 0.4572 0.4572)
			(layers "F.Cu" "F.Mask" "F.Paste")
			(net "GND")
		)
		(pad "AF22" smd circle
			(at 8.50011 12.500102 90)
			(size 0.4572 0.4572)
			(layers "F.Cu" "F.Mask" "F.Paste")
			(net "GND")
		)
		(pad "AF23" smd circle
			(at 9.500108 12.500102 90)
			(size 0.4572 0.4572)
			(layers "F.Cu" "F.Mask" "F.Paste")
			(net "EXP_RTRIM_A")
		)
		(pad "AF24" smd circle
			(at 10.500106 12.500102 90)
			(size 0.508 0.508)
			(layers "F.Cu" "F.Mask" "F.Paste")
			(net "EXP_RTRIM_A_N")
		)
		(pad "AF25" smd circle
			(at 11.500104 12.500102 90)
			(size 0.508 0.508)
			(layers "F.Cu" "F.Mask" "F.Paste")
			(net "GND")
		)
		(pad "B1" smd circle
			(at -12.500102 -11.500104 90)
			(size 0.508 0.508)
			(layers "F.Cu" "F.Mask" "F.Paste")
			(net "LSI_PROCMON")
		)
		(pad "B2" smd circle
			(at -11.500104 -11.500104 90)
			(size 0.508 0.508)
			(layers "F.Cu" "F.Mask" "F.Paste")
			(net "EXP_IDDT")
		)
		(pad "B3" smd circle
			(at -10.500106 -11.500104 90)
			(size 0.508 0.508)
			(layers "F.Cu" "F.Mask" "F.Paste")
			(net "GND")
		)
		(pad "B4" smd circle
			(at -9.500108 -11.500104 90)
			(size 0.4572 0.4572)
			(layers "F.Cu" "F.Mask" "F.Paste")
			(net "P1V8_E")
		)
		(pad "B5" smd circle
			(at -8.50011 -11.500104 90)
			(size 0.4572 0.4572)
			(layers "F.Cu" "F.Mask" "F.Paste")
			(net "EXP_XM_CS_N_0")
		)
		(pad "B6" smd circle
			(at -7.500112 -11.500104 90)
			(size 0.4572 0.4572)
			(layers "F.Cu" "F.Mask" "F.Paste")
			(net "XM_DATA5")
		)
		(pad "B7" smd circle
			(at -6.500114 -11.500104 90)
			(size 0.4572 0.4572)
			(layers "F.Cu" "F.Mask" "F.Paste")
			(net "XM_DATA3")
		)
		(pad "B8" smd circle
			(at -5.500116 -11.500104 90)
			(size 0.4572 0.4572)
			(layers "F.Cu" "F.Mask" "F.Paste")
			(net "XM_DATA15")
		)
		(pad "B9" smd circle
			(at -4.500118 -11.500104 90)
			(size 0.4572 0.4572)
			(layers "F.Cu" "F.Mask" "F.Paste")
			(net "XM_DATA10")
		)
		(pad "B10" smd circle
			(at -3.50012 -11.500104 90)
			(size 0.4572 0.4572)
			(layers "F.Cu" "F.Mask" "F.Paste")
			(net "EXP_XM_ADDR_9")
		)
		(pad "B11" smd circle
			(at -2.500122 -11.500104 90)
			(size 0.4572 0.4572)
			(layers "F.Cu" "F.Mask" "F.Paste")
			(net "EXP_XM_ADDR_25")
		)
		(pad "B12" smd circle
			(at -1.500124 -11.500104 90)
			(size 0.4572 0.4572)
			(layers "F.Cu" "F.Mask" "F.Paste")
			(net "EXP_XM_ADDR_22")
		)
		(pad "B13" smd circle
			(at -0.500126 -11.500104 90)
			(size 0.4572 0.4572)
			(layers "F.Cu" "F.Mask" "F.Paste")
			(net "EXP_XM_ADDR_19")
		)
		(pad "B14" smd circle
			(at 0.500126 -11.500104 90)
			(size 0.4572 0.4572)
			(layers "F.Cu" "F.Mask" "F.Paste")
			(net "EXP_XM_ADDR_13")
		)
		(pad "B15" smd circle
			(at 1.500124 -11.500104 90)
			(size 0.4572 0.4572)
			(layers "F.Cu" "F.Mask" "F.Paste")
			(net "EXP_XM_ADDR_1")
		)
		(pad "B16" smd circle
			(at 2.500122 -11.500104 90)
			(size 0.4572 0.4572)
			(layers "F.Cu" "F.Mask" "F.Paste")
			(net "EXP_TACH_IN1")
		)
		(pad "B17" smd circle
			(at 3.50012 -11.500104 90)
			(size 0.4572 0.4572)
			(layers "F.Cu" "F.Mask" "F.Paste")
			(net "EXP_TACH_IN0")
		)
		(pad "B18" smd circle
			(at 4.500118 -11.500104 90)
			(size 0.4572 0.4572)
			(layers "F.Cu" "F.Mask" "F.Paste")
			(net "EXP_GPIO_7")
		)
		(pad "B19" smd circle
			(at 5.500116 -11.500104 90)
			(size 0.4572 0.4572)
			(layers "F.Cu" "F.Mask" "F.Paste")
			(net "EXP_GPIO_5")
		)
		(pad "B20" smd circle
			(at 6.500114 -11.500104 90)
			(size 0.4572 0.4572)
			(layers "F.Cu" "F.Mask" "F.Paste")
			(net "EXP_GPIO_2")
		)
		(pad "B21" smd circle
			(at 7.500112 -11.500104 90)
			(size 0.4572 0.4572)
			(layers "F.Cu" "F.Mask" "F.Paste")
			(net "ICE_TMS")
		)
		(pad "B22" smd circle
			(at 8.50011 -11.500104 90)
			(size 0.4572 0.4572)
			(layers "F.Cu" "F.Mask" "F.Paste")
			(net "SMART_TX")
		)
		(pad "B23" smd circle
			(at 9.500108 -11.500104 90)
			(size 0.4572 0.4572)
			(layers "F.Cu" "F.Mask" "F.Paste")
			(net "SMART_RX")
		)
		(pad "B24" smd circle
			(at 10.500106 -11.500104 90)
			(size 0.508 0.508)
			(layers "F.Cu" "F.Mask" "F.Paste")
			(net "EXP_SIO_CLK_OUT")
		)
		(pad "B25" smd circle
			(at 11.500104 -11.500104 90)
			(size 0.508 0.508)
			(layers "F.Cu" "F.Mask" "F.Paste")
			(net "EXP_I2C_SCL_3")
		)
		(pad "B26" smd circle
			(at 12.500102 -11.500104 90)
			(size 0.508 0.508)
			(layers "F.Cu" "F.Mask" "F.Paste")
			(net "EXP_I2C_SDA_2")
		)
		(pad "C1" smd circle
			(at -12.500102 -10.500106 90)
			(size 0.508 0.508)
			(layers "F.Cu" "F.Mask" "F.Paste")
			(net "JTAG_EXP_TMS")
		)
		(pad "C2" smd circle
			(at -11.500104 -10.500106 90)
			(size 0.508 0.508)
			(layers "F.Cu" "F.Mask" "F.Paste")
			(net "JTAG_EXP_TDI")
		)
		(pad "C3" smd circle
			(at -10.500106 -10.500106 90)
			(size 0.508 0.508)
			(layers "F.Cu" "F.Mask" "F.Paste")
			(net "SOFT_RESET_N")
		)
		(pad "C4" smd circle
			(at -9.500108 -10.500106 90)
			(size 0.4572 0.4572)
			(layers "F.Cu" "F.Mask" "F.Paste")
			(net "EXP_XM_WE_N")
		)
		(pad "C5" smd circle
			(at -8.50011 -10.500106 90)
			(size 0.4572 0.4572)
			(layers "F.Cu" "F.Mask" "F.Paste")
			(net "Net_1128")
		)
		(pad "C6" smd circle
			(at -7.500112 -10.500106 90)
			(size 0.4572 0.4572)
			(layers "F.Cu" "F.Mask" "F.Paste")
			(net "GND")
		)
		(pad "C7" smd circle
			(at -6.500114 -10.500106 90)
			(size 0.4572 0.4572)
			(layers "F.Cu" "F.Mask" "F.Paste")
			(net "XM_DATA7")
		)
		(pad "C8" smd circle
			(at -5.500116 -10.500106 90)
			(size 0.4572 0.4572)
			(layers "F.Cu" "F.Mask" "F.Paste")
			(net "GND")
		)
		(pad "C9" smd circle
			(at -4.500118 -10.500106 90)
			(size 0.4572 0.4572)
			(layers "F.Cu" "F.Mask" "F.Paste")
			(net "XM_DATA11")
		)
		(pad "C10" smd circle
			(at -3.50012 -10.500106 90)
			(size 0.4572 0.4572)
			(layers "F.Cu" "F.Mask" "F.Paste")
			(net "GND")
		)
		(pad "C11" smd circle
			(at -2.500122 -10.500106 90)
			(size 0.4572 0.4572)
			(layers "F.Cu" "F.Mask" "F.Paste")
			(net "EXP_XM_ADDR_4")
		)
		(pad "C12" smd circle
			(at -1.500124 -10.500106 90)
			(size 0.4572 0.4572)
			(layers "F.Cu" "F.Mask" "F.Paste")
			(net "GND")
		)
		(pad "C13" smd circle
			(at -0.500126 -10.500106 90)
			(size 0.4572 0.4572)
			(layers "F.Cu" "F.Mask" "F.Paste")
			(net "EXP_XM_ADDR_18")
		)
		(pad "C14" smd circle
			(at 0.500126 -10.500106 90)
			(size 0.4572 0.4572)
			(layers "F.Cu" "F.Mask" "F.Paste")
			(net "GND")
		)
		(pad "C15" smd circle
			(at 1.500124 -10.500106 90)
			(size 0.4572 0.4572)
			(layers "F.Cu" "F.Mask" "F.Paste")
			(net "EXP_XM_ADDR_0")
		)
		(pad "C16" smd circle
			(at 2.500122 -10.500106 90)
			(size 0.4572 0.4572)
			(layers "F.Cu" "F.Mask" "F.Paste")
			(net "GND")
		)
		(pad "C17" smd circle
			(at 3.50012 -10.500106 90)
			(size 0.4572 0.4572)
			(layers "F.Cu" "F.Mask" "F.Paste")
			(net "EXP_GPIO_13")
		)
		(pad "C18" smd circle
			(at 4.500118 -10.500106 90)
			(size 0.4572 0.4572)
			(layers "F.Cu" "F.Mask" "F.Paste")
			(net "GND")
		)
		(pad "C19" smd circle
			(at 5.500116 -10.500106 90)
			(size 0.4572 0.4572)
			(layers "F.Cu" "F.Mask" "F.Paste")
			(net "EXP_GPIO_1")
		)
		(pad "C20" smd circle
			(at 6.500114 -10.500106 90)
			(size 0.4572 0.4572)
			(layers "F.Cu" "F.Mask" "F.Paste")
			(net "GND")
		)
		(pad "C21" smd circle
			(at 7.500112 -10.500106 90)
			(size 0.4572 0.4572)
			(layers "F.Cu" "F.Mask" "F.Paste")
			(net "ICE_TRST_N")
		)
		(pad "C22" smd circle
			(at 8.50011 -10.500106 90)
			(size 0.4572 0.4572)
			(layers "F.Cu" "F.Mask" "F.Paste")
			(net "GND")
		)
		(pad "C23" smd circle
			(at 9.500108 -10.500106 90)
			(size 0.4572 0.4572)
			(layers "F.Cu" "F.Mask" "F.Paste")
			(net "EXP_I2C_SDA_3")
		)
		(pad "C24" smd circle
			(at 10.500106 -10.500106 90)
			(size 0.508 0.508)
			(layers "F.Cu" "F.Mask" "F.Paste")
			(net "GND")
		)
		(pad "C25" smd circle
			(at 11.500104 -10.500106 90)
			(size 0.508 0.508)
			(layers "F.Cu" "F.Mask" "F.Paste")
			(net "EXP_SDA_0")
		)
		(pad "C26" smd circle
			(at 12.500102 -10.500106 90)
			(size 0.508 0.508)
			(layers "F.Cu" "F.Mask" "F.Paste")
			(net "GND")
		)
		(pad "D1" smd circle
			(at -12.500102 -9.500108 90)
			(size 0.4572 0.4572)
			(layers "F.Cu" "F.Mask" "F.Paste")
			(net "EXP_BLINK_OUT")
		)
		(pad "D2" smd circle
			(at -11.500104 -9.500108 90)
			(size 0.4572 0.4572)
			(layers "F.Cu" "F.Mask" "F.Paste")
			(net "LSI_TRST_N")
		)
		(pad "D3" smd circle
			(at -10.500106 -9.500108 90)
			(size 0.4572 0.4572)
			(layers "F.Cu" "F.Mask" "F.Paste")
			(net "GND")
		)
		(pad "D4" smd circle
			(at -9.500108 -9.500108 90)
			(size 0.4572 0.4572)
			(layers "F.Cu" "F.Mask" "F.Paste")
			(net "P1V8_E")
		)
		(pad "D5" smd circle
			(at -8.50011 -9.500108 90)
			(size 0.4572 0.4572)
			(layers "F.Cu" "F.Mask" "F.Paste")
			(net "EXP_RESET_N")
		)
		(pad "D6" smd circle
			(at -7.500112 -9.500108 90)
			(size 0.4572 0.4572)
			(layers "F.Cu" "F.Mask" "F.Paste")
			(net "P1V8_E")
		)
		(pad "D7" smd circle
			(at -6.500114 -9.500108 90)
			(size 0.4572 0.4572)
			(layers "F.Cu" "F.Mask" "F.Paste")
			(net "Net_1127")
		)
		(pad "D8" smd circle
			(at -5.500116 -9.500108 90)
			(size 0.4572 0.4572)
			(layers "F.Cu" "F.Mask" "F.Paste")
			(net "P1V8_E")
		)
		(pad "D9" smd circle
			(at -4.500118 -9.500108 90)
			(size 0.4572 0.4572)
			(layers "F.Cu" "F.Mask" "F.Paste")
			(net "XM_DATA2")
		)
		(pad "D10" smd circle
			(at -3.50012 -9.500108 90)
			(size 0.4572 0.4572)
			(layers "F.Cu" "F.Mask" "F.Paste")
			(net "P1V8_E")
		)
		(pad "D11" smd circle
			(at -2.500122 -9.500108 90)
			(size 0.4572 0.4572)
			(layers "F.Cu" "F.Mask" "F.Paste")
			(net "EXP_XM_ADDR_5")
		)
		(pad "D12" smd circle
			(at -1.500124 -9.500108 90)
			(size 0.4572 0.4572)
			(layers "F.Cu" "F.Mask" "F.Paste")
			(net "P1V8_E")
		)
		(pad "D13" smd circle
			(at -0.500126 -9.500108 90)
			(size 0.4572 0.4572)
			(layers "F.Cu" "F.Mask" "F.Paste")
			(net "EXP_XM_ADDR_16")
		)
		(pad "D14" smd circle
			(at 0.500126 -9.500108 90)
			(size 0.4572 0.4572)
			(layers "F.Cu" "F.Mask" "F.Paste")
			(net "P1V8_E")
		)
		(pad "D15" smd circle
			(at 1.500124 -9.500108 90)
			(size 0.4572 0.4572)
			(layers "F.Cu" "F.Mask" "F.Paste")
			(net "EXP_PWM_OUT0")
		)
		(pad "D16" smd circle
			(at 2.500122 -9.500108 90)
			(size 0.4572 0.4572)
			(layers "F.Cu" "F.Mask" "F.Paste")
			(net "P1V8_E")
		)
		(pad "D17" smd circle
			(at 3.50012 -9.500108 90)
			(size 0.4572 0.4572)
			(layers "F.Cu" "F.Mask" "F.Paste")
			(net "EXP_GPIO_8")
		)
		(pad "D18" smd circle
			(at 4.500118 -9.500108 90)
			(size 0.4572 0.4572)
			(layers "F.Cu" "F.Mask" "F.Paste")
			(net "P1V8_E")
		)
		(pad "D19" smd circle
			(at 5.500116 -9.500108 90)
			(size 0.4572 0.4572)
			(layers "F.Cu" "F.Mask" "F.Paste")
			(net "PHY_CLK")
		)
		(pad "D20" smd circle
			(at 6.500114 -9.500108 90)
			(size 0.4572 0.4572)
			(layers "F.Cu" "F.Mask" "F.Paste")
			(net "P1V8_E")
		)
		(pad "D21" smd circle
			(at 7.500112 -9.500108 90)
			(size 0.4572 0.4572)
			(layers "F.Cu" "F.Mask" "F.Paste")
			(net "UART_CTS")
		)
		(pad "D22" smd circle
			(at 8.50011 -9.500108 90)
			(size 0.4572 0.4572)
			(layers "F.Cu" "F.Mask" "F.Paste")
			(net "P1V8_E")
		)
		(pad "D23" smd circle
			(at 9.500108 -9.500108 90)
			(size 0.4572 0.4572)
			(layers "F.Cu" "F.Mask" "F.Paste")
			(net "EXP_I2C_SDA_1")
		)
		(pad "D24" smd circle
			(at 10.500106 -9.500108 90)
			(size 0.4572 0.4572)
			(layers "F.Cu" "F.Mask" "F.Paste")
			(net "P1V8_E")
		)
		(pad "D25" smd circle
			(at 11.500104 -9.500108 90)
			(size 0.4572 0.4572)
			(layers "F.Cu" "F.Mask" "F.Paste")
			(net "EXP_I2C_SCL_1")
		)
		(pad "D26" smd circle
			(at 12.500102 -9.500108 90)
			(size 0.4572 0.4572)
			(layers "F.Cu" "F.Mask" "F.Paste")
			(net "P1V8_E")
		)
		(pad "E1" smd circle
			(at -12.500102 -8.50011 90)
			(size 0.4572 0.4572)
			(layers "F.Cu" "F.Mask" "F.Paste")
			(net "SAS_HDD_LED1")
		)
		(pad "E2" smd circle
			(at -11.500104 -8.50011 90)
			(size 0.4572 0.4572)
			(layers "F.Cu" "F.Mask" "F.Paste")
			(net "SAS_HDD_LED0")
		)
		(pad "E3" smd circle
			(at -10.500106 -8.50011 90)
			(size 0.4572 0.4572)
			(layers "F.Cu" "F.Mask" "F.Paste")
			(net "EXP_BLINK_IN")
		)
		(pad "E4" smd circle
			(at -9.500108 -8.50011 90)
			(size 0.4572 0.4572)
			(layers "F.Cu" "F.Mask" "F.Paste")
			(net "JTAG_EXP_TDO_R")
		)
		(pad "E5" smd circle
			(at -8.50011 -8.50011 90)
			(size 0.4572 0.4572)
			(layers "F.Cu" "F.Mask" "F.Paste")
			(net "EXP_CPU_MODE_1")
		)
		(pad "E6" smd circle
			(at -7.500112 -8.50011 90)
			(size 0.4572 0.4572)
			(layers "F.Cu" "F.Mask" "F.Paste")
			(net "EXP_CLK_SEL1")
		)
		(pad "E7" smd circle
			(at -6.500114 -8.50011 90)
			(size 0.4572 0.4572)
			(layers "F.Cu" "F.Mask" "F.Paste")
			(net "Net_1131")
		)
		(pad "E8" smd circle
			(at -5.500116 -8.50011 90)
			(size 0.4572 0.4572)
			(layers "F.Cu" "F.Mask" "F.Paste")
			(net "Net_1130")
		)
		(pad "E9" smd circle
			(at -4.500118 -8.50011 90)
			(size 0.4572 0.4572)
			(layers "F.Cu" "F.Mask" "F.Paste")
			(net "P1V8_E")
		)
		(pad "E10" smd circle
			(at -3.50012 -8.50011 90)
			(size 0.4572 0.4572)
			(layers "F.Cu" "F.Mask" "F.Paste")
			(net "XM_DATA12")
		)
		(pad "E11" smd circle
			(at -2.500122 -8.50011 90)
			(size 0.4572 0.4572)
			(layers "F.Cu" "F.Mask" "F.Paste")
			(net "EXP_XM_ADDR_8")
		)
		(pad "E12" smd circle
			(at -1.500124 -8.50011 90)
			(size 0.4572 0.4572)
			(layers "F.Cu" "F.Mask" "F.Paste")
			(net "EXP_XM_ADDR_23")
		)
		(pad "E13" smd circle
			(at -0.500126 -8.50011 90)
			(size 0.4572 0.4572)
			(layers "F.Cu" "F.Mask" "F.Paste")
			(net "EXP_XM_ADDR_17")
		)
		(pad "E14" smd circle
			(at 0.500126 -8.50011 90)
			(size 0.4572 0.4572)
			(layers "F.Cu" "F.Mask" "F.Paste")
			(net "EXP_XM_ADDR_11")
		)
		(pad "E15" smd circle
			(at 1.500124 -8.50011 90)
			(size 0.4572 0.4572)
			(layers "F.Cu" "F.Mask" "F.Paste")
			(net "EXP_TACH_IN2")
		)
		(pad "E16" smd circle
			(at 2.500122 -8.50011 90)
			(size 0.4572 0.4572)
			(layers "F.Cu" "F.Mask" "F.Paste")
			(net "EXP_GPIO_10")
		)
		(pad "E17" smd circle
			(at 3.50012 -8.50011 90)
			(size 0.4572 0.4572)
			(layers "F.Cu" "F.Mask" "F.Paste")
			(net "EXP_GPIO_3")
		)
		(pad "E18" smd circle
			(at 4.500118 -8.50011 90)
			(size 0.4572 0.4572)
			(layers "F.Cu" "F.Mask" "F.Paste")
			(net "SDB_R_RX")
		)
		(pad "E19" smd circle
			(at 5.500116 -8.50011 90)
			(size 0.4572 0.4572)
			(layers "F.Cu" "F.Mask" "F.Paste")
			(net "ICE_TDO")
		)
		(pad "E20" smd circle
			(at 6.500114 -8.50011 90)
			(size 0.4572 0.4572)
			(layers "F.Cu" "F.Mask" "F.Paste")
			(net "SIO_LOAD_IN")
		)
		(pad "E21" smd circle
			(at 7.500112 -8.50011 90)
			(size 0.4572 0.4572)
			(layers "F.Cu" "F.Mask" "F.Paste")
			(net "GND")
		)
		(pad "E22" smd circle
			(at 8.50011 -8.50011 90)
			(size 0.4572 0.4572)
			(layers "F.Cu" "F.Mask" "F.Paste")
			(net "GND")
		)
		(pad "E23" smd circle
			(at 9.500108 -8.50011 90)
			(size 0.4572 0.4572)
			(layers "F.Cu" "F.Mask" "F.Paste")
			(net "EXP_SCL_0")
		)
		(pad "E24" smd circle
			(at 10.500106 -8.50011 90)
			(size 0.4572 0.4572)
			(layers "F.Cu" "F.Mask" "F.Paste")
			(net "GND")
		)
		(pad "E25" smd circle
			(at 11.500104 -8.50011 90)
			(size 0.4572 0.4572)
			(layers "F.Cu" "F.Mask" "F.Paste")
			(net "GND")
		)
		(pad "E26" smd circle
			(at 12.500102 -8.50011 90)
			(size 0.4572 0.4572)
			(layers "F.Cu" "F.Mask" "F.Paste")
			(net "GND")
		)
		(pad "F1" smd circle
			(at -12.500102 -7.500112 90)
			(size 0.4572 0.4572)
			(layers "F.Cu" "F.Mask" "F.Paste")
			(net "SAS_HDD_LED4")
		)
		(pad "F2" smd circle
			(at -11.500104 -7.500112 90)
			(size 0.4572 0.4572)
			(layers "F.Cu" "F.Mask" "F.Paste")
			(net "SAS_HDD_LED2")
		)
		(pad "F3" smd circle
			(at -10.500106 -7.500112 90)
			(size 0.4572 0.4572)
			(layers "F.Cu" "F.Mask" "F.Paste")
			(net "GND")
		)
		(pad "F4" smd circle
			(at -9.500108 -7.500112 90)
			(size 0.4572 0.4572)
			(layers "F.Cu" "F.Mask" "F.Paste")
			(net "P1V8_E")
		)
		(pad "F5" smd circle
			(at -8.50011 -7.500112 90)
			(size 0.4572 0.4572)
			(layers "F.Cu" "F.Mask" "F.Paste")
			(net "JTAG_EXP_TCK")
		)
		(pad "F6" smd circle
			(at -7.500112 -7.500112 90)
			(size 0.4572 0.4572)
			(layers "F.Cu" "F.Mask" "F.Paste")
			(net "TMUX_EN")
		)
		(pad "F7" smd circle
			(at -6.500114 -7.500112 90)
			(size 0.4572 0.4572)
			(layers "F.Cu" "F.Mask" "F.Paste")
			(net "LSI_T_N")
		)
		(pad "F8" smd circle
			(at -5.500116 -7.500112 90)
			(size 0.4572 0.4572)
			(layers "F.Cu" "F.Mask" "F.Paste")
			(net "EXP_CPU_MODE_0")
		)
		(pad "F9" smd circle
			(at -4.500118 -7.500112 90)
			(size 0.4572 0.4572)
			(layers "F.Cu" "F.Mask" "F.Paste")
			(net "EXP_XM_NOR_CS_N")
		)
		(pad "F10" smd circle
			(at -3.50012 -7.500112 90)
			(size 0.4572 0.4572)
			(layers "F.Cu" "F.Mask" "F.Paste")
			(net "XM_DATA4")
		)
		(pad "F11" smd circle
			(at -2.500122 -7.500112 90)
			(size 0.4572 0.4572)
			(layers "F.Cu" "F.Mask" "F.Paste")
			(net "XM_DATA13")
		)
		(pad "F12" smd circle
			(at -1.500124 -7.500112 90)
			(size 0.4572 0.4572)
			(layers "F.Cu" "F.Mask" "F.Paste")
			(net "XM_DATA0")
		)
		(pad "F13" smd circle
			(at -0.500126 -7.500112 90)
			(size 0.4572 0.4572)
			(layers "F.Cu" "F.Mask" "F.Paste")
			(net "EXP_XM_ADDR_2")
		)
		(pad "F14" smd circle
			(at 0.500126 -7.500112 90)
			(size 0.4572 0.4572)
			(layers "F.Cu" "F.Mask" "F.Paste")
			(net "EXP_XM_ADDR_15")
		)
		(pad "F15" smd circle
			(at 1.500124 -7.500112 90)
			(size 0.4572 0.4572)
			(layers "F.Cu" "F.Mask" "F.Paste")
			(net "EXP_FW_DET_BOARD_VER_1")
		)
		(pad "F16" smd circle
			(at 2.500122 -7.500112 90)
			(size 0.4572 0.4572)
			(layers "F.Cu" "F.Mask" "F.Paste")
			(net "LSI_EFUSE")
		)
		(pad "F17" smd circle
			(at 3.50012 -7.500112 90)
			(size 0.4572 0.4572)
			(layers "F.Cu" "F.Mask" "F.Paste")
			(net "ICE_TCK")
		)
		(pad "F18" smd circle
			(at 4.500118 -7.500112 90)
			(size 0.4572 0.4572)
			(layers "F.Cu" "F.Mask" "F.Paste")
			(net "ICE_TDI")
		)
		(pad "F19" smd circle
			(at 5.500116 -7.500112 90)
			(size 0.4572 0.4572)
			(layers "F.Cu" "F.Mask" "F.Paste")
			(net "SIO_D_IN")
		)
		(pad "F20" smd circle
			(at 6.500114 -7.500112 90)
			(size 0.4572 0.4572)
			(layers "F.Cu" "F.Mask" "F.Paste")
			(net "GND")
		)
		(pad "F21" smd circle
			(at 7.500112 -7.500112 90)
			(size 0.4572 0.4572)
			(layers "F.Cu" "F.Mask" "F.Paste")
			(net "SAS_GF_EXP_RX_DN15")
		)
		(pad "F22" smd circle
			(at 8.50011 -7.500112 90)
			(size 0.4572 0.4572)
			(layers "F.Cu" "F.Mask" "F.Paste")
			(net "SAS_GF_EXP_RX_DP15")
		)
		(pad "F23" smd circle
			(at 9.500108 -7.500112 90)
			(size 0.4572 0.4572)
			(layers "F.Cu" "F.Mask" "F.Paste")
			(net "GND")
		)
		(pad "F24" smd circle
			(at 10.500106 -7.500112 90)
			(size 0.4572 0.4572)
			(layers "F.Cu" "F.Mask" "F.Paste")
			(net "GB_VDDA")
		)
		(pad "F25" smd circle
			(at 11.500104 -7.500112 90)
			(size 0.4572 0.4572)
			(layers "F.Cu" "F.Mask" "F.Paste")
			(net "SAS_HDD_TX11_N")
		)
		(pad "F26" smd circle
			(at 12.500102 -7.500112 90)
			(size 0.4572 0.4572)
			(layers "F.Cu" "F.Mask" "F.Paste")
			(net "SAS_HDD_TX11_P")
		)
		(pad "G1" smd circle
			(at -12.500102 -6.500114 90)
			(size 0.4572 0.4572)
			(layers "F.Cu" "F.Mask" "F.Paste")
			(net "SAS_HDD_LED10")
		)
		(pad "G2" smd circle
			(at -11.500104 -6.500114 90)
			(size 0.4572 0.4572)
			(layers "F.Cu" "F.Mask" "F.Paste")
			(net "SAS_HDD_LED6")
		)
		(pad "G3" smd circle
			(at -10.500106 -6.500114 90)
			(size 0.4572 0.4572)
			(layers "F.Cu" "F.Mask" "F.Paste")
			(net "SAS_HDD_LED5")
		)
		(pad "G4" smd circle
			(at -9.500108 -6.500114 90)
			(size 0.4572 0.4572)
			(layers "F.Cu" "F.Mask" "F.Paste")
			(net "SXP_ACTIVE_2")
		)
		(pad "G5" smd circle
			(at -8.50011 -6.500114 90)
			(size 0.4572 0.4572)
			(layers "F.Cu" "F.Mask" "F.Paste")
			(net "SXP_ACTIVE_0")
		)
		(pad "G6" smd circle
			(at -7.500112 -6.500114 90)
			(size 0.4572 0.4572)
			(layers "F.Cu" "F.Mask" "F.Paste")
			(net "SAS_HDD_LED3")
		)
		(pad "G7" smd circle
			(at -6.500114 -6.500114 90)
			(size 0.4572 0.4572)
			(layers "F.Cu" "F.Mask" "F.Paste")
			(net "GND")
		)
		(pad "G8" smd circle
			(at -5.500116 -6.500114 90)
			(size 0.4572 0.4572)
			(layers "F.Cu" "F.Mask" "F.Paste")
			(net "LSI_SCAN_ENABLE")
		)
		(pad "G9" smd circle
			(at -4.500118 -6.500114 90)
			(size 0.4572 0.4572)
			(layers "F.Cu" "F.Mask" "F.Paste")
			(net "GND")
		)
		(pad "G10" smd circle
			(at -3.50012 -6.500114 90)
			(size 0.4572 0.4572)
			(layers "F.Cu" "F.Mask" "F.Paste")
			(net "XM_DATA9")
		)
		(pad "G11" smd circle
			(at -2.500122 -6.500114 90)
			(size 0.4572 0.4572)
			(layers "F.Cu" "F.Mask" "F.Paste")
			(net "GND")
		)
		(pad "G12" smd circle
			(at -1.500124 -6.500114 90)
			(size 0.4572 0.4572)
			(layers "F.Cu" "F.Mask" "F.Paste")
			(net "EXP_XM_ADDR_6")
		)
		(pad "G13" smd circle
			(at -0.500126 -6.500114 90)
			(size 0.4572 0.4572)
			(layers "F.Cu" "F.Mask" "F.Paste")
			(net "GND")
		)
		(pad "G14" smd circle
			(at 0.500126 -6.500114 90)
			(size 0.4572 0.4572)
			(layers "F.Cu" "F.Mask" "F.Paste")
			(net "EXP_XM_ADDR_10")
		)
		(pad "G15" smd circle
			(at 1.500124 -6.500114 90)
			(size 0.4572 0.4572)
			(layers "F.Cu" "F.Mask" "F.Paste")
			(net "EXP_GPIO_9")
		)
		(pad "G16" smd circle
			(at 2.500122 -6.500114 90)
			(size 0.4572 0.4572)
			(layers "F.Cu" "F.Mask" "F.Paste")
			(net "GND")
		)
		(pad "G17" smd circle
			(at 3.50012 -6.500114 90)
			(size 0.4572 0.4572)
			(layers "F.Cu" "F.Mask" "F.Paste")
			(net "SIO_LOAD_OUT")
		)
		(pad "G18" smd circle
			(at 4.500118 -6.500114 90)
			(size 0.4572 0.4572)
			(layers "F.Cu" "F.Mask" "F.Paste")
			(net "GND")
		)
		(pad "G19" smd circle
			(at 5.500116 -6.500114 90)
			(size 0.4572 0.4572)
			(layers "F.Cu" "F.Mask" "F.Paste")
			(net "EXP_I2C_SDA_4")
		)
		(pad "G20" smd circle
			(at 6.500114 -6.500114 90)
			(size 0.4572 0.4572)
			(layers "F.Cu" "F.Mask" "F.Paste")
			(net "GND")
		)
		(pad "G21" smd circle
			(at 7.500112 -6.500114 90)
			(size 0.4572 0.4572)
			(layers "F.Cu" "F.Mask" "F.Paste")
			(net "SAS_GF_EXP_RX_DN14")
		)
		(pad "G22" smd circle
			(at 8.50011 -6.500114 90)
			(size 0.4572 0.4572)
			(layers "F.Cu" "F.Mask" "F.Paste")
			(net "SAS_GF_EXP_RX_DP14")
		)
		(pad "G23" smd circle
			(at 9.500108 -6.500114 90)
			(size 0.4572 0.4572)
			(layers "F.Cu" "F.Mask" "F.Paste")
			(net "GB_VDDA")
		)
		(pad "G24" smd circle
			(at 10.500106 -6.500114 90)
			(size 0.4572 0.4572)
			(layers "F.Cu" "F.Mask" "F.Paste")
			(net "SAS_HDD_TX10_N")
		)
		(pad "G25" smd circle
			(at 11.500104 -6.500114 90)
			(size 0.4572 0.4572)
			(layers "F.Cu" "F.Mask" "F.Paste")
			(net "SAS_HDD_TX10_P")
		)
		(pad "G26" smd circle
			(at 12.500102 -6.500114 90)
			(size 0.4572 0.4572)
			(layers "F.Cu" "F.Mask" "F.Paste")
			(net "GND")
		)
		(pad "H1" smd circle
			(at -12.500102 -5.500116 90)
			(size 0.4572 0.4572)
			(layers "F.Cu" "F.Mask" "F.Paste")
			(net "GND")
		)
		(pad "H2" smd circle
			(at -11.500104 -5.500116 90)
			(size 0.4572 0.4572)
			(layers "F.Cu" "F.Mask" "F.Paste")
			(net "SAS_HDD_LED9")
		)
		(pad "H3" smd circle
			(at -10.500106 -5.500116 90)
			(size 0.4572 0.4572)
			(layers "F.Cu" "F.Mask" "F.Paste")
			(net "GND")
		)
		(pad "H4" smd circle
			(at -9.500108 -5.500116 90)
			(size 0.4572 0.4572)
			(layers "F.Cu" "F.Mask" "F.Paste")
			(net "P1V8_E")
		)
		(pad "H5" smd circle
			(at -8.50011 -5.500116 90)
			(size 0.4572 0.4572)
			(layers "F.Cu" "F.Mask" "F.Paste")
			(net "SAS_HDD_LED7")
		)
		(pad "H6" smd circle
			(at -7.500112 -5.500116 90)
			(size 0.4572 0.4572)
			(layers "F.Cu" "F.Mask" "F.Paste")
			(net "SAS_HDD_LED8")
		)
		(pad "H7" smd circle
			(at -6.500114 -5.500116 90)
			(size 0.4572 0.4572)
			(layers "F.Cu" "F.Mask" "F.Paste")
			(net "P1V8_E")
		)
		(pad "H8" smd circle
			(at -5.500116 -5.500116 90)
			(size 0.4572 0.4572)
			(layers "F.Cu" "F.Mask" "F.Paste")
			(net "SXP_ACTIVE_1")
		)
		(pad "H9" smd circle
			(at -4.500118 -5.500116 90)
			(size 0.4572 0.4572)
			(layers "F.Cu" "F.Mask" "F.Paste")
			(net "P1V8_E")
		)
		(pad "H10" smd circle
			(at -3.50012 -5.500116 90)
			(size 0.4572 0.4572)
			(layers "F.Cu" "F.Mask" "F.Paste")
			(net "EXP_CLK_SEL0")
		)
		(pad "H11" smd circle
			(at -2.500122 -5.500116 90)
			(size 0.4572 0.4572)
			(layers "F.Cu" "F.Mask" "F.Paste")
			(net "P1V8_E")
		)
		(pad "H12" smd circle
			(at -1.500124 -5.500116 90)
			(size 0.4572 0.4572)
			(layers "F.Cu" "F.Mask" "F.Paste")
			(net "EXP_XM_ADDR_24")
		)
		(pad "H13" smd circle
			(at -0.500126 -5.500116 90)
			(size 0.4572 0.4572)
			(layers "F.Cu" "F.Mask" "F.Paste")
			(net "P1V8_E")
		)
		(pad "H14" smd circle
			(at 0.500126 -5.500116 90)
			(size 0.4572 0.4572)
			(layers "F.Cu" "F.Mask" "F.Paste")
			(net "EXP_TACH_IN3")
		)
		(pad "H15" smd circle
			(at 1.500124 -5.500116 90)
			(size 0.4572 0.4572)
			(layers "F.Cu" "F.Mask" "F.Paste")
			(net "EXP_GPIO_4")
		)
		(pad "H16" smd circle
			(at 2.500122 -5.500116 90)
			(size 0.4572 0.4572)
			(layers "F.Cu" "F.Mask" "F.Paste")
			(net "P1V8_E")
		)
		(pad "H17" smd circle
			(at 3.50012 -5.500116 90)
			(size 0.4572 0.4572)
			(layers "F.Cu" "F.Mask" "F.Paste")
			(net "EXP_SIO_CLK_IN")
		)
		(pad "H18" smd circle
			(at 4.500118 -5.500116 90)
			(size 0.4572 0.4572)
			(layers "F.Cu" "F.Mask" "F.Paste")
			(net "EXP_I2C_SCL_2")
		)
		(pad "H19" smd circle
			(at 5.500116 -5.500116 90)
			(size 0.4572 0.4572)
			(layers "F.Cu" "F.Mask" "F.Paste")
			(net "GND")
		)
		(pad "H20" smd circle
			(at 6.500114 -5.500116 90)
			(size 0.4572 0.4572)
			(layers "F.Cu" "F.Mask" "F.Paste")
			(net "GND")
		)
		(pad "H21" smd circle
			(at 7.500112 -5.500116 90)
			(size 0.4572 0.4572)
			(layers "F.Cu" "F.Mask" "F.Paste")
			(net "SAS_GF_EXP_RX_DN13")
		)
		(pad "H22" smd circle
			(at 8.50011 -5.500116 90)
			(size 0.4572 0.4572)
			(layers "F.Cu" "F.Mask" "F.Paste")
			(net "SAS_GF_EXP_RX_DP13")
		)
		(pad "H23" smd circle
			(at 9.500108 -5.500116 90)
			(size 0.4572 0.4572)
			(layers "F.Cu" "F.Mask" "F.Paste")
			(net "GND")
		)
		(pad "H24" smd circle
			(at 10.500106 -5.500116 90)
			(size 0.4572 0.4572)
			(layers "F.Cu" "F.Mask" "F.Paste")
			(net "GB_VDDA")
		)
		(pad "H25" smd circle
			(at 11.500104 -5.500116 90)
			(size 0.4572 0.4572)
			(layers "F.Cu" "F.Mask" "F.Paste")
			(net "SAS_HDD_TX9_N")
		)
		(pad "H26" smd circle
			(at 12.500102 -5.500116 90)
			(size 0.4572 0.4572)
			(layers "F.Cu" "F.Mask" "F.Paste")
			(net "SAS_HDD_TX9_P")
		)
		(pad "J1" smd circle
			(at -12.500102 -4.500118 90)
			(size 0.4572 0.4572)
			(layers "F.Cu" "F.Mask" "F.Paste")
			(net "P1V8_E")
		)
		(pad "J2" smd circle
			(at -11.500104 -4.500118 90)
			(size 0.4572 0.4572)
			(layers "F.Cu" "F.Mask" "F.Paste")
			(net "SAS_HDD_LED11")
		)
		(pad "J3" smd circle
			(at -10.500106 -4.500118 90)
			(size 0.4572 0.4572)
			(layers "F.Cu" "F.Mask" "F.Paste")
			(net "EXP_ADC_IN0")
		)
		(pad "J4" smd circle
			(at -9.500108 -4.500118 90)
			(size 0.4572 0.4572)
			(layers "F.Cu" "F.Mask" "F.Paste")
			(net "TESTIBIAS")
		)
		(pad "J5" smd circle
			(at -8.50011 -4.500118 90)
			(size 0.4572 0.4572)
			(layers "F.Cu" "F.Mask" "F.Paste")
			(net "EXP_ADC_IN1")
		)
		(pad "J6" smd circle
			(at -7.500112 -4.500118 90)
			(size 0.4572 0.4572)
			(layers "F.Cu" "F.Mask" "F.Paste")
			(net "P1V8_E")
		)
		(pad "J7" smd circle
			(at -6.500114 -4.500118 90)
			(size 0.4572 0.4572)
			(layers "F.Cu" "F.Mask" "F.Paste")
			(net "GND")
		)
		(pad "J8" smd circle
			(at -5.500116 -4.500118 90)
			(size 0.4572 0.4572)
			(layers "F.Cu" "F.Mask" "F.Paste")
			(net "GND")
		)
		(pad "J9" smd circle
			(at -4.500118 -4.500118 90)
			(size 0.4572 0.4572)
			(layers "F.Cu" "F.Mask" "F.Paste")
			(net "Net_1129")
		)
		(pad "J10" smd circle
			(at -3.50012 -4.500118 90)
			(size 0.4572 0.4572)
			(layers "F.Cu" "F.Mask" "F.Paste")
			(net "GND")
		)
		(pad "J11" smd circle
			(at -2.500122 -4.500118 90)
			(size 0.4572 0.4572)
			(layers "F.Cu" "F.Mask" "F.Paste")
			(net "GND")
		)
		(pad "J12" smd circle
			(at -1.500124 -4.500118 90)
			(size 0.4572 0.4572)
			(layers "F.Cu" "F.Mask" "F.Paste")
			(net "GND")
		)
		(pad "J13" smd circle
			(at -0.500126 -4.500118 90)
			(size 0.4572 0.4572)
			(layers "F.Cu" "F.Mask" "F.Paste")
			(net "GND")
		)
		(pad "J14" smd circle
			(at 0.500126 -4.500118 90)
			(size 0.4572 0.4572)
			(layers "F.Cu" "F.Mask" "F.Paste")
			(net "GND")
		)
		(pad "J15" smd circle
			(at 1.500124 -4.500118 90)
			(size 0.4572 0.4572)
			(layers "F.Cu" "F.Mask" "F.Paste")
			(net "P1V8_E")
		)
		(pad "J16" smd circle
			(at 2.500122 -4.500118 90)
			(size 0.4572 0.4572)
			(layers "F.Cu" "F.Mask" "F.Paste")
			(net "GND")
		)
		(pad "J17" smd circle
			(at 3.50012 -4.500118 90)
			(size 0.4572 0.4572)
			(layers "F.Cu" "F.Mask" "F.Paste")
			(net "GND")
		)
		(pad "J18" smd circle
			(at 4.500118 -4.500118 90)
			(size 0.4572 0.4572)
			(layers "F.Cu" "F.Mask" "F.Paste")
			(net "GND")
		)
		(pad "J19" smd circle
			(at 5.500116 -4.500118 90)
			(size 0.4572 0.4572)
			(layers "F.Cu" "F.Mask" "F.Paste")
			(net "GND")
		)
		(pad "J20" smd circle
			(at 6.500114 -4.500118 90)
			(size 0.4572 0.4572)
			(layers "F.Cu" "F.Mask" "F.Paste")
			(net "GND")
		)
		(pad "J21" smd circle
			(at 7.500112 -4.500118 90)
			(size 0.4572 0.4572)
			(layers "F.Cu" "F.Mask" "F.Paste")
			(net "SAS_GF_EXP_RX_DN12")
		)
		(pad "J22" smd circle
			(at 8.50011 -4.500118 90)
			(size 0.4572 0.4572)
			(layers "F.Cu" "F.Mask" "F.Paste")
			(net "SAS_GF_EXP_RX_DP12")
		)
		(pad "J23" smd circle
			(at 9.500108 -4.500118 90)
			(size 0.4572 0.4572)
			(layers "F.Cu" "F.Mask" "F.Paste")
			(net "GB_VDDA")
		)
		(pad "J24" smd circle
			(at 10.500106 -4.500118 90)
			(size 0.4572 0.4572)
			(layers "F.Cu" "F.Mask" "F.Paste")
			(net "SAS_HDD_TX8_N")
		)
		(pad "J25" smd circle
			(at 11.500104 -4.500118 90)
			(size 0.4572 0.4572)
			(layers "F.Cu" "F.Mask" "F.Paste")
			(net "SAS_HDD_TX8_P")
		)
		(pad "J26" smd circle
			(at 12.500102 -4.500118 90)
			(size 0.4572 0.4572)
			(layers "F.Cu" "F.Mask" "F.Paste")
			(net "GND")
		)
		(pad "K1" smd circle
			(at -12.500102 -3.50012 90)
			(size 0.4572 0.4572)
			(layers "F.Cu" "F.Mask" "F.Paste")
			(net "EXP_LED_15")
		)
		(pad "K2" smd circle
			(at -11.500104 -3.50012 90)
			(size 0.4572 0.4572)
			(layers "F.Cu" "F.Mask" "F.Paste")
			(net "EXP_LED_12")
		)
		(pad "K3" smd circle
			(at -10.500106 -3.50012 90)
			(size 0.4572 0.4572)
			(layers "F.Cu" "F.Mask" "F.Paste")
			(net "GND")
		)
		(pad "K4" smd circle
			(at -9.500108 -3.50012 90)
			(size 0.4572 0.4572)
			(layers "F.Cu" "F.Mask" "F.Paste")
			(net "EXP_LED_13")
		)
		(pad "K5" smd circle
			(at -8.50011 -3.50012 90)
			(size 0.4572 0.4572)
			(layers "F.Cu" "F.Mask" "F.Paste")
			(net "GND")
		)
		(pad "K6" smd circle
			(at -7.500112 -3.50012 90)
			(size 0.4572 0.4572)
			(layers "F.Cu" "F.Mask" "F.Paste")
			(net "P1V8_E")
		)
		(pad "K7" smd circle
			(at -6.500114 -3.50012 90)
			(size 0.4572 0.4572)
			(layers "F.Cu" "F.Mask" "F.Paste")
			(net "GND")
		)
		(pad "K8" smd circle
			(at -5.500116 -3.50012 90)
			(size 0.4572 0.4572)
			(layers "F.Cu" "F.Mask" "F.Paste")
			(net "GND")
		)
		(pad "K9" smd circle
			(at -4.500118 -3.50012 90)
			(size 0.4572 0.4572)
			(layers "F.Cu" "F.Mask" "F.Paste")
			(net "P0V9_E")
		)
		(pad "K10" smd circle
			(at -3.50012 -3.50012 90)
			(size 0.4572 0.4572)
			(layers "F.Cu" "F.Mask" "F.Paste")
			(net "GND")
		)
		(pad "K11" smd circle
			(at -2.500122 -3.50012 90)
			(size 0.4572 0.4572)
			(layers "F.Cu" "F.Mask" "F.Paste")
			(net "P0V9_E")
		)
		(pad "K12" smd circle
			(at -1.500124 -3.50012 90)
			(size 0.4572 0.4572)
			(layers "F.Cu" "F.Mask" "F.Paste")
			(net "GND")
		)
		(pad "K13" smd circle
			(at -0.500126 -3.50012 90)
			(size 0.4572 0.4572)
			(layers "F.Cu" "F.Mask" "F.Paste")
			(net "P0V9_E")
		)
		(pad "K14" smd circle
			(at 0.500126 -3.50012 90)
			(size 0.4572 0.4572)
			(layers "F.Cu" "F.Mask" "F.Paste")
			(net "GND")
		)
		(pad "K15" smd circle
			(at 1.500124 -3.50012 90)
			(size 0.4572 0.4572)
			(layers "F.Cu" "F.Mask" "F.Paste")
			(net "P0V9_E")
		)
		(pad "K16" smd circle
			(at 2.500122 -3.50012 90)
			(size 0.4572 0.4572)
			(layers "F.Cu" "F.Mask" "F.Paste")
			(net "GND")
		)
		(pad "K17" smd circle
			(at 3.50012 -3.50012 90)
			(size 0.4572 0.4572)
			(layers "F.Cu" "F.Mask" "F.Paste")
			(net "P0V9_E")
		)
		(pad "K18" smd circle
			(at 4.500118 -3.50012 90)
			(size 0.4572 0.4572)
			(layers "F.Cu" "F.Mask" "F.Paste")
			(net "GND")
		)
		(pad "K19" smd circle
			(at 5.500116 -3.50012 90)
			(size 0.4572 0.4572)
			(layers "F.Cu" "F.Mask" "F.Paste")
			(net "GB_VDDH2")
		)
		(pad "K20" smd circle
			(at 6.500114 -3.50012 90)
			(size 0.4572 0.4572)
			(layers "F.Cu" "F.Mask" "F.Paste")
			(net "GB_VDDA")
		)
		(pad "K21" smd circle
			(at 7.500112 -3.50012 90)
			(size 0.4572 0.4572)
			(layers "F.Cu" "F.Mask" "F.Paste")
			(net "SAS_GF_EXP_RX_DN11")
		)
		(pad "K22" smd circle
			(at 8.50011 -3.50012 90)
			(size 0.4572 0.4572)
			(layers "F.Cu" "F.Mask" "F.Paste")
			(net "SAS_GF_EXP_RX_DP11")
		)
		(pad "K23" smd circle
			(at 9.500108 -3.50012 90)
			(size 0.4572 0.4572)
			(layers "F.Cu" "F.Mask" "F.Paste")
			(net "GND")
		)
		(pad "K24" smd circle
			(at 10.500106 -3.50012 90)
			(size 0.4572 0.4572)
			(layers "F.Cu" "F.Mask" "F.Paste")
			(net "GB_VDDA")
		)
		(pad "K25" smd circle
			(at 11.500104 -3.50012 90)
			(size 0.4572 0.4572)
			(layers "F.Cu" "F.Mask" "F.Paste")
			(net "SAS_HDD_TX7_N")
		)
		(pad "K26" smd circle
			(at 12.500102 -3.50012 90)
			(size 0.4572 0.4572)
			(layers "F.Cu" "F.Mask" "F.Paste")
			(net "SAS_HDD_TX7_P")
		)
		(pad "L1" smd circle
			(at -12.500102 -2.500122 90)
			(size 0.4572 0.4572)
			(layers "F.Cu" "F.Mask" "F.Paste")
			(net "SAS_HDD_LED23")
		)
		(pad "L2" smd circle
			(at -11.500104 -2.500122 90)
			(size 0.4572 0.4572)
			(layers "F.Cu" "F.Mask" "F.Paste")
			(net "SAS_STATUS_LED17")
		)
		(pad "L3" smd circle
			(at -10.500106 -2.500122 90)
			(size 0.4572 0.4572)
			(layers "F.Cu" "F.Mask" "F.Paste")
			(net "P1V8_E")
		)
		(pad "L4" smd circle
			(at -9.500108 -2.500122 90)
			(size 0.4572 0.4572)
			(layers "F.Cu" "F.Mask" "F.Paste")
			(net "EXP_LED18")
		)
		(pad "L5" smd circle
			(at -8.50011 -2.500122 90)
			(size 0.4572 0.4572)
			(layers "F.Cu" "F.Mask" "F.Paste")
			(net "EXP_LED_14")
		)
		(pad "L6" smd circle
			(at -7.500112 -2.500122 90)
			(size 0.4572 0.4572)
			(layers "F.Cu" "F.Mask" "F.Paste")
			(net "GND")
		)
		(pad "L7" smd circle
			(at -6.500114 -2.500122 90)
			(size 0.4572 0.4572)
			(layers "F.Cu" "F.Mask" "F.Paste")
			(net "SYSPLL_VDDA09")
		)
		(pad "L8" smd circle
			(at -5.500116 -2.500122 90)
			(size 0.4572 0.4572)
			(layers "F.Cu" "F.Mask" "F.Paste")
			(net "GND")
		)
		(pad "L9" smd circle
			(at -4.500118 -2.500122 90)
			(size 0.4572 0.4572)
			(layers "F.Cu" "F.Mask" "F.Paste")
			(net "GND")
		)
		(pad "L10" smd circle
			(at -3.50012 -2.500122 90)
			(size 0.4572 0.4572)
			(layers "F.Cu" "F.Mask" "F.Paste")
			(net "P0V9_E")
		)
		(pad "L11" smd circle
			(at -2.500122 -2.500122 90)
			(size 0.4572 0.4572)
			(layers "F.Cu" "F.Mask" "F.Paste")
			(net "GND")
		)
		(pad "L12" smd circle
			(at -1.500124 -2.500122 90)
			(size 0.4572 0.4572)
			(layers "F.Cu" "F.Mask" "F.Paste")
			(net "P0V9_E")
		)
		(pad "L13" smd circle
			(at -0.500126 -2.500122 90)
			(size 0.4572 0.4572)
			(layers "F.Cu" "F.Mask" "F.Paste")
			(net "GND")
		)
		(pad "L14" smd circle
			(at 0.500126 -2.500122 90)
			(size 0.4572 0.4572)
			(layers "F.Cu" "F.Mask" "F.Paste")
			(net "P0V9_E")
		)
		(pad "L15" smd circle
			(at 1.500124 -2.500122 90)
			(size 0.4572 0.4572)
			(layers "F.Cu" "F.Mask" "F.Paste")
			(net "GND")
		)
		(pad "L16" smd circle
			(at 2.500122 -2.500122 90)
			(size 0.4572 0.4572)
			(layers "F.Cu" "F.Mask" "F.Paste")
			(net "P0V9_E")
		)
		(pad "L17" smd circle
			(at 3.50012 -2.500122 90)
			(size 0.4572 0.4572)
			(layers "F.Cu" "F.Mask" "F.Paste")
			(net "GND")
		)
		(pad "L18" smd circle
			(at 4.500118 -2.500122 90)
			(size 0.4572 0.4572)
			(layers "F.Cu" "F.Mask" "F.Paste")
			(net "GND")
		)
		(pad "L19" smd circle
			(at 5.500116 -2.500122 90)
			(size 0.4572 0.4572)
			(layers "F.Cu" "F.Mask" "F.Paste")
			(net "GB_VDDH2")
		)
		(pad "L20" smd circle
			(at 6.500114 -2.500122 90)
			(size 0.4572 0.4572)
			(layers "F.Cu" "F.Mask" "F.Paste")
			(net "GND")
		)
		(pad "L21" smd circle
			(at 7.500112 -2.500122 90)
			(size 0.4572 0.4572)
			(layers "F.Cu" "F.Mask" "F.Paste")
			(net "SAS_GF_EXP_RX_DN10")
		)
		(pad "L22" smd circle
			(at 8.50011 -2.500122 90)
			(size 0.4572 0.4572)
			(layers "F.Cu" "F.Mask" "F.Paste")
			(net "SAS_GF_EXP_RX_DP10")
		)
		(pad "L23" smd circle
			(at 9.500108 -2.500122 90)
			(size 0.4572 0.4572)
			(layers "F.Cu" "F.Mask" "F.Paste")
			(net "GB_VDDA")
		)
		(pad "L24" smd circle
			(at 10.500106 -2.500122 90)
			(size 0.4572 0.4572)
			(layers "F.Cu" "F.Mask" "F.Paste")
			(net "SAS_HDD_TX6_N")
		)
		(pad "L25" smd circle
			(at 11.500104 -2.500122 90)
			(size 0.4572 0.4572)
			(layers "F.Cu" "F.Mask" "F.Paste")
			(net "SAS_HDD_TX6_P")
		)
		(pad "L26" smd circle
			(at 12.500102 -2.500122 90)
			(size 0.4572 0.4572)
			(layers "F.Cu" "F.Mask" "F.Paste")
			(net "GND")
		)
		(pad "M1" smd circle
			(at -12.500102 -1.500124 90)
			(size 0.4572 0.4572)
			(layers "F.Cu" "F.Mask" "F.Paste")
			(net "EXP_TEST_MUX28")
		)
		(pad "M2" smd circle
			(at -11.500104 -1.500124 90)
			(size 0.4572 0.4572)
			(layers "F.Cu" "F.Mask" "F.Paste")
			(net "EXP_TEST_MUX25")
		)
		(pad "M3" smd circle
			(at -10.500106 -1.500124 90)
			(size 0.4572 0.4572)
			(layers "F.Cu" "F.Mask" "F.Paste")
			(net "GND")
		)
		(pad "M4" smd circle
			(at -9.500108 -1.500124 90)
			(size 0.4572 0.4572)
			(layers "F.Cu" "F.Mask" "F.Paste")
			(net "SAS_HDD_LED20")
		)
		(pad "M5" smd circle
			(at -8.50011 -1.500124 90)
			(size 0.4572 0.4572)
			(layers "F.Cu" "F.Mask" "F.Paste")
			(net "EXP_LED19")
		)
		(pad "M6" smd circle
			(at -7.500112 -1.500124 90)
			(size 0.4572 0.4572)
			(layers "F.Cu" "F.Mask" "F.Paste")
			(net "P1V8_E")
		)
		(pad "M7" smd circle
			(at -6.500114 -1.500124 90)
			(size 0.4572 0.4572)
			(layers "F.Cu" "F.Mask" "F.Paste")
			(net "SYSPLL_VDDA18")
		)
		(pad "M8" smd circle
			(at -5.500116 -1.500124 90)
			(size 0.4572 0.4572)
			(layers "F.Cu" "F.Mask" "F.Paste")
			(net "GND")
		)
		(pad "M9" smd circle
			(at -4.500118 -1.500124 90)
			(size 0.4572 0.4572)
			(layers "F.Cu" "F.Mask" "F.Paste")
			(net "P0V9_E")
		)
		(pad "M10" smd circle
			(at -3.50012 -1.500124 90)
			(size 0.4572 0.4572)
			(layers "F.Cu" "F.Mask" "F.Paste")
			(net "GND")
		)
		(pad "M11" smd circle
			(at -2.500122 -1.500124 90)
			(size 0.4572 0.4572)
			(layers "F.Cu" "F.Mask" "F.Paste")
			(net "P0V9_E")
		)
		(pad "M12" smd circle
			(at -1.500124 -1.500124 90)
			(size 0.4572 0.4572)
			(layers "F.Cu" "F.Mask" "F.Paste")
			(net "GND")
		)
		(pad "M13" smd circle
			(at -0.500126 -1.500124 90)
			(size 0.4572 0.4572)
			(layers "F.Cu" "F.Mask" "F.Paste")
			(net "P0V9_E")
		)
		(pad "M14" smd circle
			(at 0.500126 -1.500124 90)
			(size 0.4572 0.4572)
			(layers "F.Cu" "F.Mask" "F.Paste")
			(net "GND")
		)
		(pad "M15" smd circle
			(at 1.500124 -1.500124 90)
			(size 0.4572 0.4572)
			(layers "F.Cu" "F.Mask" "F.Paste")
			(net "P0V9_E")
		)
		(pad "M16" smd circle
			(at 2.500122 -1.500124 90)
			(size 0.4572 0.4572)
			(layers "F.Cu" "F.Mask" "F.Paste")
			(net "GND")
		)
		(pad "M17" smd circle
			(at 3.50012 -1.500124 90)
			(size 0.4572 0.4572)
			(layers "F.Cu" "F.Mask" "F.Paste")
			(net "P0V9_E")
		)
		(pad "M18" smd circle
			(at 4.500118 -1.500124 90)
			(size 0.4572 0.4572)
			(layers "F.Cu" "F.Mask" "F.Paste")
			(net "GND")
		)
		(pad "M19" smd circle
			(at 5.500116 -1.500124 90)
			(size 0.4572 0.4572)
			(layers "F.Cu" "F.Mask" "F.Paste")
			(net "GB_VDDH2")
		)
		(pad "M20" smd circle
			(at 6.500114 -1.500124 90)
			(size 0.4572 0.4572)
			(layers "F.Cu" "F.Mask" "F.Paste")
			(net "GB_VDDA")
		)
		(pad "M21" smd circle
			(at 7.500112 -1.500124 90)
			(size 0.4572 0.4572)
			(layers "F.Cu" "F.Mask" "F.Paste")
			(net "SAS_GF_EXP_RX_DN9")
		)
		(pad "M22" smd circle
			(at 8.50011 -1.500124 90)
			(size 0.4572 0.4572)
			(layers "F.Cu" "F.Mask" "F.Paste")
			(net "SAS_GF_EXP_RX_DP9")
		)
		(pad "M23" smd circle
			(at 9.500108 -1.500124 90)
			(size 0.4572 0.4572)
			(layers "F.Cu" "F.Mask" "F.Paste")
			(net "GND")
		)
		(pad "M24" smd circle
			(at 10.500106 -1.500124 90)
			(size 0.4572 0.4572)
			(layers "F.Cu" "F.Mask" "F.Paste")
			(net "GB_VDDA")
		)
		(pad "M25" smd circle
			(at 11.500104 -1.500124 90)
			(size 0.4572 0.4572)
			(layers "F.Cu" "F.Mask" "F.Paste")
			(net "SAS_HDD_TX5_N")
		)
		(pad "M26" smd circle
			(at 12.500102 -1.500124 90)
			(size 0.4572 0.4572)
			(layers "F.Cu" "F.Mask" "F.Paste")
			(net "SAS_HDD_TX5_P")
		)
		(pad "N1" smd circle
			(at -12.500102 -0.500126 90)
			(size 0.4572 0.4572)
			(layers "F.Cu" "F.Mask" "F.Paste")
			(net "EXP_TEST_MUX29")
		)
		(pad "N2" smd circle
			(at -11.500104 -0.500126 90)
			(size 0.4572 0.4572)
			(layers "F.Cu" "F.Mask" "F.Paste")
			(net "EXP_TEST_MUX27")
		)
		(pad "N3" smd circle
			(at -10.500106 -0.500126 90)
			(size 0.4572 0.4572)
			(layers "F.Cu" "F.Mask" "F.Paste")
			(net "P1V8_E")
		)
		(pad "N4" smd circle
			(at -9.500108 -0.500126 90)
			(size 0.4572 0.4572)
			(layers "F.Cu" "F.Mask" "F.Paste")
			(net "EXP_TEST_MUX24")
		)
		(pad "N5" smd circle
			(at -8.50011 -0.500126 90)
			(size 0.4572 0.4572)
			(layers "F.Cu" "F.Mask" "F.Paste")
			(net "SAS_HDD_LED22")
		)
		(pad "N6" smd circle
			(at -7.500112 -0.500126 90)
			(size 0.4572 0.4572)
			(layers "F.Cu" "F.Mask" "F.Paste")
			(net "GND")
		)
		(pad "N7" smd circle
			(at -6.500114 -0.500126 90)
			(size 0.4572 0.4572)
			(layers "F.Cu" "F.Mask" "F.Paste")
			(net "PLLDDR_VDDA18")
		)
		(pad "N8" smd circle
			(at -5.500116 -0.500126 90)
			(size 0.4572 0.4572)
			(layers "F.Cu" "F.Mask" "F.Paste")
			(net "GND")
		)
		(pad "N9" smd circle
			(at -4.500118 -0.500126 90)
			(size 0.4572 0.4572)
			(layers "F.Cu" "F.Mask" "F.Paste")
			(net "GND")
		)
		(pad "N10" smd circle
			(at -3.50012 -0.500126 90)
			(size 0.4572 0.4572)
			(layers "F.Cu" "F.Mask" "F.Paste")
			(net "P0V9_E")
		)
		(pad "N11" smd circle
			(at -2.500122 -0.500126 90)
			(size 0.4572 0.4572)
			(layers "F.Cu" "F.Mask" "F.Paste")
			(net "GND")
		)
		(pad "N12" smd circle
			(at -1.500124 -0.500126 90)
			(size 0.4572 0.4572)
			(layers "F.Cu" "F.Mask" "F.Paste")
			(net "P0V9_E")
		)
		(pad "N13" smd circle
			(at -0.500126 -0.500126 90)
			(size 0.4572 0.4572)
			(layers "F.Cu" "F.Mask" "F.Paste")
			(net "GND")
		)
		(pad "N14" smd circle
			(at 0.500126 -0.500126 90)
			(size 0.4572 0.4572)
			(layers "F.Cu" "F.Mask" "F.Paste")
			(net "P0V9_E")
		)
		(pad "N15" smd circle
			(at 1.500124 -0.500126 90)
			(size 0.4572 0.4572)
			(layers "F.Cu" "F.Mask" "F.Paste")
			(net "GND")
		)
		(pad "N16" smd circle
			(at 2.500122 -0.500126 90)
			(size 0.4572 0.4572)
			(layers "F.Cu" "F.Mask" "F.Paste")
			(net "P0V9_E")
		)
		(pad "N17" smd circle
			(at 3.50012 -0.500126 90)
			(size 0.4572 0.4572)
			(layers "F.Cu" "F.Mask" "F.Paste")
			(net "GND")
		)
		(pad "N18" smd circle
			(at 4.500118 -0.500126 90)
			(size 0.4572 0.4572)
			(layers "F.Cu" "F.Mask" "F.Paste")
			(net "GND")
		)
		(pad "N19" smd circle
			(at 5.500116 -0.500126 90)
			(size 0.4572 0.4572)
			(layers "F.Cu" "F.Mask" "F.Paste")
			(net "GB_VDDH2")
		)
		(pad "N20" smd circle
			(at 6.500114 -0.500126 90)
			(size 0.4572 0.4572)
			(layers "F.Cu" "F.Mask" "F.Paste")
			(net "GND")
		)
		(pad "N21" smd circle
			(at 7.500112 -0.500126 90)
			(size 0.4572 0.4572)
			(layers "F.Cu" "F.Mask" "F.Paste")
			(net "SAS_HDD_CONN_RX8_N")
		)
		(pad "N22" smd circle
			(at 8.50011 -0.500126 90)
			(size 0.4572 0.4572)
			(layers "F.Cu" "F.Mask" "F.Paste")
			(net "SAS_HDD_CONN_RX8_P")
		)
		(pad "N23" smd circle
			(at 9.500108 -0.500126 90)
			(size 0.4572 0.4572)
			(layers "F.Cu" "F.Mask" "F.Paste")
			(net "GB_VDDA")
		)
		(pad "N24" smd circle
			(at 10.500106 -0.500126 90)
			(size 0.4572 0.4572)
			(layers "F.Cu" "F.Mask" "F.Paste")
			(net "SAS_HDD_TX4_N")
		)
		(pad "N25" smd circle
			(at 11.500104 -0.500126 90)
			(size 0.4572 0.4572)
			(layers "F.Cu" "F.Mask" "F.Paste")
			(net "SAS_HDD_TX4_P")
		)
		(pad "N26" smd circle
			(at 12.500102 -0.500126 90)
			(size 0.4572 0.4572)
			(layers "F.Cu" "F.Mask" "F.Paste")
			(net "GND")
		)
		(pad "P1" smd circle
			(at -12.500102 0.500126 90)
			(size 0.4572 0.4572)
			(layers "F.Cu" "F.Mask" "F.Paste")
			(net "EXP_TEST_MUX32")
		)
		(pad "P2" smd circle
			(at -11.500104 0.500126 90)
			(size 0.4572 0.4572)
			(layers "F.Cu" "F.Mask" "F.Paste")
			(net "EXP_TEST_MUX33")
		)
		(pad "P3" smd circle
			(at -10.500106 0.500126 90)
			(size 0.4572 0.4572)
			(layers "F.Cu" "F.Mask" "F.Paste")
			(net "GND")
		)
		(pad "P4" smd circle
			(at -9.500108 0.500126 90)
			(size 0.4572 0.4572)
			(layers "F.Cu" "F.Mask" "F.Paste")
			(net "EXP_TEST_MUX30")
		)
		(pad "P5" smd circle
			(at -8.50011 0.500126 90)
			(size 0.4572 0.4572)
			(layers "F.Cu" "F.Mask" "F.Paste")
			(net "SAS_HDD_LED21")
		)
		(pad "P6" smd circle
			(at -7.500112 0.500126 90)
			(size 0.4572 0.4572)
			(layers "F.Cu" "F.Mask" "F.Paste")
			(net "P1V8_E")
		)
		(pad "P7" smd circle
			(at -6.500114 0.500126 90)
			(size 0.4572 0.4572)
			(layers "F.Cu" "F.Mask" "F.Paste")
			(net "SAS_ACTIVITY_LED16")
		)
		(pad "P8" smd circle
			(at -5.500116 0.500126 90)
			(size 0.4572 0.4572)
			(layers "F.Cu" "F.Mask" "F.Paste")
			(net "GND")
		)
		(pad "P9" smd circle
			(at -4.500118 0.500126 90)
			(size 0.4572 0.4572)
			(layers "F.Cu" "F.Mask" "F.Paste")
			(net "P0V9_E")
		)
		(pad "P10" smd circle
			(at -3.50012 0.500126 90)
			(size 0.4572 0.4572)
			(layers "F.Cu" "F.Mask" "F.Paste")
			(net "GND")
		)
		(pad "P11" smd circle
			(at -2.500122 0.500126 90)
			(size 0.4572 0.4572)
			(layers "F.Cu" "F.Mask" "F.Paste")
			(net "P0V9_E")
		)
		(pad "P12" smd circle
			(at -1.500124 0.500126 90)
			(size 0.4572 0.4572)
			(layers "F.Cu" "F.Mask" "F.Paste")
			(net "GND")
		)
		(pad "P13" smd circle
			(at -0.500126 0.500126 90)
			(size 0.4572 0.4572)
			(layers "F.Cu" "F.Mask" "F.Paste")
			(net "P0V9_E")
		)
		(pad "P14" smd circle
			(at 0.500126 0.500126 90)
			(size 0.4572 0.4572)
			(layers "F.Cu" "F.Mask" "F.Paste")
			(net "GND")
		)
		(pad "P15" smd circle
			(at 1.500124 0.500126 90)
			(size 0.4572 0.4572)
			(layers "F.Cu" "F.Mask" "F.Paste")
			(net "P0V9_E")
		)
		(pad "P16" smd circle
			(at 2.500122 0.500126 90)
			(size 0.4572 0.4572)
			(layers "F.Cu" "F.Mask" "F.Paste")
			(net "GND")
		)
		(pad "P17" smd circle
			(at 3.50012 0.500126 90)
			(size 0.4572 0.4572)
			(layers "F.Cu" "F.Mask" "F.Paste")
			(net "P0V9_E")
		)
		(pad "P18" smd circle
			(at 4.500118 0.500126 90)
			(size 0.4572 0.4572)
			(layers "F.Cu" "F.Mask" "F.Paste")
			(net "GND")
		)
		(pad "P19" smd circle
			(at 5.500116 0.500126 90)
			(size 0.4572 0.4572)
			(layers "F.Cu" "F.Mask" "F.Paste")
			(net "GB_VDDH2")
		)
		(pad "P20" smd circle
			(at 6.500114 0.500126 90)
			(size 0.4572 0.4572)
			(layers "F.Cu" "F.Mask" "F.Paste")
			(net "GND")
		)
		(pad "P21" smd circle
			(at 7.500112 0.500126 90)
			(size 0.4572 0.4572)
			(layers "F.Cu" "F.Mask" "F.Paste")
			(net "SAS_HDD_CONN_RX7_N")
		)
		(pad "P22" smd circle
			(at 8.50011 0.500126 90)
			(size 0.4572 0.4572)
			(layers "F.Cu" "F.Mask" "F.Paste")
			(net "SAS_HDD_CONN_RX7_P")
		)
		(pad "P23" smd circle
			(at 9.500108 0.500126 90)
			(size 0.4572 0.4572)
			(layers "F.Cu" "F.Mask" "F.Paste")
			(net "GND")
		)
		(pad "P24" smd circle
			(at 10.500106 0.500126 90)
			(size 0.4572 0.4572)
			(layers "F.Cu" "F.Mask" "F.Paste")
			(net "GB_VDDA")
		)
		(pad "P25" smd circle
			(at 11.500104 0.500126 90)
			(size 0.4572 0.4572)
			(layers "F.Cu" "F.Mask" "F.Paste")
			(net "SAS_HDD_TX3_N")
		)
		(pad "P26" smd circle
			(at 12.500102 0.500126 90)
			(size 0.4572 0.4572)
			(layers "F.Cu" "F.Mask" "F.Paste")
			(net "SAS_HDD_TX3_P")
		)
		(pad "R1" smd circle
			(at -12.500102 1.500124 90)
			(size 0.4572 0.4572)
			(layers "F.Cu" "F.Mask" "F.Paste")
			(net "EXP_TEST_MUX34")
		)
		(pad "R2" smd circle
			(at -11.500104 1.500124 90)
			(size 0.4572 0.4572)
			(layers "F.Cu" "F.Mask" "F.Paste")
			(net "EXP_TEST_MUX35")
		)
		(pad "R3" smd circle
			(at -10.500106 1.500124 90)
			(size 0.4572 0.4572)
			(layers "F.Cu" "F.Mask" "F.Paste")
			(net "P1V8_E")
		)
		(pad "R4" smd circle
			(at -9.500108 1.500124 90)
			(size 0.4572 0.4572)
			(layers "F.Cu" "F.Mask" "F.Paste")
			(net "TEST_MUX_38")
		)
		(pad "R5" smd circle
			(at -8.50011 1.500124 90)
			(size 0.4572 0.4572)
			(layers "F.Cu" "F.Mask" "F.Paste")
			(net "EXP_TEST_MUX26")
		)
		(pad "R6" smd circle
			(at -7.500112 1.500124 90)
			(size 0.4572 0.4572)
			(layers "F.Cu" "F.Mask" "F.Paste")
			(net "GND")
		)
		(pad "R7" smd circle
			(at -6.500114 1.500124 90)
			(size 0.4572 0.4572)
			(layers "F.Cu" "F.Mask" "F.Paste")
			(net "EXP_TEST_MUX31")
		)
		(pad "R8" smd circle
			(at -5.500116 1.500124 90)
			(size 0.4572 0.4572)
			(layers "F.Cu" "F.Mask" "F.Paste")
			(net "GND")
		)
		(pad "R9" smd circle
			(at -4.500118 1.500124 90)
			(size 0.4572 0.4572)
			(layers "F.Cu" "F.Mask" "F.Paste")
			(net "Net_1132")
		)
		(pad "R10" smd circle
			(at -3.50012 1.500124 90)
			(size 0.4572 0.4572)
			(layers "F.Cu" "F.Mask" "F.Paste")
			(net "P0V9_E")
		)
		(pad "R11" smd circle
			(at -2.500122 1.500124 90)
			(size 0.4572 0.4572)
			(layers "F.Cu" "F.Mask" "F.Paste")
			(net "GND")
		)
		(pad "R12" smd circle
			(at -1.500124 1.500124 90)
			(size 0.4572 0.4572)
			(layers "F.Cu" "F.Mask" "F.Paste")
			(net "P0V9_E")
		)
		(pad "R13" smd circle
			(at -0.500126 1.500124 90)
			(size 0.4572 0.4572)
			(layers "F.Cu" "F.Mask" "F.Paste")
			(net "GND")
		)
		(pad "R14" smd circle
			(at 0.500126 1.500124 90)
			(size 0.4572 0.4572)
			(layers "F.Cu" "F.Mask" "F.Paste")
			(net "P0V9_E")
		)
		(pad "R15" smd circle
			(at 1.500124 1.500124 90)
			(size 0.4572 0.4572)
			(layers "F.Cu" "F.Mask" "F.Paste")
			(net "GND")
		)
		(pad "R16" smd circle
			(at 2.500122 1.500124 90)
			(size 0.4572 0.4572)
			(layers "F.Cu" "F.Mask" "F.Paste")
			(net "P0V9_E")
		)
		(pad "R17" smd circle
			(at 3.50012 1.500124 90)
			(size 0.4572 0.4572)
			(layers "F.Cu" "F.Mask" "F.Paste")
			(net "GND")
		)
		(pad "R18" smd circle
			(at 4.500118 1.500124 90)
			(size 0.4572 0.4572)
			(layers "F.Cu" "F.Mask" "F.Paste")
			(net "GND")
		)
		(pad "R19" smd circle
			(at 5.500116 1.500124 90)
			(size 0.4572 0.4572)
			(layers "F.Cu" "F.Mask" "F.Paste")
			(net "GND")
		)
		(pad "R20" smd circle
			(at 6.500114 1.500124 90)
			(size 0.4572 0.4572)
			(layers "F.Cu" "F.Mask" "F.Paste")
			(net "GND")
		)
		(pad "R21" smd circle
			(at 7.500112 1.500124 90)
			(size 0.4572 0.4572)
			(layers "F.Cu" "F.Mask" "F.Paste")
			(net "SAS_GF_EXP_RX_DN6")
		)
		(pad "R22" smd circle
			(at 8.50011 1.500124 90)
			(size 0.4572 0.4572)
			(layers "F.Cu" "F.Mask" "F.Paste")
			(net "SAS_GF_EXP_RX_DP6")
		)
		(pad "R23" smd circle
			(at 9.500108 1.500124 90)
			(size 0.4572 0.4572)
			(layers "F.Cu" "F.Mask" "F.Paste")
			(net "GB_VDDA")
		)
		(pad "R24" smd circle
			(at 10.500106 1.500124 90)
			(size 0.4572 0.4572)
			(layers "F.Cu" "F.Mask" "F.Paste")
			(net "SAS_HDD_TX2_N")
		)
		(pad "R25" smd circle
			(at 11.500104 1.500124 90)
			(size 0.4572 0.4572)
			(layers "F.Cu" "F.Mask" "F.Paste")
			(net "SAS_HDD_TX2_P")
		)
		(pad "R26" smd circle
			(at 12.500102 1.500124 90)
			(size 0.4572 0.4572)
			(layers "F.Cu" "F.Mask" "F.Paste")
			(net "GND")
		)
		(pad "T1" smd circle
			(at -12.500102 2.500122 90)
			(size 0.4572 0.4572)
			(layers "F.Cu" "F.Mask" "F.Paste")
			(net "TEST_MUX_37")
		)
		(pad "T2" smd circle
			(at -11.500104 2.500122 90)
			(size 0.4572 0.4572)
			(layers "F.Cu" "F.Mask" "F.Paste")
			(net "TEST_MUX_39")
		)
		(pad "T3" smd circle
			(at -10.500106 2.500122 90)
			(size 0.4572 0.4572)
			(layers "F.Cu" "F.Mask" "F.Paste")
			(net "GND")
		)
		(pad "T4" smd circle
			(at -9.500108 2.500122 90)
			(size 0.4572 0.4572)
			(layers "F.Cu" "F.Mask" "F.Paste")
			(net "TEST_MUX_40")
		)
		(pad "T5" smd circle
			(at -8.50011 2.500122 90)
			(size 0.4572 0.4572)
			(layers "F.Cu" "F.Mask" "F.Paste")
			(net "TEST_MUX_36")
		)
		(pad "T6" smd circle
			(at -7.500112 2.500122 90)
			(size 0.4572 0.4572)
			(layers "F.Cu" "F.Mask" "F.Paste")
			(net "P1V8_E")
		)
		(pad "T7" smd circle
			(at -6.500114 2.500122 90)
			(size 0.4572 0.4572)
			(layers "F.Cu" "F.Mask" "F.Paste")
			(net "TEST_MUX_41")
		)
		(pad "T8" smd circle
			(at -5.500116 2.500122 90)
			(size 0.4572 0.4572)
			(layers "F.Cu" "F.Mask" "F.Paste")
			(net "GND")
		)
		(pad "T9" smd circle
			(at -4.500118 2.500122 90)
			(size 0.4572 0.4572)
			(layers "F.Cu" "F.Mask" "F.Paste")
			(net "P0V9_E")
		)
		(pad "T10" smd circle
			(at -3.50012 2.500122 90)
			(size 0.4572 0.4572)
			(layers "F.Cu" "F.Mask" "F.Paste")
			(net "GND")
		)
		(pad "T11" smd circle
			(at -2.500122 2.500122 90)
			(size 0.4572 0.4572)
			(layers "F.Cu" "F.Mask" "F.Paste")
			(net "P0V9_E")
		)
		(pad "T12" smd circle
			(at -1.500124 2.500122 90)
			(size 0.4572 0.4572)
			(layers "F.Cu" "F.Mask" "F.Paste")
			(net "GND")
		)
		(pad "T13" smd circle
			(at -0.500126 2.500122 90)
			(size 0.4572 0.4572)
			(layers "F.Cu" "F.Mask" "F.Paste")
			(net "P0V9_E")
		)
		(pad "T14" smd circle
			(at 0.500126 2.500122 90)
			(size 0.4572 0.4572)
			(layers "F.Cu" "F.Mask" "F.Paste")
			(net "GND")
		)
		(pad "T15" smd circle
			(at 1.500124 2.500122 90)
			(size 0.4572 0.4572)
			(layers "F.Cu" "F.Mask" "F.Paste")
			(net "P0V9_E")
		)
		(pad "T16" smd circle
			(at 2.500122 2.500122 90)
			(size 0.4572 0.4572)
			(layers "F.Cu" "F.Mask" "F.Paste")
			(net "GND")
		)
		(pad "T17" smd circle
			(at 3.50012 2.500122 90)
			(size 0.4572 0.4572)
			(layers "F.Cu" "F.Mask" "F.Paste")
			(net "P0V9_E")
		)
		(pad "T18" smd circle
			(at 4.500118 2.500122 90)
			(size 0.4572 0.4572)
			(layers "F.Cu" "F.Mask" "F.Paste")
			(net "GND")
		)
		(pad "T19" smd circle
			(at 5.500116 2.500122 90)
			(size 0.4572 0.4572)
			(layers "F.Cu" "F.Mask" "F.Paste")
			(net "GND")
		)
		(pad "T20" smd circle
			(at 6.500114 2.500122 90)
			(size 0.4572 0.4572)
			(layers "F.Cu" "F.Mask" "F.Paste")
			(net "GB_VDDA")
		)
		(pad "T21" smd circle
			(at 7.500112 2.500122 90)
			(size 0.4572 0.4572)
			(layers "F.Cu" "F.Mask" "F.Paste")
			(net "SAS_GF_EXP_RX_DN5")
		)
		(pad "T22" smd circle
			(at 8.50011 2.500122 90)
			(size 0.4572 0.4572)
			(layers "F.Cu" "F.Mask" "F.Paste")
			(net "SAS_GF_EXP_RX_DP5")
		)
		(pad "T23" smd circle
			(at 9.500108 2.500122 90)
			(size 0.4572 0.4572)
			(layers "F.Cu" "F.Mask" "F.Paste")
			(net "GND")
		)
		(pad "T24" smd circle
			(at 10.500106 2.500122 90)
			(size 0.4572 0.4572)
			(layers "F.Cu" "F.Mask" "F.Paste")
			(net "GB_VDDA")
		)
		(pad "T25" smd circle
			(at 11.500104 2.500122 90)
			(size 0.4572 0.4572)
			(layers "F.Cu" "F.Mask" "F.Paste")
			(net "SAS_HDD_TX1_N")
		)
		(pad "T26" smd circle
			(at 12.500102 2.500122 90)
			(size 0.4572 0.4572)
			(layers "F.Cu" "F.Mask" "F.Paste")
			(net "SAS_HDD_TX1_P")
		)
		(pad "U1" smd circle
			(at -12.500102 3.50012 90)
			(size 0.4572 0.4572)
			(layers "F.Cu" "F.Mask" "F.Paste")
			(net "TEST_MUX_43")
		)
		(pad "U2" smd circle
			(at -11.500104 3.50012 90)
			(size 0.4572 0.4572)
			(layers "F.Cu" "F.Mask" "F.Paste")
			(net "TEST_MUX_42")
		)
		(pad "U3" smd circle
			(at -10.500106 3.50012 90)
			(size 0.4572 0.4572)
			(layers "F.Cu" "F.Mask" "F.Paste")
			(net "P1V8_E")
		)
		(pad "U4" smd circle
			(at -9.500108 3.50012 90)
			(size 0.4572 0.4572)
			(layers "F.Cu" "F.Mask" "F.Paste")
			(net "TEST_MUX_45")
		)
		(pad "U5" smd circle
			(at -8.50011 3.50012 90)
			(size 0.4572 0.4572)
			(layers "F.Cu" "F.Mask" "F.Paste")
			(net "TEST_MUX_46")
		)
		(pad "U6" smd circle
			(at -7.500112 3.50012 90)
			(size 0.4572 0.4572)
			(layers "F.Cu" "F.Mask" "F.Paste")
			(net "GND")
		)
		(pad "U7" smd circle
			(at -6.500114 3.50012 90)
			(size 0.4572 0.4572)
			(layers "F.Cu" "F.Mask" "F.Paste")
			(net "XTAL_VDDA09")
		)
		(pad "U8" smd circle
			(at -5.500116 3.50012 90)
			(size 0.4572 0.4572)
			(layers "F.Cu" "F.Mask" "F.Paste")
			(net "GND")
		)
		(pad "U9" smd circle
			(at -4.500118 3.50012 90)
			(size 0.4572 0.4572)
			(layers "F.Cu" "F.Mask" "F.Paste")
			(net "GND")
		)
		(pad "U10" smd circle
			(at -3.50012 3.50012 90)
			(size 0.4572 0.4572)
			(layers "F.Cu" "F.Mask" "F.Paste")
			(net "GND")
		)
		(pad "U11" smd circle
			(at -2.500122 3.50012 90)
			(size 0.4572 0.4572)
			(layers "F.Cu" "F.Mask" "F.Paste")
			(net "GND")
		)
		(pad "U12" smd circle
			(at -1.500124 3.50012 90)
			(size 0.4572 0.4572)
			(layers "F.Cu" "F.Mask" "F.Paste")
			(net "GND")
		)
		(pad "U13" smd circle
			(at -0.500126 3.50012 90)
			(size 0.4572 0.4572)
			(layers "F.Cu" "F.Mask" "F.Paste")
			(net "GND")
		)
		(pad "U14" smd circle
			(at 0.500126 3.50012 90)
			(size 0.4572 0.4572)
			(layers "F.Cu" "F.Mask" "F.Paste")
			(net "GND")
		)
		(pad "U15" smd circle
			(at 1.500124 3.50012 90)
			(size 0.4572 0.4572)
			(layers "F.Cu" "F.Mask" "F.Paste")
			(net "GND")
		)
		(pad "U16" smd circle
			(at 2.500122 3.50012 90)
			(size 0.4572 0.4572)
			(layers "F.Cu" "F.Mask" "F.Paste")
			(net "GND")
		)
		(pad "U17" smd circle
			(at 3.50012 3.50012 90)
			(size 0.4572 0.4572)
			(layers "F.Cu" "F.Mask" "F.Paste")
			(net "GND")
		)
		(pad "U18" smd circle
			(at 4.500118 3.50012 90)
			(size 0.4572 0.4572)
			(layers "F.Cu" "F.Mask" "F.Paste")
			(net "GND")
		)
		(pad "U19" smd circle
			(at 5.500116 3.50012 90)
			(size 0.4572 0.4572)
			(layers "F.Cu" "F.Mask" "F.Paste")
			(net "GND")
		)
		(pad "U20" smd circle
			(at 6.500114 3.50012 90)
			(size 0.4572 0.4572)
			(layers "F.Cu" "F.Mask" "F.Paste")
			(net "GND")
		)
		(pad "U21" smd circle
			(at 7.500112 3.50012 90)
			(size 0.4572 0.4572)
			(layers "F.Cu" "F.Mask" "F.Paste")
			(net "SAS_GF_EXP_RX_DN4")
		)
		(pad "U22" smd circle
			(at 8.50011 3.50012 90)
			(size 0.4572 0.4572)
			(layers "F.Cu" "F.Mask" "F.Paste")
			(net "SAS_GF_EXP_RX_DP4")
		)
		(pad "U23" smd circle
			(at 9.500108 3.50012 90)
			(size 0.4572 0.4572)
			(layers "F.Cu" "F.Mask" "F.Paste")
			(net "GB_VDDA")
		)
		(pad "U24" smd circle
			(at 10.500106 3.50012 90)
			(size 0.4572 0.4572)
			(layers "F.Cu" "F.Mask" "F.Paste")
			(net "SAS_HDD_TX0_N")
		)
		(pad "U25" smd circle
			(at 11.500104 3.50012 90)
			(size 0.4572 0.4572)
			(layers "F.Cu" "F.Mask" "F.Paste")
			(net "SAS_HDD_TX0_P")
		)
		(pad "U26" smd circle
			(at 12.500102 3.50012 90)
			(size 0.4572 0.4572)
			(layers "F.Cu" "F.Mask" "F.Paste")
			(net "GND")
		)
		(pad "V1" smd circle
			(at -12.500102 4.500118 90)
			(size 0.4572 0.4572)
			(layers "F.Cu" "F.Mask" "F.Paste")
			(net "GND")
		)
		(pad "V2" smd circle
			(at -11.500104 4.500118 90)
			(size 0.4572 0.4572)
			(layers "F.Cu" "F.Mask" "F.Paste")
			(net "GND")
		)
		(pad "V3" smd circle
			(at -10.500106 4.500118 90)
			(size 0.4572 0.4572)
			(layers "F.Cu" "F.Mask" "F.Paste")
			(net "GND")
		)
		(pad "V4" smd circle
			(at -9.500108 4.500118 90)
			(size 0.4572 0.4572)
			(layers "F.Cu" "F.Mask" "F.Paste")
			(net "TEST_MUX_44")
		)
		(pad "V5" smd circle
			(at -8.50011 4.500118 90)
			(size 0.4572 0.4572)
			(layers "F.Cu" "F.Mask" "F.Paste")
			(net "TEST_MUX_47")
		)
		(pad "V6" smd circle
			(at -7.500112 4.500118 90)
			(size 0.4572 0.4572)
			(layers "F.Cu" "F.Mask" "F.Paste")
			(net "GND")
		)
		(pad "V7" smd circle
			(at -6.500114 4.500118 90)
			(size 0.4572 0.4572)
			(layers "F.Cu" "F.Mask" "F.Paste")
			(net "GND")
		)
		(pad "V8" smd circle
			(at -5.500116 4.500118 90)
			(size 0.4572 0.4572)
			(layers "F.Cu" "F.Mask" "F.Paste")
			(net "GB_VDDH2")
		)
		(pad "V9" smd circle
			(at -4.500118 4.500118 90)
			(size 0.4572 0.4572)
			(layers "F.Cu" "F.Mask" "F.Paste")
			(net "GB_VDDH2")
		)
		(pad "V10" smd circle
			(at -3.50012 4.500118 90)
			(size 0.4572 0.4572)
			(layers "F.Cu" "F.Mask" "F.Paste")
			(net "GB_VDDH2")
		)
		(pad "V11" smd circle
			(at -2.500122 4.500118 90)
			(size 0.4572 0.4572)
			(layers "F.Cu" "F.Mask" "F.Paste")
			(net "GB_VDDH2")
		)
		(pad "V12" smd circle
			(at -1.500124 4.500118 90)
			(size 0.4572 0.4572)
			(layers "F.Cu" "F.Mask" "F.Paste")
			(net "GB_VDDH2")
		)
		(pad "V13" smd circle
			(at -0.500126 4.500118 90)
			(size 0.4572 0.4572)
			(layers "F.Cu" "F.Mask" "F.Paste")
			(net "GB_VDDH2")
		)
		(pad "V14" smd circle
			(at 0.500126 4.500118 90)
			(size 0.4572 0.4572)
			(layers "F.Cu" "F.Mask" "F.Paste")
			(net "GB_VDDH2")
		)
		(pad "V15" smd circle
			(at 1.500124 4.500118 90)
			(size 0.4572 0.4572)
			(layers "F.Cu" "F.Mask" "F.Paste")
			(net "GB_VDDH2")
		)
		(pad "V16" smd circle
			(at 2.500122 4.500118 90)
			(size 0.4572 0.4572)
			(layers "F.Cu" "F.Mask" "F.Paste")
			(net "GND")
		)
		(pad "V17" smd circle
			(at 3.50012 4.500118 90)
			(size 0.4572 0.4572)
			(layers "F.Cu" "F.Mask" "F.Paste")
			(net "GB_VDDA")
		)
		(pad "V18" smd circle
			(at 4.500118 4.500118 90)
			(size 0.4572 0.4572)
			(layers "F.Cu" "F.Mask" "F.Paste")
			(net "GND")
		)
		(pad "V19" smd circle
			(at 5.500116 4.500118 90)
			(size 0.4572 0.4572)
			(layers "F.Cu" "F.Mask" "F.Paste")
			(net "GND")
		)
		(pad "V20" smd circle
			(at 6.500114 4.500118 90)
			(size 0.4572 0.4572)
			(layers "F.Cu" "F.Mask" "F.Paste")
			(net "GB_VDDA")
		)
		(pad "V21" smd circle
			(at 7.500112 4.500118 90)
			(size 0.4572 0.4572)
			(layers "F.Cu" "F.Mask" "F.Paste")
			(net "Net_1086")
		)
		(pad "V22" smd circle
			(at 8.50011 4.500118 90)
			(size 0.4572 0.4572)
			(layers "F.Cu" "F.Mask" "F.Paste")
			(net "Net_1085")
		)
		(pad "V23" smd circle
			(at 9.500108 4.500118 90)
			(size 0.4572 0.4572)
			(layers "F.Cu" "F.Mask" "F.Paste")
			(net "GND")
		)
		(pad "V24" smd circle
			(at 10.500106 4.500118 90)
			(size 0.4572 0.4572)
			(layers "F.Cu" "F.Mask" "F.Paste")
			(net "GB_VDDA")
		)
		(pad "V25" smd circle
			(at 11.500104 4.500118 90)
			(size 0.4572 0.4572)
			(layers "F.Cu" "F.Mask" "F.Paste")
			(net "Net_1084")
		)
		(pad "V26" smd circle
			(at 12.500102 4.500118 90)
			(size 0.4572 0.4572)
			(layers "F.Cu" "F.Mask" "F.Paste")
			(net "Net_1078")
		)
		(pad "W1" smd circle
			(at -12.500102 5.500116 90)
			(size 0.4572 0.4572)
			(layers "F.Cu" "F.Mask" "F.Paste")
			(net "EXP_REF_CLK_N")
		)
		(pad "W2" smd circle
			(at -11.500104 5.500116 90)
			(size 0.4572 0.4572)
			(layers "F.Cu" "F.Mask" "F.Paste")
			(net "EXP_REF_CLK_P")
		)
		(pad "W3" smd circle
			(at -10.500106 5.500116 90)
			(size 0.4572 0.4572)
			(layers "F.Cu" "F.Mask" "F.Paste")
			(net "XTAL_VDDA18")
		)
		(pad "W4" smd circle
			(at -9.500108 5.500116 90)
			(size 0.4572 0.4572)
			(layers "F.Cu" "F.Mask" "F.Paste")
			(net "GND")
		)
		(pad "W5" smd circle
			(at -8.50011 5.500116 90)
			(size 0.4572 0.4572)
			(layers "F.Cu" "F.Mask" "F.Paste")
			(net "GND")
		)
		(pad "W6" smd circle
			(at -7.500112 5.500116 90)
			(size 0.4572 0.4572)
			(layers "F.Cu" "F.Mask" "F.Paste")
			(net "GND")
		)
		(pad "W7" smd circle
			(at -6.500114 5.500116 90)
			(size 0.4572 0.4572)
			(layers "F.Cu" "F.Mask" "F.Paste")
			(net "GND")
		)
		(pad "W8" smd circle
			(at -5.500116 5.500116 90)
			(size 0.4572 0.4572)
			(layers "F.Cu" "F.Mask" "F.Paste")
			(net "GND")
		)
		(pad "W9" smd circle
			(at -4.500118 5.500116 90)
			(size 0.4572 0.4572)
			(layers "F.Cu" "F.Mask" "F.Paste")
			(net "GND")
		)
		(pad "W10" smd circle
			(at -3.50012 5.500116 90)
			(size 0.4572 0.4572)
			(layers "F.Cu" "F.Mask" "F.Paste")
			(net "GND")
		)
		(pad "W11" smd circle
			(at -2.500122 5.500116 90)
			(size 0.4572 0.4572)
			(layers "F.Cu" "F.Mask" "F.Paste")
			(net "GND")
		)
		(pad "W12" smd circle
			(at -1.500124 5.500116 90)
			(size 0.4572 0.4572)
			(layers "F.Cu" "F.Mask" "F.Paste")
			(net "GND")
		)
		(pad "W13" smd circle
			(at -0.500126 5.500116 90)
			(size 0.4572 0.4572)
			(layers "F.Cu" "F.Mask" "F.Paste")
			(net "GND")
		)
		(pad "W14" smd circle
			(at 0.500126 5.500116 90)
			(size 0.4572 0.4572)
			(layers "F.Cu" "F.Mask" "F.Paste")
			(net "GND")
		)
		(pad "W15" smd circle
			(at 1.500124 5.500116 90)
			(size 0.4572 0.4572)
			(layers "F.Cu" "F.Mask" "F.Paste")
			(net "GND")
		)
		(pad "W16" smd circle
			(at 2.500122 5.500116 90)
			(size 0.4572 0.4572)
			(layers "F.Cu" "F.Mask" "F.Paste")
			(net "GND")
		)
		(pad "W17" smd circle
			(at 3.50012 5.500116 90)
			(size 0.4572 0.4572)
			(layers "F.Cu" "F.Mask" "F.Paste")
			(net "GND")
		)
		(pad "W18" smd circle
			(at 4.500118 5.500116 90)
			(size 0.4572 0.4572)
			(layers "F.Cu" "F.Mask" "F.Paste")
			(net "GND")
		)
		(pad "W19" smd circle
			(at 5.500116 5.500116 90)
			(size 0.4572 0.4572)
			(layers "F.Cu" "F.Mask" "F.Paste")
			(net "GND")
		)
		(pad "W20" smd circle
			(at 6.500114 5.500116 90)
			(size 0.4572 0.4572)
			(layers "F.Cu" "F.Mask" "F.Paste")
			(net "GND")
		)
		(pad "W21" smd circle
			(at 7.500112 5.500116 90)
			(size 0.4572 0.4572)
			(layers "F.Cu" "F.Mask" "F.Paste")
			(net "Net_1083")
		)
		(pad "W22" smd circle
			(at 8.50011 5.500116 90)
			(size 0.4572 0.4572)
			(layers "F.Cu" "F.Mask" "F.Paste")
			(net "Net_1082")
		)
		(pad "W23" smd circle
			(at 9.500108 5.500116 90)
			(size 0.4572 0.4572)
			(layers "F.Cu" "F.Mask" "F.Paste")
			(net "GB_VDDA")
		)
		(pad "W24" smd circle
			(at 10.500106 5.500116 90)
			(size 0.4572 0.4572)
			(layers "F.Cu" "F.Mask" "F.Paste")
			(net "Net_1081")
		)
		(pad "W25" smd circle
			(at 11.500104 5.500116 90)
			(size 0.4572 0.4572)
			(layers "F.Cu" "F.Mask" "F.Paste")
			(net "Net_1080")
		)
		(pad "W26" smd circle
			(at 12.500102 5.500116 90)
			(size 0.4572 0.4572)
			(layers "F.Cu" "F.Mask" "F.Paste")
			(net "GND")
		)
		(pad "Y1" smd circle
			(at -12.500102 6.500114 90)
			(size 0.4572 0.4572)
			(layers "F.Cu" "F.Mask" "F.Paste")
			(net "GND")
		)
		(pad "Y2" smd circle
			(at -11.500104 6.500114 90)
			(size 0.4572 0.4572)
			(layers "F.Cu" "F.Mask" "F.Paste")
			(net "GND")
		)
		(pad "Y3" smd circle
			(at -10.500106 6.500114 90)
			(size 0.4572 0.4572)
			(layers "F.Cu" "F.Mask" "F.Paste")
			(net "GND")
		)
		(pad "Y4" smd circle
			(at -9.500108 6.500114 90)
			(size 0.4572 0.4572)
			(layers "F.Cu" "F.Mask" "F.Paste")
			(net "GND")
		)
		(pad "Y5" smd circle
			(at -8.50011 6.500114 90)
			(size 0.4572 0.4572)
			(layers "F.Cu" "F.Mask" "F.Paste")
			(net "GND")
		)
		(pad "Y6" smd circle
			(at -7.500112 6.500114 90)
			(size 0.4572 0.4572)
			(layers "F.Cu" "F.Mask" "F.Paste")
			(net "GB_VDDA")
		)
		(pad "Y7" smd circle
			(at -6.500114 6.500114 90)
			(size 0.4572 0.4572)
			(layers "F.Cu" "F.Mask" "F.Paste")
			(net "GND")
		)
		(pad "Y8" smd circle
			(at -5.500116 6.500114 90)
			(size 0.4572 0.4572)
			(layers "F.Cu" "F.Mask" "F.Paste")
			(net "GB_VDDA")
		)
		(pad "Y9" smd circle
			(at -4.500118 6.500114 90)
			(size 0.4572 0.4572)
			(layers "F.Cu" "F.Mask" "F.Paste")
			(net "GND")
		)
		(pad "Y10" smd circle
			(at -3.50012 6.500114 90)
			(size 0.4572 0.4572)
			(layers "F.Cu" "F.Mask" "F.Paste")
			(net "GB_VDDA")
		)
		(pad "Y11" smd circle
			(at -2.500122 6.500114 90)
			(size 0.4572 0.4572)
			(layers "F.Cu" "F.Mask" "F.Paste")
			(net "GND")
		)
		(pad "Y12" smd circle
			(at -1.500124 6.500114 90)
			(size 0.4572 0.4572)
			(layers "F.Cu" "F.Mask" "F.Paste")
			(net "GB_VDDA")
		)
		(pad "Y13" smd circle
			(at -0.500126 6.500114 90)
			(size 0.4572 0.4572)
			(layers "F.Cu" "F.Mask" "F.Paste")
			(net "GND")
		)
		(pad "Y14" smd circle
			(at 0.500126 6.500114 90)
			(size 0.4572 0.4572)
			(layers "F.Cu" "F.Mask" "F.Paste")
			(net "GB_VDDA")
		)
		(pad "Y15" smd circle
			(at 1.500124 6.500114 90)
			(size 0.4572 0.4572)
			(layers "F.Cu" "F.Mask" "F.Paste")
			(net "GND")
		)
		(pad "Y16" smd circle
			(at 2.500122 6.500114 90)
			(size 0.4572 0.4572)
			(layers "F.Cu" "F.Mask" "F.Paste")
			(net "GB_VDDA")
		)
		(pad "Y17" smd circle
			(at 3.50012 6.500114 90)
			(size 0.4572 0.4572)
			(layers "F.Cu" "F.Mask" "F.Paste")
			(net "GND")
		)
		(pad "Y18" smd circle
			(at 4.500118 6.500114 90)
			(size 0.4572 0.4572)
			(layers "F.Cu" "F.Mask" "F.Paste")
			(net "GB_VDDA")
		)
		(pad "Y19" smd circle
			(at 5.500116 6.500114 90)
			(size 0.4572 0.4572)
			(layers "F.Cu" "F.Mask" "F.Paste")
			(net "GND")
		)
		(pad "Y20" smd circle
			(at 6.500114 6.500114 90)
			(size 0.4572 0.4572)
			(layers "F.Cu" "F.Mask" "F.Paste")
			(net "GB_VDDA")
		)
		(pad "Y21" smd circle
			(at 7.500112 6.500114 90)
			(size 0.4572 0.4572)
			(layers "F.Cu" "F.Mask" "F.Paste")
			(net "Net_1107")
		)
		(pad "Y22" smd circle
			(at 8.50011 6.500114 90)
			(size 0.4572 0.4572)
			(layers "F.Cu" "F.Mask" "F.Paste")
			(net "Net_1106")
		)
		(pad "Y23" smd circle
			(at 9.500108 6.500114 90)
			(size 0.4572 0.4572)
			(layers "F.Cu" "F.Mask" "F.Paste")
			(net "GND")
		)
		(pad "Y24" smd circle
			(at 10.500106 6.500114 90)
			(size 0.4572 0.4572)
			(layers "F.Cu" "F.Mask" "F.Paste")
			(net "GB_VDDA")
		)
		(pad "Y25" smd circle
			(at 11.500104 6.500114 90)
			(size 0.4572 0.4572)
			(layers "F.Cu" "F.Mask" "F.Paste")
			(net "Net_1105")
		)
		(pad "Y26" smd circle
			(at 12.500102 6.500114 90)
			(size 0.4572 0.4572)
			(layers "F.Cu" "F.Mask" "F.Paste")
			(net "Net_1079")
		)
		(zone
			(layer "F.Cu")
			(hatch none 0.5)
			(connect_pads
				(clearance 0)
			)
			(min_thickness 0.25)
			(keepout
				(tracks allowed)
				(vias not_allowed)
				(pads allowed)
				(copperpour not_allowed)
				(footprints allowed)
			)
			(placement
				(enabled no)
				(sheetname "")
			)
			(fill
				(thermal_gap 0.5)
				(thermal_bridge_width 0.5)
				(island_removal_mode 0)
			)
			(polygon
				(pts
					(arc
						(start 102.730808 -104.350058)
						(mid 101.968808 -104.350058)
						(end 102.730808 -104.350058)
					)
				)
			)
		)
		(zone
			(layer "F.Cu")
			(hatch none 0.5)
			(connect_pads
				(clearance 0)
			)
			(min_thickness 0.25)
			(keepout
				(tracks allowed)
				(vias not_allowed)
				(pads allowed)
				(copperpour not_allowed)
				(footprints allowed)
			)
			(placement
				(enabled no)
				(sheetname "")
			)
			(fill
				(thermal_gap 0.5)
				(thermal_bridge_width 0.5)
				(island_removal_mode 0)
			)
			(polygon
				(pts
					(arc
						(start 102.730808 -103.35006)
						(mid 101.968808 -103.35006)
						(end 102.730808 -103.35006)
					)
				)
			)
		)
		(zone
			(layer "F.Cu")
			(hatch none 0.5)
			(connect_pads
				(clearance 0)
			)
			(min_thickness 0.25)
			(keepout
				(tracks allowed)
				(vias not_allowed)
				(pads allowed)
				(copperpour not_allowed)
				(footprints allowed)
			)
			(placement
				(enabled no)
				(sheetname "")
			)
			(fill
				(thermal_gap 0.5)
				(thermal_bridge_width 0.5)
				(island_removal_mode 0)
			)
			(polygon
				(pts
					(arc
						(start 102.730808 -102.350062)
						(mid 101.968808 -102.350062)
						(end 102.730808 -102.350062)
					)
				)
			)
		)
		(zone
			(layer "F.Cu")
			(hatch none 0.5)
			(connect_pads
				(clearance 0)
			)
			(min_thickness 0.25)
			(keepout
				(tracks allowed)
				(vias not_allowed)
				(pads allowed)
				(copperpour not_allowed)
				(footprints allowed)
			)
			(placement
				(enabled no)
				(sheetname "")
			)
			(fill
				(thermal_gap 0.5)
				(thermal_bridge_width 0.5)
				(island_removal_mode 0)
			)
			(polygon
				(pts
					(arc
						(start 102.730808 -101.350064)
						(mid 101.968808 -101.350064)
						(end 102.730808 -101.350064)
					)
				)
			)
		)
		(zone
			(layer "F.Cu")
			(hatch none 0.5)
			(connect_pads
				(clearance 0)
			)
			(min_thickness 0.25)
			(keepout
				(tracks allowed)
				(vias not_allowed)
				(pads allowed)
				(copperpour not_allowed)
				(footprints allowed)
			)
			(placement
				(enabled no)
				(sheetname "")
			)
			(fill
				(thermal_gap 0.5)
				(thermal_bridge_width 0.5)
				(island_removal_mode 0)
			)
			(polygon
				(pts
					(arc
						(start 102.730808 -100.350066)
						(mid 101.968808 -100.350066)
						(end 102.730808 -100.350066)
					)
				)
			)
		)
		(zone
			(layer "F.Cu")
			(hatch none 0.5)
			(connect_pads
				(clearance 0)
			)
			(min_thickness 0.25)
			(keepout
				(tracks allowed)
				(vias not_allowed)
				(pads allowed)
				(copperpour not_allowed)
				(footprints allowed)
			)
			(placement
				(enabled no)
				(sheetname "")
			)
			(fill
				(thermal_gap 0.5)
				(thermal_bridge_width 0.5)
				(island_removal_mode 0)
			)
			(polygon
				(pts
					(arc
						(start 102.730808 -99.350068)
						(mid 101.968808 -99.350068)
						(end 102.730808 -99.350068)
					)
				)
			)
		)
		(zone
			(layer "F.Cu")
			(hatch none 0.5)
			(connect_pads
				(clearance 0)
			)
			(min_thickness 0.25)
			(keepout
				(tracks allowed)
				(vias not_allowed)
				(pads allowed)
				(copperpour not_allowed)
				(footprints allowed)
			)
			(placement
				(enabled no)
				(sheetname "")
			)
			(fill
				(thermal_gap 0.5)
				(thermal_bridge_width 0.5)
				(island_removal_mode 0)
			)
			(polygon
				(pts
					(arc
						(start 102.730808 -98.35007)
						(mid 101.968808 -98.35007)
						(end 102.730808 -98.35007)
					)
				)
			)
		)
		(zone
			(layer "F.Cu")
			(hatch none 0.5)
			(connect_pads
				(clearance 0)
			)
			(min_thickness 0.25)
			(keepout
				(tracks allowed)
				(vias not_allowed)
				(pads allowed)
				(copperpour not_allowed)
				(footprints allowed)
			)
			(placement
				(enabled no)
				(sheetname "")
			)
			(fill
				(thermal_gap 0.5)
				(thermal_bridge_width 0.5)
				(island_removal_mode 0)
			)
			(polygon
				(pts
					(arc
						(start 102.730808 -97.350072)
						(mid 101.968808 -97.350072)
						(end 102.730808 -97.350072)
					)
				)
			)
		)
		(zone
			(layer "F.Cu")
			(hatch none 0.5)
			(connect_pads
				(clearance 0)
			)
			(min_thickness 0.25)
			(keepout
				(tracks allowed)
				(vias not_allowed)
				(pads allowed)
				(copperpour not_allowed)
				(footprints allowed)
			)
			(placement
				(enabled no)
				(sheetname "")
			)
			(fill
				(thermal_gap 0.5)
				(thermal_bridge_width 0.5)
				(island_removal_mode 0)
			)
			(polygon
				(pts
					(arc
						(start 102.730808 -96.350074)
						(mid 101.968808 -96.350074)
						(end 102.730808 -96.350074)
					)
				)
			)
		)
		(zone
			(layer "F.Cu")
			(hatch none 0.5)
			(connect_pads
				(clearance 0)
			)
			(min_thickness 0.25)
			(keepout
				(tracks allowed)
				(vias not_allowed)
				(pads allowed)
				(copperpour not_allowed)
				(footprints allowed)
			)
			(placement
				(enabled no)
				(sheetname "")
			)
			(fill
				(thermal_gap 0.5)
				(thermal_bridge_width 0.5)
				(island_removal_mode 0)
			)
			(polygon
				(pts
					(arc
						(start 102.730808 -95.350076)
						(mid 101.968808 -95.350076)
						(end 102.730808 -95.350076)
					)
				)
			)
		)
		(zone
			(layer "F.Cu")
			(hatch none 0.5)
			(connect_pads
				(clearance 0)
			)
			(min_thickness 0.25)
			(keepout
				(tracks allowed)
				(vias not_allowed)
				(pads allowed)
				(copperpour not_allowed)
				(footprints allowed)
			)
			(placement
				(enabled no)
				(sheetname "")
			)
			(fill
				(thermal_gap 0.5)
				(thermal_bridge_width 0.5)
				(island_removal_mode 0)
			)
			(polygon
				(pts
					(arc
						(start 102.730808 -94.349824)
						(mid 101.968808 -94.349824)
						(end 102.730808 -94.349824)
					)
				)
			)
		)
		(zone
			(layer "F.Cu")
			(hatch none 0.5)
			(connect_pads
				(clearance 0)
			)
			(min_thickness 0.25)
			(keepout
				(tracks allowed)
				(vias not_allowed)
				(pads allowed)
				(copperpour not_allowed)
				(footprints allowed)
			)
			(placement
				(enabled no)
				(sheetname "")
			)
			(fill
				(thermal_gap 0.5)
				(thermal_bridge_width 0.5)
				(island_removal_mode 0)
			)
			(polygon
				(pts
					(arc
						(start 102.730808 -93.349826)
						(mid 101.968808 -93.349826)
						(end 102.730808 -93.349826)
					)
				)
			)
		)
		(zone
			(layer "F.Cu")
			(hatch none 0.5)
			(connect_pads
				(clearance 0)
			)
			(min_thickness 0.25)
			(keepout
				(tracks allowed)
				(vias not_allowed)
				(pads allowed)
				(copperpour not_allowed)
				(footprints allowed)
			)
			(placement
				(enabled no)
				(sheetname "")
			)
			(fill
				(thermal_gap 0.5)
				(thermal_bridge_width 0.5)
				(island_removal_mode 0)
			)
			(polygon
				(pts
					(arc
						(start 102.730808 -92.349828)
						(mid 101.968808 -92.349828)
						(end 102.730808 -92.349828)
					)
				)
			)
		)
		(zone
			(layer "F.Cu")
			(hatch none 0.5)
			(connect_pads
				(clearance 0)
			)
			(min_thickness 0.25)
			(keepout
				(tracks allowed)
				(vias not_allowed)
				(pads allowed)
				(copperpour not_allowed)
				(footprints allowed)
			)
			(placement
				(enabled no)
				(sheetname "")
			)
			(fill
				(thermal_gap 0.5)
				(thermal_bridge_width 0.5)
				(island_removal_mode 0)
			)
			(polygon
				(pts
					(arc
						(start 102.730808 -91.34983)
						(mid 101.968808 -91.34983)
						(end 102.730808 -91.34983)
					)
				)
			)
		)
		(zone
			(layer "F.Cu")
			(hatch none 0.5)
			(connect_pads
				(clearance 0)
			)
			(min_thickness 0.25)
			(keepout
				(tracks allowed)
				(vias not_allowed)
				(pads allowed)
				(copperpour not_allowed)
				(footprints allowed)
			)
			(placement
				(enabled no)
				(sheetname "")
			)
			(fill
				(thermal_gap 0.5)
				(thermal_bridge_width 0.5)
				(island_removal_mode 0)
			)
			(polygon
				(pts
					(arc
						(start 102.730808 -90.349832)
						(mid 101.968808 -90.349832)
						(end 102.730808 -90.349832)
					)
				)
			)
		)
		(zone
			(layer "F.Cu")
			(hatch none 0.5)
			(connect_pads
				(clearance 0)
			)
			(min_thickness 0.25)
			(keepout
				(tracks allowed)
				(vias not_allowed)
				(pads allowed)
				(copperpour not_allowed)
				(footprints allowed)
			)
			(placement
				(enabled no)
				(sheetname "")
			)
			(fill
				(thermal_gap 0.5)
				(thermal_bridge_width 0.5)
				(island_removal_mode 0)
			)
			(polygon
				(pts
					(arc
						(start 102.730808 -89.349834)
						(mid 101.968808 -89.349834)
						(end 102.730808 -89.349834)
					)
				)
			)
		)
		(zone
			(layer "F.Cu")
			(hatch none 0.5)
			(connect_pads
				(clearance 0)
			)
			(min_thickness 0.25)
			(keepout
				(tracks allowed)
				(vias not_allowed)
				(pads allowed)
				(copperpour not_allowed)
				(footprints allowed)
			)
			(placement
				(enabled no)
				(sheetname "")
			)
			(fill
				(thermal_gap 0.5)
				(thermal_bridge_width 0.5)
				(island_removal_mode 0)
			)
			(polygon
				(pts
					(arc
						(start 102.730808 -88.349836)
						(mid 101.968808 -88.349836)
						(end 102.730808 -88.349836)
					)
				)
			)
		)
		(zone
			(layer "F.Cu")
			(hatch none 0.5)
			(connect_pads
				(clearance 0)
			)
			(min_thickness 0.25)
			(keepout
				(tracks allowed)
				(vias not_allowed)
				(pads allowed)
				(copperpour not_allowed)
				(footprints allowed)
			)
			(placement
				(enabled no)
				(sheetname "")
			)
			(fill
				(thermal_gap 0.5)
				(thermal_bridge_width 0.5)
				(island_removal_mode 0)
			)
			(polygon
				(pts
					(arc
						(start 102.730808 -87.349838)
						(mid 101.968808 -87.349838)
						(end 102.730808 -87.349838)
					)
				)
			)
		)
		(zone
			(layer "F.Cu")
			(hatch none 0.5)
			(connect_pads
				(clearance 0)
			)
			(min_thickness 0.25)
			(keepout
				(tracks allowed)
				(vias not_allowed)
				(pads allowed)
				(copperpour not_allowed)
				(footprints allowed)
			)
			(placement
				(enabled no)
				(sheetname "")
			)
			(fill
				(thermal_gap 0.5)
				(thermal_bridge_width 0.5)
				(island_removal_mode 0)
			)
			(polygon
				(pts
					(arc
						(start 102.730808 -86.34984)
						(mid 101.968808 -86.34984)
						(end 102.730808 -86.34984)
					)
				)
			)
		)
		(zone
			(layer "F.Cu")
			(hatch none 0.5)
			(connect_pads
				(clearance 0)
			)
			(min_thickness 0.25)
			(keepout
				(tracks allowed)
				(vias not_allowed)
				(pads allowed)
				(copperpour not_allowed)
				(footprints allowed)
			)
			(placement
				(enabled no)
				(sheetname "")
			)
			(fill
				(thermal_gap 0.5)
				(thermal_bridge_width 0.5)
				(island_removal_mode 0)
			)
			(polygon
				(pts
					(arc
						(start 102.730808 -85.349842)
						(mid 101.968808 -85.349842)
						(end 102.730808 -85.349842)
					)
				)
			)
		)
		(zone
			(layer "F.Cu")
			(hatch none 0.5)
			(connect_pads
				(clearance 0)
			)
			(min_thickness 0.25)
			(keepout
				(tracks allowed)
				(vias not_allowed)
				(pads allowed)
				(copperpour not_allowed)
				(footprints allowed)
			)
			(placement
				(enabled no)
				(sheetname "")
			)
			(fill
				(thermal_gap 0.5)
				(thermal_bridge_width 0.5)
				(island_removal_mode 0)
			)
			(polygon
				(pts
					(arc
						(start 103.730806 -104.350058)
						(mid 102.968806 -104.350058)
						(end 103.730806 -104.350058)
					)
				)
			)
		)
		(zone
			(layer "F.Cu")
			(hatch none 0.5)
			(connect_pads
				(clearance 0)
			)
			(min_thickness 0.25)
			(keepout
				(tracks allowed)
				(vias not_allowed)
				(pads allowed)
				(copperpour not_allowed)
				(footprints allowed)
			)
			(placement
				(enabled no)
				(sheetname "")
			)
			(fill
				(thermal_gap 0.5)
				(thermal_bridge_width 0.5)
				(island_removal_mode 0)
			)
			(polygon
				(pts
					(arc
						(start 103.730806 -103.35006)
						(mid 102.968806 -103.35006)
						(end 103.730806 -103.35006)
					)
				)
			)
		)
		(zone
			(layer "F.Cu")
			(hatch none 0.5)
			(connect_pads
				(clearance 0)
			)
			(min_thickness 0.25)
			(keepout
				(tracks allowed)
				(vias not_allowed)
				(pads allowed)
				(copperpour not_allowed)
				(footprints allowed)
			)
			(placement
				(enabled no)
				(sheetname "")
			)
			(fill
				(thermal_gap 0.5)
				(thermal_bridge_width 0.5)
				(island_removal_mode 0)
			)
			(polygon
				(pts
					(arc
						(start 103.730806 -102.350062)
						(mid 102.968806 -102.350062)
						(end 103.730806 -102.350062)
					)
				)
			)
		)
		(zone
			(layer "F.Cu")
			(hatch none 0.5)
			(connect_pads
				(clearance 0)
			)
			(min_thickness 0.25)
			(keepout
				(tracks allowed)
				(vias not_allowed)
				(pads allowed)
				(copperpour not_allowed)
				(footprints allowed)
			)
			(placement
				(enabled no)
				(sheetname "")
			)
			(fill
				(thermal_gap 0.5)
				(thermal_bridge_width 0.5)
				(island_removal_mode 0)
			)
			(polygon
				(pts
					(arc
						(start 103.730806 -101.350064)
						(mid 102.968806 -101.350064)
						(end 103.730806 -101.350064)
					)
				)
			)
		)
		(zone
			(layer "F.Cu")
			(hatch none 0.5)
			(connect_pads
				(clearance 0)
			)
			(min_thickness 0.25)
			(keepout
				(tracks allowed)
				(vias not_allowed)
				(pads allowed)
				(copperpour not_allowed)
				(footprints allowed)
			)
			(placement
				(enabled no)
				(sheetname "")
			)
			(fill
				(thermal_gap 0.5)
				(thermal_bridge_width 0.5)
				(island_removal_mode 0)
			)
			(polygon
				(pts
					(arc
						(start 103.730806 -100.350066)
						(mid 102.968806 -100.350066)
						(end 103.730806 -100.350066)
					)
				)
			)
		)
		(zone
			(layer "F.Cu")
			(hatch none 0.5)
			(connect_pads
				(clearance 0)
			)
			(min_thickness 0.25)
			(keepout
				(tracks allowed)
				(vias not_allowed)
				(pads allowed)
				(copperpour not_allowed)
				(footprints allowed)
			)
			(placement
				(enabled no)
				(sheetname "")
			)
			(fill
				(thermal_gap 0.5)
				(thermal_bridge_width 0.5)
				(island_removal_mode 0)
			)
			(polygon
				(pts
					(arc
						(start 103.730806 -99.350068)
						(mid 102.968806 -99.350068)
						(end 103.730806 -99.350068)
					)
				)
			)
		)
		(zone
			(layer "F.Cu")
			(hatch none 0.5)
			(connect_pads
				(clearance 0)
			)
			(min_thickness 0.25)
			(keepout
				(tracks allowed)
				(vias not_allowed)
				(pads allowed)
				(copperpour not_allowed)
				(footprints allowed)
			)
			(placement
				(enabled no)
				(sheetname "")
			)
			(fill
				(thermal_gap 0.5)
				(thermal_bridge_width 0.5)
				(island_removal_mode 0)
			)
			(polygon
				(pts
					(arc
						(start 103.730806 -98.35007)
						(mid 102.968806 -98.35007)
						(end 103.730806 -98.35007)
					)
				)
			)
		)
		(zone
			(layer "F.Cu")
			(hatch none 0.5)
			(connect_pads
				(clearance 0)
			)
			(min_thickness 0.25)
			(keepout
				(tracks allowed)
				(vias not_allowed)
				(pads allowed)
				(copperpour not_allowed)
				(footprints allowed)
			)
			(placement
				(enabled no)
				(sheetname "")
			)
			(fill
				(thermal_gap 0.5)
				(thermal_bridge_width 0.5)
				(island_removal_mode 0)
			)
			(polygon
				(pts
					(arc
						(start 103.730806 -97.350072)
						(mid 102.968806 -97.350072)
						(end 103.730806 -97.350072)
					)
				)
			)
		)
		(zone
			(layer "F.Cu")
			(hatch none 0.5)
			(connect_pads
				(clearance 0)
			)
			(min_thickness 0.25)
			(keepout
				(tracks allowed)
				(vias not_allowed)
				(pads allowed)
				(copperpour not_allowed)
				(footprints allowed)
			)
			(placement
				(enabled no)
				(sheetname "")
			)
			(fill
				(thermal_gap 0.5)
				(thermal_bridge_width 0.5)
				(island_removal_mode 0)
			)
			(polygon
				(pts
					(arc
						(start 103.730806 -96.350074)
						(mid 102.968806 -96.350074)
						(end 103.730806 -96.350074)
					)
				)
			)
		)
		(zone
			(layer "F.Cu")
			(hatch none 0.5)
			(connect_pads
				(clearance 0)
			)
			(min_thickness 0.25)
			(keepout
				(tracks allowed)
				(vias not_allowed)
				(pads allowed)
				(copperpour not_allowed)
				(footprints allowed)
			)
			(placement
				(enabled no)
				(sheetname "")
			)
			(fill
				(thermal_gap 0.5)
				(thermal_bridge_width 0.5)
				(island_removal_mode 0)
			)
			(polygon
				(pts
					(arc
						(start 103.730806 -95.350076)
						(mid 102.968806 -95.350076)
						(end 103.730806 -95.350076)
					)
				)
			)
		)
		(zone
			(layer "F.Cu")
			(hatch none 0.5)
			(connect_pads
				(clearance 0)
			)
			(min_thickness 0.25)
			(keepout
				(tracks allowed)
				(vias not_allowed)
				(pads allowed)
				(copperpour not_allowed)
				(footprints allowed)
			)
			(placement
				(enabled no)
				(sheetname "")
			)
			(fill
				(thermal_gap 0.5)
				(thermal_bridge_width 0.5)
				(island_removal_mode 0)
			)
			(polygon
				(pts
					(arc
						(start 103.730806 -94.349824)
						(mid 102.968806 -94.349824)
						(end 103.730806 -94.349824)
					)
				)
			)
		)
		(zone
			(layer "F.Cu")
			(hatch none 0.5)
			(connect_pads
				(clearance 0)
			)
			(min_thickness 0.25)
			(keepout
				(tracks allowed)
				(vias not_allowed)
				(pads allowed)
				(copperpour not_allowed)
				(footprints allowed)
			)
			(placement
				(enabled no)
				(sheetname "")
			)
			(fill
				(thermal_gap 0.5)
				(thermal_bridge_width 0.5)
				(island_removal_mode 0)
			)
			(polygon
				(pts
					(arc
						(start 103.730806 -93.349826)
						(mid 102.968806 -93.349826)
						(end 103.730806 -93.349826)
					)
				)
			)
		)
		(zone
			(layer "F.Cu")
			(hatch none 0.5)
			(connect_pads
				(clearance 0)
			)
			(min_thickness 0.25)
			(keepout
				(tracks allowed)
				(vias not_allowed)
				(pads allowed)
				(copperpour not_allowed)
				(footprints allowed)
			)
			(placement
				(enabled no)
				(sheetname "")
			)
			(fill
				(thermal_gap 0.5)
				(thermal_bridge_width 0.5)
				(island_removal_mode 0)
			)
			(polygon
				(pts
					(arc
						(start 103.730806 -92.349828)
						(mid 102.968806 -92.349828)
						(end 103.730806 -92.349828)
					)
				)
			)
		)
		(zone
			(layer "F.Cu")
			(hatch none 0.5)
			(connect_pads
				(clearance 0)
			)
			(min_thickness 0.25)
			(keepout
				(tracks allowed)
				(vias not_allowed)
				(pads allowed)
				(copperpour not_allowed)
				(footprints allowed)
			)
			(placement
				(enabled no)
				(sheetname "")
			)
			(fill
				(thermal_gap 0.5)
				(thermal_bridge_width 0.5)
				(island_removal_mode 0)
			)
			(polygon
				(pts
					(arc
						(start 103.730806 -91.34983)
						(mid 102.968806 -91.34983)
						(end 103.730806 -91.34983)
					)
				)
			)
		)
		(zone
			(layer "F.Cu")
			(hatch none 0.5)
			(connect_pads
				(clearance 0)
			)
			(min_thickness 0.25)
			(keepout
				(tracks allowed)
				(vias not_allowed)
				(pads allowed)
				(copperpour not_allowed)
				(footprints allowed)
			)
			(placement
				(enabled no)
				(sheetname "")
			)
			(fill
				(thermal_gap 0.5)
				(thermal_bridge_width 0.5)
				(island_removal_mode 0)
			)
			(polygon
				(pts
					(arc
						(start 103.730806 -90.349832)
						(mid 102.968806 -90.349832)
						(end 103.730806 -90.349832)
					)
				)
			)
		)
		(zone
			(layer "F.Cu")
			(hatch none 0.5)
			(connect_pads
				(clearance 0)
			)
			(min_thickness 0.25)
			(keepout
				(tracks allowed)
				(vias not_allowed)
				(pads allowed)
				(copperpour not_allowed)
				(footprints allowed)
			)
			(placement
				(enabled no)
				(sheetname "")
			)
			(fill
				(thermal_gap 0.5)
				(thermal_bridge_width 0.5)
				(island_removal_mode 0)
			)
			(polygon
				(pts
					(arc
						(start 103.730806 -89.349834)
						(mid 102.968806 -89.349834)
						(end 103.730806 -89.349834)
					)
				)
			)
		)
		(zone
			(layer "F.Cu")
			(hatch none 0.5)
			(connect_pads
				(clearance 0)
			)
			(min_thickness 0.25)
			(keepout
				(tracks allowed)
				(vias not_allowed)
				(pads allowed)
				(copperpour not_allowed)
				(footprints allowed)
			)
			(placement
				(enabled no)
				(sheetname "")
			)
			(fill
				(thermal_gap 0.5)
				(thermal_bridge_width 0.5)
				(island_removal_mode 0)
			)
			(polygon
				(pts
					(arc
						(start 103.730806 -88.349836)
						(mid 102.968806 -88.349836)
						(end 103.730806 -88.349836)
					)
				)
			)
		)
		(zone
			(layer "F.Cu")
			(hatch none 0.5)
			(connect_pads
				(clearance 0)
			)
			(min_thickness 0.25)
			(keepout
				(tracks allowed)
				(vias not_allowed)
				(pads allowed)
				(copperpour not_allowed)
				(footprints allowed)
			)
			(placement
				(enabled no)
				(sheetname "")
			)
			(fill
				(thermal_gap 0.5)
				(thermal_bridge_width 0.5)
				(island_removal_mode 0)
			)
			(polygon
				(pts
					(arc
						(start 103.730806 -87.349838)
						(mid 102.968806 -87.349838)
						(end 103.730806 -87.349838)
					)
				)
			)
		)
		(zone
			(layer "F.Cu")
			(hatch none 0.5)
			(connect_pads
				(clearance 0)
			)
			(min_thickness 0.25)
			(keepout
				(tracks allowed)
				(vias not_allowed)
				(pads allowed)
				(copperpour not_allowed)
				(footprints allowed)
			)
			(placement
				(enabled no)
				(sheetname "")
			)
			(fill
				(thermal_gap 0.5)
				(thermal_bridge_width 0.5)
				(island_removal_mode 0)
			)
			(polygon
				(pts
					(arc
						(start 103.730806 -86.34984)
						(mid 102.968806 -86.34984)
						(end 103.730806 -86.34984)
					)
				)
			)
		)
		(zone
			(layer "F.Cu")
			(hatch none 0.5)
			(connect_pads
				(clearance 0)
			)
			(min_thickness 0.25)
			(keepout
				(tracks allowed)
				(vias not_allowed)
				(pads allowed)
				(copperpour not_allowed)
				(footprints allowed)
			)
			(placement
				(enabled no)
				(sheetname "")
			)
			(fill
				(thermal_gap 0.5)
				(thermal_bridge_width 0.5)
				(island_removal_mode 0)
			)
			(polygon
				(pts
					(arc
						(start 103.730806 -85.349842)
						(mid 102.968806 -85.349842)
						(end 103.730806 -85.349842)
					)
				)
			)
		)
		(zone
			(layer "F.Cu")
			(hatch none 0.5)
			(connect_pads
				(clearance 0)
			)
			(min_thickness 0.25)
			(keepout
				(tracks allowed)
				(vias not_allowed)
				(pads allowed)
				(copperpour not_allowed)
				(footprints allowed)
			)
			(placement
				(enabled no)
				(sheetname "")
			)
			(fill
				(thermal_gap 0.5)
				(thermal_bridge_width 0.5)
				(island_removal_mode 0)
			)
			(polygon
				(pts
					(arc
						(start 104.730804 -104.350058)
						(mid 103.968804 -104.350058)
						(end 104.730804 -104.350058)
					)
				)
			)
		)
		(zone
			(layer "F.Cu")
			(hatch none 0.5)
			(connect_pads
				(clearance 0)
			)
			(min_thickness 0.25)
			(keepout
				(tracks allowed)
				(vias not_allowed)
				(pads allowed)
				(copperpour not_allowed)
				(footprints allowed)
			)
			(placement
				(enabled no)
				(sheetname "")
			)
			(fill
				(thermal_gap 0.5)
				(thermal_bridge_width 0.5)
				(island_removal_mode 0)
			)
			(polygon
				(pts
					(arc
						(start 104.730804 -103.35006)
						(mid 103.968804 -103.35006)
						(end 104.730804 -103.35006)
					)
				)
			)
		)
		(zone
			(layer "F.Cu")
			(hatch none 0.5)
			(connect_pads
				(clearance 0)
			)
			(min_thickness 0.25)
			(keepout
				(tracks allowed)
				(vias not_allowed)
				(pads allowed)
				(copperpour not_allowed)
				(footprints allowed)
			)
			(placement
				(enabled no)
				(sheetname "")
			)
			(fill
				(thermal_gap 0.5)
				(thermal_bridge_width 0.5)
				(island_removal_mode 0)
			)
			(polygon
				(pts
					(arc
						(start 104.730804 -102.350062)
						(mid 103.968804 -102.350062)
						(end 104.730804 -102.350062)
					)
				)
			)
		)
		(zone
			(layer "F.Cu")
			(hatch none 0.5)
			(connect_pads
				(clearance 0)
			)
			(min_thickness 0.25)
			(keepout
				(tracks allowed)
				(vias not_allowed)
				(pads allowed)
				(copperpour not_allowed)
				(footprints allowed)
			)
			(placement
				(enabled no)
				(sheetname "")
			)
			(fill
				(thermal_gap 0.5)
				(thermal_bridge_width 0.5)
				(island_removal_mode 0)
			)
			(polygon
				(pts
					(arc
						(start 104.730804 -101.350064)
						(mid 103.968804 -101.350064)
						(end 104.730804 -101.350064)
					)
				)
			)
		)
		(zone
			(layer "F.Cu")
			(hatch none 0.5)
			(connect_pads
				(clearance 0)
			)
			(min_thickness 0.25)
			(keepout
				(tracks allowed)
				(vias not_allowed)
				(pads allowed)
				(copperpour not_allowed)
				(footprints allowed)
			)
			(placement
				(enabled no)
				(sheetname "")
			)
			(fill
				(thermal_gap 0.5)
				(thermal_bridge_width 0.5)
				(island_removal_mode 0)
			)
			(polygon
				(pts
					(arc
						(start 104.730804 -100.350066)
						(mid 103.968804 -100.350066)
						(end 104.730804 -100.350066)
					)
				)
			)
		)
		(zone
			(layer "F.Cu")
			(hatch none 0.5)
			(connect_pads
				(clearance 0)
			)
			(min_thickness 0.25)
			(keepout
				(tracks allowed)
				(vias not_allowed)
				(pads allowed)
				(copperpour not_allowed)
				(footprints allowed)
			)
			(placement
				(enabled no)
				(sheetname "")
			)
			(fill
				(thermal_gap 0.5)
				(thermal_bridge_width 0.5)
				(island_removal_mode 0)
			)
			(polygon
				(pts
					(arc
						(start 104.730804 -99.350068)
						(mid 103.968804 -99.350068)
						(end 104.730804 -99.350068)
					)
				)
			)
		)
		(zone
			(layer "F.Cu")
			(hatch none 0.5)
			(connect_pads
				(clearance 0)
			)
			(min_thickness 0.25)
			(keepout
				(tracks allowed)
				(vias not_allowed)
				(pads allowed)
				(copperpour not_allowed)
				(footprints allowed)
			)
			(placement
				(enabled no)
				(sheetname "")
			)
			(fill
				(thermal_gap 0.5)
				(thermal_bridge_width 0.5)
				(island_removal_mode 0)
			)
			(polygon
				(pts
					(arc
						(start 104.730804 -98.35007)
						(mid 103.968804 -98.35007)
						(end 104.730804 -98.35007)
					)
				)
			)
		)
		(zone
			(layer "F.Cu")
			(hatch none 0.5)
			(connect_pads
				(clearance 0)
			)
			(min_thickness 0.25)
			(keepout
				(tracks allowed)
				(vias not_allowed)
				(pads allowed)
				(copperpour not_allowed)
				(footprints allowed)
			)
			(placement
				(enabled no)
				(sheetname "")
			)
			(fill
				(thermal_gap 0.5)
				(thermal_bridge_width 0.5)
				(island_removal_mode 0)
			)
			(polygon
				(pts
					(arc
						(start 104.730804 -97.350072)
						(mid 103.968804 -97.350072)
						(end 104.730804 -97.350072)
					)
				)
			)
		)
		(zone
			(layer "F.Cu")
			(hatch none 0.5)
			(connect_pads
				(clearance 0)
			)
			(min_thickness 0.25)
			(keepout
				(tracks allowed)
				(vias not_allowed)
				(pads allowed)
				(copperpour not_allowed)
				(footprints allowed)
			)
			(placement
				(enabled no)
				(sheetname "")
			)
			(fill
				(thermal_gap 0.5)
				(thermal_bridge_width 0.5)
				(island_removal_mode 0)
			)
			(polygon
				(pts
					(arc
						(start 104.730804 -96.350074)
						(mid 103.968804 -96.350074)
						(end 104.730804 -96.350074)
					)
				)
			)
		)
		(zone
			(layer "F.Cu")
			(hatch none 0.5)
			(connect_pads
				(clearance 0)
			)
			(min_thickness 0.25)
			(keepout
				(tracks allowed)
				(vias not_allowed)
				(pads allowed)
				(copperpour not_allowed)
				(footprints allowed)
			)
			(placement
				(enabled no)
				(sheetname "")
			)
			(fill
				(thermal_gap 0.5)
				(thermal_bridge_width 0.5)
				(island_removal_mode 0)
			)
			(polygon
				(pts
					(arc
						(start 104.730804 -95.350076)
						(mid 103.968804 -95.350076)
						(end 104.730804 -95.350076)
					)
				)
			)
		)
		(zone
			(layer "F.Cu")
			(hatch none 0.5)
			(connect_pads
				(clearance 0)
			)
			(min_thickness 0.25)
			(keepout
				(tracks allowed)
				(vias not_allowed)
				(pads allowed)
				(copperpour not_allowed)
				(footprints allowed)
			)
			(placement
				(enabled no)
				(sheetname "")
			)
			(fill
				(thermal_gap 0.5)
				(thermal_bridge_width 0.5)
				(island_removal_mode 0)
			)
			(polygon
				(pts
					(arc
						(start 104.730804 -94.349824)
						(mid 103.968804 -94.349824)
						(end 104.730804 -94.349824)
					)
				)
			)
		)
		(zone
			(layer "F.Cu")
			(hatch none 0.5)
			(connect_pads
				(clearance 0)
			)
			(min_thickness 0.25)
			(keepout
				(tracks allowed)
				(vias not_allowed)
				(pads allowed)
				(copperpour not_allowed)
				(footprints allowed)
			)
			(placement
				(enabled no)
				(sheetname "")
			)
			(fill
				(thermal_gap 0.5)
				(thermal_bridge_width 0.5)
				(island_removal_mode 0)
			)
			(polygon
				(pts
					(arc
						(start 104.730804 -93.349826)
						(mid 103.968804 -93.349826)
						(end 104.730804 -93.349826)
					)
				)
			)
		)
		(zone
			(layer "F.Cu")
			(hatch none 0.5)
			(connect_pads
				(clearance 0)
			)
			(min_thickness 0.25)
			(keepout
				(tracks allowed)
				(vias not_allowed)
				(pads allowed)
				(copperpour not_allowed)
				(footprints allowed)
			)
			(placement
				(enabled no)
				(sheetname "")
			)
			(fill
				(thermal_gap 0.5)
				(thermal_bridge_width 0.5)
				(island_removal_mode 0)
			)
			(polygon
				(pts
					(arc
						(start 104.730804 -92.349828)
						(mid 103.968804 -92.349828)
						(end 104.730804 -92.349828)
					)
				)
			)
		)
		(zone
			(layer "F.Cu")
			(hatch none 0.5)
			(connect_pads
				(clearance 0)
			)
			(min_thickness 0.25)
			(keepout
				(tracks allowed)
				(vias not_allowed)
				(pads allowed)
				(copperpour not_allowed)
				(footprints allowed)
			)
			(placement
				(enabled no)
				(sheetname "")
			)
			(fill
				(thermal_gap 0.5)
				(thermal_bridge_width 0.5)
				(island_removal_mode 0)
			)
			(polygon
				(pts
					(arc
						(start 104.730804 -91.34983)
						(mid 103.968804 -91.34983)
						(end 104.730804 -91.34983)
					)
				)
			)
		)
		(zone
			(layer "F.Cu")
			(hatch none 0.5)
			(connect_pads
				(clearance 0)
			)
			(min_thickness 0.25)
			(keepout
				(tracks allowed)
				(vias not_allowed)
				(pads allowed)
				(copperpour not_allowed)
				(footprints allowed)
			)
			(placement
				(enabled no)
				(sheetname "")
			)
			(fill
				(thermal_gap 0.5)
				(thermal_bridge_width 0.5)
				(island_removal_mode 0)
			)
			(polygon
				(pts
					(arc
						(start 104.730804 -90.349832)
						(mid 103.968804 -90.349832)
						(end 104.730804 -90.349832)
					)
				)
			)
		)
		(zone
			(layer "F.Cu")
			(hatch none 0.5)
			(connect_pads
				(clearance 0)
			)
			(min_thickness 0.25)
			(keepout
				(tracks allowed)
				(vias not_allowed)
				(pads allowed)
				(copperpour not_allowed)
				(footprints allowed)
			)
			(placement
				(enabled no)
				(sheetname "")
			)
			(fill
				(thermal_gap 0.5)
				(thermal_bridge_width 0.5)
				(island_removal_mode 0)
			)
			(polygon
				(pts
					(arc
						(start 104.730804 -89.349834)
						(mid 103.968804 -89.349834)
						(end 104.730804 -89.349834)
					)
				)
			)
		)
		(zone
			(layer "F.Cu")
			(hatch none 0.5)
			(connect_pads
				(clearance 0)
			)
			(min_thickness 0.25)
			(keepout
				(tracks allowed)
				(vias not_allowed)
				(pads allowed)
				(copperpour not_allowed)
				(footprints allowed)
			)
			(placement
				(enabled no)
				(sheetname "")
			)
			(fill
				(thermal_gap 0.5)
				(thermal_bridge_width 0.5)
				(island_removal_mode 0)
			)
			(polygon
				(pts
					(arc
						(start 104.730804 -88.349836)
						(mid 103.968804 -88.349836)
						(end 104.730804 -88.349836)
					)
				)
			)
		)
		(zone
			(layer "F.Cu")
			(hatch none 0.5)
			(connect_pads
				(clearance 0)
			)
			(min_thickness 0.25)
			(keepout
				(tracks allowed)
				(vias not_allowed)
				(pads allowed)
				(copperpour not_allowed)
				(footprints allowed)
			)
			(placement
				(enabled no)
				(sheetname "")
			)
			(fill
				(thermal_gap 0.5)
				(thermal_bridge_width 0.5)
				(island_removal_mode 0)
			)
			(polygon
				(pts
					(arc
						(start 104.730804 -87.349838)
						(mid 103.968804 -87.349838)
						(end 104.730804 -87.349838)
					)
				)
			)
		)
		(zone
			(layer "F.Cu")
			(hatch none 0.5)
			(connect_pads
				(clearance 0)
			)
			(min_thickness 0.25)
			(keepout
				(tracks allowed)
				(vias not_allowed)
				(pads allowed)
				(copperpour not_allowed)
				(footprints allowed)
			)
			(placement
				(enabled no)
				(sheetname "")
			)
			(fill
				(thermal_gap 0.5)
				(thermal_bridge_width 0.5)
				(island_removal_mode 0)
			)
			(polygon
				(pts
					(arc
						(start 104.730804 -86.34984)
						(mid 103.968804 -86.34984)
						(end 104.730804 -86.34984)
					)
				)
			)
		)
		(zone
			(layer "F.Cu")
			(hatch none 0.5)
			(connect_pads
				(clearance 0)
			)
			(min_thickness 0.25)
			(keepout
				(tracks allowed)
				(vias not_allowed)
				(pads allowed)
				(copperpour not_allowed)
				(footprints allowed)
			)
			(placement
				(enabled no)
				(sheetname "")
			)
			(fill
				(thermal_gap 0.5)
				(thermal_bridge_width 0.5)
				(island_removal_mode 0)
			)
			(polygon
				(pts
					(arc
						(start 104.730804 -85.349842)
						(mid 103.968804 -85.349842)
						(end 104.730804 -85.349842)
					)
				)
			)
		)
		(zone
			(layer "F.Cu")
			(hatch none 0.5)
			(connect_pads
				(clearance 0)
			)
			(min_thickness 0.25)
			(keepout
				(tracks allowed)
				(vias not_allowed)
				(pads allowed)
				(copperpour not_allowed)
				(footprints allowed)
			)
			(placement
				(enabled no)
				(sheetname "")
			)
			(fill
				(thermal_gap 0.5)
				(thermal_bridge_width 0.5)
				(island_removal_mode 0)
			)
			(polygon
				(pts
					(arc
						(start 105.730802 -107.350052)
						(mid 104.968802 -107.350052)
						(end 105.730802 -107.350052)
					)
				)
			)
		)
		(zone
			(layer "F.Cu")
			(hatch none 0.5)
			(connect_pads
				(clearance 0)
			)
			(min_thickness 0.25)
			(keepout
				(tracks allowed)
				(vias not_allowed)
				(pads allowed)
				(copperpour not_allowed)
				(footprints allowed)
			)
			(placement
				(enabled no)
				(sheetname "")
			)
			(fill
				(thermal_gap 0.5)
				(thermal_bridge_width 0.5)
				(island_removal_mode 0)
			)
			(polygon
				(pts
					(arc
						(start 105.730802 -106.350054)
						(mid 104.968802 -106.350054)
						(end 105.730802 -106.350054)
					)
				)
			)
		)
		(zone
			(layer "F.Cu")
			(hatch none 0.5)
			(connect_pads
				(clearance 0)
			)
			(min_thickness 0.25)
			(keepout
				(tracks allowed)
				(vias not_allowed)
				(pads allowed)
				(copperpour not_allowed)
				(footprints allowed)
			)
			(placement
				(enabled no)
				(sheetname "")
			)
			(fill
				(thermal_gap 0.5)
				(thermal_bridge_width 0.5)
				(island_removal_mode 0)
			)
			(polygon
				(pts
					(arc
						(start 105.730802 -105.350056)
						(mid 104.968802 -105.350056)
						(end 105.730802 -105.350056)
					)
				)
			)
		)
		(zone
			(layer "F.Cu")
			(hatch none 0.5)
			(connect_pads
				(clearance 0)
			)
			(min_thickness 0.25)
			(keepout
				(tracks allowed)
				(vias not_allowed)
				(pads allowed)
				(copperpour not_allowed)
				(footprints allowed)
			)
			(placement
				(enabled no)
				(sheetname "")
			)
			(fill
				(thermal_gap 0.5)
				(thermal_bridge_width 0.5)
				(island_removal_mode 0)
			)
			(polygon
				(pts
					(arc
						(start 105.730802 -104.350058)
						(mid 104.968802 -104.350058)
						(end 105.730802 -104.350058)
					)
				)
			)
		)
		(zone
			(layer "F.Cu")
			(hatch none 0.5)
			(connect_pads
				(clearance 0)
			)
			(min_thickness 0.25)
			(keepout
				(tracks allowed)
				(vias not_allowed)
				(pads allowed)
				(copperpour not_allowed)
				(footprints allowed)
			)
			(placement
				(enabled no)
				(sheetname "")
			)
			(fill
				(thermal_gap 0.5)
				(thermal_bridge_width 0.5)
				(island_removal_mode 0)
			)
			(polygon
				(pts
					(arc
						(start 105.730802 -103.35006)
						(mid 104.968802 -103.35006)
						(end 105.730802 -103.35006)
					)
				)
			)
		)
		(zone
			(layer "F.Cu")
			(hatch none 0.5)
			(connect_pads
				(clearance 0)
			)
			(min_thickness 0.25)
			(keepout
				(tracks allowed)
				(vias not_allowed)
				(pads allowed)
				(copperpour not_allowed)
				(footprints allowed)
			)
			(placement
				(enabled no)
				(sheetname "")
			)
			(fill
				(thermal_gap 0.5)
				(thermal_bridge_width 0.5)
				(island_removal_mode 0)
			)
			(polygon
				(pts
					(arc
						(start 105.730802 -102.350062)
						(mid 104.968802 -102.350062)
						(end 105.730802 -102.350062)
					)
				)
			)
		)
		(zone
			(layer "F.Cu")
			(hatch none 0.5)
			(connect_pads
				(clearance 0)
			)
			(min_thickness 0.25)
			(keepout
				(tracks allowed)
				(vias not_allowed)
				(pads allowed)
				(copperpour not_allowed)
				(footprints allowed)
			)
			(placement
				(enabled no)
				(sheetname "")
			)
			(fill
				(thermal_gap 0.5)
				(thermal_bridge_width 0.5)
				(island_removal_mode 0)
			)
			(polygon
				(pts
					(arc
						(start 105.730802 -101.350064)
						(mid 104.968802 -101.350064)
						(end 105.730802 -101.350064)
					)
				)
			)
		)
		(zone
			(layer "F.Cu")
			(hatch none 0.5)
			(connect_pads
				(clearance 0)
			)
			(min_thickness 0.25)
			(keepout
				(tracks allowed)
				(vias not_allowed)
				(pads allowed)
				(copperpour not_allowed)
				(footprints allowed)
			)
			(placement
				(enabled no)
				(sheetname "")
			)
			(fill
				(thermal_gap 0.5)
				(thermal_bridge_width 0.5)
				(island_removal_mode 0)
			)
			(polygon
				(pts
					(arc
						(start 105.730802 -100.350066)
						(mid 104.968802 -100.350066)
						(end 105.730802 -100.350066)
					)
				)
			)
		)
		(zone
			(layer "F.Cu")
			(hatch none 0.5)
			(connect_pads
				(clearance 0)
			)
			(min_thickness 0.25)
			(keepout
				(tracks allowed)
				(vias not_allowed)
				(pads allowed)
				(copperpour not_allowed)
				(footprints allowed)
			)
			(placement
				(enabled no)
				(sheetname "")
			)
			(fill
				(thermal_gap 0.5)
				(thermal_bridge_width 0.5)
				(island_removal_mode 0)
			)
			(polygon
				(pts
					(arc
						(start 105.730802 -99.350068)
						(mid 104.968802 -99.350068)
						(end 105.730802 -99.350068)
					)
				)
			)
		)
		(zone
			(layer "F.Cu")
			(hatch none 0.5)
			(connect_pads
				(clearance 0)
			)
			(min_thickness 0.25)
			(keepout
				(tracks allowed)
				(vias not_allowed)
				(pads allowed)
				(copperpour not_allowed)
				(footprints allowed)
			)
			(placement
				(enabled no)
				(sheetname "")
			)
			(fill
				(thermal_gap 0.5)
				(thermal_bridge_width 0.5)
				(island_removal_mode 0)
			)
			(polygon
				(pts
					(arc
						(start 105.730802 -98.35007)
						(mid 104.968802 -98.35007)
						(end 105.730802 -98.35007)
					)
				)
			)
		)
		(zone
			(layer "F.Cu")
			(hatch none 0.5)
			(connect_pads
				(clearance 0)
			)
			(min_thickness 0.25)
			(keepout
				(tracks allowed)
				(vias not_allowed)
				(pads allowed)
				(copperpour not_allowed)
				(footprints allowed)
			)
			(placement
				(enabled no)
				(sheetname "")
			)
			(fill
				(thermal_gap 0.5)
				(thermal_bridge_width 0.5)
				(island_removal_mode 0)
			)
			(polygon
				(pts
					(arc
						(start 105.730802 -97.350072)
						(mid 104.968802 -97.350072)
						(end 105.730802 -97.350072)
					)
				)
			)
		)
		(zone
			(layer "F.Cu")
			(hatch none 0.5)
			(connect_pads
				(clearance 0)
			)
			(min_thickness 0.25)
			(keepout
				(tracks allowed)
				(vias not_allowed)
				(pads allowed)
				(copperpour not_allowed)
				(footprints allowed)
			)
			(placement
				(enabled no)
				(sheetname "")
			)
			(fill
				(thermal_gap 0.5)
				(thermal_bridge_width 0.5)
				(island_removal_mode 0)
			)
			(polygon
				(pts
					(arc
						(start 105.730802 -96.350074)
						(mid 104.968802 -96.350074)
						(end 105.730802 -96.350074)
					)
				)
			)
		)
		(zone
			(layer "F.Cu")
			(hatch none 0.5)
			(connect_pads
				(clearance 0)
			)
			(min_thickness 0.25)
			(keepout
				(tracks allowed)
				(vias not_allowed)
				(pads allowed)
				(copperpour not_allowed)
				(footprints allowed)
			)
			(placement
				(enabled no)
				(sheetname "")
			)
			(fill
				(thermal_gap 0.5)
				(thermal_bridge_width 0.5)
				(island_removal_mode 0)
			)
			(polygon
				(pts
					(arc
						(start 105.730802 -95.350076)
						(mid 104.968802 -95.350076)
						(end 105.730802 -95.350076)
					)
				)
			)
		)
		(zone
			(layer "F.Cu")
			(hatch none 0.5)
			(connect_pads
				(clearance 0)
			)
			(min_thickness 0.25)
			(keepout
				(tracks allowed)
				(vias not_allowed)
				(pads allowed)
				(copperpour not_allowed)
				(footprints allowed)
			)
			(placement
				(enabled no)
				(sheetname "")
			)
			(fill
				(thermal_gap 0.5)
				(thermal_bridge_width 0.5)
				(island_removal_mode 0)
			)
			(polygon
				(pts
					(arc
						(start 105.730802 -94.349824)
						(mid 104.968802 -94.349824)
						(end 105.730802 -94.349824)
					)
				)
			)
		)
		(zone
			(layer "F.Cu")
			(hatch none 0.5)
			(connect_pads
				(clearance 0)
			)
			(min_thickness 0.25)
			(keepout
				(tracks allowed)
				(vias not_allowed)
				(pads allowed)
				(copperpour not_allowed)
				(footprints allowed)
			)
			(placement
				(enabled no)
				(sheetname "")
			)
			(fill
				(thermal_gap 0.5)
				(thermal_bridge_width 0.5)
				(island_removal_mode 0)
			)
			(polygon
				(pts
					(arc
						(start 105.730802 -93.349826)
						(mid 104.968802 -93.349826)
						(end 105.730802 -93.349826)
					)
				)
			)
		)
		(zone
			(layer "F.Cu")
			(hatch none 0.5)
			(connect_pads
				(clearance 0)
			)
			(min_thickness 0.25)
			(keepout
				(tracks allowed)
				(vias not_allowed)
				(pads allowed)
				(copperpour not_allowed)
				(footprints allowed)
			)
			(placement
				(enabled no)
				(sheetname "")
			)
			(fill
				(thermal_gap 0.5)
				(thermal_bridge_width 0.5)
				(island_removal_mode 0)
			)
			(polygon
				(pts
					(arc
						(start 105.730802 -92.349828)
						(mid 104.968802 -92.349828)
						(end 105.730802 -92.349828)
					)
				)
			)
		)
		(zone
			(layer "F.Cu")
			(hatch none 0.5)
			(connect_pads
				(clearance 0)
			)
			(min_thickness 0.25)
			(keepout
				(tracks allowed)
				(vias not_allowed)
				(pads allowed)
				(copperpour not_allowed)
				(footprints allowed)
			)
			(placement
				(enabled no)
				(sheetname "")
			)
			(fill
				(thermal_gap 0.5)
				(thermal_bridge_width 0.5)
				(island_removal_mode 0)
			)
			(polygon
				(pts
					(arc
						(start 105.730802 -91.34983)
						(mid 104.968802 -91.34983)
						(end 105.730802 -91.34983)
					)
				)
			)
		)
		(zone
			(layer "F.Cu")
			(hatch none 0.5)
			(connect_pads
				(clearance 0)
			)
			(min_thickness 0.25)
			(keepout
				(tracks allowed)
				(vias not_allowed)
				(pads allowed)
				(copperpour not_allowed)
				(footprints allowed)
			)
			(placement
				(enabled no)
				(sheetname "")
			)
			(fill
				(thermal_gap 0.5)
				(thermal_bridge_width 0.5)
				(island_removal_mode 0)
			)
			(polygon
				(pts
					(arc
						(start 105.730802 -90.349832)
						(mid 104.968802 -90.349832)
						(end 105.730802 -90.349832)
					)
				)
			)
		)
		(zone
			(layer "F.Cu")
			(hatch none 0.5)
			(connect_pads
				(clearance 0)
			)
			(min_thickness 0.25)
			(keepout
				(tracks allowed)
				(vias not_allowed)
				(pads allowed)
				(copperpour not_allowed)
				(footprints allowed)
			)
			(placement
				(enabled no)
				(sheetname "")
			)
			(fill
				(thermal_gap 0.5)
				(thermal_bridge_width 0.5)
				(island_removal_mode 0)
			)
			(polygon
				(pts
					(arc
						(start 105.730802 -89.349834)
						(mid 104.968802 -89.349834)
						(end 105.730802 -89.349834)
					)
				)
			)
		)
		(zone
			(layer "F.Cu")
			(hatch none 0.5)
			(connect_pads
				(clearance 0)
			)
			(min_thickness 0.25)
			(keepout
				(tracks allowed)
				(vias not_allowed)
				(pads allowed)
				(copperpour not_allowed)
				(footprints allowed)
			)
			(placement
				(enabled no)
				(sheetname "")
			)
			(fill
				(thermal_gap 0.5)
				(thermal_bridge_width 0.5)
				(island_removal_mode 0)
			)
			(polygon
				(pts
					(arc
						(start 105.730802 -88.349836)
						(mid 104.968802 -88.349836)
						(end 105.730802 -88.349836)
					)
				)
			)
		)
		(zone
			(layer "F.Cu")
			(hatch none 0.5)
			(connect_pads
				(clearance 0)
			)
			(min_thickness 0.25)
			(keepout
				(tracks allowed)
				(vias not_allowed)
				(pads allowed)
				(copperpour not_allowed)
				(footprints allowed)
			)
			(placement
				(enabled no)
				(sheetname "")
			)
			(fill
				(thermal_gap 0.5)
				(thermal_bridge_width 0.5)
				(island_removal_mode 0)
			)
			(polygon
				(pts
					(arc
						(start 105.730802 -87.349838)
						(mid 104.968802 -87.349838)
						(end 105.730802 -87.349838)
					)
				)
			)
		)
		(zone
			(layer "F.Cu")
			(hatch none 0.5)
			(connect_pads
				(clearance 0)
			)
			(min_thickness 0.25)
			(keepout
				(tracks allowed)
				(vias not_allowed)
				(pads allowed)
				(copperpour not_allowed)
				(footprints allowed)
			)
			(placement
				(enabled no)
				(sheetname "")
			)
			(fill
				(thermal_gap 0.5)
				(thermal_bridge_width 0.5)
				(island_removal_mode 0)
			)
			(polygon
				(pts
					(arc
						(start 105.730802 -86.34984)
						(mid 104.968802 -86.34984)
						(end 105.730802 -86.34984)
					)
				)
			)
		)
		(zone
			(layer "F.Cu")
			(hatch none 0.5)
			(connect_pads
				(clearance 0)
			)
			(min_thickness 0.25)
			(keepout
				(tracks allowed)
				(vias not_allowed)
				(pads allowed)
				(copperpour not_allowed)
				(footprints allowed)
			)
			(placement
				(enabled no)
				(sheetname "")
			)
			(fill
				(thermal_gap 0.5)
				(thermal_bridge_width 0.5)
				(island_removal_mode 0)
			)
			(polygon
				(pts
					(arc
						(start 105.730802 -85.349842)
						(mid 104.968802 -85.349842)
						(end 105.730802 -85.349842)
					)
				)
			)
		)
		(zone
			(layer "F.Cu")
			(hatch none 0.5)
			(connect_pads
				(clearance 0)
			)
			(min_thickness 0.25)
			(keepout
				(tracks allowed)
				(vias not_allowed)
				(pads allowed)
				(copperpour not_allowed)
				(footprints allowed)
			)
			(placement
				(enabled no)
				(sheetname "")
			)
			(fill
				(thermal_gap 0.5)
				(thermal_bridge_width 0.5)
				(island_removal_mode 0)
			)
			(polygon
				(pts
					(arc
						(start 105.730802 -84.349844)
						(mid 104.968802 -84.349844)
						(end 105.730802 -84.349844)
					)
				)
			)
		)
		(zone
			(layer "F.Cu")
			(hatch none 0.5)
			(connect_pads
				(clearance 0)
			)
			(min_thickness 0.25)
			(keepout
				(tracks allowed)
				(vias not_allowed)
				(pads allowed)
				(copperpour not_allowed)
				(footprints allowed)
			)
			(placement
				(enabled no)
				(sheetname "")
			)
			(fill
				(thermal_gap 0.5)
				(thermal_bridge_width 0.5)
				(island_removal_mode 0)
			)
			(polygon
				(pts
					(arc
						(start 105.730802 -83.349846)
						(mid 104.968802 -83.349846)
						(end 105.730802 -83.349846)
					)
				)
			)
		)
		(zone
			(layer "F.Cu")
			(hatch none 0.5)
			(connect_pads
				(clearance 0)
			)
			(min_thickness 0.25)
			(keepout
				(tracks allowed)
				(vias not_allowed)
				(pads allowed)
				(copperpour not_allowed)
				(footprints allowed)
			)
			(placement
				(enabled no)
				(sheetname "")
			)
			(fill
				(thermal_gap 0.5)
				(thermal_bridge_width 0.5)
				(island_removal_mode 0)
			)
			(polygon
				(pts
					(arc
						(start 105.730802 -82.349848)
						(mid 104.968802 -82.349848)
						(end 105.730802 -82.349848)
					)
				)
			)
		)
		(zone
			(layer "F.Cu")
			(hatch none 0.5)
			(connect_pads
				(clearance 0)
			)
			(min_thickness 0.25)
			(keepout
				(tracks allowed)
				(vias not_allowed)
				(pads allowed)
				(copperpour not_allowed)
				(footprints allowed)
			)
			(placement
				(enabled no)
				(sheetname "")
			)
			(fill
				(thermal_gap 0.5)
				(thermal_bridge_width 0.5)
				(island_removal_mode 0)
			)
			(polygon
				(pts
					(arc
						(start 106.7308 -107.350052)
						(mid 105.9688 -107.350052)
						(end 106.7308 -107.350052)
					)
				)
			)
		)
		(zone
			(layer "F.Cu")
			(hatch none 0.5)
			(connect_pads
				(clearance 0)
			)
			(min_thickness 0.25)
			(keepout
				(tracks allowed)
				(vias not_allowed)
				(pads allowed)
				(copperpour not_allowed)
				(footprints allowed)
			)
			(placement
				(enabled no)
				(sheetname "")
			)
			(fill
				(thermal_gap 0.5)
				(thermal_bridge_width 0.5)
				(island_removal_mode 0)
			)
			(polygon
				(pts
					(arc
						(start 106.7308 -106.350054)
						(mid 105.9688 -106.350054)
						(end 106.7308 -106.350054)
					)
				)
			)
		)
		(zone
			(layer "F.Cu")
			(hatch none 0.5)
			(connect_pads
				(clearance 0)
			)
			(min_thickness 0.25)
			(keepout
				(tracks allowed)
				(vias not_allowed)
				(pads allowed)
				(copperpour not_allowed)
				(footprints allowed)
			)
			(placement
				(enabled no)
				(sheetname "")
			)
			(fill
				(thermal_gap 0.5)
				(thermal_bridge_width 0.5)
				(island_removal_mode 0)
			)
			(polygon
				(pts
					(arc
						(start 106.7308 -105.350056)
						(mid 105.9688 -105.350056)
						(end 106.7308 -105.350056)
					)
				)
			)
		)
		(zone
			(layer "F.Cu")
			(hatch none 0.5)
			(connect_pads
				(clearance 0)
			)
			(min_thickness 0.25)
			(keepout
				(tracks allowed)
				(vias not_allowed)
				(pads allowed)
				(copperpour not_allowed)
				(footprints allowed)
			)
			(placement
				(enabled no)
				(sheetname "")
			)
			(fill
				(thermal_gap 0.5)
				(thermal_bridge_width 0.5)
				(island_removal_mode 0)
			)
			(polygon
				(pts
					(arc
						(start 106.7308 -104.350058)
						(mid 105.9688 -104.350058)
						(end 106.7308 -104.350058)
					)
				)
			)
		)
		(zone
			(layer "F.Cu")
			(hatch none 0.5)
			(connect_pads
				(clearance 0)
			)
			(min_thickness 0.25)
			(keepout
				(tracks allowed)
				(vias not_allowed)
				(pads allowed)
				(copperpour not_allowed)
				(footprints allowed)
			)
			(placement
				(enabled no)
				(sheetname "")
			)
			(fill
				(thermal_gap 0.5)
				(thermal_bridge_width 0.5)
				(island_removal_mode 0)
			)
			(polygon
				(pts
					(arc
						(start 106.7308 -103.35006)
						(mid 105.9688 -103.35006)
						(end 106.7308 -103.35006)
					)
				)
			)
		)
		(zone
			(layer "F.Cu")
			(hatch none 0.5)
			(connect_pads
				(clearance 0)
			)
			(min_thickness 0.25)
			(keepout
				(tracks allowed)
				(vias not_allowed)
				(pads allowed)
				(copperpour not_allowed)
				(footprints allowed)
			)
			(placement
				(enabled no)
				(sheetname "")
			)
			(fill
				(thermal_gap 0.5)
				(thermal_bridge_width 0.5)
				(island_removal_mode 0)
			)
			(polygon
				(pts
					(arc
						(start 106.7308 -102.350062)
						(mid 105.9688 -102.350062)
						(end 106.7308 -102.350062)
					)
				)
			)
		)
		(zone
			(layer "F.Cu")
			(hatch none 0.5)
			(connect_pads
				(clearance 0)
			)
			(min_thickness 0.25)
			(keepout
				(tracks allowed)
				(vias not_allowed)
				(pads allowed)
				(copperpour not_allowed)
				(footprints allowed)
			)
			(placement
				(enabled no)
				(sheetname "")
			)
			(fill
				(thermal_gap 0.5)
				(thermal_bridge_width 0.5)
				(island_removal_mode 0)
			)
			(polygon
				(pts
					(arc
						(start 106.7308 -101.350064)
						(mid 105.9688 -101.350064)
						(end 106.7308 -101.350064)
					)
				)
			)
		)
		(zone
			(layer "F.Cu")
			(hatch none 0.5)
			(connect_pads
				(clearance 0)
			)
			(min_thickness 0.25)
			(keepout
				(tracks allowed)
				(vias not_allowed)
				(pads allowed)
				(copperpour not_allowed)
				(footprints allowed)
			)
			(placement
				(enabled no)
				(sheetname "")
			)
			(fill
				(thermal_gap 0.5)
				(thermal_bridge_width 0.5)
				(island_removal_mode 0)
			)
			(polygon
				(pts
					(arc
						(start 106.7308 -100.350066)
						(mid 105.9688 -100.350066)
						(end 106.7308 -100.350066)
					)
				)
			)
		)
		(zone
			(layer "F.Cu")
			(hatch none 0.5)
			(connect_pads
				(clearance 0)
			)
			(min_thickness 0.25)
			(keepout
				(tracks allowed)
				(vias not_allowed)
				(pads allowed)
				(copperpour not_allowed)
				(footprints allowed)
			)
			(placement
				(enabled no)
				(sheetname "")
			)
			(fill
				(thermal_gap 0.5)
				(thermal_bridge_width 0.5)
				(island_removal_mode 0)
			)
			(polygon
				(pts
					(arc
						(start 106.7308 -99.350068)
						(mid 105.9688 -99.350068)
						(end 106.7308 -99.350068)
					)
				)
			)
		)
		(zone
			(layer "F.Cu")
			(hatch none 0.5)
			(connect_pads
				(clearance 0)
			)
			(min_thickness 0.25)
			(keepout
				(tracks allowed)
				(vias not_allowed)
				(pads allowed)
				(copperpour not_allowed)
				(footprints allowed)
			)
			(placement
				(enabled no)
				(sheetname "")
			)
			(fill
				(thermal_gap 0.5)
				(thermal_bridge_width 0.5)
				(island_removal_mode 0)
			)
			(polygon
				(pts
					(arc
						(start 106.7308 -98.35007)
						(mid 105.9688 -98.35007)
						(end 106.7308 -98.35007)
					)
				)
			)
		)
		(zone
			(layer "F.Cu")
			(hatch none 0.5)
			(connect_pads
				(clearance 0)
			)
			(min_thickness 0.25)
			(keepout
				(tracks allowed)
				(vias not_allowed)
				(pads allowed)
				(copperpour not_allowed)
				(footprints allowed)
			)
			(placement
				(enabled no)
				(sheetname "")
			)
			(fill
				(thermal_gap 0.5)
				(thermal_bridge_width 0.5)
				(island_removal_mode 0)
			)
			(polygon
				(pts
					(arc
						(start 106.7308 -97.350072)
						(mid 105.9688 -97.350072)
						(end 106.7308 -97.350072)
					)
				)
			)
		)
		(zone
			(layer "F.Cu")
			(hatch none 0.5)
			(connect_pads
				(clearance 0)
			)
			(min_thickness 0.25)
			(keepout
				(tracks allowed)
				(vias not_allowed)
				(pads allowed)
				(copperpour not_allowed)
				(footprints allowed)
			)
			(placement
				(enabled no)
				(sheetname "")
			)
			(fill
				(thermal_gap 0.5)
				(thermal_bridge_width 0.5)
				(island_removal_mode 0)
			)
			(polygon
				(pts
					(arc
						(start 106.7308 -96.350074)
						(mid 105.9688 -96.350074)
						(end 106.7308 -96.350074)
					)
				)
			)
		)
		(zone
			(layer "F.Cu")
			(hatch none 0.5)
			(connect_pads
				(clearance 0)
			)
			(min_thickness 0.25)
			(keepout
				(tracks allowed)
				(vias not_allowed)
				(pads allowed)
				(copperpour not_allowed)
				(footprints allowed)
			)
			(placement
				(enabled no)
				(sheetname "")
			)
			(fill
				(thermal_gap 0.5)
				(thermal_bridge_width 0.5)
				(island_removal_mode 0)
			)
			(polygon
				(pts
					(arc
						(start 106.7308 -95.350076)
						(mid 105.9688 -95.350076)
						(end 106.7308 -95.350076)
					)
				)
			)
		)
		(zone
			(layer "F.Cu")
			(hatch none 0.5)
			(connect_pads
				(clearance 0)
			)
			(min_thickness 0.25)
			(keepout
				(tracks allowed)
				(vias not_allowed)
				(pads allowed)
				(copperpour not_allowed)
				(footprints allowed)
			)
			(placement
				(enabled no)
				(sheetname "")
			)
			(fill
				(thermal_gap 0.5)
				(thermal_bridge_width 0.5)
				(island_removal_mode 0)
			)
			(polygon
				(pts
					(arc
						(start 106.7308 -94.349824)
						(mid 105.9688 -94.349824)
						(end 106.7308 -94.349824)
					)
				)
			)
		)
		(zone
			(layer "F.Cu")
			(hatch none 0.5)
			(connect_pads
				(clearance 0)
			)
			(min_thickness 0.25)
			(keepout
				(tracks allowed)
				(vias not_allowed)
				(pads allowed)
				(copperpour not_allowed)
				(footprints allowed)
			)
			(placement
				(enabled no)
				(sheetname "")
			)
			(fill
				(thermal_gap 0.5)
				(thermal_bridge_width 0.5)
				(island_removal_mode 0)
			)
			(polygon
				(pts
					(arc
						(start 106.7308 -93.349826)
						(mid 105.9688 -93.349826)
						(end 106.7308 -93.349826)
					)
				)
			)
		)
		(zone
			(layer "F.Cu")
			(hatch none 0.5)
			(connect_pads
				(clearance 0)
			)
			(min_thickness 0.25)
			(keepout
				(tracks allowed)
				(vias not_allowed)
				(pads allowed)
				(copperpour not_allowed)
				(footprints allowed)
			)
			(placement
				(enabled no)
				(sheetname "")
			)
			(fill
				(thermal_gap 0.5)
				(thermal_bridge_width 0.5)
				(island_removal_mode 0)
			)
			(polygon
				(pts
					(arc
						(start 106.7308 -92.349828)
						(mid 105.9688 -92.349828)
						(end 106.7308 -92.349828)
					)
				)
			)
		)
		(zone
			(layer "F.Cu")
			(hatch none 0.5)
			(connect_pads
				(clearance 0)
			)
			(min_thickness 0.25)
			(keepout
				(tracks allowed)
				(vias not_allowed)
				(pads allowed)
				(copperpour not_allowed)
				(footprints allowed)
			)
			(placement
				(enabled no)
				(sheetname "")
			)
			(fill
				(thermal_gap 0.5)
				(thermal_bridge_width 0.5)
				(island_removal_mode 0)
			)
			(polygon
				(pts
					(arc
						(start 106.7308 -91.34983)
						(mid 105.9688 -91.34983)
						(end 106.7308 -91.34983)
					)
				)
			)
		)
		(zone
			(layer "F.Cu")
			(hatch none 0.5)
			(connect_pads
				(clearance 0)
			)
			(min_thickness 0.25)
			(keepout
				(tracks allowed)
				(vias not_allowed)
				(pads allowed)
				(copperpour not_allowed)
				(footprints allowed)
			)
			(placement
				(enabled no)
				(sheetname "")
			)
			(fill
				(thermal_gap 0.5)
				(thermal_bridge_width 0.5)
				(island_removal_mode 0)
			)
			(polygon
				(pts
					(arc
						(start 106.7308 -90.349832)
						(mid 105.9688 -90.349832)
						(end 106.7308 -90.349832)
					)
				)
			)
		)
		(zone
			(layer "F.Cu")
			(hatch none 0.5)
			(connect_pads
				(clearance 0)
			)
			(min_thickness 0.25)
			(keepout
				(tracks allowed)
				(vias not_allowed)
				(pads allowed)
				(copperpour not_allowed)
				(footprints allowed)
			)
			(placement
				(enabled no)
				(sheetname "")
			)
			(fill
				(thermal_gap 0.5)
				(thermal_bridge_width 0.5)
				(island_removal_mode 0)
			)
			(polygon
				(pts
					(arc
						(start 106.7308 -89.349834)
						(mid 105.9688 -89.349834)
						(end 106.7308 -89.349834)
					)
				)
			)
		)
		(zone
			(layer "F.Cu")
			(hatch none 0.5)
			(connect_pads
				(clearance 0)
			)
			(min_thickness 0.25)
			(keepout
				(tracks allowed)
				(vias not_allowed)
				(pads allowed)
				(copperpour not_allowed)
				(footprints allowed)
			)
			(placement
				(enabled no)
				(sheetname "")
			)
			(fill
				(thermal_gap 0.5)
				(thermal_bridge_width 0.5)
				(island_removal_mode 0)
			)
			(polygon
				(pts
					(arc
						(start 106.7308 -88.349836)
						(mid 105.9688 -88.349836)
						(end 106.7308 -88.349836)
					)
				)
			)
		)
		(zone
			(layer "F.Cu")
			(hatch none 0.5)
			(connect_pads
				(clearance 0)
			)
			(min_thickness 0.25)
			(keepout
				(tracks allowed)
				(vias not_allowed)
				(pads allowed)
				(copperpour not_allowed)
				(footprints allowed)
			)
			(placement
				(enabled no)
				(sheetname "")
			)
			(fill
				(thermal_gap 0.5)
				(thermal_bridge_width 0.5)
				(island_removal_mode 0)
			)
			(polygon
				(pts
					(arc
						(start 106.7308 -87.349838)
						(mid 105.9688 -87.349838)
						(end 106.7308 -87.349838)
					)
				)
			)
		)
		(zone
			(layer "F.Cu")
			(hatch none 0.5)
			(connect_pads
				(clearance 0)
			)
			(min_thickness 0.25)
			(keepout
				(tracks allowed)
				(vias not_allowed)
				(pads allowed)
				(copperpour not_allowed)
				(footprints allowed)
			)
			(placement
				(enabled no)
				(sheetname "")
			)
			(fill
				(thermal_gap 0.5)
				(thermal_bridge_width 0.5)
				(island_removal_mode 0)
			)
			(polygon
				(pts
					(arc
						(start 106.7308 -86.34984)
						(mid 105.9688 -86.34984)
						(end 106.7308 -86.34984)
					)
				)
			)
		)
		(zone
			(layer "F.Cu")
			(hatch none 0.5)
			(connect_pads
				(clearance 0)
			)
			(min_thickness 0.25)
			(keepout
				(tracks allowed)
				(vias not_allowed)
				(pads allowed)
				(copperpour not_allowed)
				(footprints allowed)
			)
			(placement
				(enabled no)
				(sheetname "")
			)
			(fill
				(thermal_gap 0.5)
				(thermal_bridge_width 0.5)
				(island_removal_mode 0)
			)
			(polygon
				(pts
					(arc
						(start 106.7308 -85.349842)
						(mid 105.9688 -85.349842)
						(end 106.7308 -85.349842)
					)
				)
			)
		)
		(zone
			(layer "F.Cu")
			(hatch none 0.5)
			(connect_pads
				(clearance 0)
			)
			(min_thickness 0.25)
			(keepout
				(tracks allowed)
				(vias not_allowed)
				(pads allowed)
				(copperpour not_allowed)
				(footprints allowed)
			)
			(placement
				(enabled no)
				(sheetname "")
			)
			(fill
				(thermal_gap 0.5)
				(thermal_bridge_width 0.5)
				(island_removal_mode 0)
			)
			(polygon
				(pts
					(arc
						(start 106.7308 -84.349844)
						(mid 105.9688 -84.349844)
						(end 106.7308 -84.349844)
					)
				)
			)
		)
		(zone
			(layer "F.Cu")
			(hatch none 0.5)
			(connect_pads
				(clearance 0)
			)
			(min_thickness 0.25)
			(keepout
				(tracks allowed)
				(vias not_allowed)
				(pads allowed)
				(copperpour not_allowed)
				(footprints allowed)
			)
			(placement
				(enabled no)
				(sheetname "")
			)
			(fill
				(thermal_gap 0.5)
				(thermal_bridge_width 0.5)
				(island_removal_mode 0)
			)
			(polygon
				(pts
					(arc
						(start 106.7308 -83.349846)
						(mid 105.9688 -83.349846)
						(end 106.7308 -83.349846)
					)
				)
			)
		)
		(zone
			(layer "F.Cu")
			(hatch none 0.5)
			(connect_pads
				(clearance 0)
			)
			(min_thickness 0.25)
			(keepout
				(tracks allowed)
				(vias not_allowed)
				(pads allowed)
				(copperpour not_allowed)
				(footprints allowed)
			)
			(placement
				(enabled no)
				(sheetname "")
			)
			(fill
				(thermal_gap 0.5)
				(thermal_bridge_width 0.5)
				(island_removal_mode 0)
			)
			(polygon
				(pts
					(arc
						(start 106.7308 -82.349848)
						(mid 105.9688 -82.349848)
						(end 106.7308 -82.349848)
					)
				)
			)
		)
		(zone
			(layer "F.Cu")
			(hatch none 0.5)
			(connect_pads
				(clearance 0)
			)
			(min_thickness 0.25)
			(keepout
				(tracks allowed)
				(vias not_allowed)
				(pads allowed)
				(copperpour not_allowed)
				(footprints allowed)
			)
			(placement
				(enabled no)
				(sheetname "")
			)
			(fill
				(thermal_gap 0.5)
				(thermal_bridge_width 0.5)
				(island_removal_mode 0)
			)
			(polygon
				(pts
					(arc
						(start 107.730798 -107.350052)
						(mid 106.968798 -107.350052)
						(end 107.730798 -107.350052)
					)
				)
			)
		)
		(zone
			(layer "F.Cu")
			(hatch none 0.5)
			(connect_pads
				(clearance 0)
			)
			(min_thickness 0.25)
			(keepout
				(tracks allowed)
				(vias not_allowed)
				(pads allowed)
				(copperpour not_allowed)
				(footprints allowed)
			)
			(placement
				(enabled no)
				(sheetname "")
			)
			(fill
				(thermal_gap 0.5)
				(thermal_bridge_width 0.5)
				(island_removal_mode 0)
			)
			(polygon
				(pts
					(arc
						(start 107.730798 -106.350054)
						(mid 106.968798 -106.350054)
						(end 107.730798 -106.350054)
					)
				)
			)
		)
		(zone
			(layer "F.Cu")
			(hatch none 0.5)
			(connect_pads
				(clearance 0)
			)
			(min_thickness 0.25)
			(keepout
				(tracks allowed)
				(vias not_allowed)
				(pads allowed)
				(copperpour not_allowed)
				(footprints allowed)
			)
			(placement
				(enabled no)
				(sheetname "")
			)
			(fill
				(thermal_gap 0.5)
				(thermal_bridge_width 0.5)
				(island_removal_mode 0)
			)
			(polygon
				(pts
					(arc
						(start 107.730798 -105.350056)
						(mid 106.968798 -105.350056)
						(end 107.730798 -105.350056)
					)
				)
			)
		)
		(zone
			(layer "F.Cu")
			(hatch none 0.5)
			(connect_pads
				(clearance 0)
			)
			(min_thickness 0.25)
			(keepout
				(tracks allowed)
				(vias not_allowed)
				(pads allowed)
				(copperpour not_allowed)
				(footprints allowed)
			)
			(placement
				(enabled no)
				(sheetname "")
			)
			(fill
				(thermal_gap 0.5)
				(thermal_bridge_width 0.5)
				(island_removal_mode 0)
			)
			(polygon
				(pts
					(arc
						(start 107.730798 -104.350058)
						(mid 106.968798 -104.350058)
						(end 107.730798 -104.350058)
					)
				)
			)
		)
		(zone
			(layer "F.Cu")
			(hatch none 0.5)
			(connect_pads
				(clearance 0)
			)
			(min_thickness 0.25)
			(keepout
				(tracks allowed)
				(vias not_allowed)
				(pads allowed)
				(copperpour not_allowed)
				(footprints allowed)
			)
			(placement
				(enabled no)
				(sheetname "")
			)
			(fill
				(thermal_gap 0.5)
				(thermal_bridge_width 0.5)
				(island_removal_mode 0)
			)
			(polygon
				(pts
					(arc
						(start 107.730798 -103.35006)
						(mid 106.968798 -103.35006)
						(end 107.730798 -103.35006)
					)
				)
			)
		)
		(zone
			(layer "F.Cu")
			(hatch none 0.5)
			(connect_pads
				(clearance 0)
			)
			(min_thickness 0.25)
			(keepout
				(tracks allowed)
				(vias not_allowed)
				(pads allowed)
				(copperpour not_allowed)
				(footprints allowed)
			)
			(placement
				(enabled no)
				(sheetname "")
			)
			(fill
				(thermal_gap 0.5)
				(thermal_bridge_width 0.5)
				(island_removal_mode 0)
			)
			(polygon
				(pts
					(arc
						(start 107.730798 -102.350062)
						(mid 106.968798 -102.350062)
						(end 107.730798 -102.350062)
					)
				)
			)
		)
		(zone
			(layer "F.Cu")
			(hatch none 0.5)
			(connect_pads
				(clearance 0)
			)
			(min_thickness 0.25)
			(keepout
				(tracks allowed)
				(vias not_allowed)
				(pads allowed)
				(copperpour not_allowed)
				(footprints allowed)
			)
			(placement
				(enabled no)
				(sheetname "")
			)
			(fill
				(thermal_gap 0.5)
				(thermal_bridge_width 0.5)
				(island_removal_mode 0)
			)
			(polygon
				(pts
					(arc
						(start 107.730798 -101.350064)
						(mid 106.968798 -101.350064)
						(end 107.730798 -101.350064)
					)
				)
			)
		)
		(zone
			(layer "F.Cu")
			(hatch none 0.5)
			(connect_pads
				(clearance 0)
			)
			(min_thickness 0.25)
			(keepout
				(tracks allowed)
				(vias not_allowed)
				(pads allowed)
				(copperpour not_allowed)
				(footprints allowed)
			)
			(placement
				(enabled no)
				(sheetname "")
			)
			(fill
				(thermal_gap 0.5)
				(thermal_bridge_width 0.5)
				(island_removal_mode 0)
			)
			(polygon
				(pts
					(arc
						(start 107.730798 -100.350066)
						(mid 106.968798 -100.350066)
						(end 107.730798 -100.350066)
					)
				)
			)
		)
		(zone
			(layer "F.Cu")
			(hatch none 0.5)
			(connect_pads
				(clearance 0)
			)
			(min_thickness 0.25)
			(keepout
				(tracks allowed)
				(vias not_allowed)
				(pads allowed)
				(copperpour not_allowed)
				(footprints allowed)
			)
			(placement
				(enabled no)
				(sheetname "")
			)
			(fill
				(thermal_gap 0.5)
				(thermal_bridge_width 0.5)
				(island_removal_mode 0)
			)
			(polygon
				(pts
					(arc
						(start 107.730798 -99.350068)
						(mid 106.968798 -99.350068)
						(end 107.730798 -99.350068)
					)
				)
			)
		)
		(zone
			(layer "F.Cu")
			(hatch none 0.5)
			(connect_pads
				(clearance 0)
			)
			(min_thickness 0.25)
			(keepout
				(tracks allowed)
				(vias not_allowed)
				(pads allowed)
				(copperpour not_allowed)
				(footprints allowed)
			)
			(placement
				(enabled no)
				(sheetname "")
			)
			(fill
				(thermal_gap 0.5)
				(thermal_bridge_width 0.5)
				(island_removal_mode 0)
			)
			(polygon
				(pts
					(arc
						(start 107.730798 -98.35007)
						(mid 106.968798 -98.35007)
						(end 107.730798 -98.35007)
					)
				)
			)
		)
		(zone
			(layer "F.Cu")
			(hatch none 0.5)
			(connect_pads
				(clearance 0)
			)
			(min_thickness 0.25)
			(keepout
				(tracks allowed)
				(vias not_allowed)
				(pads allowed)
				(copperpour not_allowed)
				(footprints allowed)
			)
			(placement
				(enabled no)
				(sheetname "")
			)
			(fill
				(thermal_gap 0.5)
				(thermal_bridge_width 0.5)
				(island_removal_mode 0)
			)
			(polygon
				(pts
					(arc
						(start 107.730798 -97.350072)
						(mid 106.968798 -97.350072)
						(end 107.730798 -97.350072)
					)
				)
			)
		)
		(zone
			(layer "F.Cu")
			(hatch none 0.5)
			(connect_pads
				(clearance 0)
			)
			(min_thickness 0.25)
			(keepout
				(tracks allowed)
				(vias not_allowed)
				(pads allowed)
				(copperpour not_allowed)
				(footprints allowed)
			)
			(placement
				(enabled no)
				(sheetname "")
			)
			(fill
				(thermal_gap 0.5)
				(thermal_bridge_width 0.5)
				(island_removal_mode 0)
			)
			(polygon
				(pts
					(arc
						(start 107.730798 -96.350074)
						(mid 106.968798 -96.350074)
						(end 107.730798 -96.350074)
					)
				)
			)
		)
		(zone
			(layer "F.Cu")
			(hatch none 0.5)
			(connect_pads
				(clearance 0)
			)
			(min_thickness 0.25)
			(keepout
				(tracks allowed)
				(vias not_allowed)
				(pads allowed)
				(copperpour not_allowed)
				(footprints allowed)
			)
			(placement
				(enabled no)
				(sheetname "")
			)
			(fill
				(thermal_gap 0.5)
				(thermal_bridge_width 0.5)
				(island_removal_mode 0)
			)
			(polygon
				(pts
					(arc
						(start 107.730798 -95.350076)
						(mid 106.968798 -95.350076)
						(end 107.730798 -95.350076)
					)
				)
			)
		)
		(zone
			(layer "F.Cu")
			(hatch none 0.5)
			(connect_pads
				(clearance 0)
			)
			(min_thickness 0.25)
			(keepout
				(tracks allowed)
				(vias not_allowed)
				(pads allowed)
				(copperpour not_allowed)
				(footprints allowed)
			)
			(placement
				(enabled no)
				(sheetname "")
			)
			(fill
				(thermal_gap 0.5)
				(thermal_bridge_width 0.5)
				(island_removal_mode 0)
			)
			(polygon
				(pts
					(arc
						(start 107.730798 -94.349824)
						(mid 106.968798 -94.349824)
						(end 107.730798 -94.349824)
					)
				)
			)
		)
		(zone
			(layer "F.Cu")
			(hatch none 0.5)
			(connect_pads
				(clearance 0)
			)
			(min_thickness 0.25)
			(keepout
				(tracks allowed)
				(vias not_allowed)
				(pads allowed)
				(copperpour not_allowed)
				(footprints allowed)
			)
			(placement
				(enabled no)
				(sheetname "")
			)
			(fill
				(thermal_gap 0.5)
				(thermal_bridge_width 0.5)
				(island_removal_mode 0)
			)
			(polygon
				(pts
					(arc
						(start 107.730798 -93.349826)
						(mid 106.968798 -93.349826)
						(end 107.730798 -93.349826)
					)
				)
			)
		)
		(zone
			(layer "F.Cu")
			(hatch none 0.5)
			(connect_pads
				(clearance 0)
			)
			(min_thickness 0.25)
			(keepout
				(tracks allowed)
				(vias not_allowed)
				(pads allowed)
				(copperpour not_allowed)
				(footprints allowed)
			)
			(placement
				(enabled no)
				(sheetname "")
			)
			(fill
				(thermal_gap 0.5)
				(thermal_bridge_width 0.5)
				(island_removal_mode 0)
			)
			(polygon
				(pts
					(arc
						(start 107.730798 -92.349828)
						(mid 106.968798 -92.349828)
						(end 107.730798 -92.349828)
					)
				)
			)
		)
		(zone
			(layer "F.Cu")
			(hatch none 0.5)
			(connect_pads
				(clearance 0)
			)
			(min_thickness 0.25)
			(keepout
				(tracks allowed)
				(vias not_allowed)
				(pads allowed)
				(copperpour not_allowed)
				(footprints allowed)
			)
			(placement
				(enabled no)
				(sheetname "")
			)
			(fill
				(thermal_gap 0.5)
				(thermal_bridge_width 0.5)
				(island_removal_mode 0)
			)
			(polygon
				(pts
					(arc
						(start 107.730798 -91.34983)
						(mid 106.968798 -91.34983)
						(end 107.730798 -91.34983)
					)
				)
			)
		)
		(zone
			(layer "F.Cu")
			(hatch none 0.5)
			(connect_pads
				(clearance 0)
			)
			(min_thickness 0.25)
			(keepout
				(tracks allowed)
				(vias not_allowed)
				(pads allowed)
				(copperpour not_allowed)
				(footprints allowed)
			)
			(placement
				(enabled no)
				(sheetname "")
			)
			(fill
				(thermal_gap 0.5)
				(thermal_bridge_width 0.5)
				(island_removal_mode 0)
			)
			(polygon
				(pts
					(arc
						(start 107.730798 -90.349832)
						(mid 106.968798 -90.349832)
						(end 107.730798 -90.349832)
					)
				)
			)
		)
		(zone
			(layer "F.Cu")
			(hatch none 0.5)
			(connect_pads
				(clearance 0)
			)
			(min_thickness 0.25)
			(keepout
				(tracks allowed)
				(vias not_allowed)
				(pads allowed)
				(copperpour not_allowed)
				(footprints allowed)
			)
			(placement
				(enabled no)
				(sheetname "")
			)
			(fill
				(thermal_gap 0.5)
				(thermal_bridge_width 0.5)
				(island_removal_mode 0)
			)
			(polygon
				(pts
					(arc
						(start 107.730798 -89.349834)
						(mid 106.968798 -89.349834)
						(end 107.730798 -89.349834)
					)
				)
			)
		)
		(zone
			(layer "F.Cu")
			(hatch none 0.5)
			(connect_pads
				(clearance 0)
			)
			(min_thickness 0.25)
			(keepout
				(tracks allowed)
				(vias not_allowed)
				(pads allowed)
				(copperpour not_allowed)
				(footprints allowed)
			)
			(placement
				(enabled no)
				(sheetname "")
			)
			(fill
				(thermal_gap 0.5)
				(thermal_bridge_width 0.5)
				(island_removal_mode 0)
			)
			(polygon
				(pts
					(arc
						(start 107.730798 -88.349836)
						(mid 106.968798 -88.349836)
						(end 107.730798 -88.349836)
					)
				)
			)
		)
		(zone
			(layer "F.Cu")
			(hatch none 0.5)
			(connect_pads
				(clearance 0)
			)
			(min_thickness 0.25)
			(keepout
				(tracks allowed)
				(vias not_allowed)
				(pads allowed)
				(copperpour not_allowed)
				(footprints allowed)
			)
			(placement
				(enabled no)
				(sheetname "")
			)
			(fill
				(thermal_gap 0.5)
				(thermal_bridge_width 0.5)
				(island_removal_mode 0)
			)
			(polygon
				(pts
					(arc
						(start 107.730798 -87.349838)
						(mid 106.968798 -87.349838)
						(end 107.730798 -87.349838)
					)
				)
			)
		)
		(zone
			(layer "F.Cu")
			(hatch none 0.5)
			(connect_pads
				(clearance 0)
			)
			(min_thickness 0.25)
			(keepout
				(tracks allowed)
				(vias not_allowed)
				(pads allowed)
				(copperpour not_allowed)
				(footprints allowed)
			)
			(placement
				(enabled no)
				(sheetname "")
			)
			(fill
				(thermal_gap 0.5)
				(thermal_bridge_width 0.5)
				(island_removal_mode 0)
			)
			(polygon
				(pts
					(arc
						(start 107.730798 -86.34984)
						(mid 106.968798 -86.34984)
						(end 107.730798 -86.34984)
					)
				)
			)
		)
		(zone
			(layer "F.Cu")
			(hatch none 0.5)
			(connect_pads
				(clearance 0)
			)
			(min_thickness 0.25)
			(keepout
				(tracks allowed)
				(vias not_allowed)
				(pads allowed)
				(copperpour not_allowed)
				(footprints allowed)
			)
			(placement
				(enabled no)
				(sheetname "")
			)
			(fill
				(thermal_gap 0.5)
				(thermal_bridge_width 0.5)
				(island_removal_mode 0)
			)
			(polygon
				(pts
					(arc
						(start 107.730798 -85.349842)
						(mid 106.968798 -85.349842)
						(end 107.730798 -85.349842)
					)
				)
			)
		)
		(zone
			(layer "F.Cu")
			(hatch none 0.5)
			(connect_pads
				(clearance 0)
			)
			(min_thickness 0.25)
			(keepout
				(tracks allowed)
				(vias not_allowed)
				(pads allowed)
				(copperpour not_allowed)
				(footprints allowed)
			)
			(placement
				(enabled no)
				(sheetname "")
			)
			(fill
				(thermal_gap 0.5)
				(thermal_bridge_width 0.5)
				(island_removal_mode 0)
			)
			(polygon
				(pts
					(arc
						(start 107.730798 -84.349844)
						(mid 106.968798 -84.349844)
						(end 107.730798 -84.349844)
					)
				)
			)
		)
		(zone
			(layer "F.Cu")
			(hatch none 0.5)
			(connect_pads
				(clearance 0)
			)
			(min_thickness 0.25)
			(keepout
				(tracks allowed)
				(vias not_allowed)
				(pads allowed)
				(copperpour not_allowed)
				(footprints allowed)
			)
			(placement
				(enabled no)
				(sheetname "")
			)
			(fill
				(thermal_gap 0.5)
				(thermal_bridge_width 0.5)
				(island_removal_mode 0)
			)
			(polygon
				(pts
					(arc
						(start 107.730798 -83.349846)
						(mid 106.968798 -83.349846)
						(end 107.730798 -83.349846)
					)
				)
			)
		)
		(zone
			(layer "F.Cu")
			(hatch none 0.5)
			(connect_pads
				(clearance 0)
			)
			(min_thickness 0.25)
			(keepout
				(tracks allowed)
				(vias not_allowed)
				(pads allowed)
				(copperpour not_allowed)
				(footprints allowed)
			)
			(placement
				(enabled no)
				(sheetname "")
			)
			(fill
				(thermal_gap 0.5)
				(thermal_bridge_width 0.5)
				(island_removal_mode 0)
			)
			(polygon
				(pts
					(arc
						(start 107.730798 -82.349848)
						(mid 106.968798 -82.349848)
						(end 107.730798 -82.349848)
					)
				)
			)
		)
		(zone
			(layer "F.Cu")
			(hatch none 0.5)
			(connect_pads
				(clearance 0)
			)
			(min_thickness 0.25)
			(keepout
				(tracks allowed)
				(vias not_allowed)
				(pads allowed)
				(copperpour not_allowed)
				(footprints allowed)
			)
			(placement
				(enabled no)
				(sheetname "")
			)
			(fill
				(thermal_gap 0.5)
				(thermal_bridge_width 0.5)
				(island_removal_mode 0)
			)
			(polygon
				(pts
					(arc
						(start 108.730796 -107.350052)
						(mid 107.968796 -107.350052)
						(end 108.730796 -107.350052)
					)
				)
			)
		)
		(zone
			(layer "F.Cu")
			(hatch none 0.5)
			(connect_pads
				(clearance 0)
			)
			(min_thickness 0.25)
			(keepout
				(tracks allowed)
				(vias not_allowed)
				(pads allowed)
				(copperpour not_allowed)
				(footprints allowed)
			)
			(placement
				(enabled no)
				(sheetname "")
			)
			(fill
				(thermal_gap 0.5)
				(thermal_bridge_width 0.5)
				(island_removal_mode 0)
			)
			(polygon
				(pts
					(arc
						(start 108.730796 -106.350054)
						(mid 107.968796 -106.350054)
						(end 108.730796 -106.350054)
					)
				)
			)
		)
		(zone
			(layer "F.Cu")
			(hatch none 0.5)
			(connect_pads
				(clearance 0)
			)
			(min_thickness 0.25)
			(keepout
				(tracks allowed)
				(vias not_allowed)
				(pads allowed)
				(copperpour not_allowed)
				(footprints allowed)
			)
			(placement
				(enabled no)
				(sheetname "")
			)
			(fill
				(thermal_gap 0.5)
				(thermal_bridge_width 0.5)
				(island_removal_mode 0)
			)
			(polygon
				(pts
					(arc
						(start 108.730796 -105.350056)
						(mid 107.968796 -105.350056)
						(end 108.730796 -105.350056)
					)
				)
			)
		)
		(zone
			(layer "F.Cu")
			(hatch none 0.5)
			(connect_pads
				(clearance 0)
			)
			(min_thickness 0.25)
			(keepout
				(tracks allowed)
				(vias not_allowed)
				(pads allowed)
				(copperpour not_allowed)
				(footprints allowed)
			)
			(placement
				(enabled no)
				(sheetname "")
			)
			(fill
				(thermal_gap 0.5)
				(thermal_bridge_width 0.5)
				(island_removal_mode 0)
			)
			(polygon
				(pts
					(arc
						(start 108.730796 -104.350058)
						(mid 107.968796 -104.350058)
						(end 108.730796 -104.350058)
					)
				)
			)
		)
		(zone
			(layer "F.Cu")
			(hatch none 0.5)
			(connect_pads
				(clearance 0)
			)
			(min_thickness 0.25)
			(keepout
				(tracks allowed)
				(vias not_allowed)
				(pads allowed)
				(copperpour not_allowed)
				(footprints allowed)
			)
			(placement
				(enabled no)
				(sheetname "")
			)
			(fill
				(thermal_gap 0.5)
				(thermal_bridge_width 0.5)
				(island_removal_mode 0)
			)
			(polygon
				(pts
					(arc
						(start 108.730796 -103.35006)
						(mid 107.968796 -103.35006)
						(end 108.730796 -103.35006)
					)
				)
			)
		)
		(zone
			(layer "F.Cu")
			(hatch none 0.5)
			(connect_pads
				(clearance 0)
			)
			(min_thickness 0.25)
			(keepout
				(tracks allowed)
				(vias not_allowed)
				(pads allowed)
				(copperpour not_allowed)
				(footprints allowed)
			)
			(placement
				(enabled no)
				(sheetname "")
			)
			(fill
				(thermal_gap 0.5)
				(thermal_bridge_width 0.5)
				(island_removal_mode 0)
			)
			(polygon
				(pts
					(arc
						(start 108.730796 -102.350062)
						(mid 107.968796 -102.350062)
						(end 108.730796 -102.350062)
					)
				)
			)
		)
		(zone
			(layer "F.Cu")
			(hatch none 0.5)
			(connect_pads
				(clearance 0)
			)
			(min_thickness 0.25)
			(keepout
				(tracks allowed)
				(vias not_allowed)
				(pads allowed)
				(copperpour not_allowed)
				(footprints allowed)
			)
			(placement
				(enabled no)
				(sheetname "")
			)
			(fill
				(thermal_gap 0.5)
				(thermal_bridge_width 0.5)
				(island_removal_mode 0)
			)
			(polygon
				(pts
					(arc
						(start 108.730796 -101.350064)
						(mid 107.968796 -101.350064)
						(end 108.730796 -101.350064)
					)
				)
			)
		)
		(zone
			(layer "F.Cu")
			(hatch none 0.5)
			(connect_pads
				(clearance 0)
			)
			(min_thickness 0.25)
			(keepout
				(tracks allowed)
				(vias not_allowed)
				(pads allowed)
				(copperpour not_allowed)
				(footprints allowed)
			)
			(placement
				(enabled no)
				(sheetname "")
			)
			(fill
				(thermal_gap 0.5)
				(thermal_bridge_width 0.5)
				(island_removal_mode 0)
			)
			(polygon
				(pts
					(arc
						(start 108.730796 -100.350066)
						(mid 107.968796 -100.350066)
						(end 108.730796 -100.350066)
					)
				)
			)
		)
		(zone
			(layer "F.Cu")
			(hatch none 0.5)
			(connect_pads
				(clearance 0)
			)
			(min_thickness 0.25)
			(keepout
				(tracks allowed)
				(vias not_allowed)
				(pads allowed)
				(copperpour not_allowed)
				(footprints allowed)
			)
			(placement
				(enabled no)
				(sheetname "")
			)
			(fill
				(thermal_gap 0.5)
				(thermal_bridge_width 0.5)
				(island_removal_mode 0)
			)
			(polygon
				(pts
					(arc
						(start 108.730796 -99.350068)
						(mid 107.968796 -99.350068)
						(end 108.730796 -99.350068)
					)
				)
			)
		)
		(zone
			(layer "F.Cu")
			(hatch none 0.5)
			(connect_pads
				(clearance 0)
			)
			(min_thickness 0.25)
			(keepout
				(tracks allowed)
				(vias not_allowed)
				(pads allowed)
				(copperpour not_allowed)
				(footprints allowed)
			)
			(placement
				(enabled no)
				(sheetname "")
			)
			(fill
				(thermal_gap 0.5)
				(thermal_bridge_width 0.5)
				(island_removal_mode 0)
			)
			(polygon
				(pts
					(arc
						(start 108.730796 -98.35007)
						(mid 107.968796 -98.35007)
						(end 108.730796 -98.35007)
					)
				)
			)
		)
		(zone
			(layer "F.Cu")
			(hatch none 0.5)
			(connect_pads
				(clearance 0)
			)
			(min_thickness 0.25)
			(keepout
				(tracks allowed)
				(vias not_allowed)
				(pads allowed)
				(copperpour not_allowed)
				(footprints allowed)
			)
			(placement
				(enabled no)
				(sheetname "")
			)
			(fill
				(thermal_gap 0.5)
				(thermal_bridge_width 0.5)
				(island_removal_mode 0)
			)
			(polygon
				(pts
					(arc
						(start 108.730796 -97.350072)
						(mid 107.968796 -97.350072)
						(end 108.730796 -97.350072)
					)
				)
			)
		)
		(zone
			(layer "F.Cu")
			(hatch none 0.5)
			(connect_pads
				(clearance 0)
			)
			(min_thickness 0.25)
			(keepout
				(tracks allowed)
				(vias not_allowed)
				(pads allowed)
				(copperpour not_allowed)
				(footprints allowed)
			)
			(placement
				(enabled no)
				(sheetname "")
			)
			(fill
				(thermal_gap 0.5)
				(thermal_bridge_width 0.5)
				(island_removal_mode 0)
			)
			(polygon
				(pts
					(arc
						(start 108.730796 -96.350074)
						(mid 107.968796 -96.350074)
						(end 108.730796 -96.350074)
					)
				)
			)
		)
		(zone
			(layer "F.Cu")
			(hatch none 0.5)
			(connect_pads
				(clearance 0)
			)
			(min_thickness 0.25)
			(keepout
				(tracks allowed)
				(vias not_allowed)
				(pads allowed)
				(copperpour not_allowed)
				(footprints allowed)
			)
			(placement
				(enabled no)
				(sheetname "")
			)
			(fill
				(thermal_gap 0.5)
				(thermal_bridge_width 0.5)
				(island_removal_mode 0)
			)
			(polygon
				(pts
					(arc
						(start 108.730796 -95.350076)
						(mid 107.968796 -95.350076)
						(end 108.730796 -95.350076)
					)
				)
			)
		)
		(zone
			(layer "F.Cu")
			(hatch none 0.5)
			(connect_pads
				(clearance 0)
			)
			(min_thickness 0.25)
			(keepout
				(tracks allowed)
				(vias not_allowed)
				(pads allowed)
				(copperpour not_allowed)
				(footprints allowed)
			)
			(placement
				(enabled no)
				(sheetname "")
			)
			(fill
				(thermal_gap 0.5)
				(thermal_bridge_width 0.5)
				(island_removal_mode 0)
			)
			(polygon
				(pts
					(arc
						(start 108.730796 -94.349824)
						(mid 107.968796 -94.349824)
						(end 108.730796 -94.349824)
					)
				)
			)
		)
		(zone
			(layer "F.Cu")
			(hatch none 0.5)
			(connect_pads
				(clearance 0)
			)
			(min_thickness 0.25)
			(keepout
				(tracks allowed)
				(vias not_allowed)
				(pads allowed)
				(copperpour not_allowed)
				(footprints allowed)
			)
			(placement
				(enabled no)
				(sheetname "")
			)
			(fill
				(thermal_gap 0.5)
				(thermal_bridge_width 0.5)
				(island_removal_mode 0)
			)
			(polygon
				(pts
					(arc
						(start 108.730796 -93.349826)
						(mid 107.968796 -93.349826)
						(end 108.730796 -93.349826)
					)
				)
			)
		)
		(zone
			(layer "F.Cu")
			(hatch none 0.5)
			(connect_pads
				(clearance 0)
			)
			(min_thickness 0.25)
			(keepout
				(tracks allowed)
				(vias not_allowed)
				(pads allowed)
				(copperpour not_allowed)
				(footprints allowed)
			)
			(placement
				(enabled no)
				(sheetname "")
			)
			(fill
				(thermal_gap 0.5)
				(thermal_bridge_width 0.5)
				(island_removal_mode 0)
			)
			(polygon
				(pts
					(arc
						(start 108.730796 -92.349828)
						(mid 107.968796 -92.349828)
						(end 108.730796 -92.349828)
					)
				)
			)
		)
		(zone
			(layer "F.Cu")
			(hatch none 0.5)
			(connect_pads
				(clearance 0)
			)
			(min_thickness 0.25)
			(keepout
				(tracks allowed)
				(vias not_allowed)
				(pads allowed)
				(copperpour not_allowed)
				(footprints allowed)
			)
			(placement
				(enabled no)
				(sheetname "")
			)
			(fill
				(thermal_gap 0.5)
				(thermal_bridge_width 0.5)
				(island_removal_mode 0)
			)
			(polygon
				(pts
					(arc
						(start 108.730796 -91.34983)
						(mid 107.968796 -91.34983)
						(end 108.730796 -91.34983)
					)
				)
			)
		)
		(zone
			(layer "F.Cu")
			(hatch none 0.5)
			(connect_pads
				(clearance 0)
			)
			(min_thickness 0.25)
			(keepout
				(tracks allowed)
				(vias not_allowed)
				(pads allowed)
				(copperpour not_allowed)
				(footprints allowed)
			)
			(placement
				(enabled no)
				(sheetname "")
			)
			(fill
				(thermal_gap 0.5)
				(thermal_bridge_width 0.5)
				(island_removal_mode 0)
			)
			(polygon
				(pts
					(arc
						(start 108.730796 -90.349832)
						(mid 107.968796 -90.349832)
						(end 108.730796 -90.349832)
					)
				)
			)
		)
		(zone
			(layer "F.Cu")
			(hatch none 0.5)
			(connect_pads
				(clearance 0)
			)
			(min_thickness 0.25)
			(keepout
				(tracks allowed)
				(vias not_allowed)
				(pads allowed)
				(copperpour not_allowed)
				(footprints allowed)
			)
			(placement
				(enabled no)
				(sheetname "")
			)
			(fill
				(thermal_gap 0.5)
				(thermal_bridge_width 0.5)
				(island_removal_mode 0)
			)
			(polygon
				(pts
					(arc
						(start 108.730796 -89.349834)
						(mid 107.968796 -89.349834)
						(end 108.730796 -89.349834)
					)
				)
			)
		)
		(zone
			(layer "F.Cu")
			(hatch none 0.5)
			(connect_pads
				(clearance 0)
			)
			(min_thickness 0.25)
			(keepout
				(tracks allowed)
				(vias not_allowed)
				(pads allowed)
				(copperpour not_allowed)
				(footprints allowed)
			)
			(placement
				(enabled no)
				(sheetname "")
			)
			(fill
				(thermal_gap 0.5)
				(thermal_bridge_width 0.5)
				(island_removal_mode 0)
			)
			(polygon
				(pts
					(arc
						(start 108.730796 -88.349836)
						(mid 107.968796 -88.349836)
						(end 108.730796 -88.349836)
					)
				)
			)
		)
		(zone
			(layer "F.Cu")
			(hatch none 0.5)
			(connect_pads
				(clearance 0)
			)
			(min_thickness 0.25)
			(keepout
				(tracks allowed)
				(vias not_allowed)
				(pads allowed)
				(copperpour not_allowed)
				(footprints allowed)
			)
			(placement
				(enabled no)
				(sheetname "")
			)
			(fill
				(thermal_gap 0.5)
				(thermal_bridge_width 0.5)
				(island_removal_mode 0)
			)
			(polygon
				(pts
					(arc
						(start 108.730796 -87.349838)
						(mid 107.968796 -87.349838)
						(end 108.730796 -87.349838)
					)
				)
			)
		)
		(zone
			(layer "F.Cu")
			(hatch none 0.5)
			(connect_pads
				(clearance 0)
			)
			(min_thickness 0.25)
			(keepout
				(tracks allowed)
				(vias not_allowed)
				(pads allowed)
				(copperpour not_allowed)
				(footprints allowed)
			)
			(placement
				(enabled no)
				(sheetname "")
			)
			(fill
				(thermal_gap 0.5)
				(thermal_bridge_width 0.5)
				(island_removal_mode 0)
			)
			(polygon
				(pts
					(arc
						(start 108.730796 -86.34984)
						(mid 107.968796 -86.34984)
						(end 108.730796 -86.34984)
					)
				)
			)
		)
		(zone
			(layer "F.Cu")
			(hatch none 0.5)
			(connect_pads
				(clearance 0)
			)
			(min_thickness 0.25)
			(keepout
				(tracks allowed)
				(vias not_allowed)
				(pads allowed)
				(copperpour not_allowed)
				(footprints allowed)
			)
			(placement
				(enabled no)
				(sheetname "")
			)
			(fill
				(thermal_gap 0.5)
				(thermal_bridge_width 0.5)
				(island_removal_mode 0)
			)
			(polygon
				(pts
					(arc
						(start 108.730796 -85.349842)
						(mid 107.968796 -85.349842)
						(end 108.730796 -85.349842)
					)
				)
			)
		)
		(zone
			(layer "F.Cu")
			(hatch none 0.5)
			(connect_pads
				(clearance 0)
			)
			(min_thickness 0.25)
			(keepout
				(tracks allowed)
				(vias not_allowed)
				(pads allowed)
				(copperpour not_allowed)
				(footprints allowed)
			)
			(placement
				(enabled no)
				(sheetname "")
			)
			(fill
				(thermal_gap 0.5)
				(thermal_bridge_width 0.5)
				(island_removal_mode 0)
			)
			(polygon
				(pts
					(arc
						(start 108.730796 -84.349844)
						(mid 107.968796 -84.349844)
						(end 108.730796 -84.349844)
					)
				)
			)
		)
		(zone
			(layer "F.Cu")
			(hatch none 0.5)
			(connect_pads
				(clearance 0)
			)
			(min_thickness 0.25)
			(keepout
				(tracks allowed)
				(vias not_allowed)
				(pads allowed)
				(copperpour not_allowed)
				(footprints allowed)
			)
			(placement
				(enabled no)
				(sheetname "")
			)
			(fill
				(thermal_gap 0.5)
				(thermal_bridge_width 0.5)
				(island_removal_mode 0)
			)
			(polygon
				(pts
					(arc
						(start 108.730796 -83.349846)
						(mid 107.968796 -83.349846)
						(end 108.730796 -83.349846)
					)
				)
			)
		)
		(zone
			(layer "F.Cu")
			(hatch none 0.5)
			(connect_pads
				(clearance 0)
			)
			(min_thickness 0.25)
			(keepout
				(tracks allowed)
				(vias not_allowed)
				(pads allowed)
				(copperpour not_allowed)
				(footprints allowed)
			)
			(placement
				(enabled no)
				(sheetname "")
			)
			(fill
				(thermal_gap 0.5)
				(thermal_bridge_width 0.5)
				(island_removal_mode 0)
			)
			(polygon
				(pts
					(arc
						(start 108.730796 -82.349848)
						(mid 107.968796 -82.349848)
						(end 108.730796 -82.349848)
					)
				)
			)
		)
		(zone
			(layer "F.Cu")
			(hatch none 0.5)
			(connect_pads
				(clearance 0)
			)
			(min_thickness 0.25)
			(keepout
				(tracks allowed)
				(vias not_allowed)
				(pads allowed)
				(copperpour not_allowed)
				(footprints allowed)
			)
			(placement
				(enabled no)
				(sheetname "")
			)
			(fill
				(thermal_gap 0.5)
				(thermal_bridge_width 0.5)
				(island_removal_mode 0)
			)
			(polygon
				(pts
					(arc
						(start 109.730794 -107.350052)
						(mid 108.968794 -107.350052)
						(end 109.730794 -107.350052)
					)
				)
			)
		)
		(zone
			(layer "F.Cu")
			(hatch none 0.5)
			(connect_pads
				(clearance 0)
			)
			(min_thickness 0.25)
			(keepout
				(tracks allowed)
				(vias not_allowed)
				(pads allowed)
				(copperpour not_allowed)
				(footprints allowed)
			)
			(placement
				(enabled no)
				(sheetname "")
			)
			(fill
				(thermal_gap 0.5)
				(thermal_bridge_width 0.5)
				(island_removal_mode 0)
			)
			(polygon
				(pts
					(arc
						(start 109.730794 -106.350054)
						(mid 108.968794 -106.350054)
						(end 109.730794 -106.350054)
					)
				)
			)
		)
		(zone
			(layer "F.Cu")
			(hatch none 0.5)
			(connect_pads
				(clearance 0)
			)
			(min_thickness 0.25)
			(keepout
				(tracks allowed)
				(vias not_allowed)
				(pads allowed)
				(copperpour not_allowed)
				(footprints allowed)
			)
			(placement
				(enabled no)
				(sheetname "")
			)
			(fill
				(thermal_gap 0.5)
				(thermal_bridge_width 0.5)
				(island_removal_mode 0)
			)
			(polygon
				(pts
					(arc
						(start 109.730794 -105.350056)
						(mid 108.968794 -105.350056)
						(end 109.730794 -105.350056)
					)
				)
			)
		)
		(zone
			(layer "F.Cu")
			(hatch none 0.5)
			(connect_pads
				(clearance 0)
			)
			(min_thickness 0.25)
			(keepout
				(tracks allowed)
				(vias not_allowed)
				(pads allowed)
				(copperpour not_allowed)
				(footprints allowed)
			)
			(placement
				(enabled no)
				(sheetname "")
			)
			(fill
				(thermal_gap 0.5)
				(thermal_bridge_width 0.5)
				(island_removal_mode 0)
			)
			(polygon
				(pts
					(arc
						(start 109.730794 -104.350058)
						(mid 108.968794 -104.350058)
						(end 109.730794 -104.350058)
					)
				)
			)
		)
		(zone
			(layer "F.Cu")
			(hatch none 0.5)
			(connect_pads
				(clearance 0)
			)
			(min_thickness 0.25)
			(keepout
				(tracks allowed)
				(vias not_allowed)
				(pads allowed)
				(copperpour not_allowed)
				(footprints allowed)
			)
			(placement
				(enabled no)
				(sheetname "")
			)
			(fill
				(thermal_gap 0.5)
				(thermal_bridge_width 0.5)
				(island_removal_mode 0)
			)
			(polygon
				(pts
					(arc
						(start 109.730794 -103.35006)
						(mid 108.968794 -103.35006)
						(end 109.730794 -103.35006)
					)
				)
			)
		)
		(zone
			(layer "F.Cu")
			(hatch none 0.5)
			(connect_pads
				(clearance 0)
			)
			(min_thickness 0.25)
			(keepout
				(tracks allowed)
				(vias not_allowed)
				(pads allowed)
				(copperpour not_allowed)
				(footprints allowed)
			)
			(placement
				(enabled no)
				(sheetname "")
			)
			(fill
				(thermal_gap 0.5)
				(thermal_bridge_width 0.5)
				(island_removal_mode 0)
			)
			(polygon
				(pts
					(arc
						(start 109.730794 -102.350062)
						(mid 108.968794 -102.350062)
						(end 109.730794 -102.350062)
					)
				)
			)
		)
		(zone
			(layer "F.Cu")
			(hatch none 0.5)
			(connect_pads
				(clearance 0)
			)
			(min_thickness 0.25)
			(keepout
				(tracks allowed)
				(vias not_allowed)
				(pads allowed)
				(copperpour not_allowed)
				(footprints allowed)
			)
			(placement
				(enabled no)
				(sheetname "")
			)
			(fill
				(thermal_gap 0.5)
				(thermal_bridge_width 0.5)
				(island_removal_mode 0)
			)
			(polygon
				(pts
					(arc
						(start 109.730794 -101.350064)
						(mid 108.968794 -101.350064)
						(end 109.730794 -101.350064)
					)
				)
			)
		)
		(zone
			(layer "F.Cu")
			(hatch none 0.5)
			(connect_pads
				(clearance 0)
			)
			(min_thickness 0.25)
			(keepout
				(tracks allowed)
				(vias not_allowed)
				(pads allowed)
				(copperpour not_allowed)
				(footprints allowed)
			)
			(placement
				(enabled no)
				(sheetname "")
			)
			(fill
				(thermal_gap 0.5)
				(thermal_bridge_width 0.5)
				(island_removal_mode 0)
			)
			(polygon
				(pts
					(arc
						(start 109.730794 -100.350066)
						(mid 108.968794 -100.350066)
						(end 109.730794 -100.350066)
					)
				)
			)
		)
		(zone
			(layer "F.Cu")
			(hatch none 0.5)
			(connect_pads
				(clearance 0)
			)
			(min_thickness 0.25)
			(keepout
				(tracks allowed)
				(vias not_allowed)
				(pads allowed)
				(copperpour not_allowed)
				(footprints allowed)
			)
			(placement
				(enabled no)
				(sheetname "")
			)
			(fill
				(thermal_gap 0.5)
				(thermal_bridge_width 0.5)
				(island_removal_mode 0)
			)
			(polygon
				(pts
					(arc
						(start 109.730794 -99.350068)
						(mid 108.968794 -99.350068)
						(end 109.730794 -99.350068)
					)
				)
			)
		)
		(zone
			(layer "F.Cu")
			(hatch none 0.5)
			(connect_pads
				(clearance 0)
			)
			(min_thickness 0.25)
			(keepout
				(tracks allowed)
				(vias not_allowed)
				(pads allowed)
				(copperpour not_allowed)
				(footprints allowed)
			)
			(placement
				(enabled no)
				(sheetname "")
			)
			(fill
				(thermal_gap 0.5)
				(thermal_bridge_width 0.5)
				(island_removal_mode 0)
			)
			(polygon
				(pts
					(arc
						(start 109.730794 -98.35007)
						(mid 108.968794 -98.35007)
						(end 109.730794 -98.35007)
					)
				)
			)
		)
		(zone
			(layer "F.Cu")
			(hatch none 0.5)
			(connect_pads
				(clearance 0)
			)
			(min_thickness 0.25)
			(keepout
				(tracks allowed)
				(vias not_allowed)
				(pads allowed)
				(copperpour not_allowed)
				(footprints allowed)
			)
			(placement
				(enabled no)
				(sheetname "")
			)
			(fill
				(thermal_gap 0.5)
				(thermal_bridge_width 0.5)
				(island_removal_mode 0)
			)
			(polygon
				(pts
					(arc
						(start 109.730794 -97.350072)
						(mid 108.968794 -97.350072)
						(end 109.730794 -97.350072)
					)
				)
			)
		)
		(zone
			(layer "F.Cu")
			(hatch none 0.5)
			(connect_pads
				(clearance 0)
			)
			(min_thickness 0.25)
			(keepout
				(tracks allowed)
				(vias not_allowed)
				(pads allowed)
				(copperpour not_allowed)
				(footprints allowed)
			)
			(placement
				(enabled no)
				(sheetname "")
			)
			(fill
				(thermal_gap 0.5)
				(thermal_bridge_width 0.5)
				(island_removal_mode 0)
			)
			(polygon
				(pts
					(arc
						(start 109.730794 -96.350074)
						(mid 108.968794 -96.350074)
						(end 109.730794 -96.350074)
					)
				)
			)
		)
		(zone
			(layer "F.Cu")
			(hatch none 0.5)
			(connect_pads
				(clearance 0)
			)
			(min_thickness 0.25)
			(keepout
				(tracks allowed)
				(vias not_allowed)
				(pads allowed)
				(copperpour not_allowed)
				(footprints allowed)
			)
			(placement
				(enabled no)
				(sheetname "")
			)
			(fill
				(thermal_gap 0.5)
				(thermal_bridge_width 0.5)
				(island_removal_mode 0)
			)
			(polygon
				(pts
					(arc
						(start 109.730794 -95.350076)
						(mid 108.968794 -95.350076)
						(end 109.730794 -95.350076)
					)
				)
			)
		)
		(zone
			(layer "F.Cu")
			(hatch none 0.5)
			(connect_pads
				(clearance 0)
			)
			(min_thickness 0.25)
			(keepout
				(tracks allowed)
				(vias not_allowed)
				(pads allowed)
				(copperpour not_allowed)
				(footprints allowed)
			)
			(placement
				(enabled no)
				(sheetname "")
			)
			(fill
				(thermal_gap 0.5)
				(thermal_bridge_width 0.5)
				(island_removal_mode 0)
			)
			(polygon
				(pts
					(arc
						(start 109.730794 -94.349824)
						(mid 108.968794 -94.349824)
						(end 109.730794 -94.349824)
					)
				)
			)
		)
		(zone
			(layer "F.Cu")
			(hatch none 0.5)
			(connect_pads
				(clearance 0)
			)
			(min_thickness 0.25)
			(keepout
				(tracks allowed)
				(vias not_allowed)
				(pads allowed)
				(copperpour not_allowed)
				(footprints allowed)
			)
			(placement
				(enabled no)
				(sheetname "")
			)
			(fill
				(thermal_gap 0.5)
				(thermal_bridge_width 0.5)
				(island_removal_mode 0)
			)
			(polygon
				(pts
					(arc
						(start 109.730794 -93.349826)
						(mid 108.968794 -93.349826)
						(end 109.730794 -93.349826)
					)
				)
			)
		)
		(zone
			(layer "F.Cu")
			(hatch none 0.5)
			(connect_pads
				(clearance 0)
			)
			(min_thickness 0.25)
			(keepout
				(tracks allowed)
				(vias not_allowed)
				(pads allowed)
				(copperpour not_allowed)
				(footprints allowed)
			)
			(placement
				(enabled no)
				(sheetname "")
			)
			(fill
				(thermal_gap 0.5)
				(thermal_bridge_width 0.5)
				(island_removal_mode 0)
			)
			(polygon
				(pts
					(arc
						(start 109.730794 -92.349828)
						(mid 108.968794 -92.349828)
						(end 109.730794 -92.349828)
					)
				)
			)
		)
		(zone
			(layer "F.Cu")
			(hatch none 0.5)
			(connect_pads
				(clearance 0)
			)
			(min_thickness 0.25)
			(keepout
				(tracks allowed)
				(vias not_allowed)
				(pads allowed)
				(copperpour not_allowed)
				(footprints allowed)
			)
			(placement
				(enabled no)
				(sheetname "")
			)
			(fill
				(thermal_gap 0.5)
				(thermal_bridge_width 0.5)
				(island_removal_mode 0)
			)
			(polygon
				(pts
					(arc
						(start 109.730794 -91.34983)
						(mid 108.968794 -91.34983)
						(end 109.730794 -91.34983)
					)
				)
			)
		)
		(zone
			(layer "F.Cu")
			(hatch none 0.5)
			(connect_pads
				(clearance 0)
			)
			(min_thickness 0.25)
			(keepout
				(tracks allowed)
				(vias not_allowed)
				(pads allowed)
				(copperpour not_allowed)
				(footprints allowed)
			)
			(placement
				(enabled no)
				(sheetname "")
			)
			(fill
				(thermal_gap 0.5)
				(thermal_bridge_width 0.5)
				(island_removal_mode 0)
			)
			(polygon
				(pts
					(arc
						(start 109.730794 -90.349832)
						(mid 108.968794 -90.349832)
						(end 109.730794 -90.349832)
					)
				)
			)
		)
		(zone
			(layer "F.Cu")
			(hatch none 0.5)
			(connect_pads
				(clearance 0)
			)
			(min_thickness 0.25)
			(keepout
				(tracks allowed)
				(vias not_allowed)
				(pads allowed)
				(copperpour not_allowed)
				(footprints allowed)
			)
			(placement
				(enabled no)
				(sheetname "")
			)
			(fill
				(thermal_gap 0.5)
				(thermal_bridge_width 0.5)
				(island_removal_mode 0)
			)
			(polygon
				(pts
					(arc
						(start 109.730794 -89.349834)
						(mid 108.968794 -89.349834)
						(end 109.730794 -89.349834)
					)
				)
			)
		)
		(zone
			(layer "F.Cu")
			(hatch none 0.5)
			(connect_pads
				(clearance 0)
			)
			(min_thickness 0.25)
			(keepout
				(tracks allowed)
				(vias not_allowed)
				(pads allowed)
				(copperpour not_allowed)
				(footprints allowed)
			)
			(placement
				(enabled no)
				(sheetname "")
			)
			(fill
				(thermal_gap 0.5)
				(thermal_bridge_width 0.5)
				(island_removal_mode 0)
			)
			(polygon
				(pts
					(arc
						(start 109.730794 -88.349836)
						(mid 108.968794 -88.349836)
						(end 109.730794 -88.349836)
					)
				)
			)
		)
		(zone
			(layer "F.Cu")
			(hatch none 0.5)
			(connect_pads
				(clearance 0)
			)
			(min_thickness 0.25)
			(keepout
				(tracks allowed)
				(vias not_allowed)
				(pads allowed)
				(copperpour not_allowed)
				(footprints allowed)
			)
			(placement
				(enabled no)
				(sheetname "")
			)
			(fill
				(thermal_gap 0.5)
				(thermal_bridge_width 0.5)
				(island_removal_mode 0)
			)
			(polygon
				(pts
					(arc
						(start 109.730794 -87.349838)
						(mid 108.968794 -87.349838)
						(end 109.730794 -87.349838)
					)
				)
			)
		)
		(zone
			(layer "F.Cu")
			(hatch none 0.5)
			(connect_pads
				(clearance 0)
			)
			(min_thickness 0.25)
			(keepout
				(tracks allowed)
				(vias not_allowed)
				(pads allowed)
				(copperpour not_allowed)
				(footprints allowed)
			)
			(placement
				(enabled no)
				(sheetname "")
			)
			(fill
				(thermal_gap 0.5)
				(thermal_bridge_width 0.5)
				(island_removal_mode 0)
			)
			(polygon
				(pts
					(arc
						(start 109.730794 -86.34984)
						(mid 108.968794 -86.34984)
						(end 109.730794 -86.34984)
					)
				)
			)
		)
		(zone
			(layer "F.Cu")
			(hatch none 0.5)
			(connect_pads
				(clearance 0)
			)
			(min_thickness 0.25)
			(keepout
				(tracks allowed)
				(vias not_allowed)
				(pads allowed)
				(copperpour not_allowed)
				(footprints allowed)
			)
			(placement
				(enabled no)
				(sheetname "")
			)
			(fill
				(thermal_gap 0.5)
				(thermal_bridge_width 0.5)
				(island_removal_mode 0)
			)
			(polygon
				(pts
					(arc
						(start 109.730794 -85.349842)
						(mid 108.968794 -85.349842)
						(end 109.730794 -85.349842)
					)
				)
			)
		)
		(zone
			(layer "F.Cu")
			(hatch none 0.5)
			(connect_pads
				(clearance 0)
			)
			(min_thickness 0.25)
			(keepout
				(tracks allowed)
				(vias not_allowed)
				(pads allowed)
				(copperpour not_allowed)
				(footprints allowed)
			)
			(placement
				(enabled no)
				(sheetname "")
			)
			(fill
				(thermal_gap 0.5)
				(thermal_bridge_width 0.5)
				(island_removal_mode 0)
			)
			(polygon
				(pts
					(arc
						(start 109.730794 -84.349844)
						(mid 108.968794 -84.349844)
						(end 109.730794 -84.349844)
					)
				)
			)
		)
		(zone
			(layer "F.Cu")
			(hatch none 0.5)
			(connect_pads
				(clearance 0)
			)
			(min_thickness 0.25)
			(keepout
				(tracks allowed)
				(vias not_allowed)
				(pads allowed)
				(copperpour not_allowed)
				(footprints allowed)
			)
			(placement
				(enabled no)
				(sheetname "")
			)
			(fill
				(thermal_gap 0.5)
				(thermal_bridge_width 0.5)
				(island_removal_mode 0)
			)
			(polygon
				(pts
					(arc
						(start 109.730794 -83.349846)
						(mid 108.968794 -83.349846)
						(end 109.730794 -83.349846)
					)
				)
			)
		)
		(zone
			(layer "F.Cu")
			(hatch none 0.5)
			(connect_pads
				(clearance 0)
			)
			(min_thickness 0.25)
			(keepout
				(tracks allowed)
				(vias not_allowed)
				(pads allowed)
				(copperpour not_allowed)
				(footprints allowed)
			)
			(placement
				(enabled no)
				(sheetname "")
			)
			(fill
				(thermal_gap 0.5)
				(thermal_bridge_width 0.5)
				(island_removal_mode 0)
			)
			(polygon
				(pts
					(arc
						(start 109.730794 -82.349848)
						(mid 108.968794 -82.349848)
						(end 109.730794 -82.349848)
					)
				)
			)
		)
		(zone
			(layer "F.Cu")
			(hatch none 0.5)
			(connect_pads
				(clearance 0)
			)
			(min_thickness 0.25)
			(keepout
				(tracks allowed)
				(vias not_allowed)
				(pads allowed)
				(copperpour not_allowed)
				(footprints allowed)
			)
			(placement
				(enabled no)
				(sheetname "")
			)
			(fill
				(thermal_gap 0.5)
				(thermal_bridge_width 0.5)
				(island_removal_mode 0)
			)
			(polygon
				(pts
					(arc
						(start 110.730792 -107.350052)
						(mid 109.968792 -107.350052)
						(end 110.730792 -107.350052)
					)
				)
			)
		)
		(zone
			(layer "F.Cu")
			(hatch none 0.5)
			(connect_pads
				(clearance 0)
			)
			(min_thickness 0.25)
			(keepout
				(tracks allowed)
				(vias not_allowed)
				(pads allowed)
				(copperpour not_allowed)
				(footprints allowed)
			)
			(placement
				(enabled no)
				(sheetname "")
			)
			(fill
				(thermal_gap 0.5)
				(thermal_bridge_width 0.5)
				(island_removal_mode 0)
			)
			(polygon
				(pts
					(arc
						(start 110.730792 -106.350054)
						(mid 109.968792 -106.350054)
						(end 110.730792 -106.350054)
					)
				)
			)
		)
		(zone
			(layer "F.Cu")
			(hatch none 0.5)
			(connect_pads
				(clearance 0)
			)
			(min_thickness 0.25)
			(keepout
				(tracks allowed)
				(vias not_allowed)
				(pads allowed)
				(copperpour not_allowed)
				(footprints allowed)
			)
			(placement
				(enabled no)
				(sheetname "")
			)
			(fill
				(thermal_gap 0.5)
				(thermal_bridge_width 0.5)
				(island_removal_mode 0)
			)
			(polygon
				(pts
					(arc
						(start 110.730792 -105.350056)
						(mid 109.968792 -105.350056)
						(end 110.730792 -105.350056)
					)
				)
			)
		)
		(zone
			(layer "F.Cu")
			(hatch none 0.5)
			(connect_pads
				(clearance 0)
			)
			(min_thickness 0.25)
			(keepout
				(tracks allowed)
				(vias not_allowed)
				(pads allowed)
				(copperpour not_allowed)
				(footprints allowed)
			)
			(placement
				(enabled no)
				(sheetname "")
			)
			(fill
				(thermal_gap 0.5)
				(thermal_bridge_width 0.5)
				(island_removal_mode 0)
			)
			(polygon
				(pts
					(arc
						(start 110.730792 -104.350058)
						(mid 109.968792 -104.350058)
						(end 110.730792 -104.350058)
					)
				)
			)
		)
		(zone
			(layer "F.Cu")
			(hatch none 0.5)
			(connect_pads
				(clearance 0)
			)
			(min_thickness 0.25)
			(keepout
				(tracks allowed)
				(vias not_allowed)
				(pads allowed)
				(copperpour not_allowed)
				(footprints allowed)
			)
			(placement
				(enabled no)
				(sheetname "")
			)
			(fill
				(thermal_gap 0.5)
				(thermal_bridge_width 0.5)
				(island_removal_mode 0)
			)
			(polygon
				(pts
					(arc
						(start 110.730792 -103.35006)
						(mid 109.968792 -103.35006)
						(end 110.730792 -103.35006)
					)
				)
			)
		)
		(zone
			(layer "F.Cu")
			(hatch none 0.5)
			(connect_pads
				(clearance 0)
			)
			(min_thickness 0.25)
			(keepout
				(tracks allowed)
				(vias not_allowed)
				(pads allowed)
				(copperpour not_allowed)
				(footprints allowed)
			)
			(placement
				(enabled no)
				(sheetname "")
			)
			(fill
				(thermal_gap 0.5)
				(thermal_bridge_width 0.5)
				(island_removal_mode 0)
			)
			(polygon
				(pts
					(arc
						(start 110.730792 -102.350062)
						(mid 109.968792 -102.350062)
						(end 110.730792 -102.350062)
					)
				)
			)
		)
		(zone
			(layer "F.Cu")
			(hatch none 0.5)
			(connect_pads
				(clearance 0)
			)
			(min_thickness 0.25)
			(keepout
				(tracks allowed)
				(vias not_allowed)
				(pads allowed)
				(copperpour not_allowed)
				(footprints allowed)
			)
			(placement
				(enabled no)
				(sheetname "")
			)
			(fill
				(thermal_gap 0.5)
				(thermal_bridge_width 0.5)
				(island_removal_mode 0)
			)
			(polygon
				(pts
					(arc
						(start 110.730792 -101.350064)
						(mid 109.968792 -101.350064)
						(end 110.730792 -101.350064)
					)
				)
			)
		)
		(zone
			(layer "F.Cu")
			(hatch none 0.5)
			(connect_pads
				(clearance 0)
			)
			(min_thickness 0.25)
			(keepout
				(tracks allowed)
				(vias not_allowed)
				(pads allowed)
				(copperpour not_allowed)
				(footprints allowed)
			)
			(placement
				(enabled no)
				(sheetname "")
			)
			(fill
				(thermal_gap 0.5)
				(thermal_bridge_width 0.5)
				(island_removal_mode 0)
			)
			(polygon
				(pts
					(arc
						(start 110.730792 -100.350066)
						(mid 109.968792 -100.350066)
						(end 110.730792 -100.350066)
					)
				)
			)
		)
		(zone
			(layer "F.Cu")
			(hatch none 0.5)
			(connect_pads
				(clearance 0)
			)
			(min_thickness 0.25)
			(keepout
				(tracks allowed)
				(vias not_allowed)
				(pads allowed)
				(copperpour not_allowed)
				(footprints allowed)
			)
			(placement
				(enabled no)
				(sheetname "")
			)
			(fill
				(thermal_gap 0.5)
				(thermal_bridge_width 0.5)
				(island_removal_mode 0)
			)
			(polygon
				(pts
					(arc
						(start 110.730792 -99.350068)
						(mid 109.968792 -99.350068)
						(end 110.730792 -99.350068)
					)
				)
			)
		)
		(zone
			(layer "F.Cu")
			(hatch none 0.5)
			(connect_pads
				(clearance 0)
			)
			(min_thickness 0.25)
			(keepout
				(tracks allowed)
				(vias not_allowed)
				(pads allowed)
				(copperpour not_allowed)
				(footprints allowed)
			)
			(placement
				(enabled no)
				(sheetname "")
			)
			(fill
				(thermal_gap 0.5)
				(thermal_bridge_width 0.5)
				(island_removal_mode 0)
			)
			(polygon
				(pts
					(arc
						(start 110.730792 -98.35007)
						(mid 109.968792 -98.35007)
						(end 110.730792 -98.35007)
					)
				)
			)
		)
		(zone
			(layer "F.Cu")
			(hatch none 0.5)
			(connect_pads
				(clearance 0)
			)
			(min_thickness 0.25)
			(keepout
				(tracks allowed)
				(vias not_allowed)
				(pads allowed)
				(copperpour not_allowed)
				(footprints allowed)
			)
			(placement
				(enabled no)
				(sheetname "")
			)
			(fill
				(thermal_gap 0.5)
				(thermal_bridge_width 0.5)
				(island_removal_mode 0)
			)
			(polygon
				(pts
					(arc
						(start 110.730792 -97.350072)
						(mid 109.968792 -97.350072)
						(end 110.730792 -97.350072)
					)
				)
			)
		)
		(zone
			(layer "F.Cu")
			(hatch none 0.5)
			(connect_pads
				(clearance 0)
			)
			(min_thickness 0.25)
			(keepout
				(tracks allowed)
				(vias not_allowed)
				(pads allowed)
				(copperpour not_allowed)
				(footprints allowed)
			)
			(placement
				(enabled no)
				(sheetname "")
			)
			(fill
				(thermal_gap 0.5)
				(thermal_bridge_width 0.5)
				(island_removal_mode 0)
			)
			(polygon
				(pts
					(arc
						(start 110.730792 -96.350074)
						(mid 109.968792 -96.350074)
						(end 110.730792 -96.350074)
					)
				)
			)
		)
		(zone
			(layer "F.Cu")
			(hatch none 0.5)
			(connect_pads
				(clearance 0)
			)
			(min_thickness 0.25)
			(keepout
				(tracks allowed)
				(vias not_allowed)
				(pads allowed)
				(copperpour not_allowed)
				(footprints allowed)
			)
			(placement
				(enabled no)
				(sheetname "")
			)
			(fill
				(thermal_gap 0.5)
				(thermal_bridge_width 0.5)
				(island_removal_mode 0)
			)
			(polygon
				(pts
					(arc
						(start 110.730792 -95.350076)
						(mid 109.968792 -95.350076)
						(end 110.730792 -95.350076)
					)
				)
			)
		)
		(zone
			(layer "F.Cu")
			(hatch none 0.5)
			(connect_pads
				(clearance 0)
			)
			(min_thickness 0.25)
			(keepout
				(tracks allowed)
				(vias not_allowed)
				(pads allowed)
				(copperpour not_allowed)
				(footprints allowed)
			)
			(placement
				(enabled no)
				(sheetname "")
			)
			(fill
				(thermal_gap 0.5)
				(thermal_bridge_width 0.5)
				(island_removal_mode 0)
			)
			(polygon
				(pts
					(arc
						(start 110.730792 -94.349824)
						(mid 109.968792 -94.349824)
						(end 110.730792 -94.349824)
					)
				)
			)
		)
		(zone
			(layer "F.Cu")
			(hatch none 0.5)
			(connect_pads
				(clearance 0)
			)
			(min_thickness 0.25)
			(keepout
				(tracks allowed)
				(vias not_allowed)
				(pads allowed)
				(copperpour not_allowed)
				(footprints allowed)
			)
			(placement
				(enabled no)
				(sheetname "")
			)
			(fill
				(thermal_gap 0.5)
				(thermal_bridge_width 0.5)
				(island_removal_mode 0)
			)
			(polygon
				(pts
					(arc
						(start 110.730792 -93.349826)
						(mid 109.968792 -93.349826)
						(end 110.730792 -93.349826)
					)
				)
			)
		)
		(zone
			(layer "F.Cu")
			(hatch none 0.5)
			(connect_pads
				(clearance 0)
			)
			(min_thickness 0.25)
			(keepout
				(tracks allowed)
				(vias not_allowed)
				(pads allowed)
				(copperpour not_allowed)
				(footprints allowed)
			)
			(placement
				(enabled no)
				(sheetname "")
			)
			(fill
				(thermal_gap 0.5)
				(thermal_bridge_width 0.5)
				(island_removal_mode 0)
			)
			(polygon
				(pts
					(arc
						(start 110.730792 -92.349828)
						(mid 109.968792 -92.349828)
						(end 110.730792 -92.349828)
					)
				)
			)
		)
		(zone
			(layer "F.Cu")
			(hatch none 0.5)
			(connect_pads
				(clearance 0)
			)
			(min_thickness 0.25)
			(keepout
				(tracks allowed)
				(vias not_allowed)
				(pads allowed)
				(copperpour not_allowed)
				(footprints allowed)
			)
			(placement
				(enabled no)
				(sheetname "")
			)
			(fill
				(thermal_gap 0.5)
				(thermal_bridge_width 0.5)
				(island_removal_mode 0)
			)
			(polygon
				(pts
					(arc
						(start 110.730792 -91.34983)
						(mid 109.968792 -91.34983)
						(end 110.730792 -91.34983)
					)
				)
			)
		)
		(zone
			(layer "F.Cu")
			(hatch none 0.5)
			(connect_pads
				(clearance 0)
			)
			(min_thickness 0.25)
			(keepout
				(tracks allowed)
				(vias not_allowed)
				(pads allowed)
				(copperpour not_allowed)
				(footprints allowed)
			)
			(placement
				(enabled no)
				(sheetname "")
			)
			(fill
				(thermal_gap 0.5)
				(thermal_bridge_width 0.5)
				(island_removal_mode 0)
			)
			(polygon
				(pts
					(arc
						(start 110.730792 -90.349832)
						(mid 109.968792 -90.349832)
						(end 110.730792 -90.349832)
					)
				)
			)
		)
		(zone
			(layer "F.Cu")
			(hatch none 0.5)
			(connect_pads
				(clearance 0)
			)
			(min_thickness 0.25)
			(keepout
				(tracks allowed)
				(vias not_allowed)
				(pads allowed)
				(copperpour not_allowed)
				(footprints allowed)
			)
			(placement
				(enabled no)
				(sheetname "")
			)
			(fill
				(thermal_gap 0.5)
				(thermal_bridge_width 0.5)
				(island_removal_mode 0)
			)
			(polygon
				(pts
					(arc
						(start 110.730792 -89.349834)
						(mid 109.968792 -89.349834)
						(end 110.730792 -89.349834)
					)
				)
			)
		)
		(zone
			(layer "F.Cu")
			(hatch none 0.5)
			(connect_pads
				(clearance 0)
			)
			(min_thickness 0.25)
			(keepout
				(tracks allowed)
				(vias not_allowed)
				(pads allowed)
				(copperpour not_allowed)
				(footprints allowed)
			)
			(placement
				(enabled no)
				(sheetname "")
			)
			(fill
				(thermal_gap 0.5)
				(thermal_bridge_width 0.5)
				(island_removal_mode 0)
			)
			(polygon
				(pts
					(arc
						(start 110.730792 -88.349836)
						(mid 109.968792 -88.349836)
						(end 110.730792 -88.349836)
					)
				)
			)
		)
		(zone
			(layer "F.Cu")
			(hatch none 0.5)
			(connect_pads
				(clearance 0)
			)
			(min_thickness 0.25)
			(keepout
				(tracks allowed)
				(vias not_allowed)
				(pads allowed)
				(copperpour not_allowed)
				(footprints allowed)
			)
			(placement
				(enabled no)
				(sheetname "")
			)
			(fill
				(thermal_gap 0.5)
				(thermal_bridge_width 0.5)
				(island_removal_mode 0)
			)
			(polygon
				(pts
					(arc
						(start 110.730792 -87.349838)
						(mid 109.968792 -87.349838)
						(end 110.730792 -87.349838)
					)
				)
			)
		)
		(zone
			(layer "F.Cu")
			(hatch none 0.5)
			(connect_pads
				(clearance 0)
			)
			(min_thickness 0.25)
			(keepout
				(tracks allowed)
				(vias not_allowed)
				(pads allowed)
				(copperpour not_allowed)
				(footprints allowed)
			)
			(placement
				(enabled no)
				(sheetname "")
			)
			(fill
				(thermal_gap 0.5)
				(thermal_bridge_width 0.5)
				(island_removal_mode 0)
			)
			(polygon
				(pts
					(arc
						(start 110.730792 -86.34984)
						(mid 109.968792 -86.34984)
						(end 110.730792 -86.34984)
					)
				)
			)
		)
		(zone
			(layer "F.Cu")
			(hatch none 0.5)
			(connect_pads
				(clearance 0)
			)
			(min_thickness 0.25)
			(keepout
				(tracks allowed)
				(vias not_allowed)
				(pads allowed)
				(copperpour not_allowed)
				(footprints allowed)
			)
			(placement
				(enabled no)
				(sheetname "")
			)
			(fill
				(thermal_gap 0.5)
				(thermal_bridge_width 0.5)
				(island_removal_mode 0)
			)
			(polygon
				(pts
					(arc
						(start 110.730792 -85.349842)
						(mid 109.968792 -85.349842)
						(end 110.730792 -85.349842)
					)
				)
			)
		)
		(zone
			(layer "F.Cu")
			(hatch none 0.5)
			(connect_pads
				(clearance 0)
			)
			(min_thickness 0.25)
			(keepout
				(tracks allowed)
				(vias not_allowed)
				(pads allowed)
				(copperpour not_allowed)
				(footprints allowed)
			)
			(placement
				(enabled no)
				(sheetname "")
			)
			(fill
				(thermal_gap 0.5)
				(thermal_bridge_width 0.5)
				(island_removal_mode 0)
			)
			(polygon
				(pts
					(arc
						(start 110.730792 -84.349844)
						(mid 109.968792 -84.349844)
						(end 110.730792 -84.349844)
					)
				)
			)
		)
		(zone
			(layer "F.Cu")
			(hatch none 0.5)
			(connect_pads
				(clearance 0)
			)
			(min_thickness 0.25)
			(keepout
				(tracks allowed)
				(vias not_allowed)
				(pads allowed)
				(copperpour not_allowed)
				(footprints allowed)
			)
			(placement
				(enabled no)
				(sheetname "")
			)
			(fill
				(thermal_gap 0.5)
				(thermal_bridge_width 0.5)
				(island_removal_mode 0)
			)
			(polygon
				(pts
					(arc
						(start 110.730792 -83.349846)
						(mid 109.968792 -83.349846)
						(end 110.730792 -83.349846)
					)
				)
			)
		)
		(zone
			(layer "F.Cu")
			(hatch none 0.5)
			(connect_pads
				(clearance 0)
			)
			(min_thickness 0.25)
			(keepout
				(tracks allowed)
				(vias not_allowed)
				(pads allowed)
				(copperpour not_allowed)
				(footprints allowed)
			)
			(placement
				(enabled no)
				(sheetname "")
			)
			(fill
				(thermal_gap 0.5)
				(thermal_bridge_width 0.5)
				(island_removal_mode 0)
			)
			(polygon
				(pts
					(arc
						(start 110.730792 -82.349848)
						(mid 109.968792 -82.349848)
						(end 110.730792 -82.349848)
					)
				)
			)
		)
		(zone
			(layer "F.Cu")
			(hatch none 0.5)
			(connect_pads
				(clearance 0)
			)
			(min_thickness 0.25)
			(keepout
				(tracks allowed)
				(vias not_allowed)
				(pads allowed)
				(copperpour not_allowed)
				(footprints allowed)
			)
			(placement
				(enabled no)
				(sheetname "")
			)
			(fill
				(thermal_gap 0.5)
				(thermal_bridge_width 0.5)
				(island_removal_mode 0)
			)
			(polygon
				(pts
					(arc
						(start 111.73079 -107.350052)
						(mid 110.96879 -107.350052)
						(end 111.73079 -107.350052)
					)
				)
			)
		)
		(zone
			(layer "F.Cu")
			(hatch none 0.5)
			(connect_pads
				(clearance 0)
			)
			(min_thickness 0.25)
			(keepout
				(tracks allowed)
				(vias not_allowed)
				(pads allowed)
				(copperpour not_allowed)
				(footprints allowed)
			)
			(placement
				(enabled no)
				(sheetname "")
			)
			(fill
				(thermal_gap 0.5)
				(thermal_bridge_width 0.5)
				(island_removal_mode 0)
			)
			(polygon
				(pts
					(arc
						(start 111.73079 -106.350054)
						(mid 110.96879 -106.350054)
						(end 111.73079 -106.350054)
					)
				)
			)
		)
		(zone
			(layer "F.Cu")
			(hatch none 0.5)
			(connect_pads
				(clearance 0)
			)
			(min_thickness 0.25)
			(keepout
				(tracks allowed)
				(vias not_allowed)
				(pads allowed)
				(copperpour not_allowed)
				(footprints allowed)
			)
			(placement
				(enabled no)
				(sheetname "")
			)
			(fill
				(thermal_gap 0.5)
				(thermal_bridge_width 0.5)
				(island_removal_mode 0)
			)
			(polygon
				(pts
					(arc
						(start 111.73079 -105.350056)
						(mid 110.96879 -105.350056)
						(end 111.73079 -105.350056)
					)
				)
			)
		)
		(zone
			(layer "F.Cu")
			(hatch none 0.5)
			(connect_pads
				(clearance 0)
			)
			(min_thickness 0.25)
			(keepout
				(tracks allowed)
				(vias not_allowed)
				(pads allowed)
				(copperpour not_allowed)
				(footprints allowed)
			)
			(placement
				(enabled no)
				(sheetname "")
			)
			(fill
				(thermal_gap 0.5)
				(thermal_bridge_width 0.5)
				(island_removal_mode 0)
			)
			(polygon
				(pts
					(arc
						(start 111.73079 -104.350058)
						(mid 110.96879 -104.350058)
						(end 111.73079 -104.350058)
					)
				)
			)
		)
		(zone
			(layer "F.Cu")
			(hatch none 0.5)
			(connect_pads
				(clearance 0)
			)
			(min_thickness 0.25)
			(keepout
				(tracks allowed)
				(vias not_allowed)
				(pads allowed)
				(copperpour not_allowed)
				(footprints allowed)
			)
			(placement
				(enabled no)
				(sheetname "")
			)
			(fill
				(thermal_gap 0.5)
				(thermal_bridge_width 0.5)
				(island_removal_mode 0)
			)
			(polygon
				(pts
					(arc
						(start 111.73079 -103.35006)
						(mid 110.96879 -103.35006)
						(end 111.73079 -103.35006)
					)
				)
			)
		)
		(zone
			(layer "F.Cu")
			(hatch none 0.5)
			(connect_pads
				(clearance 0)
			)
			(min_thickness 0.25)
			(keepout
				(tracks allowed)
				(vias not_allowed)
				(pads allowed)
				(copperpour not_allowed)
				(footprints allowed)
			)
			(placement
				(enabled no)
				(sheetname "")
			)
			(fill
				(thermal_gap 0.5)
				(thermal_bridge_width 0.5)
				(island_removal_mode 0)
			)
			(polygon
				(pts
					(arc
						(start 111.73079 -102.350062)
						(mid 110.96879 -102.350062)
						(end 111.73079 -102.350062)
					)
				)
			)
		)
		(zone
			(layer "F.Cu")
			(hatch none 0.5)
			(connect_pads
				(clearance 0)
			)
			(min_thickness 0.25)
			(keepout
				(tracks allowed)
				(vias not_allowed)
				(pads allowed)
				(copperpour not_allowed)
				(footprints allowed)
			)
			(placement
				(enabled no)
				(sheetname "")
			)
			(fill
				(thermal_gap 0.5)
				(thermal_bridge_width 0.5)
				(island_removal_mode 0)
			)
			(polygon
				(pts
					(arc
						(start 111.73079 -101.350064)
						(mid 110.96879 -101.350064)
						(end 111.73079 -101.350064)
					)
				)
			)
		)
		(zone
			(layer "F.Cu")
			(hatch none 0.5)
			(connect_pads
				(clearance 0)
			)
			(min_thickness 0.25)
			(keepout
				(tracks allowed)
				(vias not_allowed)
				(pads allowed)
				(copperpour not_allowed)
				(footprints allowed)
			)
			(placement
				(enabled no)
				(sheetname "")
			)
			(fill
				(thermal_gap 0.5)
				(thermal_bridge_width 0.5)
				(island_removal_mode 0)
			)
			(polygon
				(pts
					(arc
						(start 111.73079 -100.350066)
						(mid 110.96879 -100.350066)
						(end 111.73079 -100.350066)
					)
				)
			)
		)
		(zone
			(layer "F.Cu")
			(hatch none 0.5)
			(connect_pads
				(clearance 0)
			)
			(min_thickness 0.25)
			(keepout
				(tracks allowed)
				(vias not_allowed)
				(pads allowed)
				(copperpour not_allowed)
				(footprints allowed)
			)
			(placement
				(enabled no)
				(sheetname "")
			)
			(fill
				(thermal_gap 0.5)
				(thermal_bridge_width 0.5)
				(island_removal_mode 0)
			)
			(polygon
				(pts
					(arc
						(start 111.73079 -99.350068)
						(mid 110.96879 -99.350068)
						(end 111.73079 -99.350068)
					)
				)
			)
		)
		(zone
			(layer "F.Cu")
			(hatch none 0.5)
			(connect_pads
				(clearance 0)
			)
			(min_thickness 0.25)
			(keepout
				(tracks allowed)
				(vias not_allowed)
				(pads allowed)
				(copperpour not_allowed)
				(footprints allowed)
			)
			(placement
				(enabled no)
				(sheetname "")
			)
			(fill
				(thermal_gap 0.5)
				(thermal_bridge_width 0.5)
				(island_removal_mode 0)
			)
			(polygon
				(pts
					(arc
						(start 111.73079 -98.35007)
						(mid 110.96879 -98.35007)
						(end 111.73079 -98.35007)
					)
				)
			)
		)
		(zone
			(layer "F.Cu")
			(hatch none 0.5)
			(connect_pads
				(clearance 0)
			)
			(min_thickness 0.25)
			(keepout
				(tracks allowed)
				(vias not_allowed)
				(pads allowed)
				(copperpour not_allowed)
				(footprints allowed)
			)
			(placement
				(enabled no)
				(sheetname "")
			)
			(fill
				(thermal_gap 0.5)
				(thermal_bridge_width 0.5)
				(island_removal_mode 0)
			)
			(polygon
				(pts
					(arc
						(start 111.73079 -97.350072)
						(mid 110.96879 -97.350072)
						(end 111.73079 -97.350072)
					)
				)
			)
		)
		(zone
			(layer "F.Cu")
			(hatch none 0.5)
			(connect_pads
				(clearance 0)
			)
			(min_thickness 0.25)
			(keepout
				(tracks allowed)
				(vias not_allowed)
				(pads allowed)
				(copperpour not_allowed)
				(footprints allowed)
			)
			(placement
				(enabled no)
				(sheetname "")
			)
			(fill
				(thermal_gap 0.5)
				(thermal_bridge_width 0.5)
				(island_removal_mode 0)
			)
			(polygon
				(pts
					(arc
						(start 111.73079 -96.350074)
						(mid 110.96879 -96.350074)
						(end 111.73079 -96.350074)
					)
				)
			)
		)
		(zone
			(layer "F.Cu")
			(hatch none 0.5)
			(connect_pads
				(clearance 0)
			)
			(min_thickness 0.25)
			(keepout
				(tracks allowed)
				(vias not_allowed)
				(pads allowed)
				(copperpour not_allowed)
				(footprints allowed)
			)
			(placement
				(enabled no)
				(sheetname "")
			)
			(fill
				(thermal_gap 0.5)
				(thermal_bridge_width 0.5)
				(island_removal_mode 0)
			)
			(polygon
				(pts
					(arc
						(start 111.73079 -95.350076)
						(mid 110.96879 -95.350076)
						(end 111.73079 -95.350076)
					)
				)
			)
		)
		(zone
			(layer "F.Cu")
			(hatch none 0.5)
			(connect_pads
				(clearance 0)
			)
			(min_thickness 0.25)
			(keepout
				(tracks allowed)
				(vias not_allowed)
				(pads allowed)
				(copperpour not_allowed)
				(footprints allowed)
			)
			(placement
				(enabled no)
				(sheetname "")
			)
			(fill
				(thermal_gap 0.5)
				(thermal_bridge_width 0.5)
				(island_removal_mode 0)
			)
			(polygon
				(pts
					(arc
						(start 111.73079 -94.349824)
						(mid 110.96879 -94.349824)
						(end 111.73079 -94.349824)
					)
				)
			)
		)
		(zone
			(layer "F.Cu")
			(hatch none 0.5)
			(connect_pads
				(clearance 0)
			)
			(min_thickness 0.25)
			(keepout
				(tracks allowed)
				(vias not_allowed)
				(pads allowed)
				(copperpour not_allowed)
				(footprints allowed)
			)
			(placement
				(enabled no)
				(sheetname "")
			)
			(fill
				(thermal_gap 0.5)
				(thermal_bridge_width 0.5)
				(island_removal_mode 0)
			)
			(polygon
				(pts
					(arc
						(start 111.73079 -93.349826)
						(mid 110.96879 -93.349826)
						(end 111.73079 -93.349826)
					)
				)
			)
		)
		(zone
			(layer "F.Cu")
			(hatch none 0.5)
			(connect_pads
				(clearance 0)
			)
			(min_thickness 0.25)
			(keepout
				(tracks allowed)
				(vias not_allowed)
				(pads allowed)
				(copperpour not_allowed)
				(footprints allowed)
			)
			(placement
				(enabled no)
				(sheetname "")
			)
			(fill
				(thermal_gap 0.5)
				(thermal_bridge_width 0.5)
				(island_removal_mode 0)
			)
			(polygon
				(pts
					(arc
						(start 111.73079 -92.349828)
						(mid 110.96879 -92.349828)
						(end 111.73079 -92.349828)
					)
				)
			)
		)
		(zone
			(layer "F.Cu")
			(hatch none 0.5)
			(connect_pads
				(clearance 0)
			)
			(min_thickness 0.25)
			(keepout
				(tracks allowed)
				(vias not_allowed)
				(pads allowed)
				(copperpour not_allowed)
				(footprints allowed)
			)
			(placement
				(enabled no)
				(sheetname "")
			)
			(fill
				(thermal_gap 0.5)
				(thermal_bridge_width 0.5)
				(island_removal_mode 0)
			)
			(polygon
				(pts
					(arc
						(start 111.73079 -91.34983)
						(mid 110.96879 -91.34983)
						(end 111.73079 -91.34983)
					)
				)
			)
		)
		(zone
			(layer "F.Cu")
			(hatch none 0.5)
			(connect_pads
				(clearance 0)
			)
			(min_thickness 0.25)
			(keepout
				(tracks allowed)
				(vias not_allowed)
				(pads allowed)
				(copperpour not_allowed)
				(footprints allowed)
			)
			(placement
				(enabled no)
				(sheetname "")
			)
			(fill
				(thermal_gap 0.5)
				(thermal_bridge_width 0.5)
				(island_removal_mode 0)
			)
			(polygon
				(pts
					(arc
						(start 111.73079 -90.349832)
						(mid 110.96879 -90.349832)
						(end 111.73079 -90.349832)
					)
				)
			)
		)
		(zone
			(layer "F.Cu")
			(hatch none 0.5)
			(connect_pads
				(clearance 0)
			)
			(min_thickness 0.25)
			(keepout
				(tracks allowed)
				(vias not_allowed)
				(pads allowed)
				(copperpour not_allowed)
				(footprints allowed)
			)
			(placement
				(enabled no)
				(sheetname "")
			)
			(fill
				(thermal_gap 0.5)
				(thermal_bridge_width 0.5)
				(island_removal_mode 0)
			)
			(polygon
				(pts
					(arc
						(start 111.73079 -89.349834)
						(mid 110.96879 -89.349834)
						(end 111.73079 -89.349834)
					)
				)
			)
		)
		(zone
			(layer "F.Cu")
			(hatch none 0.5)
			(connect_pads
				(clearance 0)
			)
			(min_thickness 0.25)
			(keepout
				(tracks allowed)
				(vias not_allowed)
				(pads allowed)
				(copperpour not_allowed)
				(footprints allowed)
			)
			(placement
				(enabled no)
				(sheetname "")
			)
			(fill
				(thermal_gap 0.5)
				(thermal_bridge_width 0.5)
				(island_removal_mode 0)
			)
			(polygon
				(pts
					(arc
						(start 111.73079 -88.349836)
						(mid 110.96879 -88.349836)
						(end 111.73079 -88.349836)
					)
				)
			)
		)
		(zone
			(layer "F.Cu")
			(hatch none 0.5)
			(connect_pads
				(clearance 0)
			)
			(min_thickness 0.25)
			(keepout
				(tracks allowed)
				(vias not_allowed)
				(pads allowed)
				(copperpour not_allowed)
				(footprints allowed)
			)
			(placement
				(enabled no)
				(sheetname "")
			)
			(fill
				(thermal_gap 0.5)
				(thermal_bridge_width 0.5)
				(island_removal_mode 0)
			)
			(polygon
				(pts
					(arc
						(start 111.73079 -87.349838)
						(mid 110.96879 -87.349838)
						(end 111.73079 -87.349838)
					)
				)
			)
		)
		(zone
			(layer "F.Cu")
			(hatch none 0.5)
			(connect_pads
				(clearance 0)
			)
			(min_thickness 0.25)
			(keepout
				(tracks allowed)
				(vias not_allowed)
				(pads allowed)
				(copperpour not_allowed)
				(footprints allowed)
			)
			(placement
				(enabled no)
				(sheetname "")
			)
			(fill
				(thermal_gap 0.5)
				(thermal_bridge_width 0.5)
				(island_removal_mode 0)
			)
			(polygon
				(pts
					(arc
						(start 111.73079 -86.34984)
						(mid 110.96879 -86.34984)
						(end 111.73079 -86.34984)
					)
				)
			)
		)
		(zone
			(layer "F.Cu")
			(hatch none 0.5)
			(connect_pads
				(clearance 0)
			)
			(min_thickness 0.25)
			(keepout
				(tracks allowed)
				(vias not_allowed)
				(pads allowed)
				(copperpour not_allowed)
				(footprints allowed)
			)
			(placement
				(enabled no)
				(sheetname "")
			)
			(fill
				(thermal_gap 0.5)
				(thermal_bridge_width 0.5)
				(island_removal_mode 0)
			)
			(polygon
				(pts
					(arc
						(start 111.73079 -85.349842)
						(mid 110.96879 -85.349842)
						(end 111.73079 -85.349842)
					)
				)
			)
		)
		(zone
			(layer "F.Cu")
			(hatch none 0.5)
			(connect_pads
				(clearance 0)
			)
			(min_thickness 0.25)
			(keepout
				(tracks allowed)
				(vias not_allowed)
				(pads allowed)
				(copperpour not_allowed)
				(footprints allowed)
			)
			(placement
				(enabled no)
				(sheetname "")
			)
			(fill
				(thermal_gap 0.5)
				(thermal_bridge_width 0.5)
				(island_removal_mode 0)
			)
			(polygon
				(pts
					(arc
						(start 111.73079 -84.349844)
						(mid 110.96879 -84.349844)
						(end 111.73079 -84.349844)
					)
				)
			)
		)
		(zone
			(layer "F.Cu")
			(hatch none 0.5)
			(connect_pads
				(clearance 0)
			)
			(min_thickness 0.25)
			(keepout
				(tracks allowed)
				(vias not_allowed)
				(pads allowed)
				(copperpour not_allowed)
				(footprints allowed)
			)
			(placement
				(enabled no)
				(sheetname "")
			)
			(fill
				(thermal_gap 0.5)
				(thermal_bridge_width 0.5)
				(island_removal_mode 0)
			)
			(polygon
				(pts
					(arc
						(start 111.73079 -83.349846)
						(mid 110.96879 -83.349846)
						(end 111.73079 -83.349846)
					)
				)
			)
		)
		(zone
			(layer "F.Cu")
			(hatch none 0.5)
			(connect_pads
				(clearance 0)
			)
			(min_thickness 0.25)
			(keepout
				(tracks allowed)
				(vias not_allowed)
				(pads allowed)
				(copperpour not_allowed)
				(footprints allowed)
			)
			(placement
				(enabled no)
				(sheetname "")
			)
			(fill
				(thermal_gap 0.5)
				(thermal_bridge_width 0.5)
				(island_removal_mode 0)
			)
			(polygon
				(pts
					(arc
						(start 111.73079 -82.349848)
						(mid 110.96879 -82.349848)
						(end 111.73079 -82.349848)
					)
				)
			)
		)
		(zone
			(layer "F.Cu")
			(hatch none 0.5)
			(connect_pads
				(clearance 0)
			)
			(min_thickness 0.25)
			(keepout
				(tracks allowed)
				(vias not_allowed)
				(pads allowed)
				(copperpour not_allowed)
				(footprints allowed)
			)
			(placement
				(enabled no)
				(sheetname "")
			)
			(fill
				(thermal_gap 0.5)
				(thermal_bridge_width 0.5)
				(island_removal_mode 0)
			)
			(polygon
				(pts
					(arc
						(start 112.730788 -107.350052)
						(mid 111.968788 -107.350052)
						(end 112.730788 -107.350052)
					)
				)
			)
		)
		(zone
			(layer "F.Cu")
			(hatch none 0.5)
			(connect_pads
				(clearance 0)
			)
			(min_thickness 0.25)
			(keepout
				(tracks allowed)
				(vias not_allowed)
				(pads allowed)
				(copperpour not_allowed)
				(footprints allowed)
			)
			(placement
				(enabled no)
				(sheetname "")
			)
			(fill
				(thermal_gap 0.5)
				(thermal_bridge_width 0.5)
				(island_removal_mode 0)
			)
			(polygon
				(pts
					(arc
						(start 112.730788 -106.350054)
						(mid 111.968788 -106.350054)
						(end 112.730788 -106.350054)
					)
				)
			)
		)
		(zone
			(layer "F.Cu")
			(hatch none 0.5)
			(connect_pads
				(clearance 0)
			)
			(min_thickness 0.25)
			(keepout
				(tracks allowed)
				(vias not_allowed)
				(pads allowed)
				(copperpour not_allowed)
				(footprints allowed)
			)
			(placement
				(enabled no)
				(sheetname "")
			)
			(fill
				(thermal_gap 0.5)
				(thermal_bridge_width 0.5)
				(island_removal_mode 0)
			)
			(polygon
				(pts
					(arc
						(start 112.730788 -105.350056)
						(mid 111.968788 -105.350056)
						(end 112.730788 -105.350056)
					)
				)
			)
		)
		(zone
			(layer "F.Cu")
			(hatch none 0.5)
			(connect_pads
				(clearance 0)
			)
			(min_thickness 0.25)
			(keepout
				(tracks allowed)
				(vias not_allowed)
				(pads allowed)
				(copperpour not_allowed)
				(footprints allowed)
			)
			(placement
				(enabled no)
				(sheetname "")
			)
			(fill
				(thermal_gap 0.5)
				(thermal_bridge_width 0.5)
				(island_removal_mode 0)
			)
			(polygon
				(pts
					(arc
						(start 112.730788 -104.350058)
						(mid 111.968788 -104.350058)
						(end 112.730788 -104.350058)
					)
				)
			)
		)
		(zone
			(layer "F.Cu")
			(hatch none 0.5)
			(connect_pads
				(clearance 0)
			)
			(min_thickness 0.25)
			(keepout
				(tracks allowed)
				(vias not_allowed)
				(pads allowed)
				(copperpour not_allowed)
				(footprints allowed)
			)
			(placement
				(enabled no)
				(sheetname "")
			)
			(fill
				(thermal_gap 0.5)
				(thermal_bridge_width 0.5)
				(island_removal_mode 0)
			)
			(polygon
				(pts
					(arc
						(start 112.730788 -103.35006)
						(mid 111.968788 -103.35006)
						(end 112.730788 -103.35006)
					)
				)
			)
		)
		(zone
			(layer "F.Cu")
			(hatch none 0.5)
			(connect_pads
				(clearance 0)
			)
			(min_thickness 0.25)
			(keepout
				(tracks allowed)
				(vias not_allowed)
				(pads allowed)
				(copperpour not_allowed)
				(footprints allowed)
			)
			(placement
				(enabled no)
				(sheetname "")
			)
			(fill
				(thermal_gap 0.5)
				(thermal_bridge_width 0.5)
				(island_removal_mode 0)
			)
			(polygon
				(pts
					(arc
						(start 112.730788 -102.350062)
						(mid 111.968788 -102.350062)
						(end 112.730788 -102.350062)
					)
				)
			)
		)
		(zone
			(layer "F.Cu")
			(hatch none 0.5)
			(connect_pads
				(clearance 0)
			)
			(min_thickness 0.25)
			(keepout
				(tracks allowed)
				(vias not_allowed)
				(pads allowed)
				(copperpour not_allowed)
				(footprints allowed)
			)
			(placement
				(enabled no)
				(sheetname "")
			)
			(fill
				(thermal_gap 0.5)
				(thermal_bridge_width 0.5)
				(island_removal_mode 0)
			)
			(polygon
				(pts
					(arc
						(start 112.730788 -101.350064)
						(mid 111.968788 -101.350064)
						(end 112.730788 -101.350064)
					)
				)
			)
		)
		(zone
			(layer "F.Cu")
			(hatch none 0.5)
			(connect_pads
				(clearance 0)
			)
			(min_thickness 0.25)
			(keepout
				(tracks allowed)
				(vias not_allowed)
				(pads allowed)
				(copperpour not_allowed)
				(footprints allowed)
			)
			(placement
				(enabled no)
				(sheetname "")
			)
			(fill
				(thermal_gap 0.5)
				(thermal_bridge_width 0.5)
				(island_removal_mode 0)
			)
			(polygon
				(pts
					(arc
						(start 112.730788 -100.350066)
						(mid 111.968788 -100.350066)
						(end 112.730788 -100.350066)
					)
				)
			)
		)
		(zone
			(layer "F.Cu")
			(hatch none 0.5)
			(connect_pads
				(clearance 0)
			)
			(min_thickness 0.25)
			(keepout
				(tracks allowed)
				(vias not_allowed)
				(pads allowed)
				(copperpour not_allowed)
				(footprints allowed)
			)
			(placement
				(enabled no)
				(sheetname "")
			)
			(fill
				(thermal_gap 0.5)
				(thermal_bridge_width 0.5)
				(island_removal_mode 0)
			)
			(polygon
				(pts
					(arc
						(start 112.730788 -99.350068)
						(mid 111.968788 -99.350068)
						(end 112.730788 -99.350068)
					)
				)
			)
		)
		(zone
			(layer "F.Cu")
			(hatch none 0.5)
			(connect_pads
				(clearance 0)
			)
			(min_thickness 0.25)
			(keepout
				(tracks allowed)
				(vias not_allowed)
				(pads allowed)
				(copperpour not_allowed)
				(footprints allowed)
			)
			(placement
				(enabled no)
				(sheetname "")
			)
			(fill
				(thermal_gap 0.5)
				(thermal_bridge_width 0.5)
				(island_removal_mode 0)
			)
			(polygon
				(pts
					(arc
						(start 112.730788 -98.35007)
						(mid 111.968788 -98.35007)
						(end 112.730788 -98.35007)
					)
				)
			)
		)
		(zone
			(layer "F.Cu")
			(hatch none 0.5)
			(connect_pads
				(clearance 0)
			)
			(min_thickness 0.25)
			(keepout
				(tracks allowed)
				(vias not_allowed)
				(pads allowed)
				(copperpour not_allowed)
				(footprints allowed)
			)
			(placement
				(enabled no)
				(sheetname "")
			)
			(fill
				(thermal_gap 0.5)
				(thermal_bridge_width 0.5)
				(island_removal_mode 0)
			)
			(polygon
				(pts
					(arc
						(start 112.730788 -97.350072)
						(mid 111.968788 -97.350072)
						(end 112.730788 -97.350072)
					)
				)
			)
		)
		(zone
			(layer "F.Cu")
			(hatch none 0.5)
			(connect_pads
				(clearance 0)
			)
			(min_thickness 0.25)
			(keepout
				(tracks allowed)
				(vias not_allowed)
				(pads allowed)
				(copperpour not_allowed)
				(footprints allowed)
			)
			(placement
				(enabled no)
				(sheetname "")
			)
			(fill
				(thermal_gap 0.5)
				(thermal_bridge_width 0.5)
				(island_removal_mode 0)
			)
			(polygon
				(pts
					(arc
						(start 112.730788 -96.350074)
						(mid 111.968788 -96.350074)
						(end 112.730788 -96.350074)
					)
				)
			)
		)
		(zone
			(layer "F.Cu")
			(hatch none 0.5)
			(connect_pads
				(clearance 0)
			)
			(min_thickness 0.25)
			(keepout
				(tracks allowed)
				(vias not_allowed)
				(pads allowed)
				(copperpour not_allowed)
				(footprints allowed)
			)
			(placement
				(enabled no)
				(sheetname "")
			)
			(fill
				(thermal_gap 0.5)
				(thermal_bridge_width 0.5)
				(island_removal_mode 0)
			)
			(polygon
				(pts
					(arc
						(start 112.730788 -95.350076)
						(mid 111.968788 -95.350076)
						(end 112.730788 -95.350076)
					)
				)
			)
		)
		(zone
			(layer "F.Cu")
			(hatch none 0.5)
			(connect_pads
				(clearance 0)
			)
			(min_thickness 0.25)
			(keepout
				(tracks allowed)
				(vias not_allowed)
				(pads allowed)
				(copperpour not_allowed)
				(footprints allowed)
			)
			(placement
				(enabled no)
				(sheetname "")
			)
			(fill
				(thermal_gap 0.5)
				(thermal_bridge_width 0.5)
				(island_removal_mode 0)
			)
			(polygon
				(pts
					(arc
						(start 112.730788 -94.349824)
						(mid 111.968788 -94.349824)
						(end 112.730788 -94.349824)
					)
				)
			)
		)
		(zone
			(layer "F.Cu")
			(hatch none 0.5)
			(connect_pads
				(clearance 0)
			)
			(min_thickness 0.25)
			(keepout
				(tracks allowed)
				(vias not_allowed)
				(pads allowed)
				(copperpour not_allowed)
				(footprints allowed)
			)
			(placement
				(enabled no)
				(sheetname "")
			)
			(fill
				(thermal_gap 0.5)
				(thermal_bridge_width 0.5)
				(island_removal_mode 0)
			)
			(polygon
				(pts
					(arc
						(start 112.730788 -93.349826)
						(mid 111.968788 -93.349826)
						(end 112.730788 -93.349826)
					)
				)
			)
		)
		(zone
			(layer "F.Cu")
			(hatch none 0.5)
			(connect_pads
				(clearance 0)
			)
			(min_thickness 0.25)
			(keepout
				(tracks allowed)
				(vias not_allowed)
				(pads allowed)
				(copperpour not_allowed)
				(footprints allowed)
			)
			(placement
				(enabled no)
				(sheetname "")
			)
			(fill
				(thermal_gap 0.5)
				(thermal_bridge_width 0.5)
				(island_removal_mode 0)
			)
			(polygon
				(pts
					(arc
						(start 112.730788 -92.349828)
						(mid 111.968788 -92.349828)
						(end 112.730788 -92.349828)
					)
				)
			)
		)
		(zone
			(layer "F.Cu")
			(hatch none 0.5)
			(connect_pads
				(clearance 0)
			)
			(min_thickness 0.25)
			(keepout
				(tracks allowed)
				(vias not_allowed)
				(pads allowed)
				(copperpour not_allowed)
				(footprints allowed)
			)
			(placement
				(enabled no)
				(sheetname "")
			)
			(fill
				(thermal_gap 0.5)
				(thermal_bridge_width 0.5)
				(island_removal_mode 0)
			)
			(polygon
				(pts
					(arc
						(start 112.730788 -91.34983)
						(mid 111.968788 -91.34983)
						(end 112.730788 -91.34983)
					)
				)
			)
		)
		(zone
			(layer "F.Cu")
			(hatch none 0.5)
			(connect_pads
				(clearance 0)
			)
			(min_thickness 0.25)
			(keepout
				(tracks allowed)
				(vias not_allowed)
				(pads allowed)
				(copperpour not_allowed)
				(footprints allowed)
			)
			(placement
				(enabled no)
				(sheetname "")
			)
			(fill
				(thermal_gap 0.5)
				(thermal_bridge_width 0.5)
				(island_removal_mode 0)
			)
			(polygon
				(pts
					(arc
						(start 112.730788 -90.349832)
						(mid 111.968788 -90.349832)
						(end 112.730788 -90.349832)
					)
				)
			)
		)
		(zone
			(layer "F.Cu")
			(hatch none 0.5)
			(connect_pads
				(clearance 0)
			)
			(min_thickness 0.25)
			(keepout
				(tracks allowed)
				(vias not_allowed)
				(pads allowed)
				(copperpour not_allowed)
				(footprints allowed)
			)
			(placement
				(enabled no)
				(sheetname "")
			)
			(fill
				(thermal_gap 0.5)
				(thermal_bridge_width 0.5)
				(island_removal_mode 0)
			)
			(polygon
				(pts
					(arc
						(start 112.730788 -89.349834)
						(mid 111.968788 -89.349834)
						(end 112.730788 -89.349834)
					)
				)
			)
		)
		(zone
			(layer "F.Cu")
			(hatch none 0.5)
			(connect_pads
				(clearance 0)
			)
			(min_thickness 0.25)
			(keepout
				(tracks allowed)
				(vias not_allowed)
				(pads allowed)
				(copperpour not_allowed)
				(footprints allowed)
			)
			(placement
				(enabled no)
				(sheetname "")
			)
			(fill
				(thermal_gap 0.5)
				(thermal_bridge_width 0.5)
				(island_removal_mode 0)
			)
			(polygon
				(pts
					(arc
						(start 112.730788 -88.349836)
						(mid 111.968788 -88.349836)
						(end 112.730788 -88.349836)
					)
				)
			)
		)
		(zone
			(layer "F.Cu")
			(hatch none 0.5)
			(connect_pads
				(clearance 0)
			)
			(min_thickness 0.25)
			(keepout
				(tracks allowed)
				(vias not_allowed)
				(pads allowed)
				(copperpour not_allowed)
				(footprints allowed)
			)
			(placement
				(enabled no)
				(sheetname "")
			)
			(fill
				(thermal_gap 0.5)
				(thermal_bridge_width 0.5)
				(island_removal_mode 0)
			)
			(polygon
				(pts
					(arc
						(start 112.730788 -87.349838)
						(mid 111.968788 -87.349838)
						(end 112.730788 -87.349838)
					)
				)
			)
		)
		(zone
			(layer "F.Cu")
			(hatch none 0.5)
			(connect_pads
				(clearance 0)
			)
			(min_thickness 0.25)
			(keepout
				(tracks allowed)
				(vias not_allowed)
				(pads allowed)
				(copperpour not_allowed)
				(footprints allowed)
			)
			(placement
				(enabled no)
				(sheetname "")
			)
			(fill
				(thermal_gap 0.5)
				(thermal_bridge_width 0.5)
				(island_removal_mode 0)
			)
			(polygon
				(pts
					(arc
						(start 112.730788 -86.34984)
						(mid 111.968788 -86.34984)
						(end 112.730788 -86.34984)
					)
				)
			)
		)
		(zone
			(layer "F.Cu")
			(hatch none 0.5)
			(connect_pads
				(clearance 0)
			)
			(min_thickness 0.25)
			(keepout
				(tracks allowed)
				(vias not_allowed)
				(pads allowed)
				(copperpour not_allowed)
				(footprints allowed)
			)
			(placement
				(enabled no)
				(sheetname "")
			)
			(fill
				(thermal_gap 0.5)
				(thermal_bridge_width 0.5)
				(island_removal_mode 0)
			)
			(polygon
				(pts
					(arc
						(start 112.730788 -85.349842)
						(mid 111.968788 -85.349842)
						(end 112.730788 -85.349842)
					)
				)
			)
		)
		(zone
			(layer "F.Cu")
			(hatch none 0.5)
			(connect_pads
				(clearance 0)
			)
			(min_thickness 0.25)
			(keepout
				(tracks allowed)
				(vias not_allowed)
				(pads allowed)
				(copperpour not_allowed)
				(footprints allowed)
			)
			(placement
				(enabled no)
				(sheetname "")
			)
			(fill
				(thermal_gap 0.5)
				(thermal_bridge_width 0.5)
				(island_removal_mode 0)
			)
			(polygon
				(pts
					(arc
						(start 112.730788 -84.349844)
						(mid 111.968788 -84.349844)
						(end 112.730788 -84.349844)
					)
				)
			)
		)
		(zone
			(layer "F.Cu")
			(hatch none 0.5)
			(connect_pads
				(clearance 0)
			)
			(min_thickness 0.25)
			(keepout
				(tracks allowed)
				(vias not_allowed)
				(pads allowed)
				(copperpour not_allowed)
				(footprints allowed)
			)
			(placement
				(enabled no)
				(sheetname "")
			)
			(fill
				(thermal_gap 0.5)
				(thermal_bridge_width 0.5)
				(island_removal_mode 0)
			)
			(polygon
				(pts
					(arc
						(start 112.730788 -83.349846)
						(mid 111.968788 -83.349846)
						(end 112.730788 -83.349846)
					)
				)
			)
		)
		(zone
			(layer "F.Cu")
			(hatch none 0.5)
			(connect_pads
				(clearance 0)
			)
			(min_thickness 0.25)
			(keepout
				(tracks allowed)
				(vias not_allowed)
				(pads allowed)
				(copperpour not_allowed)
				(footprints allowed)
			)
			(placement
				(enabled no)
				(sheetname "")
			)
			(fill
				(thermal_gap 0.5)
				(thermal_bridge_width 0.5)
				(island_removal_mode 0)
			)
			(polygon
				(pts
					(arc
						(start 112.730788 -82.349848)
						(mid 111.968788 -82.349848)
						(end 112.730788 -82.349848)
					)
				)
			)
		)
		(zone
			(layer "F.Cu")
			(hatch none 0.5)
			(connect_pads
				(clearance 0)
			)
			(min_thickness 0.25)
			(keepout
				(tracks allowed)
				(vias not_allowed)
				(pads allowed)
				(copperpour not_allowed)
				(footprints allowed)
			)
			(placement
				(enabled no)
				(sheetname "")
			)
			(fill
				(thermal_gap 0.5)
				(thermal_bridge_width 0.5)
				(island_removal_mode 0)
			)
			(polygon
				(pts
					(arc
						(start 113.730786 -107.350052)
						(mid 112.968786 -107.350052)
						(end 113.730786 -107.350052)
					)
				)
			)
		)
		(zone
			(layer "F.Cu")
			(hatch none 0.5)
			(connect_pads
				(clearance 0)
			)
			(min_thickness 0.25)
			(keepout
				(tracks allowed)
				(vias not_allowed)
				(pads allowed)
				(copperpour not_allowed)
				(footprints allowed)
			)
			(placement
				(enabled no)
				(sheetname "")
			)
			(fill
				(thermal_gap 0.5)
				(thermal_bridge_width 0.5)
				(island_removal_mode 0)
			)
			(polygon
				(pts
					(arc
						(start 113.730786 -106.350054)
						(mid 112.968786 -106.350054)
						(end 113.730786 -106.350054)
					)
				)
			)
		)
		(zone
			(layer "F.Cu")
			(hatch none 0.5)
			(connect_pads
				(clearance 0)
			)
			(min_thickness 0.25)
			(keepout
				(tracks allowed)
				(vias not_allowed)
				(pads allowed)
				(copperpour not_allowed)
				(footprints allowed)
			)
			(placement
				(enabled no)
				(sheetname "")
			)
			(fill
				(thermal_gap 0.5)
				(thermal_bridge_width 0.5)
				(island_removal_mode 0)
			)
			(polygon
				(pts
					(arc
						(start 113.730786 -105.350056)
						(mid 112.968786 -105.350056)
						(end 113.730786 -105.350056)
					)
				)
			)
		)
		(zone
			(layer "F.Cu")
			(hatch none 0.5)
			(connect_pads
				(clearance 0)
			)
			(min_thickness 0.25)
			(keepout
				(tracks allowed)
				(vias not_allowed)
				(pads allowed)
				(copperpour not_allowed)
				(footprints allowed)
			)
			(placement
				(enabled no)
				(sheetname "")
			)
			(fill
				(thermal_gap 0.5)
				(thermal_bridge_width 0.5)
				(island_removal_mode 0)
			)
			(polygon
				(pts
					(arc
						(start 113.730786 -104.350058)
						(mid 112.968786 -104.350058)
						(end 113.730786 -104.350058)
					)
				)
			)
		)
		(zone
			(layer "F.Cu")
			(hatch none 0.5)
			(connect_pads
				(clearance 0)
			)
			(min_thickness 0.25)
			(keepout
				(tracks allowed)
				(vias not_allowed)
				(pads allowed)
				(copperpour not_allowed)
				(footprints allowed)
			)
			(placement
				(enabled no)
				(sheetname "")
			)
			(fill
				(thermal_gap 0.5)
				(thermal_bridge_width 0.5)
				(island_removal_mode 0)
			)
			(polygon
				(pts
					(arc
						(start 113.730786 -103.35006)
						(mid 112.968786 -103.35006)
						(end 113.730786 -103.35006)
					)
				)
			)
		)
		(zone
			(layer "F.Cu")
			(hatch none 0.5)
			(connect_pads
				(clearance 0)
			)
			(min_thickness 0.25)
			(keepout
				(tracks allowed)
				(vias not_allowed)
				(pads allowed)
				(copperpour not_allowed)
				(footprints allowed)
			)
			(placement
				(enabled no)
				(sheetname "")
			)
			(fill
				(thermal_gap 0.5)
				(thermal_bridge_width 0.5)
				(island_removal_mode 0)
			)
			(polygon
				(pts
					(arc
						(start 113.730786 -102.350062)
						(mid 112.968786 -102.350062)
						(end 113.730786 -102.350062)
					)
				)
			)
		)
		(zone
			(layer "F.Cu")
			(hatch none 0.5)
			(connect_pads
				(clearance 0)
			)
			(min_thickness 0.25)
			(keepout
				(tracks allowed)
				(vias not_allowed)
				(pads allowed)
				(copperpour not_allowed)
				(footprints allowed)
			)
			(placement
				(enabled no)
				(sheetname "")
			)
			(fill
				(thermal_gap 0.5)
				(thermal_bridge_width 0.5)
				(island_removal_mode 0)
			)
			(polygon
				(pts
					(arc
						(start 113.730786 -101.350064)
						(mid 112.968786 -101.350064)
						(end 113.730786 -101.350064)
					)
				)
			)
		)
		(zone
			(layer "F.Cu")
			(hatch none 0.5)
			(connect_pads
				(clearance 0)
			)
			(min_thickness 0.25)
			(keepout
				(tracks allowed)
				(vias not_allowed)
				(pads allowed)
				(copperpour not_allowed)
				(footprints allowed)
			)
			(placement
				(enabled no)
				(sheetname "")
			)
			(fill
				(thermal_gap 0.5)
				(thermal_bridge_width 0.5)
				(island_removal_mode 0)
			)
			(polygon
				(pts
					(arc
						(start 113.730786 -100.350066)
						(mid 112.968786 -100.350066)
						(end 113.730786 -100.350066)
					)
				)
			)
		)
		(zone
			(layer "F.Cu")
			(hatch none 0.5)
			(connect_pads
				(clearance 0)
			)
			(min_thickness 0.25)
			(keepout
				(tracks allowed)
				(vias not_allowed)
				(pads allowed)
				(copperpour not_allowed)
				(footprints allowed)
			)
			(placement
				(enabled no)
				(sheetname "")
			)
			(fill
				(thermal_gap 0.5)
				(thermal_bridge_width 0.5)
				(island_removal_mode 0)
			)
			(polygon
				(pts
					(arc
						(start 113.730786 -99.350068)
						(mid 112.968786 -99.350068)
						(end 113.730786 -99.350068)
					)
				)
			)
		)
		(zone
			(layer "F.Cu")
			(hatch none 0.5)
			(connect_pads
				(clearance 0)
			)
			(min_thickness 0.25)
			(keepout
				(tracks allowed)
				(vias not_allowed)
				(pads allowed)
				(copperpour not_allowed)
				(footprints allowed)
			)
			(placement
				(enabled no)
				(sheetname "")
			)
			(fill
				(thermal_gap 0.5)
				(thermal_bridge_width 0.5)
				(island_removal_mode 0)
			)
			(polygon
				(pts
					(arc
						(start 113.730786 -98.35007)
						(mid 112.968786 -98.35007)
						(end 113.730786 -98.35007)
					)
				)
			)
		)
		(zone
			(layer "F.Cu")
			(hatch none 0.5)
			(connect_pads
				(clearance 0)
			)
			(min_thickness 0.25)
			(keepout
				(tracks allowed)
				(vias not_allowed)
				(pads allowed)
				(copperpour not_allowed)
				(footprints allowed)
			)
			(placement
				(enabled no)
				(sheetname "")
			)
			(fill
				(thermal_gap 0.5)
				(thermal_bridge_width 0.5)
				(island_removal_mode 0)
			)
			(polygon
				(pts
					(arc
						(start 113.730786 -97.350072)
						(mid 112.968786 -97.350072)
						(end 113.730786 -97.350072)
					)
				)
			)
		)
		(zone
			(layer "F.Cu")
			(hatch none 0.5)
			(connect_pads
				(clearance 0)
			)
			(min_thickness 0.25)
			(keepout
				(tracks allowed)
				(vias not_allowed)
				(pads allowed)
				(copperpour not_allowed)
				(footprints allowed)
			)
			(placement
				(enabled no)
				(sheetname "")
			)
			(fill
				(thermal_gap 0.5)
				(thermal_bridge_width 0.5)
				(island_removal_mode 0)
			)
			(polygon
				(pts
					(arc
						(start 113.730786 -96.350074)
						(mid 112.968786 -96.350074)
						(end 113.730786 -96.350074)
					)
				)
			)
		)
		(zone
			(layer "F.Cu")
			(hatch none 0.5)
			(connect_pads
				(clearance 0)
			)
			(min_thickness 0.25)
			(keepout
				(tracks allowed)
				(vias not_allowed)
				(pads allowed)
				(copperpour not_allowed)
				(footprints allowed)
			)
			(placement
				(enabled no)
				(sheetname "")
			)
			(fill
				(thermal_gap 0.5)
				(thermal_bridge_width 0.5)
				(island_removal_mode 0)
			)
			(polygon
				(pts
					(arc
						(start 113.730786 -95.350076)
						(mid 112.968786 -95.350076)
						(end 113.730786 -95.350076)
					)
				)
			)
		)
		(zone
			(layer "F.Cu")
			(hatch none 0.5)
			(connect_pads
				(clearance 0)
			)
			(min_thickness 0.25)
			(keepout
				(tracks allowed)
				(vias not_allowed)
				(pads allowed)
				(copperpour not_allowed)
				(footprints allowed)
			)
			(placement
				(enabled no)
				(sheetname "")
			)
			(fill
				(thermal_gap 0.5)
				(thermal_bridge_width 0.5)
				(island_removal_mode 0)
			)
			(polygon
				(pts
					(arc
						(start 113.730786 -94.349824)
						(mid 112.968786 -94.349824)
						(end 113.730786 -94.349824)
					)
				)
			)
		)
		(zone
			(layer "F.Cu")
			(hatch none 0.5)
			(connect_pads
				(clearance 0)
			)
			(min_thickness 0.25)
			(keepout
				(tracks allowed)
				(vias not_allowed)
				(pads allowed)
				(copperpour not_allowed)
				(footprints allowed)
			)
			(placement
				(enabled no)
				(sheetname "")
			)
			(fill
				(thermal_gap 0.5)
				(thermal_bridge_width 0.5)
				(island_removal_mode 0)
			)
			(polygon
				(pts
					(arc
						(start 113.730786 -93.349826)
						(mid 112.968786 -93.349826)
						(end 113.730786 -93.349826)
					)
				)
			)
		)
		(zone
			(layer "F.Cu")
			(hatch none 0.5)
			(connect_pads
				(clearance 0)
			)
			(min_thickness 0.25)
			(keepout
				(tracks allowed)
				(vias not_allowed)
				(pads allowed)
				(copperpour not_allowed)
				(footprints allowed)
			)
			(placement
				(enabled no)
				(sheetname "")
			)
			(fill
				(thermal_gap 0.5)
				(thermal_bridge_width 0.5)
				(island_removal_mode 0)
			)
			(polygon
				(pts
					(arc
						(start 113.730786 -92.349828)
						(mid 112.968786 -92.349828)
						(end 113.730786 -92.349828)
					)
				)
			)
		)
		(zone
			(layer "F.Cu")
			(hatch none 0.5)
			(connect_pads
				(clearance 0)
			)
			(min_thickness 0.25)
			(keepout
				(tracks allowed)
				(vias not_allowed)
				(pads allowed)
				(copperpour not_allowed)
				(footprints allowed)
			)
			(placement
				(enabled no)
				(sheetname "")
			)
			(fill
				(thermal_gap 0.5)
				(thermal_bridge_width 0.5)
				(island_removal_mode 0)
			)
			(polygon
				(pts
					(arc
						(start 113.730786 -91.34983)
						(mid 112.968786 -91.34983)
						(end 113.730786 -91.34983)
					)
				)
			)
		)
		(zone
			(layer "F.Cu")
			(hatch none 0.5)
			(connect_pads
				(clearance 0)
			)
			(min_thickness 0.25)
			(keepout
				(tracks allowed)
				(vias not_allowed)
				(pads allowed)
				(copperpour not_allowed)
				(footprints allowed)
			)
			(placement
				(enabled no)
				(sheetname "")
			)
			(fill
				(thermal_gap 0.5)
				(thermal_bridge_width 0.5)
				(island_removal_mode 0)
			)
			(polygon
				(pts
					(arc
						(start 113.730786 -90.349832)
						(mid 112.968786 -90.349832)
						(end 113.730786 -90.349832)
					)
				)
			)
		)
		(zone
			(layer "F.Cu")
			(hatch none 0.5)
			(connect_pads
				(clearance 0)
			)
			(min_thickness 0.25)
			(keepout
				(tracks allowed)
				(vias not_allowed)
				(pads allowed)
				(copperpour not_allowed)
				(footprints allowed)
			)
			(placement
				(enabled no)
				(sheetname "")
			)
			(fill
				(thermal_gap 0.5)
				(thermal_bridge_width 0.5)
				(island_removal_mode 0)
			)
			(polygon
				(pts
					(arc
						(start 113.730786 -89.349834)
						(mid 112.968786 -89.349834)
						(end 113.730786 -89.349834)
					)
				)
			)
		)
		(zone
			(layer "F.Cu")
			(hatch none 0.5)
			(connect_pads
				(clearance 0)
			)
			(min_thickness 0.25)
			(keepout
				(tracks allowed)
				(vias not_allowed)
				(pads allowed)
				(copperpour not_allowed)
				(footprints allowed)
			)
			(placement
				(enabled no)
				(sheetname "")
			)
			(fill
				(thermal_gap 0.5)
				(thermal_bridge_width 0.5)
				(island_removal_mode 0)
			)
			(polygon
				(pts
					(arc
						(start 113.730786 -88.349836)
						(mid 112.968786 -88.349836)
						(end 113.730786 -88.349836)
					)
				)
			)
		)
		(zone
			(layer "F.Cu")
			(hatch none 0.5)
			(connect_pads
				(clearance 0)
			)
			(min_thickness 0.25)
			(keepout
				(tracks allowed)
				(vias not_allowed)
				(pads allowed)
				(copperpour not_allowed)
				(footprints allowed)
			)
			(placement
				(enabled no)
				(sheetname "")
			)
			(fill
				(thermal_gap 0.5)
				(thermal_bridge_width 0.5)
				(island_removal_mode 0)
			)
			(polygon
				(pts
					(arc
						(start 113.730786 -87.349838)
						(mid 112.968786 -87.349838)
						(end 113.730786 -87.349838)
					)
				)
			)
		)
		(zone
			(layer "F.Cu")
			(hatch none 0.5)
			(connect_pads
				(clearance 0)
			)
			(min_thickness 0.25)
			(keepout
				(tracks allowed)
				(vias not_allowed)
				(pads allowed)
				(copperpour not_allowed)
				(footprints allowed)
			)
			(placement
				(enabled no)
				(sheetname "")
			)
			(fill
				(thermal_gap 0.5)
				(thermal_bridge_width 0.5)
				(island_removal_mode 0)
			)
			(polygon
				(pts
					(arc
						(start 113.730786 -86.34984)
						(mid 112.968786 -86.34984)
						(end 113.730786 -86.34984)
					)
				)
			)
		)
		(zone
			(layer "F.Cu")
			(hatch none 0.5)
			(connect_pads
				(clearance 0)
			)
			(min_thickness 0.25)
			(keepout
				(tracks allowed)
				(vias not_allowed)
				(pads allowed)
				(copperpour not_allowed)
				(footprints allowed)
			)
			(placement
				(enabled no)
				(sheetname "")
			)
			(fill
				(thermal_gap 0.5)
				(thermal_bridge_width 0.5)
				(island_removal_mode 0)
			)
			(polygon
				(pts
					(arc
						(start 113.730786 -85.349842)
						(mid 112.968786 -85.349842)
						(end 113.730786 -85.349842)
					)
				)
			)
		)
		(zone
			(layer "F.Cu")
			(hatch none 0.5)
			(connect_pads
				(clearance 0)
			)
			(min_thickness 0.25)
			(keepout
				(tracks allowed)
				(vias not_allowed)
				(pads allowed)
				(copperpour not_allowed)
				(footprints allowed)
			)
			(placement
				(enabled no)
				(sheetname "")
			)
			(fill
				(thermal_gap 0.5)
				(thermal_bridge_width 0.5)
				(island_removal_mode 0)
			)
			(polygon
				(pts
					(arc
						(start 113.730786 -84.349844)
						(mid 112.968786 -84.349844)
						(end 113.730786 -84.349844)
					)
				)
			)
		)
		(zone
			(layer "F.Cu")
			(hatch none 0.5)
			(connect_pads
				(clearance 0)
			)
			(min_thickness 0.25)
			(keepout
				(tracks allowed)
				(vias not_allowed)
				(pads allowed)
				(copperpour not_allowed)
				(footprints allowed)
			)
			(placement
				(enabled no)
				(sheetname "")
			)
			(fill
				(thermal_gap 0.5)
				(thermal_bridge_width 0.5)
				(island_removal_mode 0)
			)
			(polygon
				(pts
					(arc
						(start 113.730786 -83.349846)
						(mid 112.968786 -83.349846)
						(end 113.730786 -83.349846)
					)
				)
			)
		)
		(zone
			(layer "F.Cu")
			(hatch none 0.5)
			(connect_pads
				(clearance 0)
			)
			(min_thickness 0.25)
			(keepout
				(tracks allowed)
				(vias not_allowed)
				(pads allowed)
				(copperpour not_allowed)
				(footprints allowed)
			)
			(placement
				(enabled no)
				(sheetname "")
			)
			(fill
				(thermal_gap 0.5)
				(thermal_bridge_width 0.5)
				(island_removal_mode 0)
			)
			(polygon
				(pts
					(arc
						(start 113.730786 -82.349848)
						(mid 112.968786 -82.349848)
						(end 113.730786 -82.349848)
					)
				)
			)
		)
		(zone
			(layer "F.Cu")
			(hatch none 0.5)
			(connect_pads
				(clearance 0)
			)
			(min_thickness 0.25)
			(keepout
				(tracks allowed)
				(vias not_allowed)
				(pads allowed)
				(copperpour not_allowed)
				(footprints allowed)
			)
			(placement
				(enabled no)
				(sheetname "")
			)
			(fill
				(thermal_gap 0.5)
				(thermal_bridge_width 0.5)
				(island_removal_mode 0)
			)
			(polygon
				(pts
					(arc
						(start 114.730784 -107.350052)
						(mid 113.968784 -107.350052)
						(end 114.730784 -107.350052)
					)
				)
			)
		)
		(zone
			(layer "F.Cu")
			(hatch none 0.5)
			(connect_pads
				(clearance 0)
			)
			(min_thickness 0.25)
			(keepout
				(tracks allowed)
				(vias not_allowed)
				(pads allowed)
				(copperpour not_allowed)
				(footprints allowed)
			)
			(placement
				(enabled no)
				(sheetname "")
			)
			(fill
				(thermal_gap 0.5)
				(thermal_bridge_width 0.5)
				(island_removal_mode 0)
			)
			(polygon
				(pts
					(arc
						(start 114.730784 -106.350054)
						(mid 113.968784 -106.350054)
						(end 114.730784 -106.350054)
					)
				)
			)
		)
		(zone
			(layer "F.Cu")
			(hatch none 0.5)
			(connect_pads
				(clearance 0)
			)
			(min_thickness 0.25)
			(keepout
				(tracks allowed)
				(vias not_allowed)
				(pads allowed)
				(copperpour not_allowed)
				(footprints allowed)
			)
			(placement
				(enabled no)
				(sheetname "")
			)
			(fill
				(thermal_gap 0.5)
				(thermal_bridge_width 0.5)
				(island_removal_mode 0)
			)
			(polygon
				(pts
					(arc
						(start 114.730784 -105.350056)
						(mid 113.968784 -105.350056)
						(end 114.730784 -105.350056)
					)
				)
			)
		)
		(zone
			(layer "F.Cu")
			(hatch none 0.5)
			(connect_pads
				(clearance 0)
			)
			(min_thickness 0.25)
			(keepout
				(tracks allowed)
				(vias not_allowed)
				(pads allowed)
				(copperpour not_allowed)
				(footprints allowed)
			)
			(placement
				(enabled no)
				(sheetname "")
			)
			(fill
				(thermal_gap 0.5)
				(thermal_bridge_width 0.5)
				(island_removal_mode 0)
			)
			(polygon
				(pts
					(arc
						(start 114.730784 -104.350058)
						(mid 113.968784 -104.350058)
						(end 114.730784 -104.350058)
					)
				)
			)
		)
		(zone
			(layer "F.Cu")
			(hatch none 0.5)
			(connect_pads
				(clearance 0)
			)
			(min_thickness 0.25)
			(keepout
				(tracks allowed)
				(vias not_allowed)
				(pads allowed)
				(copperpour not_allowed)
				(footprints allowed)
			)
			(placement
				(enabled no)
				(sheetname "")
			)
			(fill
				(thermal_gap 0.5)
				(thermal_bridge_width 0.5)
				(island_removal_mode 0)
			)
			(polygon
				(pts
					(arc
						(start 114.730784 -103.35006)
						(mid 113.968784 -103.35006)
						(end 114.730784 -103.35006)
					)
				)
			)
		)
		(zone
			(layer "F.Cu")
			(hatch none 0.5)
			(connect_pads
				(clearance 0)
			)
			(min_thickness 0.25)
			(keepout
				(tracks allowed)
				(vias not_allowed)
				(pads allowed)
				(copperpour not_allowed)
				(footprints allowed)
			)
			(placement
				(enabled no)
				(sheetname "")
			)
			(fill
				(thermal_gap 0.5)
				(thermal_bridge_width 0.5)
				(island_removal_mode 0)
			)
			(polygon
				(pts
					(arc
						(start 114.730784 -102.350062)
						(mid 113.968784 -102.350062)
						(end 114.730784 -102.350062)
					)
				)
			)
		)
		(zone
			(layer "F.Cu")
			(hatch none 0.5)
			(connect_pads
				(clearance 0)
			)
			(min_thickness 0.25)
			(keepout
				(tracks allowed)
				(vias not_allowed)
				(pads allowed)
				(copperpour not_allowed)
				(footprints allowed)
			)
			(placement
				(enabled no)
				(sheetname "")
			)
			(fill
				(thermal_gap 0.5)
				(thermal_bridge_width 0.5)
				(island_removal_mode 0)
			)
			(polygon
				(pts
					(arc
						(start 114.730784 -101.350064)
						(mid 113.968784 -101.350064)
						(end 114.730784 -101.350064)
					)
				)
			)
		)
		(zone
			(layer "F.Cu")
			(hatch none 0.5)
			(connect_pads
				(clearance 0)
			)
			(min_thickness 0.25)
			(keepout
				(tracks allowed)
				(vias not_allowed)
				(pads allowed)
				(copperpour not_allowed)
				(footprints allowed)
			)
			(placement
				(enabled no)
				(sheetname "")
			)
			(fill
				(thermal_gap 0.5)
				(thermal_bridge_width 0.5)
				(island_removal_mode 0)
			)
			(polygon
				(pts
					(arc
						(start 114.730784 -100.350066)
						(mid 113.968784 -100.350066)
						(end 114.730784 -100.350066)
					)
				)
			)
		)
		(zone
			(layer "F.Cu")
			(hatch none 0.5)
			(connect_pads
				(clearance 0)
			)
			(min_thickness 0.25)
			(keepout
				(tracks allowed)
				(vias not_allowed)
				(pads allowed)
				(copperpour not_allowed)
				(footprints allowed)
			)
			(placement
				(enabled no)
				(sheetname "")
			)
			(fill
				(thermal_gap 0.5)
				(thermal_bridge_width 0.5)
				(island_removal_mode 0)
			)
			(polygon
				(pts
					(arc
						(start 114.730784 -99.350068)
						(mid 113.968784 -99.350068)
						(end 114.730784 -99.350068)
					)
				)
			)
		)
		(zone
			(layer "F.Cu")
			(hatch none 0.5)
			(connect_pads
				(clearance 0)
			)
			(min_thickness 0.25)
			(keepout
				(tracks allowed)
				(vias not_allowed)
				(pads allowed)
				(copperpour not_allowed)
				(footprints allowed)
			)
			(placement
				(enabled no)
				(sheetname "")
			)
			(fill
				(thermal_gap 0.5)
				(thermal_bridge_width 0.5)
				(island_removal_mode 0)
			)
			(polygon
				(pts
					(arc
						(start 114.730784 -98.35007)
						(mid 113.968784 -98.35007)
						(end 114.730784 -98.35007)
					)
				)
			)
		)
		(zone
			(layer "F.Cu")
			(hatch none 0.5)
			(connect_pads
				(clearance 0)
			)
			(min_thickness 0.25)
			(keepout
				(tracks allowed)
				(vias not_allowed)
				(pads allowed)
				(copperpour not_allowed)
				(footprints allowed)
			)
			(placement
				(enabled no)
				(sheetname "")
			)
			(fill
				(thermal_gap 0.5)
				(thermal_bridge_width 0.5)
				(island_removal_mode 0)
			)
			(polygon
				(pts
					(arc
						(start 114.730784 -97.350072)
						(mid 113.968784 -97.350072)
						(end 114.730784 -97.350072)
					)
				)
			)
		)
		(zone
			(layer "F.Cu")
			(hatch none 0.5)
			(connect_pads
				(clearance 0)
			)
			(min_thickness 0.25)
			(keepout
				(tracks allowed)
				(vias not_allowed)
				(pads allowed)
				(copperpour not_allowed)
				(footprints allowed)
			)
			(placement
				(enabled no)
				(sheetname "")
			)
			(fill
				(thermal_gap 0.5)
				(thermal_bridge_width 0.5)
				(island_removal_mode 0)
			)
			(polygon
				(pts
					(arc
						(start 114.730784 -96.350074)
						(mid 113.968784 -96.350074)
						(end 114.730784 -96.350074)
					)
				)
			)
		)
		(zone
			(layer "F.Cu")
			(hatch none 0.5)
			(connect_pads
				(clearance 0)
			)
			(min_thickness 0.25)
			(keepout
				(tracks allowed)
				(vias not_allowed)
				(pads allowed)
				(copperpour not_allowed)
				(footprints allowed)
			)
			(placement
				(enabled no)
				(sheetname "")
			)
			(fill
				(thermal_gap 0.5)
				(thermal_bridge_width 0.5)
				(island_removal_mode 0)
			)
			(polygon
				(pts
					(arc
						(start 114.730784 -95.350076)
						(mid 113.968784 -95.350076)
						(end 114.730784 -95.350076)
					)
				)
			)
		)
		(zone
			(layer "F.Cu")
			(hatch none 0.5)
			(connect_pads
				(clearance 0)
			)
			(min_thickness 0.25)
			(keepout
				(tracks allowed)
				(vias not_allowed)
				(pads allowed)
				(copperpour not_allowed)
				(footprints allowed)
			)
			(placement
				(enabled no)
				(sheetname "")
			)
			(fill
				(thermal_gap 0.5)
				(thermal_bridge_width 0.5)
				(island_removal_mode 0)
			)
			(polygon
				(pts
					(arc
						(start 114.730784 -94.349824)
						(mid 113.968784 -94.349824)
						(end 114.730784 -94.349824)
					)
				)
			)
		)
		(zone
			(layer "F.Cu")
			(hatch none 0.5)
			(connect_pads
				(clearance 0)
			)
			(min_thickness 0.25)
			(keepout
				(tracks allowed)
				(vias not_allowed)
				(pads allowed)
				(copperpour not_allowed)
				(footprints allowed)
			)
			(placement
				(enabled no)
				(sheetname "")
			)
			(fill
				(thermal_gap 0.5)
				(thermal_bridge_width 0.5)
				(island_removal_mode 0)
			)
			(polygon
				(pts
					(arc
						(start 114.730784 -93.349826)
						(mid 113.968784 -93.349826)
						(end 114.730784 -93.349826)
					)
				)
			)
		)
		(zone
			(layer "F.Cu")
			(hatch none 0.5)
			(connect_pads
				(clearance 0)
			)
			(min_thickness 0.25)
			(keepout
				(tracks allowed)
				(vias not_allowed)
				(pads allowed)
				(copperpour not_allowed)
				(footprints allowed)
			)
			(placement
				(enabled no)
				(sheetname "")
			)
			(fill
				(thermal_gap 0.5)
				(thermal_bridge_width 0.5)
				(island_removal_mode 0)
			)
			(polygon
				(pts
					(arc
						(start 114.730784 -92.349828)
						(mid 113.968784 -92.349828)
						(end 114.730784 -92.349828)
					)
				)
			)
		)
		(zone
			(layer "F.Cu")
			(hatch none 0.5)
			(connect_pads
				(clearance 0)
			)
			(min_thickness 0.25)
			(keepout
				(tracks allowed)
				(vias not_allowed)
				(pads allowed)
				(copperpour not_allowed)
				(footprints allowed)
			)
			(placement
				(enabled no)
				(sheetname "")
			)
			(fill
				(thermal_gap 0.5)
				(thermal_bridge_width 0.5)
				(island_removal_mode 0)
			)
			(polygon
				(pts
					(arc
						(start 114.730784 -91.34983)
						(mid 113.968784 -91.34983)
						(end 114.730784 -91.34983)
					)
				)
			)
		)
		(zone
			(layer "F.Cu")
			(hatch none 0.5)
			(connect_pads
				(clearance 0)
			)
			(min_thickness 0.25)
			(keepout
				(tracks allowed)
				(vias not_allowed)
				(pads allowed)
				(copperpour not_allowed)
				(footprints allowed)
			)
			(placement
				(enabled no)
				(sheetname "")
			)
			(fill
				(thermal_gap 0.5)
				(thermal_bridge_width 0.5)
				(island_removal_mode 0)
			)
			(polygon
				(pts
					(arc
						(start 114.730784 -90.349832)
						(mid 113.968784 -90.349832)
						(end 114.730784 -90.349832)
					)
				)
			)
		)
		(zone
			(layer "F.Cu")
			(hatch none 0.5)
			(connect_pads
				(clearance 0)
			)
			(min_thickness 0.25)
			(keepout
				(tracks allowed)
				(vias not_allowed)
				(pads allowed)
				(copperpour not_allowed)
				(footprints allowed)
			)
			(placement
				(enabled no)
				(sheetname "")
			)
			(fill
				(thermal_gap 0.5)
				(thermal_bridge_width 0.5)
				(island_removal_mode 0)
			)
			(polygon
				(pts
					(arc
						(start 114.730784 -89.349834)
						(mid 113.968784 -89.349834)
						(end 114.730784 -89.349834)
					)
				)
			)
		)
		(zone
			(layer "F.Cu")
			(hatch none 0.5)
			(connect_pads
				(clearance 0)
			)
			(min_thickness 0.25)
			(keepout
				(tracks allowed)
				(vias not_allowed)
				(pads allowed)
				(copperpour not_allowed)
				(footprints allowed)
			)
			(placement
				(enabled no)
				(sheetname "")
			)
			(fill
				(thermal_gap 0.5)
				(thermal_bridge_width 0.5)
				(island_removal_mode 0)
			)
			(polygon
				(pts
					(arc
						(start 114.730784 -88.349836)
						(mid 113.968784 -88.349836)
						(end 114.730784 -88.349836)
					)
				)
			)
		)
		(zone
			(layer "F.Cu")
			(hatch none 0.5)
			(connect_pads
				(clearance 0)
			)
			(min_thickness 0.25)
			(keepout
				(tracks allowed)
				(vias not_allowed)
				(pads allowed)
				(copperpour not_allowed)
				(footprints allowed)
			)
			(placement
				(enabled no)
				(sheetname "")
			)
			(fill
				(thermal_gap 0.5)
				(thermal_bridge_width 0.5)
				(island_removal_mode 0)
			)
			(polygon
				(pts
					(arc
						(start 114.730784 -87.349838)
						(mid 113.968784 -87.349838)
						(end 114.730784 -87.349838)
					)
				)
			)
		)
		(zone
			(layer "F.Cu")
			(hatch none 0.5)
			(connect_pads
				(clearance 0)
			)
			(min_thickness 0.25)
			(keepout
				(tracks allowed)
				(vias not_allowed)
				(pads allowed)
				(copperpour not_allowed)
				(footprints allowed)
			)
			(placement
				(enabled no)
				(sheetname "")
			)
			(fill
				(thermal_gap 0.5)
				(thermal_bridge_width 0.5)
				(island_removal_mode 0)
			)
			(polygon
				(pts
					(arc
						(start 114.730784 -86.34984)
						(mid 113.968784 -86.34984)
						(end 114.730784 -86.34984)
					)
				)
			)
		)
		(zone
			(layer "F.Cu")
			(hatch none 0.5)
			(connect_pads
				(clearance 0)
			)
			(min_thickness 0.25)
			(keepout
				(tracks allowed)
				(vias not_allowed)
				(pads allowed)
				(copperpour not_allowed)
				(footprints allowed)
			)
			(placement
				(enabled no)
				(sheetname "")
			)
			(fill
				(thermal_gap 0.5)
				(thermal_bridge_width 0.5)
				(island_removal_mode 0)
			)
			(polygon
				(pts
					(arc
						(start 114.730784 -85.349842)
						(mid 113.968784 -85.349842)
						(end 114.730784 -85.349842)
					)
				)
			)
		)
		(zone
			(layer "F.Cu")
			(hatch none 0.5)
			(connect_pads
				(clearance 0)
			)
			(min_thickness 0.25)
			(keepout
				(tracks allowed)
				(vias not_allowed)
				(pads allowed)
				(copperpour not_allowed)
				(footprints allowed)
			)
			(placement
				(enabled no)
				(sheetname "")
			)
			(fill
				(thermal_gap 0.5)
				(thermal_bridge_width 0.5)
				(island_removal_mode 0)
			)
			(polygon
				(pts
					(arc
						(start 114.730784 -84.349844)
						(mid 113.968784 -84.349844)
						(end 114.730784 -84.349844)
					)
				)
			)
		)
		(zone
			(layer "F.Cu")
			(hatch none 0.5)
			(connect_pads
				(clearance 0)
			)
			(min_thickness 0.25)
			(keepout
				(tracks allowed)
				(vias not_allowed)
				(pads allowed)
				(copperpour not_allowed)
				(footprints allowed)
			)
			(placement
				(enabled no)
				(sheetname "")
			)
			(fill
				(thermal_gap 0.5)
				(thermal_bridge_width 0.5)
				(island_removal_mode 0)
			)
			(polygon
				(pts
					(arc
						(start 114.730784 -83.349846)
						(mid 113.968784 -83.349846)
						(end 114.730784 -83.349846)
					)
				)
			)
		)
		(zone
			(layer "F.Cu")
			(hatch none 0.5)
			(connect_pads
				(clearance 0)
			)
			(min_thickness 0.25)
			(keepout
				(tracks allowed)
				(vias not_allowed)
				(pads allowed)
				(copperpour not_allowed)
				(footprints allowed)
			)
			(placement
				(enabled no)
				(sheetname "")
			)
			(fill
				(thermal_gap 0.5)
				(thermal_bridge_width 0.5)
				(island_removal_mode 0)
			)
			(polygon
				(pts
					(arc
						(start 114.730784 -82.349848)
						(mid 113.968784 -82.349848)
						(end 114.730784 -82.349848)
					)
				)
			)
		)
		(zone
			(layer "F.Cu")
			(hatch none 0.5)
			(connect_pads
				(clearance 0)
			)
			(min_thickness 0.25)
			(keepout
				(tracks allowed)
				(vias not_allowed)
				(pads allowed)
				(copperpour not_allowed)
				(footprints allowed)
			)
			(placement
				(enabled no)
				(sheetname "")
			)
			(fill
				(thermal_gap 0.5)
				(thermal_bridge_width 0.5)
				(island_removal_mode 0)
			)
			(polygon
				(pts
					(arc
						(start 115.731036 -107.350052)
						(mid 114.969036 -107.350052)
						(end 115.731036 -107.350052)
					)
				)
			)
		)
		(zone
			(layer "F.Cu")
			(hatch none 0.5)
			(connect_pads
				(clearance 0)
			)
			(min_thickness 0.25)
			(keepout
				(tracks allowed)
				(vias not_allowed)
				(pads allowed)
				(copperpour not_allowed)
				(footprints allowed)
			)
			(placement
				(enabled no)
				(sheetname "")
			)
			(fill
				(thermal_gap 0.5)
				(thermal_bridge_width 0.5)
				(island_removal_mode 0)
			)
			(polygon
				(pts
					(arc
						(start 115.731036 -106.350054)
						(mid 114.969036 -106.350054)
						(end 115.731036 -106.350054)
					)
				)
			)
		)
		(zone
			(layer "F.Cu")
			(hatch none 0.5)
			(connect_pads
				(clearance 0)
			)
			(min_thickness 0.25)
			(keepout
				(tracks allowed)
				(vias not_allowed)
				(pads allowed)
				(copperpour not_allowed)
				(footprints allowed)
			)
			(placement
				(enabled no)
				(sheetname "")
			)
			(fill
				(thermal_gap 0.5)
				(thermal_bridge_width 0.5)
				(island_removal_mode 0)
			)
			(polygon
				(pts
					(arc
						(start 115.731036 -105.350056)
						(mid 114.969036 -105.350056)
						(end 115.731036 -105.350056)
					)
				)
			)
		)
		(zone
			(layer "F.Cu")
			(hatch none 0.5)
			(connect_pads
				(clearance 0)
			)
			(min_thickness 0.25)
			(keepout
				(tracks allowed)
				(vias not_allowed)
				(pads allowed)
				(copperpour not_allowed)
				(footprints allowed)
			)
			(placement
				(enabled no)
				(sheetname "")
			)
			(fill
				(thermal_gap 0.5)
				(thermal_bridge_width 0.5)
				(island_removal_mode 0)
			)
			(polygon
				(pts
					(arc
						(start 115.731036 -104.350058)
						(mid 114.969036 -104.350058)
						(end 115.731036 -104.350058)
					)
				)
			)
		)
		(zone
			(layer "F.Cu")
			(hatch none 0.5)
			(connect_pads
				(clearance 0)
			)
			(min_thickness 0.25)
			(keepout
				(tracks allowed)
				(vias not_allowed)
				(pads allowed)
				(copperpour not_allowed)
				(footprints allowed)
			)
			(placement
				(enabled no)
				(sheetname "")
			)
			(fill
				(thermal_gap 0.5)
				(thermal_bridge_width 0.5)
				(island_removal_mode 0)
			)
			(polygon
				(pts
					(arc
						(start 115.731036 -103.35006)
						(mid 114.969036 -103.35006)
						(end 115.731036 -103.35006)
					)
				)
			)
		)
		(zone
			(layer "F.Cu")
			(hatch none 0.5)
			(connect_pads
				(clearance 0)
			)
			(min_thickness 0.25)
			(keepout
				(tracks allowed)
				(vias not_allowed)
				(pads allowed)
				(copperpour not_allowed)
				(footprints allowed)
			)
			(placement
				(enabled no)
				(sheetname "")
			)
			(fill
				(thermal_gap 0.5)
				(thermal_bridge_width 0.5)
				(island_removal_mode 0)
			)
			(polygon
				(pts
					(arc
						(start 115.731036 -102.350062)
						(mid 114.969036 -102.350062)
						(end 115.731036 -102.350062)
					)
				)
			)
		)
		(zone
			(layer "F.Cu")
			(hatch none 0.5)
			(connect_pads
				(clearance 0)
			)
			(min_thickness 0.25)
			(keepout
				(tracks allowed)
				(vias not_allowed)
				(pads allowed)
				(copperpour not_allowed)
				(footprints allowed)
			)
			(placement
				(enabled no)
				(sheetname "")
			)
			(fill
				(thermal_gap 0.5)
				(thermal_bridge_width 0.5)
				(island_removal_mode 0)
			)
			(polygon
				(pts
					(arc
						(start 115.731036 -101.350064)
						(mid 114.969036 -101.350064)
						(end 115.731036 -101.350064)
					)
				)
			)
		)
		(zone
			(layer "F.Cu")
			(hatch none 0.5)
			(connect_pads
				(clearance 0)
			)
			(min_thickness 0.25)
			(keepout
				(tracks allowed)
				(vias not_allowed)
				(pads allowed)
				(copperpour not_allowed)
				(footprints allowed)
			)
			(placement
				(enabled no)
				(sheetname "")
			)
			(fill
				(thermal_gap 0.5)
				(thermal_bridge_width 0.5)
				(island_removal_mode 0)
			)
			(polygon
				(pts
					(arc
						(start 115.731036 -100.350066)
						(mid 114.969036 -100.350066)
						(end 115.731036 -100.350066)
					)
				)
			)
		)
		(zone
			(layer "F.Cu")
			(hatch none 0.5)
			(connect_pads
				(clearance 0)
			)
			(min_thickness 0.25)
			(keepout
				(tracks allowed)
				(vias not_allowed)
				(pads allowed)
				(copperpour not_allowed)
				(footprints allowed)
			)
			(placement
				(enabled no)
				(sheetname "")
			)
			(fill
				(thermal_gap 0.5)
				(thermal_bridge_width 0.5)
				(island_removal_mode 0)
			)
			(polygon
				(pts
					(arc
						(start 115.731036 -99.350068)
						(mid 114.969036 -99.350068)
						(end 115.731036 -99.350068)
					)
				)
			)
		)
		(zone
			(layer "F.Cu")
			(hatch none 0.5)
			(connect_pads
				(clearance 0)
			)
			(min_thickness 0.25)
			(keepout
				(tracks allowed)
				(vias not_allowed)
				(pads allowed)
				(copperpour not_allowed)
				(footprints allowed)
			)
			(placement
				(enabled no)
				(sheetname "")
			)
			(fill
				(thermal_gap 0.5)
				(thermal_bridge_width 0.5)
				(island_removal_mode 0)
			)
			(polygon
				(pts
					(arc
						(start 115.731036 -98.35007)
						(mid 114.969036 -98.35007)
						(end 115.731036 -98.35007)
					)
				)
			)
		)
		(zone
			(layer "F.Cu")
			(hatch none 0.5)
			(connect_pads
				(clearance 0)
			)
			(min_thickness 0.25)
			(keepout
				(tracks allowed)
				(vias not_allowed)
				(pads allowed)
				(copperpour not_allowed)
				(footprints allowed)
			)
			(placement
				(enabled no)
				(sheetname "")
			)
			(fill
				(thermal_gap 0.5)
				(thermal_bridge_width 0.5)
				(island_removal_mode 0)
			)
			(polygon
				(pts
					(arc
						(start 115.731036 -97.350072)
						(mid 114.969036 -97.350072)
						(end 115.731036 -97.350072)
					)
				)
			)
		)
		(zone
			(layer "F.Cu")
			(hatch none 0.5)
			(connect_pads
				(clearance 0)
			)
			(min_thickness 0.25)
			(keepout
				(tracks allowed)
				(vias not_allowed)
				(pads allowed)
				(copperpour not_allowed)
				(footprints allowed)
			)
			(placement
				(enabled no)
				(sheetname "")
			)
			(fill
				(thermal_gap 0.5)
				(thermal_bridge_width 0.5)
				(island_removal_mode 0)
			)
			(polygon
				(pts
					(arc
						(start 115.731036 -96.350074)
						(mid 114.969036 -96.350074)
						(end 115.731036 -96.350074)
					)
				)
			)
		)
		(zone
			(layer "F.Cu")
			(hatch none 0.5)
			(connect_pads
				(clearance 0)
			)
			(min_thickness 0.25)
			(keepout
				(tracks allowed)
				(vias not_allowed)
				(pads allowed)
				(copperpour not_allowed)
				(footprints allowed)
			)
			(placement
				(enabled no)
				(sheetname "")
			)
			(fill
				(thermal_gap 0.5)
				(thermal_bridge_width 0.5)
				(island_removal_mode 0)
			)
			(polygon
				(pts
					(arc
						(start 115.731036 -95.350076)
						(mid 114.969036 -95.350076)
						(end 115.731036 -95.350076)
					)
				)
			)
		)
		(zone
			(layer "F.Cu")
			(hatch none 0.5)
			(connect_pads
				(clearance 0)
			)
			(min_thickness 0.25)
			(keepout
				(tracks allowed)
				(vias not_allowed)
				(pads allowed)
				(copperpour not_allowed)
				(footprints allowed)
			)
			(placement
				(enabled no)
				(sheetname "")
			)
			(fill
				(thermal_gap 0.5)
				(thermal_bridge_width 0.5)
				(island_removal_mode 0)
			)
			(polygon
				(pts
					(arc
						(start 115.731036 -94.349824)
						(mid 114.969036 -94.349824)
						(end 115.731036 -94.349824)
					)
				)
			)
		)
		(zone
			(layer "F.Cu")
			(hatch none 0.5)
			(connect_pads
				(clearance 0)
			)
			(min_thickness 0.25)
			(keepout
				(tracks allowed)
				(vias not_allowed)
				(pads allowed)
				(copperpour not_allowed)
				(footprints allowed)
			)
			(placement
				(enabled no)
				(sheetname "")
			)
			(fill
				(thermal_gap 0.5)
				(thermal_bridge_width 0.5)
				(island_removal_mode 0)
			)
			(polygon
				(pts
					(arc
						(start 115.731036 -93.349826)
						(mid 114.969036 -93.349826)
						(end 115.731036 -93.349826)
					)
				)
			)
		)
		(zone
			(layer "F.Cu")
			(hatch none 0.5)
			(connect_pads
				(clearance 0)
			)
			(min_thickness 0.25)
			(keepout
				(tracks allowed)
				(vias not_allowed)
				(pads allowed)
				(copperpour not_allowed)
				(footprints allowed)
			)
			(placement
				(enabled no)
				(sheetname "")
			)
			(fill
				(thermal_gap 0.5)
				(thermal_bridge_width 0.5)
				(island_removal_mode 0)
			)
			(polygon
				(pts
					(arc
						(start 115.731036 -92.349828)
						(mid 114.969036 -92.349828)
						(end 115.731036 -92.349828)
					)
				)
			)
		)
		(zone
			(layer "F.Cu")
			(hatch none 0.5)
			(connect_pads
				(clearance 0)
			)
			(min_thickness 0.25)
			(keepout
				(tracks allowed)
				(vias not_allowed)
				(pads allowed)
				(copperpour not_allowed)
				(footprints allowed)
			)
			(placement
				(enabled no)
				(sheetname "")
			)
			(fill
				(thermal_gap 0.5)
				(thermal_bridge_width 0.5)
				(island_removal_mode 0)
			)
			(polygon
				(pts
					(arc
						(start 115.731036 -91.34983)
						(mid 114.969036 -91.34983)
						(end 115.731036 -91.34983)
					)
				)
			)
		)
		(zone
			(layer "F.Cu")
			(hatch none 0.5)
			(connect_pads
				(clearance 0)
			)
			(min_thickness 0.25)
			(keepout
				(tracks allowed)
				(vias not_allowed)
				(pads allowed)
				(copperpour not_allowed)
				(footprints allowed)
			)
			(placement
				(enabled no)
				(sheetname "")
			)
			(fill
				(thermal_gap 0.5)
				(thermal_bridge_width 0.5)
				(island_removal_mode 0)
			)
			(polygon
				(pts
					(arc
						(start 115.731036 -90.349832)
						(mid 114.969036 -90.349832)
						(end 115.731036 -90.349832)
					)
				)
			)
		)
		(zone
			(layer "F.Cu")
			(hatch none 0.5)
			(connect_pads
				(clearance 0)
			)
			(min_thickness 0.25)
			(keepout
				(tracks allowed)
				(vias not_allowed)
				(pads allowed)
				(copperpour not_allowed)
				(footprints allowed)
			)
			(placement
				(enabled no)
				(sheetname "")
			)
			(fill
				(thermal_gap 0.5)
				(thermal_bridge_width 0.5)
				(island_removal_mode 0)
			)
			(polygon
				(pts
					(arc
						(start 115.731036 -89.349834)
						(mid 114.969036 -89.349834)
						(end 115.731036 -89.349834)
					)
				)
			)
		)
		(zone
			(layer "F.Cu")
			(hatch none 0.5)
			(connect_pads
				(clearance 0)
			)
			(min_thickness 0.25)
			(keepout
				(tracks allowed)
				(vias not_allowed)
				(pads allowed)
				(copperpour not_allowed)
				(footprints allowed)
			)
			(placement
				(enabled no)
				(sheetname "")
			)
			(fill
				(thermal_gap 0.5)
				(thermal_bridge_width 0.5)
				(island_removal_mode 0)
			)
			(polygon
				(pts
					(arc
						(start 115.731036 -88.349836)
						(mid 114.969036 -88.349836)
						(end 115.731036 -88.349836)
					)
				)
			)
		)
		(zone
			(layer "F.Cu")
			(hatch none 0.5)
			(connect_pads
				(clearance 0)
			)
			(min_thickness 0.25)
			(keepout
				(tracks allowed)
				(vias not_allowed)
				(pads allowed)
				(copperpour not_allowed)
				(footprints allowed)
			)
			(placement
				(enabled no)
				(sheetname "")
			)
			(fill
				(thermal_gap 0.5)
				(thermal_bridge_width 0.5)
				(island_removal_mode 0)
			)
			(polygon
				(pts
					(arc
						(start 115.731036 -87.349838)
						(mid 114.969036 -87.349838)
						(end 115.731036 -87.349838)
					)
				)
			)
		)
		(zone
			(layer "F.Cu")
			(hatch none 0.5)
			(connect_pads
				(clearance 0)
			)
			(min_thickness 0.25)
			(keepout
				(tracks allowed)
				(vias not_allowed)
				(pads allowed)
				(copperpour not_allowed)
				(footprints allowed)
			)
			(placement
				(enabled no)
				(sheetname "")
			)
			(fill
				(thermal_gap 0.5)
				(thermal_bridge_width 0.5)
				(island_removal_mode 0)
			)
			(polygon
				(pts
					(arc
						(start 115.731036 -86.34984)
						(mid 114.969036 -86.34984)
						(end 115.731036 -86.34984)
					)
				)
			)
		)
		(zone
			(layer "F.Cu")
			(hatch none 0.5)
			(connect_pads
				(clearance 0)
			)
			(min_thickness 0.25)
			(keepout
				(tracks allowed)
				(vias not_allowed)
				(pads allowed)
				(copperpour not_allowed)
				(footprints allowed)
			)
			(placement
				(enabled no)
				(sheetname "")
			)
			(fill
				(thermal_gap 0.5)
				(thermal_bridge_width 0.5)
				(island_removal_mode 0)
			)
			(polygon
				(pts
					(arc
						(start 115.731036 -85.349842)
						(mid 114.969036 -85.349842)
						(end 115.731036 -85.349842)
					)
				)
			)
		)
		(zone
			(layer "F.Cu")
			(hatch none 0.5)
			(connect_pads
				(clearance 0)
			)
			(min_thickness 0.25)
			(keepout
				(tracks allowed)
				(vias not_allowed)
				(pads allowed)
				(copperpour not_allowed)
				(footprints allowed)
			)
			(placement
				(enabled no)
				(sheetname "")
			)
			(fill
				(thermal_gap 0.5)
				(thermal_bridge_width 0.5)
				(island_removal_mode 0)
			)
			(polygon
				(pts
					(arc
						(start 115.731036 -84.349844)
						(mid 114.969036 -84.349844)
						(end 115.731036 -84.349844)
					)
				)
			)
		)
		(zone
			(layer "F.Cu")
			(hatch none 0.5)
			(connect_pads
				(clearance 0)
			)
			(min_thickness 0.25)
			(keepout
				(tracks allowed)
				(vias not_allowed)
				(pads allowed)
				(copperpour not_allowed)
				(footprints allowed)
			)
			(placement
				(enabled no)
				(sheetname "")
			)
			(fill
				(thermal_gap 0.5)
				(thermal_bridge_width 0.5)
				(island_removal_mode 0)
			)
			(polygon
				(pts
					(arc
						(start 115.731036 -83.349846)
						(mid 114.969036 -83.349846)
						(end 115.731036 -83.349846)
					)
				)
			)
		)
		(zone
			(layer "F.Cu")
			(hatch none 0.5)
			(connect_pads
				(clearance 0)
			)
			(min_thickness 0.25)
			(keepout
				(tracks allowed)
				(vias not_allowed)
				(pads allowed)
				(copperpour not_allowed)
				(footprints allowed)
			)
			(placement
				(enabled no)
				(sheetname "")
			)
			(fill
				(thermal_gap 0.5)
				(thermal_bridge_width 0.5)
				(island_removal_mode 0)
			)
			(polygon
				(pts
					(arc
						(start 115.731036 -82.349848)
						(mid 114.969036 -82.349848)
						(end 115.731036 -82.349848)
					)
				)
			)
		)
		(zone
			(layer "F.Cu")
			(hatch none 0.5)
			(connect_pads
				(clearance 0)
			)
			(min_thickness 0.25)
			(keepout
				(tracks allowed)
				(vias not_allowed)
				(pads allowed)
				(copperpour not_allowed)
				(footprints allowed)
			)
			(placement
				(enabled no)
				(sheetname "")
			)
			(fill
				(thermal_gap 0.5)
				(thermal_bridge_width 0.5)
				(island_removal_mode 0)
			)
			(polygon
				(pts
					(arc
						(start 116.731034 -107.350052)
						(mid 115.969034 -107.350052)
						(end 116.731034 -107.350052)
					)
				)
			)
		)
		(zone
			(layer "F.Cu")
			(hatch none 0.5)
			(connect_pads
				(clearance 0)
			)
			(min_thickness 0.25)
			(keepout
				(tracks allowed)
				(vias not_allowed)
				(pads allowed)
				(copperpour not_allowed)
				(footprints allowed)
			)
			(placement
				(enabled no)
				(sheetname "")
			)
			(fill
				(thermal_gap 0.5)
				(thermal_bridge_width 0.5)
				(island_removal_mode 0)
			)
			(polygon
				(pts
					(arc
						(start 116.731034 -106.350054)
						(mid 115.969034 -106.350054)
						(end 116.731034 -106.350054)
					)
				)
			)
		)
		(zone
			(layer "F.Cu")
			(hatch none 0.5)
			(connect_pads
				(clearance 0)
			)
			(min_thickness 0.25)
			(keepout
				(tracks allowed)
				(vias not_allowed)
				(pads allowed)
				(copperpour not_allowed)
				(footprints allowed)
			)
			(placement
				(enabled no)
				(sheetname "")
			)
			(fill
				(thermal_gap 0.5)
				(thermal_bridge_width 0.5)
				(island_removal_mode 0)
			)
			(polygon
				(pts
					(arc
						(start 116.731034 -105.350056)
						(mid 115.969034 -105.350056)
						(end 116.731034 -105.350056)
					)
				)
			)
		)
		(zone
			(layer "F.Cu")
			(hatch none 0.5)
			(connect_pads
				(clearance 0)
			)
			(min_thickness 0.25)
			(keepout
				(tracks allowed)
				(vias not_allowed)
				(pads allowed)
				(copperpour not_allowed)
				(footprints allowed)
			)
			(placement
				(enabled no)
				(sheetname "")
			)
			(fill
				(thermal_gap 0.5)
				(thermal_bridge_width 0.5)
				(island_removal_mode 0)
			)
			(polygon
				(pts
					(arc
						(start 116.731034 -104.350058)
						(mid 115.969034 -104.350058)
						(end 116.731034 -104.350058)
					)
				)
			)
		)
		(zone
			(layer "F.Cu")
			(hatch none 0.5)
			(connect_pads
				(clearance 0)
			)
			(min_thickness 0.25)
			(keepout
				(tracks allowed)
				(vias not_allowed)
				(pads allowed)
				(copperpour not_allowed)
				(footprints allowed)
			)
			(placement
				(enabled no)
				(sheetname "")
			)
			(fill
				(thermal_gap 0.5)
				(thermal_bridge_width 0.5)
				(island_removal_mode 0)
			)
			(polygon
				(pts
					(arc
						(start 116.731034 -103.35006)
						(mid 115.969034 -103.35006)
						(end 116.731034 -103.35006)
					)
				)
			)
		)
		(zone
			(layer "F.Cu")
			(hatch none 0.5)
			(connect_pads
				(clearance 0)
			)
			(min_thickness 0.25)
			(keepout
				(tracks allowed)
				(vias not_allowed)
				(pads allowed)
				(copperpour not_allowed)
				(footprints allowed)
			)
			(placement
				(enabled no)
				(sheetname "")
			)
			(fill
				(thermal_gap 0.5)
				(thermal_bridge_width 0.5)
				(island_removal_mode 0)
			)
			(polygon
				(pts
					(arc
						(start 116.731034 -102.350062)
						(mid 115.969034 -102.350062)
						(end 116.731034 -102.350062)
					)
				)
			)
		)
		(zone
			(layer "F.Cu")
			(hatch none 0.5)
			(connect_pads
				(clearance 0)
			)
			(min_thickness 0.25)
			(keepout
				(tracks allowed)
				(vias not_allowed)
				(pads allowed)
				(copperpour not_allowed)
				(footprints allowed)
			)
			(placement
				(enabled no)
				(sheetname "")
			)
			(fill
				(thermal_gap 0.5)
				(thermal_bridge_width 0.5)
				(island_removal_mode 0)
			)
			(polygon
				(pts
					(arc
						(start 116.731034 -101.350064)
						(mid 115.969034 -101.350064)
						(end 116.731034 -101.350064)
					)
				)
			)
		)
		(zone
			(layer "F.Cu")
			(hatch none 0.5)
			(connect_pads
				(clearance 0)
			)
			(min_thickness 0.25)
			(keepout
				(tracks allowed)
				(vias not_allowed)
				(pads allowed)
				(copperpour not_allowed)
				(footprints allowed)
			)
			(placement
				(enabled no)
				(sheetname "")
			)
			(fill
				(thermal_gap 0.5)
				(thermal_bridge_width 0.5)
				(island_removal_mode 0)
			)
			(polygon
				(pts
					(arc
						(start 116.731034 -100.350066)
						(mid 115.969034 -100.350066)
						(end 116.731034 -100.350066)
					)
				)
			)
		)
		(zone
			(layer "F.Cu")
			(hatch none 0.5)
			(connect_pads
				(clearance 0)
			)
			(min_thickness 0.25)
			(keepout
				(tracks allowed)
				(vias not_allowed)
				(pads allowed)
				(copperpour not_allowed)
				(footprints allowed)
			)
			(placement
				(enabled no)
				(sheetname "")
			)
			(fill
				(thermal_gap 0.5)
				(thermal_bridge_width 0.5)
				(island_removal_mode 0)
			)
			(polygon
				(pts
					(arc
						(start 116.731034 -99.350068)
						(mid 115.969034 -99.350068)
						(end 116.731034 -99.350068)
					)
				)
			)
		)
		(zone
			(layer "F.Cu")
			(hatch none 0.5)
			(connect_pads
				(clearance 0)
			)
			(min_thickness 0.25)
			(keepout
				(tracks allowed)
				(vias not_allowed)
				(pads allowed)
				(copperpour not_allowed)
				(footprints allowed)
			)
			(placement
				(enabled no)
				(sheetname "")
			)
			(fill
				(thermal_gap 0.5)
				(thermal_bridge_width 0.5)
				(island_removal_mode 0)
			)
			(polygon
				(pts
					(arc
						(start 116.731034 -98.35007)
						(mid 115.969034 -98.35007)
						(end 116.731034 -98.35007)
					)
				)
			)
		)
		(zone
			(layer "F.Cu")
			(hatch none 0.5)
			(connect_pads
				(clearance 0)
			)
			(min_thickness 0.25)
			(keepout
				(tracks allowed)
				(vias not_allowed)
				(pads allowed)
				(copperpour not_allowed)
				(footprints allowed)
			)
			(placement
				(enabled no)
				(sheetname "")
			)
			(fill
				(thermal_gap 0.5)
				(thermal_bridge_width 0.5)
				(island_removal_mode 0)
			)
			(polygon
				(pts
					(arc
						(start 116.731034 -97.350072)
						(mid 115.969034 -97.350072)
						(end 116.731034 -97.350072)
					)
				)
			)
		)
		(zone
			(layer "F.Cu")
			(hatch none 0.5)
			(connect_pads
				(clearance 0)
			)
			(min_thickness 0.25)
			(keepout
				(tracks allowed)
				(vias not_allowed)
				(pads allowed)
				(copperpour not_allowed)
				(footprints allowed)
			)
			(placement
				(enabled no)
				(sheetname "")
			)
			(fill
				(thermal_gap 0.5)
				(thermal_bridge_width 0.5)
				(island_removal_mode 0)
			)
			(polygon
				(pts
					(arc
						(start 116.731034 -96.350074)
						(mid 115.969034 -96.350074)
						(end 116.731034 -96.350074)
					)
				)
			)
		)
		(zone
			(layer "F.Cu")
			(hatch none 0.5)
			(connect_pads
				(clearance 0)
			)
			(min_thickness 0.25)
			(keepout
				(tracks allowed)
				(vias not_allowed)
				(pads allowed)
				(copperpour not_allowed)
				(footprints allowed)
			)
			(placement
				(enabled no)
				(sheetname "")
			)
			(fill
				(thermal_gap 0.5)
				(thermal_bridge_width 0.5)
				(island_removal_mode 0)
			)
			(polygon
				(pts
					(arc
						(start 116.731034 -95.350076)
						(mid 115.969034 -95.350076)
						(end 116.731034 -95.350076)
					)
				)
			)
		)
		(zone
			(layer "F.Cu")
			(hatch none 0.5)
			(connect_pads
				(clearance 0)
			)
			(min_thickness 0.25)
			(keepout
				(tracks allowed)
				(vias not_allowed)
				(pads allowed)
				(copperpour not_allowed)
				(footprints allowed)
			)
			(placement
				(enabled no)
				(sheetname "")
			)
			(fill
				(thermal_gap 0.5)
				(thermal_bridge_width 0.5)
				(island_removal_mode 0)
			)
			(polygon
				(pts
					(arc
						(start 116.731034 -94.349824)
						(mid 115.969034 -94.349824)
						(end 116.731034 -94.349824)
					)
				)
			)
		)
		(zone
			(layer "F.Cu")
			(hatch none 0.5)
			(connect_pads
				(clearance 0)
			)
			(min_thickness 0.25)
			(keepout
				(tracks allowed)
				(vias not_allowed)
				(pads allowed)
				(copperpour not_allowed)
				(footprints allowed)
			)
			(placement
				(enabled no)
				(sheetname "")
			)
			(fill
				(thermal_gap 0.5)
				(thermal_bridge_width 0.5)
				(island_removal_mode 0)
			)
			(polygon
				(pts
					(arc
						(start 116.731034 -93.349826)
						(mid 115.969034 -93.349826)
						(end 116.731034 -93.349826)
					)
				)
			)
		)
		(zone
			(layer "F.Cu")
			(hatch none 0.5)
			(connect_pads
				(clearance 0)
			)
			(min_thickness 0.25)
			(keepout
				(tracks allowed)
				(vias not_allowed)
				(pads allowed)
				(copperpour not_allowed)
				(footprints allowed)
			)
			(placement
				(enabled no)
				(sheetname "")
			)
			(fill
				(thermal_gap 0.5)
				(thermal_bridge_width 0.5)
				(island_removal_mode 0)
			)
			(polygon
				(pts
					(arc
						(start 116.731034 -92.349828)
						(mid 115.969034 -92.349828)
						(end 116.731034 -92.349828)
					)
				)
			)
		)
		(zone
			(layer "F.Cu")
			(hatch none 0.5)
			(connect_pads
				(clearance 0)
			)
			(min_thickness 0.25)
			(keepout
				(tracks allowed)
				(vias not_allowed)
				(pads allowed)
				(copperpour not_allowed)
				(footprints allowed)
			)
			(placement
				(enabled no)
				(sheetname "")
			)
			(fill
				(thermal_gap 0.5)
				(thermal_bridge_width 0.5)
				(island_removal_mode 0)
			)
			(polygon
				(pts
					(arc
						(start 116.731034 -91.34983)
						(mid 115.969034 -91.34983)
						(end 116.731034 -91.34983)
					)
				)
			)
		)
		(zone
			(layer "F.Cu")
			(hatch none 0.5)
			(connect_pads
				(clearance 0)
			)
			(min_thickness 0.25)
			(keepout
				(tracks allowed)
				(vias not_allowed)
				(pads allowed)
				(copperpour not_allowed)
				(footprints allowed)
			)
			(placement
				(enabled no)
				(sheetname "")
			)
			(fill
				(thermal_gap 0.5)
				(thermal_bridge_width 0.5)
				(island_removal_mode 0)
			)
			(polygon
				(pts
					(arc
						(start 116.731034 -90.349832)
						(mid 115.969034 -90.349832)
						(end 116.731034 -90.349832)
					)
				)
			)
		)
		(zone
			(layer "F.Cu")
			(hatch none 0.5)
			(connect_pads
				(clearance 0)
			)
			(min_thickness 0.25)
			(keepout
				(tracks allowed)
				(vias not_allowed)
				(pads allowed)
				(copperpour not_allowed)
				(footprints allowed)
			)
			(placement
				(enabled no)
				(sheetname "")
			)
			(fill
				(thermal_gap 0.5)
				(thermal_bridge_width 0.5)
				(island_removal_mode 0)
			)
			(polygon
				(pts
					(arc
						(start 116.731034 -89.349834)
						(mid 115.969034 -89.349834)
						(end 116.731034 -89.349834)
					)
				)
			)
		)
		(zone
			(layer "F.Cu")
			(hatch none 0.5)
			(connect_pads
				(clearance 0)
			)
			(min_thickness 0.25)
			(keepout
				(tracks allowed)
				(vias not_allowed)
				(pads allowed)
				(copperpour not_allowed)
				(footprints allowed)
			)
			(placement
				(enabled no)
				(sheetname "")
			)
			(fill
				(thermal_gap 0.5)
				(thermal_bridge_width 0.5)
				(island_removal_mode 0)
			)
			(polygon
				(pts
					(arc
						(start 116.731034 -88.349836)
						(mid 115.969034 -88.349836)
						(end 116.731034 -88.349836)
					)
				)
			)
		)
		(zone
			(layer "F.Cu")
			(hatch none 0.5)
			(connect_pads
				(clearance 0)
			)
			(min_thickness 0.25)
			(keepout
				(tracks allowed)
				(vias not_allowed)
				(pads allowed)
				(copperpour not_allowed)
				(footprints allowed)
			)
			(placement
				(enabled no)
				(sheetname "")
			)
			(fill
				(thermal_gap 0.5)
				(thermal_bridge_width 0.5)
				(island_removal_mode 0)
			)
			(polygon
				(pts
					(arc
						(start 116.731034 -87.349838)
						(mid 115.969034 -87.349838)
						(end 116.731034 -87.349838)
					)
				)
			)
		)
		(zone
			(layer "F.Cu")
			(hatch none 0.5)
			(connect_pads
				(clearance 0)
			)
			(min_thickness 0.25)
			(keepout
				(tracks allowed)
				(vias not_allowed)
				(pads allowed)
				(copperpour not_allowed)
				(footprints allowed)
			)
			(placement
				(enabled no)
				(sheetname "")
			)
			(fill
				(thermal_gap 0.5)
				(thermal_bridge_width 0.5)
				(island_removal_mode 0)
			)
			(polygon
				(pts
					(arc
						(start 116.731034 -86.34984)
						(mid 115.969034 -86.34984)
						(end 116.731034 -86.34984)
					)
				)
			)
		)
		(zone
			(layer "F.Cu")
			(hatch none 0.5)
			(connect_pads
				(clearance 0)
			)
			(min_thickness 0.25)
			(keepout
				(tracks allowed)
				(vias not_allowed)
				(pads allowed)
				(copperpour not_allowed)
				(footprints allowed)
			)
			(placement
				(enabled no)
				(sheetname "")
			)
			(fill
				(thermal_gap 0.5)
				(thermal_bridge_width 0.5)
				(island_removal_mode 0)
			)
			(polygon
				(pts
					(arc
						(start 116.731034 -85.349842)
						(mid 115.969034 -85.349842)
						(end 116.731034 -85.349842)
					)
				)
			)
		)
		(zone
			(layer "F.Cu")
			(hatch none 0.5)
			(connect_pads
				(clearance 0)
			)
			(min_thickness 0.25)
			(keepout
				(tracks allowed)
				(vias not_allowed)
				(pads allowed)
				(copperpour not_allowed)
				(footprints allowed)
			)
			(placement
				(enabled no)
				(sheetname "")
			)
			(fill
				(thermal_gap 0.5)
				(thermal_bridge_width 0.5)
				(island_removal_mode 0)
			)
			(polygon
				(pts
					(arc
						(start 116.731034 -84.349844)
						(mid 115.969034 -84.349844)
						(end 116.731034 -84.349844)
					)
				)
			)
		)
		(zone
			(layer "F.Cu")
			(hatch none 0.5)
			(connect_pads
				(clearance 0)
			)
			(min_thickness 0.25)
			(keepout
				(tracks allowed)
				(vias not_allowed)
				(pads allowed)
				(copperpour not_allowed)
				(footprints allowed)
			)
			(placement
				(enabled no)
				(sheetname "")
			)
			(fill
				(thermal_gap 0.5)
				(thermal_bridge_width 0.5)
				(island_removal_mode 0)
			)
			(polygon
				(pts
					(arc
						(start 116.731034 -83.349846)
						(mid 115.969034 -83.349846)
						(end 116.731034 -83.349846)
					)
				)
			)
		)
		(zone
			(layer "F.Cu")
			(hatch none 0.5)
			(connect_pads
				(clearance 0)
			)
			(min_thickness 0.25)
			(keepout
				(tracks allowed)
				(vias not_allowed)
				(pads allowed)
				(copperpour not_allowed)
				(footprints allowed)
			)
			(placement
				(enabled no)
				(sheetname "")
			)
			(fill
				(thermal_gap 0.5)
				(thermal_bridge_width 0.5)
				(island_removal_mode 0)
			)
			(polygon
				(pts
					(arc
						(start 116.731034 -82.349848)
						(mid 115.969034 -82.349848)
						(end 116.731034 -82.349848)
					)
				)
			)
		)
		(zone
			(layer "F.Cu")
			(hatch none 0.5)
			(connect_pads
				(clearance 0)
			)
			(min_thickness 0.25)
			(keepout
				(tracks allowed)
				(vias not_allowed)
				(pads allowed)
				(copperpour not_allowed)
				(footprints allowed)
			)
			(placement
				(enabled no)
				(sheetname "")
			)
			(fill
				(thermal_gap 0.5)
				(thermal_bridge_width 0.5)
				(island_removal_mode 0)
			)
			(polygon
				(pts
					(arc
						(start 117.731032 -107.350052)
						(mid 116.969032 -107.350052)
						(end 117.731032 -107.350052)
					)
				)
			)
		)
		(zone
			(layer "F.Cu")
			(hatch none 0.5)
			(connect_pads
				(clearance 0)
			)
			(min_thickness 0.25)
			(keepout
				(tracks allowed)
				(vias not_allowed)
				(pads allowed)
				(copperpour not_allowed)
				(footprints allowed)
			)
			(placement
				(enabled no)
				(sheetname "")
			)
			(fill
				(thermal_gap 0.5)
				(thermal_bridge_width 0.5)
				(island_removal_mode 0)
			)
			(polygon
				(pts
					(arc
						(start 117.731032 -106.350054)
						(mid 116.969032 -106.350054)
						(end 117.731032 -106.350054)
					)
				)
			)
		)
		(zone
			(layer "F.Cu")
			(hatch none 0.5)
			(connect_pads
				(clearance 0)
			)
			(min_thickness 0.25)
			(keepout
				(tracks allowed)
				(vias not_allowed)
				(pads allowed)
				(copperpour not_allowed)
				(footprints allowed)
			)
			(placement
				(enabled no)
				(sheetname "")
			)
			(fill
				(thermal_gap 0.5)
				(thermal_bridge_width 0.5)
				(island_removal_mode 0)
			)
			(polygon
				(pts
					(arc
						(start 117.731032 -105.350056)
						(mid 116.969032 -105.350056)
						(end 117.731032 -105.350056)
					)
				)
			)
		)
		(zone
			(layer "F.Cu")
			(hatch none 0.5)
			(connect_pads
				(clearance 0)
			)
			(min_thickness 0.25)
			(keepout
				(tracks allowed)
				(vias not_allowed)
				(pads allowed)
				(copperpour not_allowed)
				(footprints allowed)
			)
			(placement
				(enabled no)
				(sheetname "")
			)
			(fill
				(thermal_gap 0.5)
				(thermal_bridge_width 0.5)
				(island_removal_mode 0)
			)
			(polygon
				(pts
					(arc
						(start 117.731032 -104.350058)
						(mid 116.969032 -104.350058)
						(end 117.731032 -104.350058)
					)
				)
			)
		)
		(zone
			(layer "F.Cu")
			(hatch none 0.5)
			(connect_pads
				(clearance 0)
			)
			(min_thickness 0.25)
			(keepout
				(tracks allowed)
				(vias not_allowed)
				(pads allowed)
				(copperpour not_allowed)
				(footprints allowed)
			)
			(placement
				(enabled no)
				(sheetname "")
			)
			(fill
				(thermal_gap 0.5)
				(thermal_bridge_width 0.5)
				(island_removal_mode 0)
			)
			(polygon
				(pts
					(arc
						(start 117.731032 -103.35006)
						(mid 116.969032 -103.35006)
						(end 117.731032 -103.35006)
					)
				)
			)
		)
		(zone
			(layer "F.Cu")
			(hatch none 0.5)
			(connect_pads
				(clearance 0)
			)
			(min_thickness 0.25)
			(keepout
				(tracks allowed)
				(vias not_allowed)
				(pads allowed)
				(copperpour not_allowed)
				(footprints allowed)
			)
			(placement
				(enabled no)
				(sheetname "")
			)
			(fill
				(thermal_gap 0.5)
				(thermal_bridge_width 0.5)
				(island_removal_mode 0)
			)
			(polygon
				(pts
					(arc
						(start 117.731032 -102.350062)
						(mid 116.969032 -102.350062)
						(end 117.731032 -102.350062)
					)
				)
			)
		)
		(zone
			(layer "F.Cu")
			(hatch none 0.5)
			(connect_pads
				(clearance 0)
			)
			(min_thickness 0.25)
			(keepout
				(tracks allowed)
				(vias not_allowed)
				(pads allowed)
				(copperpour not_allowed)
				(footprints allowed)
			)
			(placement
				(enabled no)
				(sheetname "")
			)
			(fill
				(thermal_gap 0.5)
				(thermal_bridge_width 0.5)
				(island_removal_mode 0)
			)
			(polygon
				(pts
					(arc
						(start 117.731032 -101.350064)
						(mid 116.969032 -101.350064)
						(end 117.731032 -101.350064)
					)
				)
			)
		)
		(zone
			(layer "F.Cu")
			(hatch none 0.5)
			(connect_pads
				(clearance 0)
			)
			(min_thickness 0.25)
			(keepout
				(tracks allowed)
				(vias not_allowed)
				(pads allowed)
				(copperpour not_allowed)
				(footprints allowed)
			)
			(placement
				(enabled no)
				(sheetname "")
			)
			(fill
				(thermal_gap 0.5)
				(thermal_bridge_width 0.5)
				(island_removal_mode 0)
			)
			(polygon
				(pts
					(arc
						(start 117.731032 -100.350066)
						(mid 116.969032 -100.350066)
						(end 117.731032 -100.350066)
					)
				)
			)
		)
		(zone
			(layer "F.Cu")
			(hatch none 0.5)
			(connect_pads
				(clearance 0)
			)
			(min_thickness 0.25)
			(keepout
				(tracks allowed)
				(vias not_allowed)
				(pads allowed)
				(copperpour not_allowed)
				(footprints allowed)
			)
			(placement
				(enabled no)
				(sheetname "")
			)
			(fill
				(thermal_gap 0.5)
				(thermal_bridge_width 0.5)
				(island_removal_mode 0)
			)
			(polygon
				(pts
					(arc
						(start 117.731032 -99.350068)
						(mid 116.969032 -99.350068)
						(end 117.731032 -99.350068)
					)
				)
			)
		)
		(zone
			(layer "F.Cu")
			(hatch none 0.5)
			(connect_pads
				(clearance 0)
			)
			(min_thickness 0.25)
			(keepout
				(tracks allowed)
				(vias not_allowed)
				(pads allowed)
				(copperpour not_allowed)
				(footprints allowed)
			)
			(placement
				(enabled no)
				(sheetname "")
			)
			(fill
				(thermal_gap 0.5)
				(thermal_bridge_width 0.5)
				(island_removal_mode 0)
			)
			(polygon
				(pts
					(arc
						(start 117.731032 -98.35007)
						(mid 116.969032 -98.35007)
						(end 117.731032 -98.35007)
					)
				)
			)
		)
		(zone
			(layer "F.Cu")
			(hatch none 0.5)
			(connect_pads
				(clearance 0)
			)
			(min_thickness 0.25)
			(keepout
				(tracks allowed)
				(vias not_allowed)
				(pads allowed)
				(copperpour not_allowed)
				(footprints allowed)
			)
			(placement
				(enabled no)
				(sheetname "")
			)
			(fill
				(thermal_gap 0.5)
				(thermal_bridge_width 0.5)
				(island_removal_mode 0)
			)
			(polygon
				(pts
					(arc
						(start 117.731032 -97.350072)
						(mid 116.969032 -97.350072)
						(end 117.731032 -97.350072)
					)
				)
			)
		)
		(zone
			(layer "F.Cu")
			(hatch none 0.5)
			(connect_pads
				(clearance 0)
			)
			(min_thickness 0.25)
			(keepout
				(tracks allowed)
				(vias not_allowed)
				(pads allowed)
				(copperpour not_allowed)
				(footprints allowed)
			)
			(placement
				(enabled no)
				(sheetname "")
			)
			(fill
				(thermal_gap 0.5)
				(thermal_bridge_width 0.5)
				(island_removal_mode 0)
			)
			(polygon
				(pts
					(arc
						(start 117.731032 -96.350074)
						(mid 116.969032 -96.350074)
						(end 117.731032 -96.350074)
					)
				)
			)
		)
		(zone
			(layer "F.Cu")
			(hatch none 0.5)
			(connect_pads
				(clearance 0)
			)
			(min_thickness 0.25)
			(keepout
				(tracks allowed)
				(vias not_allowed)
				(pads allowed)
				(copperpour not_allowed)
				(footprints allowed)
			)
			(placement
				(enabled no)
				(sheetname "")
			)
			(fill
				(thermal_gap 0.5)
				(thermal_bridge_width 0.5)
				(island_removal_mode 0)
			)
			(polygon
				(pts
					(arc
						(start 117.731032 -95.350076)
						(mid 116.969032 -95.350076)
						(end 117.731032 -95.350076)
					)
				)
			)
		)
		(zone
			(layer "F.Cu")
			(hatch none 0.5)
			(connect_pads
				(clearance 0)
			)
			(min_thickness 0.25)
			(keepout
				(tracks allowed)
				(vias not_allowed)
				(pads allowed)
				(copperpour not_allowed)
				(footprints allowed)
			)
			(placement
				(enabled no)
				(sheetname "")
			)
			(fill
				(thermal_gap 0.5)
				(thermal_bridge_width 0.5)
				(island_removal_mode 0)
			)
			(polygon
				(pts
					(arc
						(start 117.731032 -94.349824)
						(mid 116.969032 -94.349824)
						(end 117.731032 -94.349824)
					)
				)
			)
		)
		(zone
			(layer "F.Cu")
			(hatch none 0.5)
			(connect_pads
				(clearance 0)
			)
			(min_thickness 0.25)
			(keepout
				(tracks allowed)
				(vias not_allowed)
				(pads allowed)
				(copperpour not_allowed)
				(footprints allowed)
			)
			(placement
				(enabled no)
				(sheetname "")
			)
			(fill
				(thermal_gap 0.5)
				(thermal_bridge_width 0.5)
				(island_removal_mode 0)
			)
			(polygon
				(pts
					(arc
						(start 117.731032 -93.349826)
						(mid 116.969032 -93.349826)
						(end 117.731032 -93.349826)
					)
				)
			)
		)
		(zone
			(layer "F.Cu")
			(hatch none 0.5)
			(connect_pads
				(clearance 0)
			)
			(min_thickness 0.25)
			(keepout
				(tracks allowed)
				(vias not_allowed)
				(pads allowed)
				(copperpour not_allowed)
				(footprints allowed)
			)
			(placement
				(enabled no)
				(sheetname "")
			)
			(fill
				(thermal_gap 0.5)
				(thermal_bridge_width 0.5)
				(island_removal_mode 0)
			)
			(polygon
				(pts
					(arc
						(start 117.731032 -92.349828)
						(mid 116.969032 -92.349828)
						(end 117.731032 -92.349828)
					)
				)
			)
		)
		(zone
			(layer "F.Cu")
			(hatch none 0.5)
			(connect_pads
				(clearance 0)
			)
			(min_thickness 0.25)
			(keepout
				(tracks allowed)
				(vias not_allowed)
				(pads allowed)
				(copperpour not_allowed)
				(footprints allowed)
			)
			(placement
				(enabled no)
				(sheetname "")
			)
			(fill
				(thermal_gap 0.5)
				(thermal_bridge_width 0.5)
				(island_removal_mode 0)
			)
			(polygon
				(pts
					(arc
						(start 117.731032 -91.34983)
						(mid 116.969032 -91.34983)
						(end 117.731032 -91.34983)
					)
				)
			)
		)
		(zone
			(layer "F.Cu")
			(hatch none 0.5)
			(connect_pads
				(clearance 0)
			)
			(min_thickness 0.25)
			(keepout
				(tracks allowed)
				(vias not_allowed)
				(pads allowed)
				(copperpour not_allowed)
				(footprints allowed)
			)
			(placement
				(enabled no)
				(sheetname "")
			)
			(fill
				(thermal_gap 0.5)
				(thermal_bridge_width 0.5)
				(island_removal_mode 0)
			)
			(polygon
				(pts
					(arc
						(start 117.731032 -90.349832)
						(mid 116.969032 -90.349832)
						(end 117.731032 -90.349832)
					)
				)
			)
		)
		(zone
			(layer "F.Cu")
			(hatch none 0.5)
			(connect_pads
				(clearance 0)
			)
			(min_thickness 0.25)
			(keepout
				(tracks allowed)
				(vias not_allowed)
				(pads allowed)
				(copperpour not_allowed)
				(footprints allowed)
			)
			(placement
				(enabled no)
				(sheetname "")
			)
			(fill
				(thermal_gap 0.5)
				(thermal_bridge_width 0.5)
				(island_removal_mode 0)
			)
			(polygon
				(pts
					(arc
						(start 117.731032 -89.349834)
						(mid 116.969032 -89.349834)
						(end 117.731032 -89.349834)
					)
				)
			)
		)
		(zone
			(layer "F.Cu")
			(hatch none 0.5)
			(connect_pads
				(clearance 0)
			)
			(min_thickness 0.25)
			(keepout
				(tracks allowed)
				(vias not_allowed)
				(pads allowed)
				(copperpour not_allowed)
				(footprints allowed)
			)
			(placement
				(enabled no)
				(sheetname "")
			)
			(fill
				(thermal_gap 0.5)
				(thermal_bridge_width 0.5)
				(island_removal_mode 0)
			)
			(polygon
				(pts
					(arc
						(start 117.731032 -88.349836)
						(mid 116.969032 -88.349836)
						(end 117.731032 -88.349836)
					)
				)
			)
		)
		(zone
			(layer "F.Cu")
			(hatch none 0.5)
			(connect_pads
				(clearance 0)
			)
			(min_thickness 0.25)
			(keepout
				(tracks allowed)
				(vias not_allowed)
				(pads allowed)
				(copperpour not_allowed)
				(footprints allowed)
			)
			(placement
				(enabled no)
				(sheetname "")
			)
			(fill
				(thermal_gap 0.5)
				(thermal_bridge_width 0.5)
				(island_removal_mode 0)
			)
			(polygon
				(pts
					(arc
						(start 117.731032 -87.349838)
						(mid 116.969032 -87.349838)
						(end 117.731032 -87.349838)
					)
				)
			)
		)
		(zone
			(layer "F.Cu")
			(hatch none 0.5)
			(connect_pads
				(clearance 0)
			)
			(min_thickness 0.25)
			(keepout
				(tracks allowed)
				(vias not_allowed)
				(pads allowed)
				(copperpour not_allowed)
				(footprints allowed)
			)
			(placement
				(enabled no)
				(sheetname "")
			)
			(fill
				(thermal_gap 0.5)
				(thermal_bridge_width 0.5)
				(island_removal_mode 0)
			)
			(polygon
				(pts
					(arc
						(start 117.731032 -86.34984)
						(mid 116.969032 -86.34984)
						(end 117.731032 -86.34984)
					)
				)
			)
		)
		(zone
			(layer "F.Cu")
			(hatch none 0.5)
			(connect_pads
				(clearance 0)
			)
			(min_thickness 0.25)
			(keepout
				(tracks allowed)
				(vias not_allowed)
				(pads allowed)
				(copperpour not_allowed)
				(footprints allowed)
			)
			(placement
				(enabled no)
				(sheetname "")
			)
			(fill
				(thermal_gap 0.5)
				(thermal_bridge_width 0.5)
				(island_removal_mode 0)
			)
			(polygon
				(pts
					(arc
						(start 117.731032 -85.349842)
						(mid 116.969032 -85.349842)
						(end 117.731032 -85.349842)
					)
				)
			)
		)
		(zone
			(layer "F.Cu")
			(hatch none 0.5)
			(connect_pads
				(clearance 0)
			)
			(min_thickness 0.25)
			(keepout
				(tracks allowed)
				(vias not_allowed)
				(pads allowed)
				(copperpour not_allowed)
				(footprints allowed)
			)
			(placement
				(enabled no)
				(sheetname "")
			)
			(fill
				(thermal_gap 0.5)
				(thermal_bridge_width 0.5)
				(island_removal_mode 0)
			)
			(polygon
				(pts
					(arc
						(start 117.731032 -84.349844)
						(mid 116.969032 -84.349844)
						(end 117.731032 -84.349844)
					)
				)
			)
		)
		(zone
			(layer "F.Cu")
			(hatch none 0.5)
			(connect_pads
				(clearance 0)
			)
			(min_thickness 0.25)
			(keepout
				(tracks allowed)
				(vias not_allowed)
				(pads allowed)
				(copperpour not_allowed)
				(footprints allowed)
			)
			(placement
				(enabled no)
				(sheetname "")
			)
			(fill
				(thermal_gap 0.5)
				(thermal_bridge_width 0.5)
				(island_removal_mode 0)
			)
			(polygon
				(pts
					(arc
						(start 117.731032 -83.349846)
						(mid 116.969032 -83.349846)
						(end 117.731032 -83.349846)
					)
				)
			)
		)
		(zone
			(layer "F.Cu")
			(hatch none 0.5)
			(connect_pads
				(clearance 0)
			)
			(min_thickness 0.25)
			(keepout
				(tracks allowed)
				(vias not_allowed)
				(pads allowed)
				(copperpour not_allowed)
				(footprints allowed)
			)
			(placement
				(enabled no)
				(sheetname "")
			)
			(fill
				(thermal_gap 0.5)
				(thermal_bridge_width 0.5)
				(island_removal_mode 0)
			)
			(polygon
				(pts
					(arc
						(start 117.731032 -82.349848)
						(mid 116.969032 -82.349848)
						(end 117.731032 -82.349848)
					)
				)
			)
		)
		(zone
			(layer "F.Cu")
			(hatch none 0.5)
			(connect_pads
				(clearance 0)
			)
			(min_thickness 0.25)
			(keepout
				(tracks allowed)
				(vias not_allowed)
				(pads allowed)
				(copperpour not_allowed)
				(footprints allowed)
			)
			(placement
				(enabled no)
				(sheetname "")
			)
			(fill
				(thermal_gap 0.5)
				(thermal_bridge_width 0.5)
				(island_removal_mode 0)
			)
			(polygon
				(pts
					(arc
						(start 118.73103 -107.350052)
						(mid 117.96903 -107.350052)
						(end 118.73103 -107.350052)
					)
				)
			)
		)
		(zone
			(layer "F.Cu")
			(hatch none 0.5)
			(connect_pads
				(clearance 0)
			)
			(min_thickness 0.25)
			(keepout
				(tracks allowed)
				(vias not_allowed)
				(pads allowed)
				(copperpour not_allowed)
				(footprints allowed)
			)
			(placement
				(enabled no)
				(sheetname "")
			)
			(fill
				(thermal_gap 0.5)
				(thermal_bridge_width 0.5)
				(island_removal_mode 0)
			)
			(polygon
				(pts
					(arc
						(start 118.73103 -106.350054)
						(mid 117.96903 -106.350054)
						(end 118.73103 -106.350054)
					)
				)
			)
		)
		(zone
			(layer "F.Cu")
			(hatch none 0.5)
			(connect_pads
				(clearance 0)
			)
			(min_thickness 0.25)
			(keepout
				(tracks allowed)
				(vias not_allowed)
				(pads allowed)
				(copperpour not_allowed)
				(footprints allowed)
			)
			(placement
				(enabled no)
				(sheetname "")
			)
			(fill
				(thermal_gap 0.5)
				(thermal_bridge_width 0.5)
				(island_removal_mode 0)
			)
			(polygon
				(pts
					(arc
						(start 118.73103 -105.350056)
						(mid 117.96903 -105.350056)
						(end 118.73103 -105.350056)
					)
				)
			)
		)
		(zone
			(layer "F.Cu")
			(hatch none 0.5)
			(connect_pads
				(clearance 0)
			)
			(min_thickness 0.25)
			(keepout
				(tracks allowed)
				(vias not_allowed)
				(pads allowed)
				(copperpour not_allowed)
				(footprints allowed)
			)
			(placement
				(enabled no)
				(sheetname "")
			)
			(fill
				(thermal_gap 0.5)
				(thermal_bridge_width 0.5)
				(island_removal_mode 0)
			)
			(polygon
				(pts
					(arc
						(start 118.73103 -104.350058)
						(mid 117.96903 -104.350058)
						(end 118.73103 -104.350058)
					)
				)
			)
		)
		(zone
			(layer "F.Cu")
			(hatch none 0.5)
			(connect_pads
				(clearance 0)
			)
			(min_thickness 0.25)
			(keepout
				(tracks allowed)
				(vias not_allowed)
				(pads allowed)
				(copperpour not_allowed)
				(footprints allowed)
			)
			(placement
				(enabled no)
				(sheetname "")
			)
			(fill
				(thermal_gap 0.5)
				(thermal_bridge_width 0.5)
				(island_removal_mode 0)
			)
			(polygon
				(pts
					(arc
						(start 118.73103 -103.35006)
						(mid 117.96903 -103.35006)
						(end 118.73103 -103.35006)
					)
				)
			)
		)
		(zone
			(layer "F.Cu")
			(hatch none 0.5)
			(connect_pads
				(clearance 0)
			)
			(min_thickness 0.25)
			(keepout
				(tracks allowed)
				(vias not_allowed)
				(pads allowed)
				(copperpour not_allowed)
				(footprints allowed)
			)
			(placement
				(enabled no)
				(sheetname "")
			)
			(fill
				(thermal_gap 0.5)
				(thermal_bridge_width 0.5)
				(island_removal_mode 0)
			)
			(polygon
				(pts
					(arc
						(start 118.73103 -102.350062)
						(mid 117.96903 -102.350062)
						(end 118.73103 -102.350062)
					)
				)
			)
		)
		(zone
			(layer "F.Cu")
			(hatch none 0.5)
			(connect_pads
				(clearance 0)
			)
			(min_thickness 0.25)
			(keepout
				(tracks allowed)
				(vias not_allowed)
				(pads allowed)
				(copperpour not_allowed)
				(footprints allowed)
			)
			(placement
				(enabled no)
				(sheetname "")
			)
			(fill
				(thermal_gap 0.5)
				(thermal_bridge_width 0.5)
				(island_removal_mode 0)
			)
			(polygon
				(pts
					(arc
						(start 118.73103 -101.350064)
						(mid 117.96903 -101.350064)
						(end 118.73103 -101.350064)
					)
				)
			)
		)
		(zone
			(layer "F.Cu")
			(hatch none 0.5)
			(connect_pads
				(clearance 0)
			)
			(min_thickness 0.25)
			(keepout
				(tracks allowed)
				(vias not_allowed)
				(pads allowed)
				(copperpour not_allowed)
				(footprints allowed)
			)
			(placement
				(enabled no)
				(sheetname "")
			)
			(fill
				(thermal_gap 0.5)
				(thermal_bridge_width 0.5)
				(island_removal_mode 0)
			)
			(polygon
				(pts
					(arc
						(start 118.73103 -100.350066)
						(mid 117.96903 -100.350066)
						(end 118.73103 -100.350066)
					)
				)
			)
		)
		(zone
			(layer "F.Cu")
			(hatch none 0.5)
			(connect_pads
				(clearance 0)
			)
			(min_thickness 0.25)
			(keepout
				(tracks allowed)
				(vias not_allowed)
				(pads allowed)
				(copperpour not_allowed)
				(footprints allowed)
			)
			(placement
				(enabled no)
				(sheetname "")
			)
			(fill
				(thermal_gap 0.5)
				(thermal_bridge_width 0.5)
				(island_removal_mode 0)
			)
			(polygon
				(pts
					(arc
						(start 118.73103 -99.350068)
						(mid 117.96903 -99.350068)
						(end 118.73103 -99.350068)
					)
				)
			)
		)
		(zone
			(layer "F.Cu")
			(hatch none 0.5)
			(connect_pads
				(clearance 0)
			)
			(min_thickness 0.25)
			(keepout
				(tracks allowed)
				(vias not_allowed)
				(pads allowed)
				(copperpour not_allowed)
				(footprints allowed)
			)
			(placement
				(enabled no)
				(sheetname "")
			)
			(fill
				(thermal_gap 0.5)
				(thermal_bridge_width 0.5)
				(island_removal_mode 0)
			)
			(polygon
				(pts
					(arc
						(start 118.73103 -98.35007)
						(mid 117.96903 -98.35007)
						(end 118.73103 -98.35007)
					)
				)
			)
		)
		(zone
			(layer "F.Cu")
			(hatch none 0.5)
			(connect_pads
				(clearance 0)
			)
			(min_thickness 0.25)
			(keepout
				(tracks allowed)
				(vias not_allowed)
				(pads allowed)
				(copperpour not_allowed)
				(footprints allowed)
			)
			(placement
				(enabled no)
				(sheetname "")
			)
			(fill
				(thermal_gap 0.5)
				(thermal_bridge_width 0.5)
				(island_removal_mode 0)
			)
			(polygon
				(pts
					(arc
						(start 118.73103 -97.350072)
						(mid 117.96903 -97.350072)
						(end 118.73103 -97.350072)
					)
				)
			)
		)
		(zone
			(layer "F.Cu")
			(hatch none 0.5)
			(connect_pads
				(clearance 0)
			)
			(min_thickness 0.25)
			(keepout
				(tracks allowed)
				(vias not_allowed)
				(pads allowed)
				(copperpour not_allowed)
				(footprints allowed)
			)
			(placement
				(enabled no)
				(sheetname "")
			)
			(fill
				(thermal_gap 0.5)
				(thermal_bridge_width 0.5)
				(island_removal_mode 0)
			)
			(polygon
				(pts
					(arc
						(start 118.73103 -96.350074)
						(mid 117.96903 -96.350074)
						(end 118.73103 -96.350074)
					)
				)
			)
		)
		(zone
			(layer "F.Cu")
			(hatch none 0.5)
			(connect_pads
				(clearance 0)
			)
			(min_thickness 0.25)
			(keepout
				(tracks allowed)
				(vias not_allowed)
				(pads allowed)
				(copperpour not_allowed)
				(footprints allowed)
			)
			(placement
				(enabled no)
				(sheetname "")
			)
			(fill
				(thermal_gap 0.5)
				(thermal_bridge_width 0.5)
				(island_removal_mode 0)
			)
			(polygon
				(pts
					(arc
						(start 118.73103 -95.350076)
						(mid 117.96903 -95.350076)
						(end 118.73103 -95.350076)
					)
				)
			)
		)
		(zone
			(layer "F.Cu")
			(hatch none 0.5)
			(connect_pads
				(clearance 0)
			)
			(min_thickness 0.25)
			(keepout
				(tracks allowed)
				(vias not_allowed)
				(pads allowed)
				(copperpour not_allowed)
				(footprints allowed)
			)
			(placement
				(enabled no)
				(sheetname "")
			)
			(fill
				(thermal_gap 0.5)
				(thermal_bridge_width 0.5)
				(island_removal_mode 0)
			)
			(polygon
				(pts
					(arc
						(start 118.73103 -94.349824)
						(mid 117.96903 -94.349824)
						(end 118.73103 -94.349824)
					)
				)
			)
		)
		(zone
			(layer "F.Cu")
			(hatch none 0.5)
			(connect_pads
				(clearance 0)
			)
			(min_thickness 0.25)
			(keepout
				(tracks allowed)
				(vias not_allowed)
				(pads allowed)
				(copperpour not_allowed)
				(footprints allowed)
			)
			(placement
				(enabled no)
				(sheetname "")
			)
			(fill
				(thermal_gap 0.5)
				(thermal_bridge_width 0.5)
				(island_removal_mode 0)
			)
			(polygon
				(pts
					(arc
						(start 118.73103 -93.349826)
						(mid 117.96903 -93.349826)
						(end 118.73103 -93.349826)
					)
				)
			)
		)
		(zone
			(layer "F.Cu")
			(hatch none 0.5)
			(connect_pads
				(clearance 0)
			)
			(min_thickness 0.25)
			(keepout
				(tracks allowed)
				(vias not_allowed)
				(pads allowed)
				(copperpour not_allowed)
				(footprints allowed)
			)
			(placement
				(enabled no)
				(sheetname "")
			)
			(fill
				(thermal_gap 0.5)
				(thermal_bridge_width 0.5)
				(island_removal_mode 0)
			)
			(polygon
				(pts
					(arc
						(start 118.73103 -92.349828)
						(mid 117.96903 -92.349828)
						(end 118.73103 -92.349828)
					)
				)
			)
		)
		(zone
			(layer "F.Cu")
			(hatch none 0.5)
			(connect_pads
				(clearance 0)
			)
			(min_thickness 0.25)
			(keepout
				(tracks allowed)
				(vias not_allowed)
				(pads allowed)
				(copperpour not_allowed)
				(footprints allowed)
			)
			(placement
				(enabled no)
				(sheetname "")
			)
			(fill
				(thermal_gap 0.5)
				(thermal_bridge_width 0.5)
				(island_removal_mode 0)
			)
			(polygon
				(pts
					(arc
						(start 118.73103 -91.34983)
						(mid 117.96903 -91.34983)
						(end 118.73103 -91.34983)
					)
				)
			)
		)
		(zone
			(layer "F.Cu")
			(hatch none 0.5)
			(connect_pads
				(clearance 0)
			)
			(min_thickness 0.25)
			(keepout
				(tracks allowed)
				(vias not_allowed)
				(pads allowed)
				(copperpour not_allowed)
				(footprints allowed)
			)
			(placement
				(enabled no)
				(sheetname "")
			)
			(fill
				(thermal_gap 0.5)
				(thermal_bridge_width 0.5)
				(island_removal_mode 0)
			)
			(polygon
				(pts
					(arc
						(start 118.73103 -90.349832)
						(mid 117.96903 -90.349832)
						(end 118.73103 -90.349832)
					)
				)
			)
		)
		(zone
			(layer "F.Cu")
			(hatch none 0.5)
			(connect_pads
				(clearance 0)
			)
			(min_thickness 0.25)
			(keepout
				(tracks allowed)
				(vias not_allowed)
				(pads allowed)
				(copperpour not_allowed)
				(footprints allowed)
			)
			(placement
				(enabled no)
				(sheetname "")
			)
			(fill
				(thermal_gap 0.5)
				(thermal_bridge_width 0.5)
				(island_removal_mode 0)
			)
			(polygon
				(pts
					(arc
						(start 118.73103 -89.349834)
						(mid 117.96903 -89.349834)
						(end 118.73103 -89.349834)
					)
				)
			)
		)
		(zone
			(layer "F.Cu")
			(hatch none 0.5)
			(connect_pads
				(clearance 0)
			)
			(min_thickness 0.25)
			(keepout
				(tracks allowed)
				(vias not_allowed)
				(pads allowed)
				(copperpour not_allowed)
				(footprints allowed)
			)
			(placement
				(enabled no)
				(sheetname "")
			)
			(fill
				(thermal_gap 0.5)
				(thermal_bridge_width 0.5)
				(island_removal_mode 0)
			)
			(polygon
				(pts
					(arc
						(start 118.73103 -88.349836)
						(mid 117.96903 -88.349836)
						(end 118.73103 -88.349836)
					)
				)
			)
		)
		(zone
			(layer "F.Cu")
			(hatch none 0.5)
			(connect_pads
				(clearance 0)
			)
			(min_thickness 0.25)
			(keepout
				(tracks allowed)
				(vias not_allowed)
				(pads allowed)
				(copperpour not_allowed)
				(footprints allowed)
			)
			(placement
				(enabled no)
				(sheetname "")
			)
			(fill
				(thermal_gap 0.5)
				(thermal_bridge_width 0.5)
				(island_removal_mode 0)
			)
			(polygon
				(pts
					(arc
						(start 118.73103 -87.349838)
						(mid 117.96903 -87.349838)
						(end 118.73103 -87.349838)
					)
				)
			)
		)
		(zone
			(layer "F.Cu")
			(hatch none 0.5)
			(connect_pads
				(clearance 0)
			)
			(min_thickness 0.25)
			(keepout
				(tracks allowed)
				(vias not_allowed)
				(pads allowed)
				(copperpour not_allowed)
				(footprints allowed)
			)
			(placement
				(enabled no)
				(sheetname "")
			)
			(fill
				(thermal_gap 0.5)
				(thermal_bridge_width 0.5)
				(island_removal_mode 0)
			)
			(polygon
				(pts
					(arc
						(start 118.73103 -86.34984)
						(mid 117.96903 -86.34984)
						(end 118.73103 -86.34984)
					)
				)
			)
		)
		(zone
			(layer "F.Cu")
			(hatch none 0.5)
			(connect_pads
				(clearance 0)
			)
			(min_thickness 0.25)
			(keepout
				(tracks allowed)
				(vias not_allowed)
				(pads allowed)
				(copperpour not_allowed)
				(footprints allowed)
			)
			(placement
				(enabled no)
				(sheetname "")
			)
			(fill
				(thermal_gap 0.5)
				(thermal_bridge_width 0.5)
				(island_removal_mode 0)
			)
			(polygon
				(pts
					(arc
						(start 118.73103 -85.349842)
						(mid 117.96903 -85.349842)
						(end 118.73103 -85.349842)
					)
				)
			)
		)
		(zone
			(layer "F.Cu")
			(hatch none 0.5)
			(connect_pads
				(clearance 0)
			)
			(min_thickness 0.25)
			(keepout
				(tracks allowed)
				(vias not_allowed)
				(pads allowed)
				(copperpour not_allowed)
				(footprints allowed)
			)
			(placement
				(enabled no)
				(sheetname "")
			)
			(fill
				(thermal_gap 0.5)
				(thermal_bridge_width 0.5)
				(island_removal_mode 0)
			)
			(polygon
				(pts
					(arc
						(start 118.73103 -84.349844)
						(mid 117.96903 -84.349844)
						(end 118.73103 -84.349844)
					)
				)
			)
		)
		(zone
			(layer "F.Cu")
			(hatch none 0.5)
			(connect_pads
				(clearance 0)
			)
			(min_thickness 0.25)
			(keepout
				(tracks allowed)
				(vias not_allowed)
				(pads allowed)
				(copperpour not_allowed)
				(footprints allowed)
			)
			(placement
				(enabled no)
				(sheetname "")
			)
			(fill
				(thermal_gap 0.5)
				(thermal_bridge_width 0.5)
				(island_removal_mode 0)
			)
			(polygon
				(pts
					(arc
						(start 118.73103 -83.349846)
						(mid 117.96903 -83.349846)
						(end 118.73103 -83.349846)
					)
				)
			)
		)
		(zone
			(layer "F.Cu")
			(hatch none 0.5)
			(connect_pads
				(clearance 0)
			)
			(min_thickness 0.25)
			(keepout
				(tracks allowed)
				(vias not_allowed)
				(pads allowed)
				(copperpour not_allowed)
				(footprints allowed)
			)
			(placement
				(enabled no)
				(sheetname "")
			)
			(fill
				(thermal_gap 0.5)
				(thermal_bridge_width 0.5)
				(island_removal_mode 0)
			)
			(polygon
				(pts
					(arc
						(start 118.73103 -82.349848)
						(mid 117.96903 -82.349848)
						(end 118.73103 -82.349848)
					)
				)
			)
		)
		(zone
			(layer "F.Cu")
			(hatch none 0.5)
			(connect_pads
				(clearance 0)
			)
			(min_thickness 0.25)
			(keepout
				(tracks allowed)
				(vias not_allowed)
				(pads allowed)
				(copperpour not_allowed)
				(footprints allowed)
			)
			(placement
				(enabled no)
				(sheetname "")
			)
			(fill
				(thermal_gap 0.5)
				(thermal_bridge_width 0.5)
				(island_removal_mode 0)
			)
			(polygon
				(pts
					(arc
						(start 119.731028 -107.350052)
						(mid 118.969028 -107.350052)
						(end 119.731028 -107.350052)
					)
				)
			)
		)
		(zone
			(layer "F.Cu")
			(hatch none 0.5)
			(connect_pads
				(clearance 0)
			)
			(min_thickness 0.25)
			(keepout
				(tracks allowed)
				(vias not_allowed)
				(pads allowed)
				(copperpour not_allowed)
				(footprints allowed)
			)
			(placement
				(enabled no)
				(sheetname "")
			)
			(fill
				(thermal_gap 0.5)
				(thermal_bridge_width 0.5)
				(island_removal_mode 0)
			)
			(polygon
				(pts
					(arc
						(start 119.731028 -106.350054)
						(mid 118.969028 -106.350054)
						(end 119.731028 -106.350054)
					)
				)
			)
		)
		(zone
			(layer "F.Cu")
			(hatch none 0.5)
			(connect_pads
				(clearance 0)
			)
			(min_thickness 0.25)
			(keepout
				(tracks allowed)
				(vias not_allowed)
				(pads allowed)
				(copperpour not_allowed)
				(footprints allowed)
			)
			(placement
				(enabled no)
				(sheetname "")
			)
			(fill
				(thermal_gap 0.5)
				(thermal_bridge_width 0.5)
				(island_removal_mode 0)
			)
			(polygon
				(pts
					(arc
						(start 119.731028 -105.350056)
						(mid 118.969028 -105.350056)
						(end 119.731028 -105.350056)
					)
				)
			)
		)
		(zone
			(layer "F.Cu")
			(hatch none 0.5)
			(connect_pads
				(clearance 0)
			)
			(min_thickness 0.25)
			(keepout
				(tracks allowed)
				(vias not_allowed)
				(pads allowed)
				(copperpour not_allowed)
				(footprints allowed)
			)
			(placement
				(enabled no)
				(sheetname "")
			)
			(fill
				(thermal_gap 0.5)
				(thermal_bridge_width 0.5)
				(island_removal_mode 0)
			)
			(polygon
				(pts
					(arc
						(start 119.731028 -104.350058)
						(mid 118.969028 -104.350058)
						(end 119.731028 -104.350058)
					)
				)
			)
		)
		(zone
			(layer "F.Cu")
			(hatch none 0.5)
			(connect_pads
				(clearance 0)
			)
			(min_thickness 0.25)
			(keepout
				(tracks allowed)
				(vias not_allowed)
				(pads allowed)
				(copperpour not_allowed)
				(footprints allowed)
			)
			(placement
				(enabled no)
				(sheetname "")
			)
			(fill
				(thermal_gap 0.5)
				(thermal_bridge_width 0.5)
				(island_removal_mode 0)
			)
			(polygon
				(pts
					(arc
						(start 119.731028 -103.35006)
						(mid 118.969028 -103.35006)
						(end 119.731028 -103.35006)
					)
				)
			)
		)
		(zone
			(layer "F.Cu")
			(hatch none 0.5)
			(connect_pads
				(clearance 0)
			)
			(min_thickness 0.25)
			(keepout
				(tracks allowed)
				(vias not_allowed)
				(pads allowed)
				(copperpour not_allowed)
				(footprints allowed)
			)
			(placement
				(enabled no)
				(sheetname "")
			)
			(fill
				(thermal_gap 0.5)
				(thermal_bridge_width 0.5)
				(island_removal_mode 0)
			)
			(polygon
				(pts
					(arc
						(start 119.731028 -102.350062)
						(mid 118.969028 -102.350062)
						(end 119.731028 -102.350062)
					)
				)
			)
		)
		(zone
			(layer "F.Cu")
			(hatch none 0.5)
			(connect_pads
				(clearance 0)
			)
			(min_thickness 0.25)
			(keepout
				(tracks allowed)
				(vias not_allowed)
				(pads allowed)
				(copperpour not_allowed)
				(footprints allowed)
			)
			(placement
				(enabled no)
				(sheetname "")
			)
			(fill
				(thermal_gap 0.5)
				(thermal_bridge_width 0.5)
				(island_removal_mode 0)
			)
			(polygon
				(pts
					(arc
						(start 119.731028 -101.350064)
						(mid 118.969028 -101.350064)
						(end 119.731028 -101.350064)
					)
				)
			)
		)
		(zone
			(layer "F.Cu")
			(hatch none 0.5)
			(connect_pads
				(clearance 0)
			)
			(min_thickness 0.25)
			(keepout
				(tracks allowed)
				(vias not_allowed)
				(pads allowed)
				(copperpour not_allowed)
				(footprints allowed)
			)
			(placement
				(enabled no)
				(sheetname "")
			)
			(fill
				(thermal_gap 0.5)
				(thermal_bridge_width 0.5)
				(island_removal_mode 0)
			)
			(polygon
				(pts
					(arc
						(start 119.731028 -100.350066)
						(mid 118.969028 -100.350066)
						(end 119.731028 -100.350066)
					)
				)
			)
		)
		(zone
			(layer "F.Cu")
			(hatch none 0.5)
			(connect_pads
				(clearance 0)
			)
			(min_thickness 0.25)
			(keepout
				(tracks allowed)
				(vias not_allowed)
				(pads allowed)
				(copperpour not_allowed)
				(footprints allowed)
			)
			(placement
				(enabled no)
				(sheetname "")
			)
			(fill
				(thermal_gap 0.5)
				(thermal_bridge_width 0.5)
				(island_removal_mode 0)
			)
			(polygon
				(pts
					(arc
						(start 119.731028 -99.350068)
						(mid 118.969028 -99.350068)
						(end 119.731028 -99.350068)
					)
				)
			)
		)
		(zone
			(layer "F.Cu")
			(hatch none 0.5)
			(connect_pads
				(clearance 0)
			)
			(min_thickness 0.25)
			(keepout
				(tracks allowed)
				(vias not_allowed)
				(pads allowed)
				(copperpour not_allowed)
				(footprints allowed)
			)
			(placement
				(enabled no)
				(sheetname "")
			)
			(fill
				(thermal_gap 0.5)
				(thermal_bridge_width 0.5)
				(island_removal_mode 0)
			)
			(polygon
				(pts
					(arc
						(start 119.731028 -98.35007)
						(mid 118.969028 -98.35007)
						(end 119.731028 -98.35007)
					)
				)
			)
		)
		(zone
			(layer "F.Cu")
			(hatch none 0.5)
			(connect_pads
				(clearance 0)
			)
			(min_thickness 0.25)
			(keepout
				(tracks allowed)
				(vias not_allowed)
				(pads allowed)
				(copperpour not_allowed)
				(footprints allowed)
			)
			(placement
				(enabled no)
				(sheetname "")
			)
			(fill
				(thermal_gap 0.5)
				(thermal_bridge_width 0.5)
				(island_removal_mode 0)
			)
			(polygon
				(pts
					(arc
						(start 119.731028 -97.350072)
						(mid 118.969028 -97.350072)
						(end 119.731028 -97.350072)
					)
				)
			)
		)
		(zone
			(layer "F.Cu")
			(hatch none 0.5)
			(connect_pads
				(clearance 0)
			)
			(min_thickness 0.25)
			(keepout
				(tracks allowed)
				(vias not_allowed)
				(pads allowed)
				(copperpour not_allowed)
				(footprints allowed)
			)
			(placement
				(enabled no)
				(sheetname "")
			)
			(fill
				(thermal_gap 0.5)
				(thermal_bridge_width 0.5)
				(island_removal_mode 0)
			)
			(polygon
				(pts
					(arc
						(start 119.731028 -96.350074)
						(mid 118.969028 -96.350074)
						(end 119.731028 -96.350074)
					)
				)
			)
		)
		(zone
			(layer "F.Cu")
			(hatch none 0.5)
			(connect_pads
				(clearance 0)
			)
			(min_thickness 0.25)
			(keepout
				(tracks allowed)
				(vias not_allowed)
				(pads allowed)
				(copperpour not_allowed)
				(footprints allowed)
			)
			(placement
				(enabled no)
				(sheetname "")
			)
			(fill
				(thermal_gap 0.5)
				(thermal_bridge_width 0.5)
				(island_removal_mode 0)
			)
			(polygon
				(pts
					(arc
						(start 119.731028 -95.350076)
						(mid 118.969028 -95.350076)
						(end 119.731028 -95.350076)
					)
				)
			)
		)
		(zone
			(layer "F.Cu")
			(hatch none 0.5)
			(connect_pads
				(clearance 0)
			)
			(min_thickness 0.25)
			(keepout
				(tracks allowed)
				(vias not_allowed)
				(pads allowed)
				(copperpour not_allowed)
				(footprints allowed)
			)
			(placement
				(enabled no)
				(sheetname "")
			)
			(fill
				(thermal_gap 0.5)
				(thermal_bridge_width 0.5)
				(island_removal_mode 0)
			)
			(polygon
				(pts
					(arc
						(start 119.731028 -94.349824)
						(mid 118.969028 -94.349824)
						(end 119.731028 -94.349824)
					)
				)
			)
		)
		(zone
			(layer "F.Cu")
			(hatch none 0.5)
			(connect_pads
				(clearance 0)
			)
			(min_thickness 0.25)
			(keepout
				(tracks allowed)
				(vias not_allowed)
				(pads allowed)
				(copperpour not_allowed)
				(footprints allowed)
			)
			(placement
				(enabled no)
				(sheetname "")
			)
			(fill
				(thermal_gap 0.5)
				(thermal_bridge_width 0.5)
				(island_removal_mode 0)
			)
			(polygon
				(pts
					(arc
						(start 119.731028 -93.349826)
						(mid 118.969028 -93.349826)
						(end 119.731028 -93.349826)
					)
				)
			)
		)
		(zone
			(layer "F.Cu")
			(hatch none 0.5)
			(connect_pads
				(clearance 0)
			)
			(min_thickness 0.25)
			(keepout
				(tracks allowed)
				(vias not_allowed)
				(pads allowed)
				(copperpour not_allowed)
				(footprints allowed)
			)
			(placement
				(enabled no)
				(sheetname "")
			)
			(fill
				(thermal_gap 0.5)
				(thermal_bridge_width 0.5)
				(island_removal_mode 0)
			)
			(polygon
				(pts
					(arc
						(start 119.731028 -92.349828)
						(mid 118.969028 -92.349828)
						(end 119.731028 -92.349828)
					)
				)
			)
		)
		(zone
			(layer "F.Cu")
			(hatch none 0.5)
			(connect_pads
				(clearance 0)
			)
			(min_thickness 0.25)
			(keepout
				(tracks allowed)
				(vias not_allowed)
				(pads allowed)
				(copperpour not_allowed)
				(footprints allowed)
			)
			(placement
				(enabled no)
				(sheetname "")
			)
			(fill
				(thermal_gap 0.5)
				(thermal_bridge_width 0.5)
				(island_removal_mode 0)
			)
			(polygon
				(pts
					(arc
						(start 119.731028 -91.34983)
						(mid 118.969028 -91.34983)
						(end 119.731028 -91.34983)
					)
				)
			)
		)
		(zone
			(layer "F.Cu")
			(hatch none 0.5)
			(connect_pads
				(clearance 0)
			)
			(min_thickness 0.25)
			(keepout
				(tracks allowed)
				(vias not_allowed)
				(pads allowed)
				(copperpour not_allowed)
				(footprints allowed)
			)
			(placement
				(enabled no)
				(sheetname "")
			)
			(fill
				(thermal_gap 0.5)
				(thermal_bridge_width 0.5)
				(island_removal_mode 0)
			)
			(polygon
				(pts
					(arc
						(start 119.731028 -90.349832)
						(mid 118.969028 -90.349832)
						(end 119.731028 -90.349832)
					)
				)
			)
		)
		(zone
			(layer "F.Cu")
			(hatch none 0.5)
			(connect_pads
				(clearance 0)
			)
			(min_thickness 0.25)
			(keepout
				(tracks allowed)
				(vias not_allowed)
				(pads allowed)
				(copperpour not_allowed)
				(footprints allowed)
			)
			(placement
				(enabled no)
				(sheetname "")
			)
			(fill
				(thermal_gap 0.5)
				(thermal_bridge_width 0.5)
				(island_removal_mode 0)
			)
			(polygon
				(pts
					(arc
						(start 119.731028 -89.349834)
						(mid 118.969028 -89.349834)
						(end 119.731028 -89.349834)
					)
				)
			)
		)
		(zone
			(layer "F.Cu")
			(hatch none 0.5)
			(connect_pads
				(clearance 0)
			)
			(min_thickness 0.25)
			(keepout
				(tracks allowed)
				(vias not_allowed)
				(pads allowed)
				(copperpour not_allowed)
				(footprints allowed)
			)
			(placement
				(enabled no)
				(sheetname "")
			)
			(fill
				(thermal_gap 0.5)
				(thermal_bridge_width 0.5)
				(island_removal_mode 0)
			)
			(polygon
				(pts
					(arc
						(start 119.731028 -88.349836)
						(mid 118.969028 -88.349836)
						(end 119.731028 -88.349836)
					)
				)
			)
		)
		(zone
			(layer "F.Cu")
			(hatch none 0.5)
			(connect_pads
				(clearance 0)
			)
			(min_thickness 0.25)
			(keepout
				(tracks allowed)
				(vias not_allowed)
				(pads allowed)
				(copperpour not_allowed)
				(footprints allowed)
			)
			(placement
				(enabled no)
				(sheetname "")
			)
			(fill
				(thermal_gap 0.5)
				(thermal_bridge_width 0.5)
				(island_removal_mode 0)
			)
			(polygon
				(pts
					(arc
						(start 119.731028 -87.349838)
						(mid 118.969028 -87.349838)
						(end 119.731028 -87.349838)
					)
				)
			)
		)
		(zone
			(layer "F.Cu")
			(hatch none 0.5)
			(connect_pads
				(clearance 0)
			)
			(min_thickness 0.25)
			(keepout
				(tracks allowed)
				(vias not_allowed)
				(pads allowed)
				(copperpour not_allowed)
				(footprints allowed)
			)
			(placement
				(enabled no)
				(sheetname "")
			)
			(fill
				(thermal_gap 0.5)
				(thermal_bridge_width 0.5)
				(island_removal_mode 0)
			)
			(polygon
				(pts
					(arc
						(start 119.731028 -86.34984)
						(mid 118.969028 -86.34984)
						(end 119.731028 -86.34984)
					)
				)
			)
		)
		(zone
			(layer "F.Cu")
			(hatch none 0.5)
			(connect_pads
				(clearance 0)
			)
			(min_thickness 0.25)
			(keepout
				(tracks allowed)
				(vias not_allowed)
				(pads allowed)
				(copperpour not_allowed)
				(footprints allowed)
			)
			(placement
				(enabled no)
				(sheetname "")
			)
			(fill
				(thermal_gap 0.5)
				(thermal_bridge_width 0.5)
				(island_removal_mode 0)
			)
			(polygon
				(pts
					(arc
						(start 119.731028 -85.349842)
						(mid 118.969028 -85.349842)
						(end 119.731028 -85.349842)
					)
				)
			)
		)
		(zone
			(layer "F.Cu")
			(hatch none 0.5)
			(connect_pads
				(clearance 0)
			)
			(min_thickness 0.25)
			(keepout
				(tracks allowed)
				(vias not_allowed)
				(pads allowed)
				(copperpour not_allowed)
				(footprints allowed)
			)
			(placement
				(enabled no)
				(sheetname "")
			)
			(fill
				(thermal_gap 0.5)
				(thermal_bridge_width 0.5)
				(island_removal_mode 0)
			)
			(polygon
				(pts
					(arc
						(start 119.731028 -84.349844)
						(mid 118.969028 -84.349844)
						(end 119.731028 -84.349844)
					)
				)
			)
		)
		(zone
			(layer "F.Cu")
			(hatch none 0.5)
			(connect_pads
				(clearance 0)
			)
			(min_thickness 0.25)
			(keepout
				(tracks allowed)
				(vias not_allowed)
				(pads allowed)
				(copperpour not_allowed)
				(footprints allowed)
			)
			(placement
				(enabled no)
				(sheetname "")
			)
			(fill
				(thermal_gap 0.5)
				(thermal_bridge_width 0.5)
				(island_removal_mode 0)
			)
			(polygon
				(pts
					(arc
						(start 119.731028 -83.349846)
						(mid 118.969028 -83.349846)
						(end 119.731028 -83.349846)
					)
				)
			)
		)
		(zone
			(layer "F.Cu")
			(hatch none 0.5)
			(connect_pads
				(clearance 0)
			)
			(min_thickness 0.25)
			(keepout
				(tracks allowed)
				(vias not_allowed)
				(pads allowed)
				(copperpour not_allowed)
				(footprints allowed)
			)
			(placement
				(enabled no)
				(sheetname "")
			)
			(fill
				(thermal_gap 0.5)
				(thermal_bridge_width 0.5)
				(island_removal_mode 0)
			)
			(polygon
				(pts
					(arc
						(start 119.731028 -82.349848)
						(mid 118.969028 -82.349848)
						(end 119.731028 -82.349848)
					)
				)
			)
		)
		(zone
			(layer "F.Cu")
			(hatch none 0.5)
			(connect_pads
				(clearance 0)
			)
			(min_thickness 0.25)
			(keepout
				(tracks allowed)
				(vias not_allowed)
				(pads allowed)
				(copperpour not_allowed)
				(footprints allowed)
			)
			(placement
				(enabled no)
				(sheetname "")
			)
			(fill
				(thermal_gap 0.5)
				(thermal_bridge_width 0.5)
				(island_removal_mode 0)
			)
			(polygon
				(pts
					(arc
						(start 120.731026 -107.350052)
						(mid 119.969026 -107.350052)
						(end 120.731026 -107.350052)
					)
				)
			)
		)
		(zone
			(layer "F.Cu")
			(hatch none 0.5)
			(connect_pads
				(clearance 0)
			)
			(min_thickness 0.25)
			(keepout
				(tracks allowed)
				(vias not_allowed)
				(pads allowed)
				(copperpour not_allowed)
				(footprints allowed)
			)
			(placement
				(enabled no)
				(sheetname "")
			)
			(fill
				(thermal_gap 0.5)
				(thermal_bridge_width 0.5)
				(island_removal_mode 0)
			)
			(polygon
				(pts
					(arc
						(start 120.731026 -106.350054)
						(mid 119.969026 -106.350054)
						(end 120.731026 -106.350054)
					)
				)
			)
		)
		(zone
			(layer "F.Cu")
			(hatch none 0.5)
			(connect_pads
				(clearance 0)
			)
			(min_thickness 0.25)
			(keepout
				(tracks allowed)
				(vias not_allowed)
				(pads allowed)
				(copperpour not_allowed)
				(footprints allowed)
			)
			(placement
				(enabled no)
				(sheetname "")
			)
			(fill
				(thermal_gap 0.5)
				(thermal_bridge_width 0.5)
				(island_removal_mode 0)
			)
			(polygon
				(pts
					(arc
						(start 120.731026 -105.350056)
						(mid 119.969026 -105.350056)
						(end 120.731026 -105.350056)
					)
				)
			)
		)
		(zone
			(layer "F.Cu")
			(hatch none 0.5)
			(connect_pads
				(clearance 0)
			)
			(min_thickness 0.25)
			(keepout
				(tracks allowed)
				(vias not_allowed)
				(pads allowed)
				(copperpour not_allowed)
				(footprints allowed)
			)
			(placement
				(enabled no)
				(sheetname "")
			)
			(fill
				(thermal_gap 0.5)
				(thermal_bridge_width 0.5)
				(island_removal_mode 0)
			)
			(polygon
				(pts
					(arc
						(start 120.731026 -104.350058)
						(mid 119.969026 -104.350058)
						(end 120.731026 -104.350058)
					)
				)
			)
		)
		(zone
			(layer "F.Cu")
			(hatch none 0.5)
			(connect_pads
				(clearance 0)
			)
			(min_thickness 0.25)
			(keepout
				(tracks allowed)
				(vias not_allowed)
				(pads allowed)
				(copperpour not_allowed)
				(footprints allowed)
			)
			(placement
				(enabled no)
				(sheetname "")
			)
			(fill
				(thermal_gap 0.5)
				(thermal_bridge_width 0.5)
				(island_removal_mode 0)
			)
			(polygon
				(pts
					(arc
						(start 120.731026 -103.35006)
						(mid 119.969026 -103.35006)
						(end 120.731026 -103.35006)
					)
				)
			)
		)
		(zone
			(layer "F.Cu")
			(hatch none 0.5)
			(connect_pads
				(clearance 0)
			)
			(min_thickness 0.25)
			(keepout
				(tracks allowed)
				(vias not_allowed)
				(pads allowed)
				(copperpour not_allowed)
				(footprints allowed)
			)
			(placement
				(enabled no)
				(sheetname "")
			)
			(fill
				(thermal_gap 0.5)
				(thermal_bridge_width 0.5)
				(island_removal_mode 0)
			)
			(polygon
				(pts
					(arc
						(start 120.731026 -102.350062)
						(mid 119.969026 -102.350062)
						(end 120.731026 -102.350062)
					)
				)
			)
		)
		(zone
			(layer "F.Cu")
			(hatch none 0.5)
			(connect_pads
				(clearance 0)
			)
			(min_thickness 0.25)
			(keepout
				(tracks allowed)
				(vias not_allowed)
				(pads allowed)
				(copperpour not_allowed)
				(footprints allowed)
			)
			(placement
				(enabled no)
				(sheetname "")
			)
			(fill
				(thermal_gap 0.5)
				(thermal_bridge_width 0.5)
				(island_removal_mode 0)
			)
			(polygon
				(pts
					(arc
						(start 120.731026 -101.350064)
						(mid 119.969026 -101.350064)
						(end 120.731026 -101.350064)
					)
				)
			)
		)
		(zone
			(layer "F.Cu")
			(hatch none 0.5)
			(connect_pads
				(clearance 0)
			)
			(min_thickness 0.25)
			(keepout
				(tracks allowed)
				(vias not_allowed)
				(pads allowed)
				(copperpour not_allowed)
				(footprints allowed)
			)
			(placement
				(enabled no)
				(sheetname "")
			)
			(fill
				(thermal_gap 0.5)
				(thermal_bridge_width 0.5)
				(island_removal_mode 0)
			)
			(polygon
				(pts
					(arc
						(start 120.731026 -100.350066)
						(mid 119.969026 -100.350066)
						(end 120.731026 -100.350066)
					)
				)
			)
		)
		(zone
			(layer "F.Cu")
			(hatch none 0.5)
			(connect_pads
				(clearance 0)
			)
			(min_thickness 0.25)
			(keepout
				(tracks allowed)
				(vias not_allowed)
				(pads allowed)
				(copperpour not_allowed)
				(footprints allowed)
			)
			(placement
				(enabled no)
				(sheetname "")
			)
			(fill
				(thermal_gap 0.5)
				(thermal_bridge_width 0.5)
				(island_removal_mode 0)
			)
			(polygon
				(pts
					(arc
						(start 120.731026 -99.350068)
						(mid 119.969026 -99.350068)
						(end 120.731026 -99.350068)
					)
				)
			)
		)
		(zone
			(layer "F.Cu")
			(hatch none 0.5)
			(connect_pads
				(clearance 0)
			)
			(min_thickness 0.25)
			(keepout
				(tracks allowed)
				(vias not_allowed)
				(pads allowed)
				(copperpour not_allowed)
				(footprints allowed)
			)
			(placement
				(enabled no)
				(sheetname "")
			)
			(fill
				(thermal_gap 0.5)
				(thermal_bridge_width 0.5)
				(island_removal_mode 0)
			)
			(polygon
				(pts
					(arc
						(start 120.731026 -98.35007)
						(mid 119.969026 -98.35007)
						(end 120.731026 -98.35007)
					)
				)
			)
		)
		(zone
			(layer "F.Cu")
			(hatch none 0.5)
			(connect_pads
				(clearance 0)
			)
			(min_thickness 0.25)
			(keepout
				(tracks allowed)
				(vias not_allowed)
				(pads allowed)
				(copperpour not_allowed)
				(footprints allowed)
			)
			(placement
				(enabled no)
				(sheetname "")
			)
			(fill
				(thermal_gap 0.5)
				(thermal_bridge_width 0.5)
				(island_removal_mode 0)
			)
			(polygon
				(pts
					(arc
						(start 120.731026 -97.350072)
						(mid 119.969026 -97.350072)
						(end 120.731026 -97.350072)
					)
				)
			)
		)
		(zone
			(layer "F.Cu")
			(hatch none 0.5)
			(connect_pads
				(clearance 0)
			)
			(min_thickness 0.25)
			(keepout
				(tracks allowed)
				(vias not_allowed)
				(pads allowed)
				(copperpour not_allowed)
				(footprints allowed)
			)
			(placement
				(enabled no)
				(sheetname "")
			)
			(fill
				(thermal_gap 0.5)
				(thermal_bridge_width 0.5)
				(island_removal_mode 0)
			)
			(polygon
				(pts
					(arc
						(start 120.731026 -96.350074)
						(mid 119.969026 -96.350074)
						(end 120.731026 -96.350074)
					)
				)
			)
		)
		(zone
			(layer "F.Cu")
			(hatch none 0.5)
			(connect_pads
				(clearance 0)
			)
			(min_thickness 0.25)
			(keepout
				(tracks allowed)
				(vias not_allowed)
				(pads allowed)
				(copperpour not_allowed)
				(footprints allowed)
			)
			(placement
				(enabled no)
				(sheetname "")
			)
			(fill
				(thermal_gap 0.5)
				(thermal_bridge_width 0.5)
				(island_removal_mode 0)
			)
			(polygon
				(pts
					(arc
						(start 120.731026 -95.350076)
						(mid 119.969026 -95.350076)
						(end 120.731026 -95.350076)
					)
				)
			)
		)
		(zone
			(layer "F.Cu")
			(hatch none 0.5)
			(connect_pads
				(clearance 0)
			)
			(min_thickness 0.25)
			(keepout
				(tracks allowed)
				(vias not_allowed)
				(pads allowed)
				(copperpour not_allowed)
				(footprints allowed)
			)
			(placement
				(enabled no)
				(sheetname "")
			)
			(fill
				(thermal_gap 0.5)
				(thermal_bridge_width 0.5)
				(island_removal_mode 0)
			)
			(polygon
				(pts
					(arc
						(start 120.731026 -94.349824)
						(mid 119.969026 -94.349824)
						(end 120.731026 -94.349824)
					)
				)
			)
		)
		(zone
			(layer "F.Cu")
			(hatch none 0.5)
			(connect_pads
				(clearance 0)
			)
			(min_thickness 0.25)
			(keepout
				(tracks allowed)
				(vias not_allowed)
				(pads allowed)
				(copperpour not_allowed)
				(footprints allowed)
			)
			(placement
				(enabled no)
				(sheetname "")
			)
			(fill
				(thermal_gap 0.5)
				(thermal_bridge_width 0.5)
				(island_removal_mode 0)
			)
			(polygon
				(pts
					(arc
						(start 120.731026 -93.349826)
						(mid 119.969026 -93.349826)
						(end 120.731026 -93.349826)
					)
				)
			)
		)
		(zone
			(layer "F.Cu")
			(hatch none 0.5)
			(connect_pads
				(clearance 0)
			)
			(min_thickness 0.25)
			(keepout
				(tracks allowed)
				(vias not_allowed)
				(pads allowed)
				(copperpour not_allowed)
				(footprints allowed)
			)
			(placement
				(enabled no)
				(sheetname "")
			)
			(fill
				(thermal_gap 0.5)
				(thermal_bridge_width 0.5)
				(island_removal_mode 0)
			)
			(polygon
				(pts
					(arc
						(start 120.731026 -92.349828)
						(mid 119.969026 -92.349828)
						(end 120.731026 -92.349828)
					)
				)
			)
		)
		(zone
			(layer "F.Cu")
			(hatch none 0.5)
			(connect_pads
				(clearance 0)
			)
			(min_thickness 0.25)
			(keepout
				(tracks allowed)
				(vias not_allowed)
				(pads allowed)
				(copperpour not_allowed)
				(footprints allowed)
			)
			(placement
				(enabled no)
				(sheetname "")
			)
			(fill
				(thermal_gap 0.5)
				(thermal_bridge_width 0.5)
				(island_removal_mode 0)
			)
			(polygon
				(pts
					(arc
						(start 120.731026 -91.34983)
						(mid 119.969026 -91.34983)
						(end 120.731026 -91.34983)
					)
				)
			)
		)
		(zone
			(layer "F.Cu")
			(hatch none 0.5)
			(connect_pads
				(clearance 0)
			)
			(min_thickness 0.25)
			(keepout
				(tracks allowed)
				(vias not_allowed)
				(pads allowed)
				(copperpour not_allowed)
				(footprints allowed)
			)
			(placement
				(enabled no)
				(sheetname "")
			)
			(fill
				(thermal_gap 0.5)
				(thermal_bridge_width 0.5)
				(island_removal_mode 0)
			)
			(polygon
				(pts
					(arc
						(start 120.731026 -90.349832)
						(mid 119.969026 -90.349832)
						(end 120.731026 -90.349832)
					)
				)
			)
		)
		(zone
			(layer "F.Cu")
			(hatch none 0.5)
			(connect_pads
				(clearance 0)
			)
			(min_thickness 0.25)
			(keepout
				(tracks allowed)
				(vias not_allowed)
				(pads allowed)
				(copperpour not_allowed)
				(footprints allowed)
			)
			(placement
				(enabled no)
				(sheetname "")
			)
			(fill
				(thermal_gap 0.5)
				(thermal_bridge_width 0.5)
				(island_removal_mode 0)
			)
			(polygon
				(pts
					(arc
						(start 120.731026 -89.349834)
						(mid 119.969026 -89.349834)
						(end 120.731026 -89.349834)
					)
				)
			)
		)
		(zone
			(layer "F.Cu")
			(hatch none 0.5)
			(connect_pads
				(clearance 0)
			)
			(min_thickness 0.25)
			(keepout
				(tracks allowed)
				(vias not_allowed)
				(pads allowed)
				(copperpour not_allowed)
				(footprints allowed)
			)
			(placement
				(enabled no)
				(sheetname "")
			)
			(fill
				(thermal_gap 0.5)
				(thermal_bridge_width 0.5)
				(island_removal_mode 0)
			)
			(polygon
				(pts
					(arc
						(start 120.731026 -88.349836)
						(mid 119.969026 -88.349836)
						(end 120.731026 -88.349836)
					)
				)
			)
		)
		(zone
			(layer "F.Cu")
			(hatch none 0.5)
			(connect_pads
				(clearance 0)
			)
			(min_thickness 0.25)
			(keepout
				(tracks allowed)
				(vias not_allowed)
				(pads allowed)
				(copperpour not_allowed)
				(footprints allowed)
			)
			(placement
				(enabled no)
				(sheetname "")
			)
			(fill
				(thermal_gap 0.5)
				(thermal_bridge_width 0.5)
				(island_removal_mode 0)
			)
			(polygon
				(pts
					(arc
						(start 120.731026 -87.349838)
						(mid 119.969026 -87.349838)
						(end 120.731026 -87.349838)
					)
				)
			)
		)
		(zone
			(layer "F.Cu")
			(hatch none 0.5)
			(connect_pads
				(clearance 0)
			)
			(min_thickness 0.25)
			(keepout
				(tracks allowed)
				(vias not_allowed)
				(pads allowed)
				(copperpour not_allowed)
				(footprints allowed)
			)
			(placement
				(enabled no)
				(sheetname "")
			)
			(fill
				(thermal_gap 0.5)
				(thermal_bridge_width 0.5)
				(island_removal_mode 0)
			)
			(polygon
				(pts
					(arc
						(start 120.731026 -86.34984)
						(mid 119.969026 -86.34984)
						(end 120.731026 -86.34984)
					)
				)
			)
		)
		(zone
			(layer "F.Cu")
			(hatch none 0.5)
			(connect_pads
				(clearance 0)
			)
			(min_thickness 0.25)
			(keepout
				(tracks allowed)
				(vias not_allowed)
				(pads allowed)
				(copperpour not_allowed)
				(footprints allowed)
			)
			(placement
				(enabled no)
				(sheetname "")
			)
			(fill
				(thermal_gap 0.5)
				(thermal_bridge_width 0.5)
				(island_removal_mode 0)
			)
			(polygon
				(pts
					(arc
						(start 120.731026 -85.349842)
						(mid 119.969026 -85.349842)
						(end 120.731026 -85.349842)
					)
				)
			)
		)
		(zone
			(layer "F.Cu")
			(hatch none 0.5)
			(connect_pads
				(clearance 0)
			)
			(min_thickness 0.25)
			(keepout
				(tracks allowed)
				(vias not_allowed)
				(pads allowed)
				(copperpour not_allowed)
				(footprints allowed)
			)
			(placement
				(enabled no)
				(sheetname "")
			)
			(fill
				(thermal_gap 0.5)
				(thermal_bridge_width 0.5)
				(island_removal_mode 0)
			)
			(polygon
				(pts
					(arc
						(start 120.731026 -84.349844)
						(mid 119.969026 -84.349844)
						(end 120.731026 -84.349844)
					)
				)
			)
		)
		(zone
			(layer "F.Cu")
			(hatch none 0.5)
			(connect_pads
				(clearance 0)
			)
			(min_thickness 0.25)
			(keepout
				(tracks allowed)
				(vias not_allowed)
				(pads allowed)
				(copperpour not_allowed)
				(footprints allowed)
			)
			(placement
				(enabled no)
				(sheetname "")
			)
			(fill
				(thermal_gap 0.5)
				(thermal_bridge_width 0.5)
				(island_removal_mode 0)
			)
			(polygon
				(pts
					(arc
						(start 120.731026 -83.349846)
						(mid 119.969026 -83.349846)
						(end 120.731026 -83.349846)
					)
				)
			)
		)
		(zone
			(layer "F.Cu")
			(hatch none 0.5)
			(connect_pads
				(clearance 0)
			)
			(min_thickness 0.25)
			(keepout
				(tracks allowed)
				(vias not_allowed)
				(pads allowed)
				(copperpour not_allowed)
				(footprints allowed)
			)
			(placement
				(enabled no)
				(sheetname "")
			)
			(fill
				(thermal_gap 0.5)
				(thermal_bridge_width 0.5)
				(island_removal_mode 0)
			)
			(polygon
				(pts
					(arc
						(start 120.731026 -82.349848)
						(mid 119.969026 -82.349848)
						(end 120.731026 -82.349848)
					)
				)
			)
		)
		(zone
			(layer "F.Cu")
			(hatch none 0.5)
			(connect_pads
				(clearance 0)
			)
			(min_thickness 0.25)
			(keepout
				(tracks allowed)
				(vias not_allowed)
				(pads allowed)
				(copperpour not_allowed)
				(footprints allowed)
			)
			(placement
				(enabled no)
				(sheetname "")
			)
			(fill
				(thermal_gap 0.5)
				(thermal_bridge_width 0.5)
				(island_removal_mode 0)
			)
			(polygon
				(pts
					(arc
						(start 121.731024 -107.350052)
						(mid 120.969024 -107.350052)
						(end 121.731024 -107.350052)
					)
				)
			)
		)
		(zone
			(layer "F.Cu")
			(hatch none 0.5)
			(connect_pads
				(clearance 0)
			)
			(min_thickness 0.25)
			(keepout
				(tracks allowed)
				(vias not_allowed)
				(pads allowed)
				(copperpour not_allowed)
				(footprints allowed)
			)
			(placement
				(enabled no)
				(sheetname "")
			)
			(fill
				(thermal_gap 0.5)
				(thermal_bridge_width 0.5)
				(island_removal_mode 0)
			)
			(polygon
				(pts
					(arc
						(start 121.731024 -106.350054)
						(mid 120.969024 -106.350054)
						(end 121.731024 -106.350054)
					)
				)
			)
		)
		(zone
			(layer "F.Cu")
			(hatch none 0.5)
			(connect_pads
				(clearance 0)
			)
			(min_thickness 0.25)
			(keepout
				(tracks allowed)
				(vias not_allowed)
				(pads allowed)
				(copperpour not_allowed)
				(footprints allowed)
			)
			(placement
				(enabled no)
				(sheetname "")
			)
			(fill
				(thermal_gap 0.5)
				(thermal_bridge_width 0.5)
				(island_removal_mode 0)
			)
			(polygon
				(pts
					(arc
						(start 121.731024 -105.350056)
						(mid 120.969024 -105.350056)
						(end 121.731024 -105.350056)
					)
				)
			)
		)
		(zone
			(layer "F.Cu")
			(hatch none 0.5)
			(connect_pads
				(clearance 0)
			)
			(min_thickness 0.25)
			(keepout
				(tracks allowed)
				(vias not_allowed)
				(pads allowed)
				(copperpour not_allowed)
				(footprints allowed)
			)
			(placement
				(enabled no)
				(sheetname "")
			)
			(fill
				(thermal_gap 0.5)
				(thermal_bridge_width 0.5)
				(island_removal_mode 0)
			)
			(polygon
				(pts
					(arc
						(start 121.731024 -104.350058)
						(mid 120.969024 -104.350058)
						(end 121.731024 -104.350058)
					)
				)
			)
		)
		(zone
			(layer "F.Cu")
			(hatch none 0.5)
			(connect_pads
				(clearance 0)
			)
			(min_thickness 0.25)
			(keepout
				(tracks allowed)
				(vias not_allowed)
				(pads allowed)
				(copperpour not_allowed)
				(footprints allowed)
			)
			(placement
				(enabled no)
				(sheetname "")
			)
			(fill
				(thermal_gap 0.5)
				(thermal_bridge_width 0.5)
				(island_removal_mode 0)
			)
			(polygon
				(pts
					(arc
						(start 121.731024 -103.35006)
						(mid 120.969024 -103.35006)
						(end 121.731024 -103.35006)
					)
				)
			)
		)
		(zone
			(layer "F.Cu")
			(hatch none 0.5)
			(connect_pads
				(clearance 0)
			)
			(min_thickness 0.25)
			(keepout
				(tracks allowed)
				(vias not_allowed)
				(pads allowed)
				(copperpour not_allowed)
				(footprints allowed)
			)
			(placement
				(enabled no)
				(sheetname "")
			)
			(fill
				(thermal_gap 0.5)
				(thermal_bridge_width 0.5)
				(island_removal_mode 0)
			)
			(polygon
				(pts
					(arc
						(start 121.731024 -102.350062)
						(mid 120.969024 -102.350062)
						(end 121.731024 -102.350062)
					)
				)
			)
		)
		(zone
			(layer "F.Cu")
			(hatch none 0.5)
			(connect_pads
				(clearance 0)
			)
			(min_thickness 0.25)
			(keepout
				(tracks allowed)
				(vias not_allowed)
				(pads allowed)
				(copperpour not_allowed)
				(footprints allowed)
			)
			(placement
				(enabled no)
				(sheetname "")
			)
			(fill
				(thermal_gap 0.5)
				(thermal_bridge_width 0.5)
				(island_removal_mode 0)
			)
			(polygon
				(pts
					(arc
						(start 121.731024 -101.350064)
						(mid 120.969024 -101.350064)
						(end 121.731024 -101.350064)
					)
				)
			)
		)
		(zone
			(layer "F.Cu")
			(hatch none 0.5)
			(connect_pads
				(clearance 0)
			)
			(min_thickness 0.25)
			(keepout
				(tracks allowed)
				(vias not_allowed)
				(pads allowed)
				(copperpour not_allowed)
				(footprints allowed)
			)
			(placement
				(enabled no)
				(sheetname "")
			)
			(fill
				(thermal_gap 0.5)
				(thermal_bridge_width 0.5)
				(island_removal_mode 0)
			)
			(polygon
				(pts
					(arc
						(start 121.731024 -100.350066)
						(mid 120.969024 -100.350066)
						(end 121.731024 -100.350066)
					)
				)
			)
		)
		(zone
			(layer "F.Cu")
			(hatch none 0.5)
			(connect_pads
				(clearance 0)
			)
			(min_thickness 0.25)
			(keepout
				(tracks allowed)
				(vias not_allowed)
				(pads allowed)
				(copperpour not_allowed)
				(footprints allowed)
			)
			(placement
				(enabled no)
				(sheetname "")
			)
			(fill
				(thermal_gap 0.5)
				(thermal_bridge_width 0.5)
				(island_removal_mode 0)
			)
			(polygon
				(pts
					(arc
						(start 121.731024 -99.350068)
						(mid 120.969024 -99.350068)
						(end 121.731024 -99.350068)
					)
				)
			)
		)
		(zone
			(layer "F.Cu")
			(hatch none 0.5)
			(connect_pads
				(clearance 0)
			)
			(min_thickness 0.25)
			(keepout
				(tracks allowed)
				(vias not_allowed)
				(pads allowed)
				(copperpour not_allowed)
				(footprints allowed)
			)
			(placement
				(enabled no)
				(sheetname "")
			)
			(fill
				(thermal_gap 0.5)
				(thermal_bridge_width 0.5)
				(island_removal_mode 0)
			)
			(polygon
				(pts
					(arc
						(start 121.731024 -98.35007)
						(mid 120.969024 -98.35007)
						(end 121.731024 -98.35007)
					)
				)
			)
		)
		(zone
			(layer "F.Cu")
			(hatch none 0.5)
			(connect_pads
				(clearance 0)
			)
			(min_thickness 0.25)
			(keepout
				(tracks allowed)
				(vias not_allowed)
				(pads allowed)
				(copperpour not_allowed)
				(footprints allowed)
			)
			(placement
				(enabled no)
				(sheetname "")
			)
			(fill
				(thermal_gap 0.5)
				(thermal_bridge_width 0.5)
				(island_removal_mode 0)
			)
			(polygon
				(pts
					(arc
						(start 121.731024 -97.350072)
						(mid 120.969024 -97.350072)
						(end 121.731024 -97.350072)
					)
				)
			)
		)
		(zone
			(layer "F.Cu")
			(hatch none 0.5)
			(connect_pads
				(clearance 0)
			)
			(min_thickness 0.25)
			(keepout
				(tracks allowed)
				(vias not_allowed)
				(pads allowed)
				(copperpour not_allowed)
				(footprints allowed)
			)
			(placement
				(enabled no)
				(sheetname "")
			)
			(fill
				(thermal_gap 0.5)
				(thermal_bridge_width 0.5)
				(island_removal_mode 0)
			)
			(polygon
				(pts
					(arc
						(start 121.731024 -96.350074)
						(mid 120.969024 -96.350074)
						(end 121.731024 -96.350074)
					)
				)
			)
		)
		(zone
			(layer "F.Cu")
			(hatch none 0.5)
			(connect_pads
				(clearance 0)
			)
			(min_thickness 0.25)
			(keepout
				(tracks allowed)
				(vias not_allowed)
				(pads allowed)
				(copperpour not_allowed)
				(footprints allowed)
			)
			(placement
				(enabled no)
				(sheetname "")
			)
			(fill
				(thermal_gap 0.5)
				(thermal_bridge_width 0.5)
				(island_removal_mode 0)
			)
			(polygon
				(pts
					(arc
						(start 121.731024 -95.350076)
						(mid 120.969024 -95.350076)
						(end 121.731024 -95.350076)
					)
				)
			)
		)
		(zone
			(layer "F.Cu")
			(hatch none 0.5)
			(connect_pads
				(clearance 0)
			)
			(min_thickness 0.25)
			(keepout
				(tracks allowed)
				(vias not_allowed)
				(pads allowed)
				(copperpour not_allowed)
				(footprints allowed)
			)
			(placement
				(enabled no)
				(sheetname "")
			)
			(fill
				(thermal_gap 0.5)
				(thermal_bridge_width 0.5)
				(island_removal_mode 0)
			)
			(polygon
				(pts
					(arc
						(start 121.731024 -94.349824)
						(mid 120.969024 -94.349824)
						(end 121.731024 -94.349824)
					)
				)
			)
		)
		(zone
			(layer "F.Cu")
			(hatch none 0.5)
			(connect_pads
				(clearance 0)
			)
			(min_thickness 0.25)
			(keepout
				(tracks allowed)
				(vias not_allowed)
				(pads allowed)
				(copperpour not_allowed)
				(footprints allowed)
			)
			(placement
				(enabled no)
				(sheetname "")
			)
			(fill
				(thermal_gap 0.5)
				(thermal_bridge_width 0.5)
				(island_removal_mode 0)
			)
			(polygon
				(pts
					(arc
						(start 121.731024 -93.349826)
						(mid 120.969024 -93.349826)
						(end 121.731024 -93.349826)
					)
				)
			)
		)
		(zone
			(layer "F.Cu")
			(hatch none 0.5)
			(connect_pads
				(clearance 0)
			)
			(min_thickness 0.25)
			(keepout
				(tracks allowed)
				(vias not_allowed)
				(pads allowed)
				(copperpour not_allowed)
				(footprints allowed)
			)
			(placement
				(enabled no)
				(sheetname "")
			)
			(fill
				(thermal_gap 0.5)
				(thermal_bridge_width 0.5)
				(island_removal_mode 0)
			)
			(polygon
				(pts
					(arc
						(start 121.731024 -92.349828)
						(mid 120.969024 -92.349828)
						(end 121.731024 -92.349828)
					)
				)
			)
		)
		(zone
			(layer "F.Cu")
			(hatch none 0.5)
			(connect_pads
				(clearance 0)
			)
			(min_thickness 0.25)
			(keepout
				(tracks allowed)
				(vias not_allowed)
				(pads allowed)
				(copperpour not_allowed)
				(footprints allowed)
			)
			(placement
				(enabled no)
				(sheetname "")
			)
			(fill
				(thermal_gap 0.5)
				(thermal_bridge_width 0.5)
				(island_removal_mode 0)
			)
			(polygon
				(pts
					(arc
						(start 121.731024 -91.34983)
						(mid 120.969024 -91.34983)
						(end 121.731024 -91.34983)
					)
				)
			)
		)
		(zone
			(layer "F.Cu")
			(hatch none 0.5)
			(connect_pads
				(clearance 0)
			)
			(min_thickness 0.25)
			(keepout
				(tracks allowed)
				(vias not_allowed)
				(pads allowed)
				(copperpour not_allowed)
				(footprints allowed)
			)
			(placement
				(enabled no)
				(sheetname "")
			)
			(fill
				(thermal_gap 0.5)
				(thermal_bridge_width 0.5)
				(island_removal_mode 0)
			)
			(polygon
				(pts
					(arc
						(start 121.731024 -90.349832)
						(mid 120.969024 -90.349832)
						(end 121.731024 -90.349832)
					)
				)
			)
		)
		(zone
			(layer "F.Cu")
			(hatch none 0.5)
			(connect_pads
				(clearance 0)
			)
			(min_thickness 0.25)
			(keepout
				(tracks allowed)
				(vias not_allowed)
				(pads allowed)
				(copperpour not_allowed)
				(footprints allowed)
			)
			(placement
				(enabled no)
				(sheetname "")
			)
			(fill
				(thermal_gap 0.5)
				(thermal_bridge_width 0.5)
				(island_removal_mode 0)
			)
			(polygon
				(pts
					(arc
						(start 121.731024 -89.349834)
						(mid 120.969024 -89.349834)
						(end 121.731024 -89.349834)
					)
				)
			)
		)
		(zone
			(layer "F.Cu")
			(hatch none 0.5)
			(connect_pads
				(clearance 0)
			)
			(min_thickness 0.25)
			(keepout
				(tracks allowed)
				(vias not_allowed)
				(pads allowed)
				(copperpour not_allowed)
				(footprints allowed)
			)
			(placement
				(enabled no)
				(sheetname "")
			)
			(fill
				(thermal_gap 0.5)
				(thermal_bridge_width 0.5)
				(island_removal_mode 0)
			)
			(polygon
				(pts
					(arc
						(start 121.731024 -88.349836)
						(mid 120.969024 -88.349836)
						(end 121.731024 -88.349836)
					)
				)
			)
		)
		(zone
			(layer "F.Cu")
			(hatch none 0.5)
			(connect_pads
				(clearance 0)
			)
			(min_thickness 0.25)
			(keepout
				(tracks allowed)
				(vias not_allowed)
				(pads allowed)
				(copperpour not_allowed)
				(footprints allowed)
			)
			(placement
				(enabled no)
				(sheetname "")
			)
			(fill
				(thermal_gap 0.5)
				(thermal_bridge_width 0.5)
				(island_removal_mode 0)
			)
			(polygon
				(pts
					(arc
						(start 121.731024 -87.349838)
						(mid 120.969024 -87.349838)
						(end 121.731024 -87.349838)
					)
				)
			)
		)
		(zone
			(layer "F.Cu")
			(hatch none 0.5)
			(connect_pads
				(clearance 0)
			)
			(min_thickness 0.25)
			(keepout
				(tracks allowed)
				(vias not_allowed)
				(pads allowed)
				(copperpour not_allowed)
				(footprints allowed)
			)
			(placement
				(enabled no)
				(sheetname "")
			)
			(fill
				(thermal_gap 0.5)
				(thermal_bridge_width 0.5)
				(island_removal_mode 0)
			)
			(polygon
				(pts
					(arc
						(start 121.731024 -86.34984)
						(mid 120.969024 -86.34984)
						(end 121.731024 -86.34984)
					)
				)
			)
		)
		(zone
			(layer "F.Cu")
			(hatch none 0.5)
			(connect_pads
				(clearance 0)
			)
			(min_thickness 0.25)
			(keepout
				(tracks allowed)
				(vias not_allowed)
				(pads allowed)
				(copperpour not_allowed)
				(footprints allowed)
			)
			(placement
				(enabled no)
				(sheetname "")
			)
			(fill
				(thermal_gap 0.5)
				(thermal_bridge_width 0.5)
				(island_removal_mode 0)
			)
			(polygon
				(pts
					(arc
						(start 121.731024 -85.349842)
						(mid 120.969024 -85.349842)
						(end 121.731024 -85.349842)
					)
				)
			)
		)
		(zone
			(layer "F.Cu")
			(hatch none 0.5)
			(connect_pads
				(clearance 0)
			)
			(min_thickness 0.25)
			(keepout
				(tracks allowed)
				(vias not_allowed)
				(pads allowed)
				(copperpour not_allowed)
				(footprints allowed)
			)
			(placement
				(enabled no)
				(sheetname "")
			)
			(fill
				(thermal_gap 0.5)
				(thermal_bridge_width 0.5)
				(island_removal_mode 0)
			)
			(polygon
				(pts
					(arc
						(start 121.731024 -84.349844)
						(mid 120.969024 -84.349844)
						(end 121.731024 -84.349844)
					)
				)
			)
		)
		(zone
			(layer "F.Cu")
			(hatch none 0.5)
			(connect_pads
				(clearance 0)
			)
			(min_thickness 0.25)
			(keepout
				(tracks allowed)
				(vias not_allowed)
				(pads allowed)
				(copperpour not_allowed)
				(footprints allowed)
			)
			(placement
				(enabled no)
				(sheetname "")
			)
			(fill
				(thermal_gap 0.5)
				(thermal_bridge_width 0.5)
				(island_removal_mode 0)
			)
			(polygon
				(pts
					(arc
						(start 121.731024 -83.349846)
						(mid 120.969024 -83.349846)
						(end 121.731024 -83.349846)
					)
				)
			)
		)
		(zone
			(layer "F.Cu")
			(hatch none 0.5)
			(connect_pads
				(clearance 0)
			)
			(min_thickness 0.25)
			(keepout
				(tracks allowed)
				(vias not_allowed)
				(pads allowed)
				(copperpour not_allowed)
				(footprints allowed)
			)
			(placement
				(enabled no)
				(sheetname "")
			)
			(fill
				(thermal_gap 0.5)
				(thermal_bridge_width 0.5)
				(island_removal_mode 0)
			)
			(polygon
				(pts
					(arc
						(start 121.731024 -82.349848)
						(mid 120.969024 -82.349848)
						(end 121.731024 -82.349848)
					)
				)
			)
		)
		(zone
			(layer "F.Cu")
			(hatch none 0.5)
			(connect_pads
				(clearance 0)
			)
			(min_thickness 0.25)
			(keepout
				(tracks allowed)
				(vias not_allowed)
				(pads allowed)
				(copperpour not_allowed)
				(footprints allowed)
			)
			(placement
				(enabled no)
				(sheetname "")
			)
			(fill
				(thermal_gap 0.5)
				(thermal_bridge_width 0.5)
				(island_removal_mode 0)
			)
			(polygon
				(pts
					(arc
						(start 122.731022 -107.350052)
						(mid 121.969022 -107.350052)
						(end 122.731022 -107.350052)
					)
				)
			)
		)
		(zone
			(layer "F.Cu")
			(hatch none 0.5)
			(connect_pads
				(clearance 0)
			)
			(min_thickness 0.25)
			(keepout
				(tracks allowed)
				(vias not_allowed)
				(pads allowed)
				(copperpour not_allowed)
				(footprints allowed)
			)
			(placement
				(enabled no)
				(sheetname "")
			)
			(fill
				(thermal_gap 0.5)
				(thermal_bridge_width 0.5)
				(island_removal_mode 0)
			)
			(polygon
				(pts
					(arc
						(start 122.731022 -106.350054)
						(mid 121.969022 -106.350054)
						(end 122.731022 -106.350054)
					)
				)
			)
		)
		(zone
			(layer "F.Cu")
			(hatch none 0.5)
			(connect_pads
				(clearance 0)
			)
			(min_thickness 0.25)
			(keepout
				(tracks allowed)
				(vias not_allowed)
				(pads allowed)
				(copperpour not_allowed)
				(footprints allowed)
			)
			(placement
				(enabled no)
				(sheetname "")
			)
			(fill
				(thermal_gap 0.5)
				(thermal_bridge_width 0.5)
				(island_removal_mode 0)
			)
			(polygon
				(pts
					(arc
						(start 122.731022 -105.350056)
						(mid 121.969022 -105.350056)
						(end 122.731022 -105.350056)
					)
				)
			)
		)
		(zone
			(layer "F.Cu")
			(hatch none 0.5)
			(connect_pads
				(clearance 0)
			)
			(min_thickness 0.25)
			(keepout
				(tracks allowed)
				(vias not_allowed)
				(pads allowed)
				(copperpour not_allowed)
				(footprints allowed)
			)
			(placement
				(enabled no)
				(sheetname "")
			)
			(fill
				(thermal_gap 0.5)
				(thermal_bridge_width 0.5)
				(island_removal_mode 0)
			)
			(polygon
				(pts
					(arc
						(start 122.731022 -104.350058)
						(mid 121.969022 -104.350058)
						(end 122.731022 -104.350058)
					)
				)
			)
		)
		(zone
			(layer "F.Cu")
			(hatch none 0.5)
			(connect_pads
				(clearance 0)
			)
			(min_thickness 0.25)
			(keepout
				(tracks allowed)
				(vias not_allowed)
				(pads allowed)
				(copperpour not_allowed)
				(footprints allowed)
			)
			(placement
				(enabled no)
				(sheetname "")
			)
			(fill
				(thermal_gap 0.5)
				(thermal_bridge_width 0.5)
				(island_removal_mode 0)
			)
			(polygon
				(pts
					(arc
						(start 122.731022 -103.35006)
						(mid 121.969022 -103.35006)
						(end 122.731022 -103.35006)
					)
				)
			)
		)
		(zone
			(layer "F.Cu")
			(hatch none 0.5)
			(connect_pads
				(clearance 0)
			)
			(min_thickness 0.25)
			(keepout
				(tracks allowed)
				(vias not_allowed)
				(pads allowed)
				(copperpour not_allowed)
				(footprints allowed)
			)
			(placement
				(enabled no)
				(sheetname "")
			)
			(fill
				(thermal_gap 0.5)
				(thermal_bridge_width 0.5)
				(island_removal_mode 0)
			)
			(polygon
				(pts
					(arc
						(start 122.731022 -102.350062)
						(mid 121.969022 -102.350062)
						(end 122.731022 -102.350062)
					)
				)
			)
		)
		(zone
			(layer "F.Cu")
			(hatch none 0.5)
			(connect_pads
				(clearance 0)
			)
			(min_thickness 0.25)
			(keepout
				(tracks allowed)
				(vias not_allowed)
				(pads allowed)
				(copperpour not_allowed)
				(footprints allowed)
			)
			(placement
				(enabled no)
				(sheetname "")
			)
			(fill
				(thermal_gap 0.5)
				(thermal_bridge_width 0.5)
				(island_removal_mode 0)
			)
			(polygon
				(pts
					(arc
						(start 122.731022 -101.350064)
						(mid 121.969022 -101.350064)
						(end 122.731022 -101.350064)
					)
				)
			)
		)
		(zone
			(layer "F.Cu")
			(hatch none 0.5)
			(connect_pads
				(clearance 0)
			)
			(min_thickness 0.25)
			(keepout
				(tracks allowed)
				(vias not_allowed)
				(pads allowed)
				(copperpour not_allowed)
				(footprints allowed)
			)
			(placement
				(enabled no)
				(sheetname "")
			)
			(fill
				(thermal_gap 0.5)
				(thermal_bridge_width 0.5)
				(island_removal_mode 0)
			)
			(polygon
				(pts
					(arc
						(start 122.731022 -100.350066)
						(mid 121.969022 -100.350066)
						(end 122.731022 -100.350066)
					)
				)
			)
		)
		(zone
			(layer "F.Cu")
			(hatch none 0.5)
			(connect_pads
				(clearance 0)
			)
			(min_thickness 0.25)
			(keepout
				(tracks allowed)
				(vias not_allowed)
				(pads allowed)
				(copperpour not_allowed)
				(footprints allowed)
			)
			(placement
				(enabled no)
				(sheetname "")
			)
			(fill
				(thermal_gap 0.5)
				(thermal_bridge_width 0.5)
				(island_removal_mode 0)
			)
			(polygon
				(pts
					(arc
						(start 122.731022 -99.350068)
						(mid 121.969022 -99.350068)
						(end 122.731022 -99.350068)
					)
				)
			)
		)
		(zone
			(layer "F.Cu")
			(hatch none 0.5)
			(connect_pads
				(clearance 0)
			)
			(min_thickness 0.25)
			(keepout
				(tracks allowed)
				(vias not_allowed)
				(pads allowed)
				(copperpour not_allowed)
				(footprints allowed)
			)
			(placement
				(enabled no)
				(sheetname "")
			)
			(fill
				(thermal_gap 0.5)
				(thermal_bridge_width 0.5)
				(island_removal_mode 0)
			)
			(polygon
				(pts
					(arc
						(start 122.731022 -98.35007)
						(mid 121.969022 -98.35007)
						(end 122.731022 -98.35007)
					)
				)
			)
		)
		(zone
			(layer "F.Cu")
			(hatch none 0.5)
			(connect_pads
				(clearance 0)
			)
			(min_thickness 0.25)
			(keepout
				(tracks allowed)
				(vias not_allowed)
				(pads allowed)
				(copperpour not_allowed)
				(footprints allowed)
			)
			(placement
				(enabled no)
				(sheetname "")
			)
			(fill
				(thermal_gap 0.5)
				(thermal_bridge_width 0.5)
				(island_removal_mode 0)
			)
			(polygon
				(pts
					(arc
						(start 122.731022 -97.350072)
						(mid 121.969022 -97.350072)
						(end 122.731022 -97.350072)
					)
				)
			)
		)
		(zone
			(layer "F.Cu")
			(hatch none 0.5)
			(connect_pads
				(clearance 0)
			)
			(min_thickness 0.25)
			(keepout
				(tracks allowed)
				(vias not_allowed)
				(pads allowed)
				(copperpour not_allowed)
				(footprints allowed)
			)
			(placement
				(enabled no)
				(sheetname "")
			)
			(fill
				(thermal_gap 0.5)
				(thermal_bridge_width 0.5)
				(island_removal_mode 0)
			)
			(polygon
				(pts
					(arc
						(start 122.731022 -96.350074)
						(mid 121.969022 -96.350074)
						(end 122.731022 -96.350074)
					)
				)
			)
		)
		(zone
			(layer "F.Cu")
			(hatch none 0.5)
			(connect_pads
				(clearance 0)
			)
			(min_thickness 0.25)
			(keepout
				(tracks allowed)
				(vias not_allowed)
				(pads allowed)
				(copperpour not_allowed)
				(footprints allowed)
			)
			(placement
				(enabled no)
				(sheetname "")
			)
			(fill
				(thermal_gap 0.5)
				(thermal_bridge_width 0.5)
				(island_removal_mode 0)
			)
			(polygon
				(pts
					(arc
						(start 122.731022 -95.350076)
						(mid 121.969022 -95.350076)
						(end 122.731022 -95.350076)
					)
				)
			)
		)
		(zone
			(layer "F.Cu")
			(hatch none 0.5)
			(connect_pads
				(clearance 0)
			)
			(min_thickness 0.25)
			(keepout
				(tracks allowed)
				(vias not_allowed)
				(pads allowed)
				(copperpour not_allowed)
				(footprints allowed)
			)
			(placement
				(enabled no)
				(sheetname "")
			)
			(fill
				(thermal_gap 0.5)
				(thermal_bridge_width 0.5)
				(island_removal_mode 0)
			)
			(polygon
				(pts
					(arc
						(start 122.731022 -94.349824)
						(mid 121.969022 -94.349824)
						(end 122.731022 -94.349824)
					)
				)
			)
		)
		(zone
			(layer "F.Cu")
			(hatch none 0.5)
			(connect_pads
				(clearance 0)
			)
			(min_thickness 0.25)
			(keepout
				(tracks allowed)
				(vias not_allowed)
				(pads allowed)
				(copperpour not_allowed)
				(footprints allowed)
			)
			(placement
				(enabled no)
				(sheetname "")
			)
			(fill
				(thermal_gap 0.5)
				(thermal_bridge_width 0.5)
				(island_removal_mode 0)
			)
			(polygon
				(pts
					(arc
						(start 122.731022 -93.349826)
						(mid 121.969022 -93.349826)
						(end 122.731022 -93.349826)
					)
				)
			)
		)
		(zone
			(layer "F.Cu")
			(hatch none 0.5)
			(connect_pads
				(clearance 0)
			)
			(min_thickness 0.25)
			(keepout
				(tracks allowed)
				(vias not_allowed)
				(pads allowed)
				(copperpour not_allowed)
				(footprints allowed)
			)
			(placement
				(enabled no)
				(sheetname "")
			)
			(fill
				(thermal_gap 0.5)
				(thermal_bridge_width 0.5)
				(island_removal_mode 0)
			)
			(polygon
				(pts
					(arc
						(start 122.731022 -92.349828)
						(mid 121.969022 -92.349828)
						(end 122.731022 -92.349828)
					)
				)
			)
		)
		(zone
			(layer "F.Cu")
			(hatch none 0.5)
			(connect_pads
				(clearance 0)
			)
			(min_thickness 0.25)
			(keepout
				(tracks allowed)
				(vias not_allowed)
				(pads allowed)
				(copperpour not_allowed)
				(footprints allowed)
			)
			(placement
				(enabled no)
				(sheetname "")
			)
			(fill
				(thermal_gap 0.5)
				(thermal_bridge_width 0.5)
				(island_removal_mode 0)
			)
			(polygon
				(pts
					(arc
						(start 122.731022 -91.34983)
						(mid 121.969022 -91.34983)
						(end 122.731022 -91.34983)
					)
				)
			)
		)
		(zone
			(layer "F.Cu")
			(hatch none 0.5)
			(connect_pads
				(clearance 0)
			)
			(min_thickness 0.25)
			(keepout
				(tracks allowed)
				(vias not_allowed)
				(pads allowed)
				(copperpour not_allowed)
				(footprints allowed)
			)
			(placement
				(enabled no)
				(sheetname "")
			)
			(fill
				(thermal_gap 0.5)
				(thermal_bridge_width 0.5)
				(island_removal_mode 0)
			)
			(polygon
				(pts
					(arc
						(start 122.731022 -90.349832)
						(mid 121.969022 -90.349832)
						(end 122.731022 -90.349832)
					)
				)
			)
		)
		(zone
			(layer "F.Cu")
			(hatch none 0.5)
			(connect_pads
				(clearance 0)
			)
			(min_thickness 0.25)
			(keepout
				(tracks allowed)
				(vias not_allowed)
				(pads allowed)
				(copperpour not_allowed)
				(footprints allowed)
			)
			(placement
				(enabled no)
				(sheetname "")
			)
			(fill
				(thermal_gap 0.5)
				(thermal_bridge_width 0.5)
				(island_removal_mode 0)
			)
			(polygon
				(pts
					(arc
						(start 122.731022 -89.349834)
						(mid 121.969022 -89.349834)
						(end 122.731022 -89.349834)
					)
				)
			)
		)
		(zone
			(layer "F.Cu")
			(hatch none 0.5)
			(connect_pads
				(clearance 0)
			)
			(min_thickness 0.25)
			(keepout
				(tracks allowed)
				(vias not_allowed)
				(pads allowed)
				(copperpour not_allowed)
				(footprints allowed)
			)
			(placement
				(enabled no)
				(sheetname "")
			)
			(fill
				(thermal_gap 0.5)
				(thermal_bridge_width 0.5)
				(island_removal_mode 0)
			)
			(polygon
				(pts
					(arc
						(start 122.731022 -88.349836)
						(mid 121.969022 -88.349836)
						(end 122.731022 -88.349836)
					)
				)
			)
		)
		(zone
			(layer "F.Cu")
			(hatch none 0.5)
			(connect_pads
				(clearance 0)
			)
			(min_thickness 0.25)
			(keepout
				(tracks allowed)
				(vias not_allowed)
				(pads allowed)
				(copperpour not_allowed)
				(footprints allowed)
			)
			(placement
				(enabled no)
				(sheetname "")
			)
			(fill
				(thermal_gap 0.5)
				(thermal_bridge_width 0.5)
				(island_removal_mode 0)
			)
			(polygon
				(pts
					(arc
						(start 122.731022 -87.349838)
						(mid 121.969022 -87.349838)
						(end 122.731022 -87.349838)
					)
				)
			)
		)
		(zone
			(layer "F.Cu")
			(hatch none 0.5)
			(connect_pads
				(clearance 0)
			)
			(min_thickness 0.25)
			(keepout
				(tracks allowed)
				(vias not_allowed)
				(pads allowed)
				(copperpour not_allowed)
				(footprints allowed)
			)
			(placement
				(enabled no)
				(sheetname "")
			)
			(fill
				(thermal_gap 0.5)
				(thermal_bridge_width 0.5)
				(island_removal_mode 0)
			)
			(polygon
				(pts
					(arc
						(start 122.731022 -86.34984)
						(mid 121.969022 -86.34984)
						(end 122.731022 -86.34984)
					)
				)
			)
		)
		(zone
			(layer "F.Cu")
			(hatch none 0.5)
			(connect_pads
				(clearance 0)
			)
			(min_thickness 0.25)
			(keepout
				(tracks allowed)
				(vias not_allowed)
				(pads allowed)
				(copperpour not_allowed)
				(footprints allowed)
			)
			(placement
				(enabled no)
				(sheetname "")
			)
			(fill
				(thermal_gap 0.5)
				(thermal_bridge_width 0.5)
				(island_removal_mode 0)
			)
			(polygon
				(pts
					(arc
						(start 122.731022 -85.349842)
						(mid 121.969022 -85.349842)
						(end 122.731022 -85.349842)
					)
				)
			)
		)
		(zone
			(layer "F.Cu")
			(hatch none 0.5)
			(connect_pads
				(clearance 0)
			)
			(min_thickness 0.25)
			(keepout
				(tracks allowed)
				(vias not_allowed)
				(pads allowed)
				(copperpour not_allowed)
				(footprints allowed)
			)
			(placement
				(enabled no)
				(sheetname "")
			)
			(fill
				(thermal_gap 0.5)
				(thermal_bridge_width 0.5)
				(island_removal_mode 0)
			)
			(polygon
				(pts
					(arc
						(start 122.731022 -84.349844)
						(mid 121.969022 -84.349844)
						(end 122.731022 -84.349844)
					)
				)
			)
		)
		(zone
			(layer "F.Cu")
			(hatch none 0.5)
			(connect_pads
				(clearance 0)
			)
			(min_thickness 0.25)
			(keepout
				(tracks allowed)
				(vias not_allowed)
				(pads allowed)
				(copperpour not_allowed)
				(footprints allowed)
			)
			(placement
				(enabled no)
				(sheetname "")
			)
			(fill
				(thermal_gap 0.5)
				(thermal_bridge_width 0.5)
				(island_removal_mode 0)
			)
			(polygon
				(pts
					(arc
						(start 122.731022 -83.349846)
						(mid 121.969022 -83.349846)
						(end 122.731022 -83.349846)
					)
				)
			)
		)
		(zone
			(layer "F.Cu")
			(hatch none 0.5)
			(connect_pads
				(clearance 0)
			)
			(min_thickness 0.25)
			(keepout
				(tracks allowed)
				(vias not_allowed)
				(pads allowed)
				(copperpour not_allowed)
				(footprints allowed)
			)
			(placement
				(enabled no)
				(sheetname "")
			)
			(fill
				(thermal_gap 0.5)
				(thermal_bridge_width 0.5)
				(island_removal_mode 0)
			)
			(polygon
				(pts
					(arc
						(start 122.731022 -82.349848)
						(mid 121.969022 -82.349848)
						(end 122.731022 -82.349848)
					)
				)
			)
		)
		(zone
			(layer "F.Cu")
			(hatch none 0.5)
			(connect_pads
				(clearance 0)
			)
			(min_thickness 0.25)
			(keepout
				(tracks allowed)
				(vias not_allowed)
				(pads allowed)
				(copperpour not_allowed)
				(footprints allowed)
			)
			(placement
				(enabled no)
				(sheetname "")
			)
			(fill
				(thermal_gap 0.5)
				(thermal_bridge_width 0.5)
				(island_removal_mode 0)
			)
			(polygon
				(pts
					(arc
						(start 123.73102 -107.350052)
						(mid 122.96902 -107.350052)
						(end 123.73102 -107.350052)
					)
				)
			)
		)
		(zone
			(layer "F.Cu")
			(hatch none 0.5)
			(connect_pads
				(clearance 0)
			)
			(min_thickness 0.25)
			(keepout
				(tracks allowed)
				(vias not_allowed)
				(pads allowed)
				(copperpour not_allowed)
				(footprints allowed)
			)
			(placement
				(enabled no)
				(sheetname "")
			)
			(fill
				(thermal_gap 0.5)
				(thermal_bridge_width 0.5)
				(island_removal_mode 0)
			)
			(polygon
				(pts
					(arc
						(start 123.73102 -106.350054)
						(mid 122.96902 -106.350054)
						(end 123.73102 -106.350054)
					)
				)
			)
		)
		(zone
			(layer "F.Cu")
			(hatch none 0.5)
			(connect_pads
				(clearance 0)
			)
			(min_thickness 0.25)
			(keepout
				(tracks allowed)
				(vias not_allowed)
				(pads allowed)
				(copperpour not_allowed)
				(footprints allowed)
			)
			(placement
				(enabled no)
				(sheetname "")
			)
			(fill
				(thermal_gap 0.5)
				(thermal_bridge_width 0.5)
				(island_removal_mode 0)
			)
			(polygon
				(pts
					(arc
						(start 123.73102 -105.350056)
						(mid 122.96902 -105.350056)
						(end 123.73102 -105.350056)
					)
				)
			)
		)
		(zone
			(layer "F.Cu")
			(hatch none 0.5)
			(connect_pads
				(clearance 0)
			)
			(min_thickness 0.25)
			(keepout
				(tracks allowed)
				(vias not_allowed)
				(pads allowed)
				(copperpour not_allowed)
				(footprints allowed)
			)
			(placement
				(enabled no)
				(sheetname "")
			)
			(fill
				(thermal_gap 0.5)
				(thermal_bridge_width 0.5)
				(island_removal_mode 0)
			)
			(polygon
				(pts
					(arc
						(start 123.73102 -104.350058)
						(mid 122.96902 -104.350058)
						(end 123.73102 -104.350058)
					)
				)
			)
		)
		(zone
			(layer "F.Cu")
			(hatch none 0.5)
			(connect_pads
				(clearance 0)
			)
			(min_thickness 0.25)
			(keepout
				(tracks allowed)
				(vias not_allowed)
				(pads allowed)
				(copperpour not_allowed)
				(footprints allowed)
			)
			(placement
				(enabled no)
				(sheetname "")
			)
			(fill
				(thermal_gap 0.5)
				(thermal_bridge_width 0.5)
				(island_removal_mode 0)
			)
			(polygon
				(pts
					(arc
						(start 123.73102 -103.35006)
						(mid 122.96902 -103.35006)
						(end 123.73102 -103.35006)
					)
				)
			)
		)
		(zone
			(layer "F.Cu")
			(hatch none 0.5)
			(connect_pads
				(clearance 0)
			)
			(min_thickness 0.25)
			(keepout
				(tracks allowed)
				(vias not_allowed)
				(pads allowed)
				(copperpour not_allowed)
				(footprints allowed)
			)
			(placement
				(enabled no)
				(sheetname "")
			)
			(fill
				(thermal_gap 0.5)
				(thermal_bridge_width 0.5)
				(island_removal_mode 0)
			)
			(polygon
				(pts
					(arc
						(start 123.73102 -102.350062)
						(mid 122.96902 -102.350062)
						(end 123.73102 -102.350062)
					)
				)
			)
		)
		(zone
			(layer "F.Cu")
			(hatch none 0.5)
			(connect_pads
				(clearance 0)
			)
			(min_thickness 0.25)
			(keepout
				(tracks allowed)
				(vias not_allowed)
				(pads allowed)
				(copperpour not_allowed)
				(footprints allowed)
			)
			(placement
				(enabled no)
				(sheetname "")
			)
			(fill
				(thermal_gap 0.5)
				(thermal_bridge_width 0.5)
				(island_removal_mode 0)
			)
			(polygon
				(pts
					(arc
						(start 123.73102 -101.350064)
						(mid 122.96902 -101.350064)
						(end 123.73102 -101.350064)
					)
				)
			)
		)
		(zone
			(layer "F.Cu")
			(hatch none 0.5)
			(connect_pads
				(clearance 0)
			)
			(min_thickness 0.25)
			(keepout
				(tracks allowed)
				(vias not_allowed)
				(pads allowed)
				(copperpour not_allowed)
				(footprints allowed)
			)
			(placement
				(enabled no)
				(sheetname "")
			)
			(fill
				(thermal_gap 0.5)
				(thermal_bridge_width 0.5)
				(island_removal_mode 0)
			)
			(polygon
				(pts
					(arc
						(start 123.73102 -100.350066)
						(mid 122.96902 -100.350066)
						(end 123.73102 -100.350066)
					)
				)
			)
		)
		(zone
			(layer "F.Cu")
			(hatch none 0.5)
			(connect_pads
				(clearance 0)
			)
			(min_thickness 0.25)
			(keepout
				(tracks allowed)
				(vias not_allowed)
				(pads allowed)
				(copperpour not_allowed)
				(footprints allowed)
			)
			(placement
				(enabled no)
				(sheetname "")
			)
			(fill
				(thermal_gap 0.5)
				(thermal_bridge_width 0.5)
				(island_removal_mode 0)
			)
			(polygon
				(pts
					(arc
						(start 123.73102 -99.350068)
						(mid 122.96902 -99.350068)
						(end 123.73102 -99.350068)
					)
				)
			)
		)
		(zone
			(layer "F.Cu")
			(hatch none 0.5)
			(connect_pads
				(clearance 0)
			)
			(min_thickness 0.25)
			(keepout
				(tracks allowed)
				(vias not_allowed)
				(pads allowed)
				(copperpour not_allowed)
				(footprints allowed)
			)
			(placement
				(enabled no)
				(sheetname "")
			)
			(fill
				(thermal_gap 0.5)
				(thermal_bridge_width 0.5)
				(island_removal_mode 0)
			)
			(polygon
				(pts
					(arc
						(start 123.73102 -98.35007)
						(mid 122.96902 -98.35007)
						(end 123.73102 -98.35007)
					)
				)
			)
		)
		(zone
			(layer "F.Cu")
			(hatch none 0.5)
			(connect_pads
				(clearance 0)
			)
			(min_thickness 0.25)
			(keepout
				(tracks allowed)
				(vias not_allowed)
				(pads allowed)
				(copperpour not_allowed)
				(footprints allowed)
			)
			(placement
				(enabled no)
				(sheetname "")
			)
			(fill
				(thermal_gap 0.5)
				(thermal_bridge_width 0.5)
				(island_removal_mode 0)
			)
			(polygon
				(pts
					(arc
						(start 123.73102 -97.350072)
						(mid 122.96902 -97.350072)
						(end 123.73102 -97.350072)
					)
				)
			)
		)
		(zone
			(layer "F.Cu")
			(hatch none 0.5)
			(connect_pads
				(clearance 0)
			)
			(min_thickness 0.25)
			(keepout
				(tracks allowed)
				(vias not_allowed)
				(pads allowed)
				(copperpour not_allowed)
				(footprints allowed)
			)
			(placement
				(enabled no)
				(sheetname "")
			)
			(fill
				(thermal_gap 0.5)
				(thermal_bridge_width 0.5)
				(island_removal_mode 0)
			)
			(polygon
				(pts
					(arc
						(start 123.73102 -96.350074)
						(mid 122.96902 -96.350074)
						(end 123.73102 -96.350074)
					)
				)
			)
		)
		(zone
			(layer "F.Cu")
			(hatch none 0.5)
			(connect_pads
				(clearance 0)
			)
			(min_thickness 0.25)
			(keepout
				(tracks allowed)
				(vias not_allowed)
				(pads allowed)
				(copperpour not_allowed)
				(footprints allowed)
			)
			(placement
				(enabled no)
				(sheetname "")
			)
			(fill
				(thermal_gap 0.5)
				(thermal_bridge_width 0.5)
				(island_removal_mode 0)
			)
			(polygon
				(pts
					(arc
						(start 123.73102 -95.350076)
						(mid 122.96902 -95.350076)
						(end 123.73102 -95.350076)
					)
				)
			)
		)
		(zone
			(layer "F.Cu")
			(hatch none 0.5)
			(connect_pads
				(clearance 0)
			)
			(min_thickness 0.25)
			(keepout
				(tracks allowed)
				(vias not_allowed)
				(pads allowed)
				(copperpour not_allowed)
				(footprints allowed)
			)
			(placement
				(enabled no)
				(sheetname "")
			)
			(fill
				(thermal_gap 0.5)
				(thermal_bridge_width 0.5)
				(island_removal_mode 0)
			)
			(polygon
				(pts
					(arc
						(start 123.73102 -94.349824)
						(mid 122.96902 -94.349824)
						(end 123.73102 -94.349824)
					)
				)
			)
		)
		(zone
			(layer "F.Cu")
			(hatch none 0.5)
			(connect_pads
				(clearance 0)
			)
			(min_thickness 0.25)
			(keepout
				(tracks allowed)
				(vias not_allowed)
				(pads allowed)
				(copperpour not_allowed)
				(footprints allowed)
			)
			(placement
				(enabled no)
				(sheetname "")
			)
			(fill
				(thermal_gap 0.5)
				(thermal_bridge_width 0.5)
				(island_removal_mode 0)
			)
			(polygon
				(pts
					(arc
						(start 123.73102 -93.349826)
						(mid 122.96902 -93.349826)
						(end 123.73102 -93.349826)
					)
				)
			)
		)
		(zone
			(layer "F.Cu")
			(hatch none 0.5)
			(connect_pads
				(clearance 0)
			)
			(min_thickness 0.25)
			(keepout
				(tracks allowed)
				(vias not_allowed)
				(pads allowed)
				(copperpour not_allowed)
				(footprints allowed)
			)
			(placement
				(enabled no)
				(sheetname "")
			)
			(fill
				(thermal_gap 0.5)
				(thermal_bridge_width 0.5)
				(island_removal_mode 0)
			)
			(polygon
				(pts
					(arc
						(start 123.73102 -92.349828)
						(mid 122.96902 -92.349828)
						(end 123.73102 -92.349828)
					)
				)
			)
		)
		(zone
			(layer "F.Cu")
			(hatch none 0.5)
			(connect_pads
				(clearance 0)
			)
			(min_thickness 0.25)
			(keepout
				(tracks allowed)
				(vias not_allowed)
				(pads allowed)
				(copperpour not_allowed)
				(footprints allowed)
			)
			(placement
				(enabled no)
				(sheetname "")
			)
			(fill
				(thermal_gap 0.5)
				(thermal_bridge_width 0.5)
				(island_removal_mode 0)
			)
			(polygon
				(pts
					(arc
						(start 123.73102 -91.34983)
						(mid 122.96902 -91.34983)
						(end 123.73102 -91.34983)
					)
				)
			)
		)
		(zone
			(layer "F.Cu")
			(hatch none 0.5)
			(connect_pads
				(clearance 0)
			)
			(min_thickness 0.25)
			(keepout
				(tracks allowed)
				(vias not_allowed)
				(pads allowed)
				(copperpour not_allowed)
				(footprints allowed)
			)
			(placement
				(enabled no)
				(sheetname "")
			)
			(fill
				(thermal_gap 0.5)
				(thermal_bridge_width 0.5)
				(island_removal_mode 0)
			)
			(polygon
				(pts
					(arc
						(start 123.73102 -90.349832)
						(mid 122.96902 -90.349832)
						(end 123.73102 -90.349832)
					)
				)
			)
		)
		(zone
			(layer "F.Cu")
			(hatch none 0.5)
			(connect_pads
				(clearance 0)
			)
			(min_thickness 0.25)
			(keepout
				(tracks allowed)
				(vias not_allowed)
				(pads allowed)
				(copperpour not_allowed)
				(footprints allowed)
			)
			(placement
				(enabled no)
				(sheetname "")
			)
			(fill
				(thermal_gap 0.5)
				(thermal_bridge_width 0.5)
				(island_removal_mode 0)
			)
			(polygon
				(pts
					(arc
						(start 123.73102 -89.349834)
						(mid 122.96902 -89.349834)
						(end 123.73102 -89.349834)
					)
				)
			)
		)
		(zone
			(layer "F.Cu")
			(hatch none 0.5)
			(connect_pads
				(clearance 0)
			)
			(min_thickness 0.25)
			(keepout
				(tracks allowed)
				(vias not_allowed)
				(pads allowed)
				(copperpour not_allowed)
				(footprints allowed)
			)
			(placement
				(enabled no)
				(sheetname "")
			)
			(fill
				(thermal_gap 0.5)
				(thermal_bridge_width 0.5)
				(island_removal_mode 0)
			)
			(polygon
				(pts
					(arc
						(start 123.73102 -88.349836)
						(mid 122.96902 -88.349836)
						(end 123.73102 -88.349836)
					)
				)
			)
		)
		(zone
			(layer "F.Cu")
			(hatch none 0.5)
			(connect_pads
				(clearance 0)
			)
			(min_thickness 0.25)
			(keepout
				(tracks allowed)
				(vias not_allowed)
				(pads allowed)
				(copperpour not_allowed)
				(footprints allowed)
			)
			(placement
				(enabled no)
				(sheetname "")
			)
			(fill
				(thermal_gap 0.5)
				(thermal_bridge_width 0.5)
				(island_removal_mode 0)
			)
			(polygon
				(pts
					(arc
						(start 123.73102 -87.349838)
						(mid 122.96902 -87.349838)
						(end 123.73102 -87.349838)
					)
				)
			)
		)
		(zone
			(layer "F.Cu")
			(hatch none 0.5)
			(connect_pads
				(clearance 0)
			)
			(min_thickness 0.25)
			(keepout
				(tracks allowed)
				(vias not_allowed)
				(pads allowed)
				(copperpour not_allowed)
				(footprints allowed)
			)
			(placement
				(enabled no)
				(sheetname "")
			)
			(fill
				(thermal_gap 0.5)
				(thermal_bridge_width 0.5)
				(island_removal_mode 0)
			)
			(polygon
				(pts
					(arc
						(start 123.73102 -86.34984)
						(mid 122.96902 -86.34984)
						(end 123.73102 -86.34984)
					)
				)
			)
		)
		(zone
			(layer "F.Cu")
			(hatch none 0.5)
			(connect_pads
				(clearance 0)
			)
			(min_thickness 0.25)
			(keepout
				(tracks allowed)
				(vias not_allowed)
				(pads allowed)
				(copperpour not_allowed)
				(footprints allowed)
			)
			(placement
				(enabled no)
				(sheetname "")
			)
			(fill
				(thermal_gap 0.5)
				(thermal_bridge_width 0.5)
				(island_removal_mode 0)
			)
			(polygon
				(pts
					(arc
						(start 123.73102 -85.349842)
						(mid 122.96902 -85.349842)
						(end 123.73102 -85.349842)
					)
				)
			)
		)
		(zone
			(layer "F.Cu")
			(hatch none 0.5)
			(connect_pads
				(clearance 0)
			)
			(min_thickness 0.25)
			(keepout
				(tracks allowed)
				(vias not_allowed)
				(pads allowed)
				(copperpour not_allowed)
				(footprints allowed)
			)
			(placement
				(enabled no)
				(sheetname "")
			)
			(fill
				(thermal_gap 0.5)
				(thermal_bridge_width 0.5)
				(island_removal_mode 0)
			)
			(polygon
				(pts
					(arc
						(start 123.73102 -84.349844)
						(mid 122.96902 -84.349844)
						(end 123.73102 -84.349844)
					)
				)
			)
		)
		(zone
			(layer "F.Cu")
			(hatch none 0.5)
			(connect_pads
				(clearance 0)
			)
			(min_thickness 0.25)
			(keepout
				(tracks allowed)
				(vias not_allowed)
				(pads allowed)
				(copperpour not_allowed)
				(footprints allowed)
			)
			(placement
				(enabled no)
				(sheetname "")
			)
			(fill
				(thermal_gap 0.5)
				(thermal_bridge_width 0.5)
				(island_removal_mode 0)
			)
			(polygon
				(pts
					(arc
						(start 123.73102 -83.349846)
						(mid 122.96902 -83.349846)
						(end 123.73102 -83.349846)
					)
				)
			)
		)
		(zone
			(layer "F.Cu")
			(hatch none 0.5)
			(connect_pads
				(clearance 0)
			)
			(min_thickness 0.25)
			(keepout
				(tracks allowed)
				(vias not_allowed)
				(pads allowed)
				(copperpour not_allowed)
				(footprints allowed)
			)
			(placement
				(enabled no)
				(sheetname "")
			)
			(fill
				(thermal_gap 0.5)
				(thermal_bridge_width 0.5)
				(island_removal_mode 0)
			)
			(polygon
				(pts
					(arc
						(start 123.73102 -82.349848)
						(mid 122.96902 -82.349848)
						(end 123.73102 -82.349848)
					)
				)
			)
		)
		(zone
			(layer "F.Cu")
			(hatch none 0.5)
			(connect_pads
				(clearance 0)
			)
			(min_thickness 0.25)
			(keepout
				(tracks allowed)
				(vias not_allowed)
				(pads allowed)
				(copperpour not_allowed)
				(footprints allowed)
			)
			(placement
				(enabled no)
				(sheetname "")
			)
			(fill
				(thermal_gap 0.5)
				(thermal_bridge_width 0.5)
				(island_removal_mode 0)
			)
			(polygon
				(pts
					(arc
						(start 124.731018 -107.350052)
						(mid 123.969018 -107.350052)
						(end 124.731018 -107.350052)
					)
				)
			)
		)
		(zone
			(layer "F.Cu")
			(hatch none 0.5)
			(connect_pads
				(clearance 0)
			)
			(min_thickness 0.25)
			(keepout
				(tracks allowed)
				(vias not_allowed)
				(pads allowed)
				(copperpour not_allowed)
				(footprints allowed)
			)
			(placement
				(enabled no)
				(sheetname "")
			)
			(fill
				(thermal_gap 0.5)
				(thermal_bridge_width 0.5)
				(island_removal_mode 0)
			)
			(polygon
				(pts
					(arc
						(start 124.731018 -106.350054)
						(mid 123.969018 -106.350054)
						(end 124.731018 -106.350054)
					)
				)
			)
		)
		(zone
			(layer "F.Cu")
			(hatch none 0.5)
			(connect_pads
				(clearance 0)
			)
			(min_thickness 0.25)
			(keepout
				(tracks allowed)
				(vias not_allowed)
				(pads allowed)
				(copperpour not_allowed)
				(footprints allowed)
			)
			(placement
				(enabled no)
				(sheetname "")
			)
			(fill
				(thermal_gap 0.5)
				(thermal_bridge_width 0.5)
				(island_removal_mode 0)
			)
			(polygon
				(pts
					(arc
						(start 124.731018 -105.350056)
						(mid 123.969018 -105.350056)
						(end 124.731018 -105.350056)
					)
				)
			)
		)
		(zone
			(layer "F.Cu")
			(hatch none 0.5)
			(connect_pads
				(clearance 0)
			)
			(min_thickness 0.25)
			(keepout
				(tracks allowed)
				(vias not_allowed)
				(pads allowed)
				(copperpour not_allowed)
				(footprints allowed)
			)
			(placement
				(enabled no)
				(sheetname "")
			)
			(fill
				(thermal_gap 0.5)
				(thermal_bridge_width 0.5)
				(island_removal_mode 0)
			)
			(polygon
				(pts
					(arc
						(start 124.731018 -104.350058)
						(mid 123.969018 -104.350058)
						(end 124.731018 -104.350058)
					)
				)
			)
		)
		(zone
			(layer "F.Cu")
			(hatch none 0.5)
			(connect_pads
				(clearance 0)
			)
			(min_thickness 0.25)
			(keepout
				(tracks allowed)
				(vias not_allowed)
				(pads allowed)
				(copperpour not_allowed)
				(footprints allowed)
			)
			(placement
				(enabled no)
				(sheetname "")
			)
			(fill
				(thermal_gap 0.5)
				(thermal_bridge_width 0.5)
				(island_removal_mode 0)
			)
			(polygon
				(pts
					(arc
						(start 124.731018 -103.35006)
						(mid 123.969018 -103.35006)
						(end 124.731018 -103.35006)
					)
				)
			)
		)
		(zone
			(layer "F.Cu")
			(hatch none 0.5)
			(connect_pads
				(clearance 0)
			)
			(min_thickness 0.25)
			(keepout
				(tracks allowed)
				(vias not_allowed)
				(pads allowed)
				(copperpour not_allowed)
				(footprints allowed)
			)
			(placement
				(enabled no)
				(sheetname "")
			)
			(fill
				(thermal_gap 0.5)
				(thermal_bridge_width 0.5)
				(island_removal_mode 0)
			)
			(polygon
				(pts
					(arc
						(start 124.731018 -102.350062)
						(mid 123.969018 -102.350062)
						(end 124.731018 -102.350062)
					)
				)
			)
		)
		(zone
			(layer "F.Cu")
			(hatch none 0.5)
			(connect_pads
				(clearance 0)
			)
			(min_thickness 0.25)
			(keepout
				(tracks allowed)
				(vias not_allowed)
				(pads allowed)
				(copperpour not_allowed)
				(footprints allowed)
			)
			(placement
				(enabled no)
				(sheetname "")
			)
			(fill
				(thermal_gap 0.5)
				(thermal_bridge_width 0.5)
				(island_removal_mode 0)
			)
			(polygon
				(pts
					(arc
						(start 124.731018 -101.350064)
						(mid 123.969018 -101.350064)
						(end 124.731018 -101.350064)
					)
				)
			)
		)
		(zone
			(layer "F.Cu")
			(hatch none 0.5)
			(connect_pads
				(clearance 0)
			)
			(min_thickness 0.25)
			(keepout
				(tracks allowed)
				(vias not_allowed)
				(pads allowed)
				(copperpour not_allowed)
				(footprints allowed)
			)
			(placement
				(enabled no)
				(sheetname "")
			)
			(fill
				(thermal_gap 0.5)
				(thermal_bridge_width 0.5)
				(island_removal_mode 0)
			)
			(polygon
				(pts
					(arc
						(start 124.731018 -100.350066)
						(mid 123.969018 -100.350066)
						(end 124.731018 -100.350066)
					)
				)
			)
		)
		(zone
			(layer "F.Cu")
			(hatch none 0.5)
			(connect_pads
				(clearance 0)
			)
			(min_thickness 0.25)
			(keepout
				(tracks allowed)
				(vias not_allowed)
				(pads allowed)
				(copperpour not_allowed)
				(footprints allowed)
			)
			(placement
				(enabled no)
				(sheetname "")
			)
			(fill
				(thermal_gap 0.5)
				(thermal_bridge_width 0.5)
				(island_removal_mode 0)
			)
			(polygon
				(pts
					(arc
						(start 124.731018 -99.350068)
						(mid 123.969018 -99.350068)
						(end 124.731018 -99.350068)
					)
				)
			)
		)
		(zone
			(layer "F.Cu")
			(hatch none 0.5)
			(connect_pads
				(clearance 0)
			)
			(min_thickness 0.25)
			(keepout
				(tracks allowed)
				(vias not_allowed)
				(pads allowed)
				(copperpour not_allowed)
				(footprints allowed)
			)
			(placement
				(enabled no)
				(sheetname "")
			)
			(fill
				(thermal_gap 0.5)
				(thermal_bridge_width 0.5)
				(island_removal_mode 0)
			)
			(polygon
				(pts
					(arc
						(start 124.731018 -98.35007)
						(mid 123.969018 -98.35007)
						(end 124.731018 -98.35007)
					)
				)
			)
		)
		(zone
			(layer "F.Cu")
			(hatch none 0.5)
			(connect_pads
				(clearance 0)
			)
			(min_thickness 0.25)
			(keepout
				(tracks allowed)
				(vias not_allowed)
				(pads allowed)
				(copperpour not_allowed)
				(footprints allowed)
			)
			(placement
				(enabled no)
				(sheetname "")
			)
			(fill
				(thermal_gap 0.5)
				(thermal_bridge_width 0.5)
				(island_removal_mode 0)
			)
			(polygon
				(pts
					(arc
						(start 124.731018 -97.350072)
						(mid 123.969018 -97.350072)
						(end 124.731018 -97.350072)
					)
				)
			)
		)
		(zone
			(layer "F.Cu")
			(hatch none 0.5)
			(connect_pads
				(clearance 0)
			)
			(min_thickness 0.25)
			(keepout
				(tracks allowed)
				(vias not_allowed)
				(pads allowed)
				(copperpour not_allowed)
				(footprints allowed)
			)
			(placement
				(enabled no)
				(sheetname "")
			)
			(fill
				(thermal_gap 0.5)
				(thermal_bridge_width 0.5)
				(island_removal_mode 0)
			)
			(polygon
				(pts
					(arc
						(start 124.731018 -96.350074)
						(mid 123.969018 -96.350074)
						(end 124.731018 -96.350074)
					)
				)
			)
		)
		(zone
			(layer "F.Cu")
			(hatch none 0.5)
			(connect_pads
				(clearance 0)
			)
			(min_thickness 0.25)
			(keepout
				(tracks allowed)
				(vias not_allowed)
				(pads allowed)
				(copperpour not_allowed)
				(footprints allowed)
			)
			(placement
				(enabled no)
				(sheetname "")
			)
			(fill
				(thermal_gap 0.5)
				(thermal_bridge_width 0.5)
				(island_removal_mode 0)
			)
			(polygon
				(pts
					(arc
						(start 124.731018 -95.350076)
						(mid 123.969018 -95.350076)
						(end 124.731018 -95.350076)
					)
				)
			)
		)
		(zone
			(layer "F.Cu")
			(hatch none 0.5)
			(connect_pads
				(clearance 0)
			)
			(min_thickness 0.25)
			(keepout
				(tracks allowed)
				(vias not_allowed)
				(pads allowed)
				(copperpour not_allowed)
				(footprints allowed)
			)
			(placement
				(enabled no)
				(sheetname "")
			)
			(fill
				(thermal_gap 0.5)
				(thermal_bridge_width 0.5)
				(island_removal_mode 0)
			)
			(polygon
				(pts
					(arc
						(start 124.731018 -94.349824)
						(mid 123.969018 -94.349824)
						(end 124.731018 -94.349824)
					)
				)
			)
		)
		(zone
			(layer "F.Cu")
			(hatch none 0.5)
			(connect_pads
				(clearance 0)
			)
			(min_thickness 0.25)
			(keepout
				(tracks allowed)
				(vias not_allowed)
				(pads allowed)
				(copperpour not_allowed)
				(footprints allowed)
			)
			(placement
				(enabled no)
				(sheetname "")
			)
			(fill
				(thermal_gap 0.5)
				(thermal_bridge_width 0.5)
				(island_removal_mode 0)
			)
			(polygon
				(pts
					(arc
						(start 124.731018 -93.349826)
						(mid 123.969018 -93.349826)
						(end 124.731018 -93.349826)
					)
				)
			)
		)
		(zone
			(layer "F.Cu")
			(hatch none 0.5)
			(connect_pads
				(clearance 0)
			)
			(min_thickness 0.25)
			(keepout
				(tracks allowed)
				(vias not_allowed)
				(pads allowed)
				(copperpour not_allowed)
				(footprints allowed)
			)
			(placement
				(enabled no)
				(sheetname "")
			)
			(fill
				(thermal_gap 0.5)
				(thermal_bridge_width 0.5)
				(island_removal_mode 0)
			)
			(polygon
				(pts
					(arc
						(start 124.731018 -92.349828)
						(mid 123.969018 -92.349828)
						(end 124.731018 -92.349828)
					)
				)
			)
		)
		(zone
			(layer "F.Cu")
			(hatch none 0.5)
			(connect_pads
				(clearance 0)
			)
			(min_thickness 0.25)
			(keepout
				(tracks allowed)
				(vias not_allowed)
				(pads allowed)
				(copperpour not_allowed)
				(footprints allowed)
			)
			(placement
				(enabled no)
				(sheetname "")
			)
			(fill
				(thermal_gap 0.5)
				(thermal_bridge_width 0.5)
				(island_removal_mode 0)
			)
			(polygon
				(pts
					(arc
						(start 124.731018 -91.34983)
						(mid 123.969018 -91.34983)
						(end 124.731018 -91.34983)
					)
				)
			)
		)
		(zone
			(layer "F.Cu")
			(hatch none 0.5)
			(connect_pads
				(clearance 0)
			)
			(min_thickness 0.25)
			(keepout
				(tracks allowed)
				(vias not_allowed)
				(pads allowed)
				(copperpour not_allowed)
				(footprints allowed)
			)
			(placement
				(enabled no)
				(sheetname "")
			)
			(fill
				(thermal_gap 0.5)
				(thermal_bridge_width 0.5)
				(island_removal_mode 0)
			)
			(polygon
				(pts
					(arc
						(start 124.731018 -90.349832)
						(mid 123.969018 -90.349832)
						(end 124.731018 -90.349832)
					)
				)
			)
		)
		(zone
			(layer "F.Cu")
			(hatch none 0.5)
			(connect_pads
				(clearance 0)
			)
			(min_thickness 0.25)
			(keepout
				(tracks allowed)
				(vias not_allowed)
				(pads allowed)
				(copperpour not_allowed)
				(footprints allowed)
			)
			(placement
				(enabled no)
				(sheetname "")
			)
			(fill
				(thermal_gap 0.5)
				(thermal_bridge_width 0.5)
				(island_removal_mode 0)
			)
			(polygon
				(pts
					(arc
						(start 124.731018 -89.349834)
						(mid 123.969018 -89.349834)
						(end 124.731018 -89.349834)
					)
				)
			)
		)
		(zone
			(layer "F.Cu")
			(hatch none 0.5)
			(connect_pads
				(clearance 0)
			)
			(min_thickness 0.25)
			(keepout
				(tracks allowed)
				(vias not_allowed)
				(pads allowed)
				(copperpour not_allowed)
				(footprints allowed)
			)
			(placement
				(enabled no)
				(sheetname "")
			)
			(fill
				(thermal_gap 0.5)
				(thermal_bridge_width 0.5)
				(island_removal_mode 0)
			)
			(polygon
				(pts
					(arc
						(start 124.731018 -88.349836)
						(mid 123.969018 -88.349836)
						(end 124.731018 -88.349836)
					)
				)
			)
		)
		(zone
			(layer "F.Cu")
			(hatch none 0.5)
			(connect_pads
				(clearance 0)
			)
			(min_thickness 0.25)
			(keepout
				(tracks allowed)
				(vias not_allowed)
				(pads allowed)
				(copperpour not_allowed)
				(footprints allowed)
			)
			(placement
				(enabled no)
				(sheetname "")
			)
			(fill
				(thermal_gap 0.5)
				(thermal_bridge_width 0.5)
				(island_removal_mode 0)
			)
			(polygon
				(pts
					(arc
						(start 124.731018 -87.349838)
						(mid 123.969018 -87.349838)
						(end 124.731018 -87.349838)
					)
				)
			)
		)
		(zone
			(layer "F.Cu")
			(hatch none 0.5)
			(connect_pads
				(clearance 0)
			)
			(min_thickness 0.25)
			(keepout
				(tracks allowed)
				(vias not_allowed)
				(pads allowed)
				(copperpour not_allowed)
				(footprints allowed)
			)
			(placement
				(enabled no)
				(sheetname "")
			)
			(fill
				(thermal_gap 0.5)
				(thermal_bridge_width 0.5)
				(island_removal_mode 0)
			)
			(polygon
				(pts
					(arc
						(start 124.731018 -86.34984)
						(mid 123.969018 -86.34984)
						(end 124.731018 -86.34984)
					)
				)
			)
		)
		(zone
			(layer "F.Cu")
			(hatch none 0.5)
			(connect_pads
				(clearance 0)
			)
			(min_thickness 0.25)
			(keepout
				(tracks allowed)
				(vias not_allowed)
				(pads allowed)
				(copperpour not_allowed)
				(footprints allowed)
			)
			(placement
				(enabled no)
				(sheetname "")
			)
			(fill
				(thermal_gap 0.5)
				(thermal_bridge_width 0.5)
				(island_removal_mode 0)
			)
			(polygon
				(pts
					(arc
						(start 124.731018 -85.349842)
						(mid 123.969018 -85.349842)
						(end 124.731018 -85.349842)
					)
				)
			)
		)
		(zone
			(layer "F.Cu")
			(hatch none 0.5)
			(connect_pads
				(clearance 0)
			)
			(min_thickness 0.25)
			(keepout
				(tracks allowed)
				(vias not_allowed)
				(pads allowed)
				(copperpour not_allowed)
				(footprints allowed)
			)
			(placement
				(enabled no)
				(sheetname "")
			)
			(fill
				(thermal_gap 0.5)
				(thermal_bridge_width 0.5)
				(island_removal_mode 0)
			)
			(polygon
				(pts
					(arc
						(start 124.731018 -84.349844)
						(mid 123.969018 -84.349844)
						(end 124.731018 -84.349844)
					)
				)
			)
		)
		(zone
			(layer "F.Cu")
			(hatch none 0.5)
			(connect_pads
				(clearance 0)
			)
			(min_thickness 0.25)
			(keepout
				(tracks allowed)
				(vias not_allowed)
				(pads allowed)
				(copperpour not_allowed)
				(footprints allowed)
			)
			(placement
				(enabled no)
				(sheetname "")
			)
			(fill
				(thermal_gap 0.5)
				(thermal_bridge_width 0.5)
				(island_removal_mode 0)
			)
			(polygon
				(pts
					(arc
						(start 124.731018 -83.349846)
						(mid 123.969018 -83.349846)
						(end 124.731018 -83.349846)
					)
				)
			)
		)
		(zone
			(layer "F.Cu")
			(hatch none 0.5)
			(connect_pads
				(clearance 0)
			)
			(min_thickness 0.25)
			(keepout
				(tracks allowed)
				(vias not_allowed)
				(pads allowed)
				(copperpour not_allowed)
				(footprints allowed)
			)
			(placement
				(enabled no)
				(sheetname "")
			)
			(fill
				(thermal_gap 0.5)
				(thermal_bridge_width 0.5)
				(island_removal_mode 0)
			)
			(polygon
				(pts
					(arc
						(start 124.731018 -82.349848)
						(mid 123.969018 -82.349848)
						(end 124.731018 -82.349848)
					)
				)
			)
		)
		(zone
			(layer "F.Cu")
			(hatch none 0.5)
			(connect_pads
				(clearance 0)
			)
			(min_thickness 0.25)
			(keepout
				(tracks allowed)
				(vias not_allowed)
				(pads allowed)
				(copperpour not_allowed)
				(footprints allowed)
			)
			(placement
				(enabled no)
				(sheetname "")
			)
			(fill
				(thermal_gap 0.5)
				(thermal_bridge_width 0.5)
				(island_removal_mode 0)
			)
			(polygon
				(pts
					(arc
						(start 125.731016 -104.350058)
						(mid 124.969016 -104.350058)
						(end 125.731016 -104.350058)
					)
				)
			)
		)
		(zone
			(layer "F.Cu")
			(hatch none 0.5)
			(connect_pads
				(clearance 0)
			)
			(min_thickness 0.25)
			(keepout
				(tracks allowed)
				(vias not_allowed)
				(pads allowed)
				(copperpour not_allowed)
				(footprints allowed)
			)
			(placement
				(enabled no)
				(sheetname "")
			)
			(fill
				(thermal_gap 0.5)
				(thermal_bridge_width 0.5)
				(island_removal_mode 0)
			)
			(polygon
				(pts
					(arc
						(start 125.731016 -103.35006)
						(mid 124.969016 -103.35006)
						(end 125.731016 -103.35006)
					)
				)
			)
		)
		(zone
			(layer "F.Cu")
			(hatch none 0.5)
			(connect_pads
				(clearance 0)
			)
			(min_thickness 0.25)
			(keepout
				(tracks allowed)
				(vias not_allowed)
				(pads allowed)
				(copperpour not_allowed)
				(footprints allowed)
			)
			(placement
				(enabled no)
				(sheetname "")
			)
			(fill
				(thermal_gap 0.5)
				(thermal_bridge_width 0.5)
				(island_removal_mode 0)
			)
			(polygon
				(pts
					(arc
						(start 125.731016 -102.350062)
						(mid 124.969016 -102.350062)
						(end 125.731016 -102.350062)
					)
				)
			)
		)
		(zone
			(layer "F.Cu")
			(hatch none 0.5)
			(connect_pads
				(clearance 0)
			)
			(min_thickness 0.25)
			(keepout
				(tracks allowed)
				(vias not_allowed)
				(pads allowed)
				(copperpour not_allowed)
				(footprints allowed)
			)
			(placement
				(enabled no)
				(sheetname "")
			)
			(fill
				(thermal_gap 0.5)
				(thermal_bridge_width 0.5)
				(island_removal_mode 0)
			)
			(polygon
				(pts
					(arc
						(start 125.731016 -101.350064)
						(mid 124.969016 -101.350064)
						(end 125.731016 -101.350064)
					)
				)
			)
		)
		(zone
			(layer "F.Cu")
			(hatch none 0.5)
			(connect_pads
				(clearance 0)
			)
			(min_thickness 0.25)
			(keepout
				(tracks allowed)
				(vias not_allowed)
				(pads allowed)
				(copperpour not_allowed)
				(footprints allowed)
			)
			(placement
				(enabled no)
				(sheetname "")
			)
			(fill
				(thermal_gap 0.5)
				(thermal_bridge_width 0.5)
				(island_removal_mode 0)
			)
			(polygon
				(pts
					(arc
						(start 125.731016 -100.350066)
						(mid 124.969016 -100.350066)
						(end 125.731016 -100.350066)
					)
				)
			)
		)
		(zone
			(layer "F.Cu")
			(hatch none 0.5)
			(connect_pads
				(clearance 0)
			)
			(min_thickness 0.25)
			(keepout
				(tracks allowed)
				(vias not_allowed)
				(pads allowed)
				(copperpour not_allowed)
				(footprints allowed)
			)
			(placement
				(enabled no)
				(sheetname "")
			)
			(fill
				(thermal_gap 0.5)
				(thermal_bridge_width 0.5)
				(island_removal_mode 0)
			)
			(polygon
				(pts
					(arc
						(start 125.731016 -99.350068)
						(mid 124.969016 -99.350068)
						(end 125.731016 -99.350068)
					)
				)
			)
		)
		(zone
			(layer "F.Cu")
			(hatch none 0.5)
			(connect_pads
				(clearance 0)
			)
			(min_thickness 0.25)
			(keepout
				(tracks allowed)
				(vias not_allowed)
				(pads allowed)
				(copperpour not_allowed)
				(footprints allowed)
			)
			(placement
				(enabled no)
				(sheetname "")
			)
			(fill
				(thermal_gap 0.5)
				(thermal_bridge_width 0.5)
				(island_removal_mode 0)
			)
			(polygon
				(pts
					(arc
						(start 125.731016 -98.35007)
						(mid 124.969016 -98.35007)
						(end 125.731016 -98.35007)
					)
				)
			)
		)
		(zone
			(layer "F.Cu")
			(hatch none 0.5)
			(connect_pads
				(clearance 0)
			)
			(min_thickness 0.25)
			(keepout
				(tracks allowed)
				(vias not_allowed)
				(pads allowed)
				(copperpour not_allowed)
				(footprints allowed)
			)
			(placement
				(enabled no)
				(sheetname "")
			)
			(fill
				(thermal_gap 0.5)
				(thermal_bridge_width 0.5)
				(island_removal_mode 0)
			)
			(polygon
				(pts
					(arc
						(start 125.731016 -97.350072)
						(mid 124.969016 -97.350072)
						(end 125.731016 -97.350072)
					)
				)
			)
		)
		(zone
			(layer "F.Cu")
			(hatch none 0.5)
			(connect_pads
				(clearance 0)
			)
			(min_thickness 0.25)
			(keepout
				(tracks allowed)
				(vias not_allowed)
				(pads allowed)
				(copperpour not_allowed)
				(footprints allowed)
			)
			(placement
				(enabled no)
				(sheetname "")
			)
			(fill
				(thermal_gap 0.5)
				(thermal_bridge_width 0.5)
				(island_removal_mode 0)
			)
			(polygon
				(pts
					(arc
						(start 125.731016 -96.350074)
						(mid 124.969016 -96.350074)
						(end 125.731016 -96.350074)
					)
				)
			)
		)
		(zone
			(layer "F.Cu")
			(hatch none 0.5)
			(connect_pads
				(clearance 0)
			)
			(min_thickness 0.25)
			(keepout
				(tracks allowed)
				(vias not_allowed)
				(pads allowed)
				(copperpour not_allowed)
				(footprints allowed)
			)
			(placement
				(enabled no)
				(sheetname "")
			)
			(fill
				(thermal_gap 0.5)
				(thermal_bridge_width 0.5)
				(island_removal_mode 0)
			)
			(polygon
				(pts
					(arc
						(start 125.731016 -95.350076)
						(mid 124.969016 -95.350076)
						(end 125.731016 -95.350076)
					)
				)
			)
		)
		(zone
			(layer "F.Cu")
			(hatch none 0.5)
			(connect_pads
				(clearance 0)
			)
			(min_thickness 0.25)
			(keepout
				(tracks allowed)
				(vias not_allowed)
				(pads allowed)
				(copperpour not_allowed)
				(footprints allowed)
			)
			(placement
				(enabled no)
				(sheetname "")
			)
			(fill
				(thermal_gap 0.5)
				(thermal_bridge_width 0.5)
				(island_removal_mode 0)
			)
			(polygon
				(pts
					(arc
						(start 125.731016 -94.349824)
						(mid 124.969016 -94.349824)
						(end 125.731016 -94.349824)
					)
				)
			)
		)
		(zone
			(layer "F.Cu")
			(hatch none 0.5)
			(connect_pads
				(clearance 0)
			)
			(min_thickness 0.25)
			(keepout
				(tracks allowed)
				(vias not_allowed)
				(pads allowed)
				(copperpour not_allowed)
				(footprints allowed)
			)
			(placement
				(enabled no)
				(sheetname "")
			)
			(fill
				(thermal_gap 0.5)
				(thermal_bridge_width 0.5)
				(island_removal_mode 0)
			)
			(polygon
				(pts
					(arc
						(start 125.731016 -93.349826)
						(mid 124.969016 -93.349826)
						(end 125.731016 -93.349826)
					)
				)
			)
		)
		(zone
			(layer "F.Cu")
			(hatch none 0.5)
			(connect_pads
				(clearance 0)
			)
			(min_thickness 0.25)
			(keepout
				(tracks allowed)
				(vias not_allowed)
				(pads allowed)
				(copperpour not_allowed)
				(footprints allowed)
			)
			(placement
				(enabled no)
				(sheetname "")
			)
			(fill
				(thermal_gap 0.5)
				(thermal_bridge_width 0.5)
				(island_removal_mode 0)
			)
			(polygon
				(pts
					(arc
						(start 125.731016 -92.349828)
						(mid 124.969016 -92.349828)
						(end 125.731016 -92.349828)
					)
				)
			)
		)
		(zone
			(layer "F.Cu")
			(hatch none 0.5)
			(connect_pads
				(clearance 0)
			)
			(min_thickness 0.25)
			(keepout
				(tracks allowed)
				(vias not_allowed)
				(pads allowed)
				(copperpour not_allowed)
				(footprints allowed)
			)
			(placement
				(enabled no)
				(sheetname "")
			)
			(fill
				(thermal_gap 0.5)
				(thermal_bridge_width 0.5)
				(island_removal_mode 0)
			)
			(polygon
				(pts
					(arc
						(start 125.731016 -91.34983)
						(mid 124.969016 -91.34983)
						(end 125.731016 -91.34983)
					)
				)
			)
		)
		(zone
			(layer "F.Cu")
			(hatch none 0.5)
			(connect_pads
				(clearance 0)
			)
			(min_thickness 0.25)
			(keepout
				(tracks allowed)
				(vias not_allowed)
				(pads allowed)
				(copperpour not_allowed)
				(footprints allowed)
			)
			(placement
				(enabled no)
				(sheetname "")
			)
			(fill
				(thermal_gap 0.5)
				(thermal_bridge_width 0.5)
				(island_removal_mode 0)
			)
			(polygon
				(pts
					(arc
						(start 125.731016 -90.349832)
						(mid 124.969016 -90.349832)
						(end 125.731016 -90.349832)
					)
				)
			)
		)
		(zone
			(layer "F.Cu")
			(hatch none 0.5)
			(connect_pads
				(clearance 0)
			)
			(min_thickness 0.25)
			(keepout
				(tracks allowed)
				(vias not_allowed)
				(pads allowed)
				(copperpour not_allowed)
				(footprints allowed)
			)
			(placement
				(enabled no)
				(sheetname "")
			)
			(fill
				(thermal_gap 0.5)
				(thermal_bridge_width 0.5)
				(island_removal_mode 0)
			)
			(polygon
				(pts
					(arc
						(start 125.731016 -89.349834)
						(mid 124.969016 -89.349834)
						(end 125.731016 -89.349834)
					)
				)
			)
		)
		(zone
			(layer "F.Cu")
			(hatch none 0.5)
			(connect_pads
				(clearance 0)
			)
			(min_thickness 0.25)
			(keepout
				(tracks allowed)
				(vias not_allowed)
				(pads allowed)
				(copperpour not_allowed)
				(footprints allowed)
			)
			(placement
				(enabled no)
				(sheetname "")
			)
			(fill
				(thermal_gap 0.5)
				(thermal_bridge_width 0.5)
				(island_removal_mode 0)
			)
			(polygon
				(pts
					(arc
						(start 125.731016 -88.349836)
						(mid 124.969016 -88.349836)
						(end 125.731016 -88.349836)
					)
				)
			)
		)
		(zone
			(layer "F.Cu")
			(hatch none 0.5)
			(connect_pads
				(clearance 0)
			)
			(min_thickness 0.25)
			(keepout
				(tracks allowed)
				(vias not_allowed)
				(pads allowed)
				(copperpour not_allowed)
				(footprints allowed)
			)
			(placement
				(enabled no)
				(sheetname "")
			)
			(fill
				(thermal_gap 0.5)
				(thermal_bridge_width 0.5)
				(island_removal_mode 0)
			)
			(polygon
				(pts
					(arc
						(start 125.731016 -87.349838)
						(mid 124.969016 -87.349838)
						(end 125.731016 -87.349838)
					)
				)
			)
		)
		(zone
			(layer "F.Cu")
			(hatch none 0.5)
			(connect_pads
				(clearance 0)
			)
			(min_thickness 0.25)
			(keepout
				(tracks allowed)
				(vias not_allowed)
				(pads allowed)
				(copperpour not_allowed)
				(footprints allowed)
			)
			(placement
				(enabled no)
				(sheetname "")
			)
			(fill
				(thermal_gap 0.5)
				(thermal_bridge_width 0.5)
				(island_removal_mode 0)
			)
			(polygon
				(pts
					(arc
						(start 125.731016 -86.34984)
						(mid 124.969016 -86.34984)
						(end 125.731016 -86.34984)
					)
				)
			)
		)
		(zone
			(layer "F.Cu")
			(hatch none 0.5)
			(connect_pads
				(clearance 0)
			)
			(min_thickness 0.25)
			(keepout
				(tracks allowed)
				(vias not_allowed)
				(pads allowed)
				(copperpour not_allowed)
				(footprints allowed)
			)
			(placement
				(enabled no)
				(sheetname "")
			)
			(fill
				(thermal_gap 0.5)
				(thermal_bridge_width 0.5)
				(island_removal_mode 0)
			)
			(polygon
				(pts
					(arc
						(start 125.731016 -85.349842)
						(mid 124.969016 -85.349842)
						(end 125.731016 -85.349842)
					)
				)
			)
		)
		(zone
			(layer "F.Cu")
			(hatch none 0.5)
			(connect_pads
				(clearance 0)
			)
			(min_thickness 0.25)
			(keepout
				(tracks allowed)
				(vias not_allowed)
				(pads allowed)
				(copperpour not_allowed)
				(footprints allowed)
			)
			(placement
				(enabled no)
				(sheetname "")
			)
			(fill
				(thermal_gap 0.5)
				(thermal_bridge_width 0.5)
				(island_removal_mode 0)
			)
			(polygon
				(pts
					(arc
						(start 126.731014 -104.350058)
						(mid 125.969014 -104.350058)
						(end 126.731014 -104.350058)
					)
				)
			)
		)
		(zone
			(layer "F.Cu")
			(hatch none 0.5)
			(connect_pads
				(clearance 0)
			)
			(min_thickness 0.25)
			(keepout
				(tracks allowed)
				(vias not_allowed)
				(pads allowed)
				(copperpour not_allowed)
				(footprints allowed)
			)
			(placement
				(enabled no)
				(sheetname "")
			)
			(fill
				(thermal_gap 0.5)
				(thermal_bridge_width 0.5)
				(island_removal_mode 0)
			)
			(polygon
				(pts
					(arc
						(start 126.731014 -103.35006)
						(mid 125.969014 -103.35006)
						(end 126.731014 -103.35006)
					)
				)
			)
		)
		(zone
			(layer "F.Cu")
			(hatch none 0.5)
			(connect_pads
				(clearance 0)
			)
			(min_thickness 0.25)
			(keepout
				(tracks allowed)
				(vias not_allowed)
				(pads allowed)
				(copperpour not_allowed)
				(footprints allowed)
			)
			(placement
				(enabled no)
				(sheetname "")
			)
			(fill
				(thermal_gap 0.5)
				(thermal_bridge_width 0.5)
				(island_removal_mode 0)
			)
			(polygon
				(pts
					(arc
						(start 126.731014 -102.350062)
						(mid 125.969014 -102.350062)
						(end 126.731014 -102.350062)
					)
				)
			)
		)
		(zone
			(layer "F.Cu")
			(hatch none 0.5)
			(connect_pads
				(clearance 0)
			)
			(min_thickness 0.25)
			(keepout
				(tracks allowed)
				(vias not_allowed)
				(pads allowed)
				(copperpour not_allowed)
				(footprints allowed)
			)
			(placement
				(enabled no)
				(sheetname "")
			)
			(fill
				(thermal_gap 0.5)
				(thermal_bridge_width 0.5)
				(island_removal_mode 0)
			)
			(polygon
				(pts
					(arc
						(start 126.731014 -101.350064)
						(mid 125.969014 -101.350064)
						(end 126.731014 -101.350064)
					)
				)
			)
		)
		(zone
			(layer "F.Cu")
			(hatch none 0.5)
			(connect_pads
				(clearance 0)
			)
			(min_thickness 0.25)
			(keepout
				(tracks allowed)
				(vias not_allowed)
				(pads allowed)
				(copperpour not_allowed)
				(footprints allowed)
			)
			(placement
				(enabled no)
				(sheetname "")
			)
			(fill
				(thermal_gap 0.5)
				(thermal_bridge_width 0.5)
				(island_removal_mode 0)
			)
			(polygon
				(pts
					(arc
						(start 126.731014 -100.350066)
						(mid 125.969014 -100.350066)
						(end 126.731014 -100.350066)
					)
				)
			)
		)
		(zone
			(layer "F.Cu")
			(hatch none 0.5)
			(connect_pads
				(clearance 0)
			)
			(min_thickness 0.25)
			(keepout
				(tracks allowed)
				(vias not_allowed)
				(pads allowed)
				(copperpour not_allowed)
				(footprints allowed)
			)
			(placement
				(enabled no)
				(sheetname "")
			)
			(fill
				(thermal_gap 0.5)
				(thermal_bridge_width 0.5)
				(island_removal_mode 0)
			)
			(polygon
				(pts
					(arc
						(start 126.731014 -99.350068)
						(mid 125.969014 -99.350068)
						(end 126.731014 -99.350068)
					)
				)
			)
		)
		(zone
			(layer "F.Cu")
			(hatch none 0.5)
			(connect_pads
				(clearance 0)
			)
			(min_thickness 0.25)
			(keepout
				(tracks allowed)
				(vias not_allowed)
				(pads allowed)
				(copperpour not_allowed)
				(footprints allowed)
			)
			(placement
				(enabled no)
				(sheetname "")
			)
			(fill
				(thermal_gap 0.5)
				(thermal_bridge_width 0.5)
				(island_removal_mode 0)
			)
			(polygon
				(pts
					(arc
						(start 126.731014 -98.35007)
						(mid 125.969014 -98.35007)
						(end 126.731014 -98.35007)
					)
				)
			)
		)
		(zone
			(layer "F.Cu")
			(hatch none 0.5)
			(connect_pads
				(clearance 0)
			)
			(min_thickness 0.25)
			(keepout
				(tracks allowed)
				(vias not_allowed)
				(pads allowed)
				(copperpour not_allowed)
				(footprints allowed)
			)
			(placement
				(enabled no)
				(sheetname "")
			)
			(fill
				(thermal_gap 0.5)
				(thermal_bridge_width 0.5)
				(island_removal_mode 0)
			)
			(polygon
				(pts
					(arc
						(start 126.731014 -97.350072)
						(mid 125.969014 -97.350072)
						(end 126.731014 -97.350072)
					)
				)
			)
		)
		(zone
			(layer "F.Cu")
			(hatch none 0.5)
			(connect_pads
				(clearance 0)
			)
			(min_thickness 0.25)
			(keepout
				(tracks allowed)
				(vias not_allowed)
				(pads allowed)
				(copperpour not_allowed)
				(footprints allowed)
			)
			(placement
				(enabled no)
				(sheetname "")
			)
			(fill
				(thermal_gap 0.5)
				(thermal_bridge_width 0.5)
				(island_removal_mode 0)
			)
			(polygon
				(pts
					(arc
						(start 126.731014 -96.350074)
						(mid 125.969014 -96.350074)
						(end 126.731014 -96.350074)
					)
				)
			)
		)
		(zone
			(layer "F.Cu")
			(hatch none 0.5)
			(connect_pads
				(clearance 0)
			)
			(min_thickness 0.25)
			(keepout
				(tracks allowed)
				(vias not_allowed)
				(pads allowed)
				(copperpour not_allowed)
				(footprints allowed)
			)
			(placement
				(enabled no)
				(sheetname "")
			)
			(fill
				(thermal_gap 0.5)
				(thermal_bridge_width 0.5)
				(island_removal_mode 0)
			)
			(polygon
				(pts
					(arc
						(start 126.731014 -95.350076)
						(mid 125.969014 -95.350076)
						(end 126.731014 -95.350076)
					)
				)
			)
		)
		(zone
			(layer "F.Cu")
			(hatch none 0.5)
			(connect_pads
				(clearance 0)
			)
			(min_thickness 0.25)
			(keepout
				(tracks allowed)
				(vias not_allowed)
				(pads allowed)
				(copperpour not_allowed)
				(footprints allowed)
			)
			(placement
				(enabled no)
				(sheetname "")
			)
			(fill
				(thermal_gap 0.5)
				(thermal_bridge_width 0.5)
				(island_removal_mode 0)
			)
			(polygon
				(pts
					(arc
						(start 126.731014 -94.349824)
						(mid 125.969014 -94.349824)
						(end 126.731014 -94.349824)
					)
				)
			)
		)
		(zone
			(layer "F.Cu")
			(hatch none 0.5)
			(connect_pads
				(clearance 0)
			)
			(min_thickness 0.25)
			(keepout
				(tracks allowed)
				(vias not_allowed)
				(pads allowed)
				(copperpour not_allowed)
				(footprints allowed)
			)
			(placement
				(enabled no)
				(sheetname "")
			)
			(fill
				(thermal_gap 0.5)
				(thermal_bridge_width 0.5)
				(island_removal_mode 0)
			)
			(polygon
				(pts
					(arc
						(start 126.731014 -93.349826)
						(mid 125.969014 -93.349826)
						(end 126.731014 -93.349826)
					)
				)
			)
		)
		(zone
			(layer "F.Cu")
			(hatch none 0.5)
			(connect_pads
				(clearance 0)
			)
			(min_thickness 0.25)
			(keepout
				(tracks allowed)
				(vias not_allowed)
				(pads allowed)
				(copperpour not_allowed)
				(footprints allowed)
			)
			(placement
				(enabled no)
				(sheetname "")
			)
			(fill
				(thermal_gap 0.5)
				(thermal_bridge_width 0.5)
				(island_removal_mode 0)
			)
			(polygon
				(pts
					(arc
						(start 126.731014 -92.349828)
						(mid 125.969014 -92.349828)
						(end 126.731014 -92.349828)
					)
				)
			)
		)
		(zone
			(layer "F.Cu")
			(hatch none 0.5)
			(connect_pads
				(clearance 0)
			)
			(min_thickness 0.25)
			(keepout
				(tracks allowed)
				(vias not_allowed)
				(pads allowed)
				(copperpour not_allowed)
				(footprints allowed)
			)
			(placement
				(enabled no)
				(sheetname "")
			)
			(fill
				(thermal_gap 0.5)
				(thermal_bridge_width 0.5)
				(island_removal_mode 0)
			)
			(polygon
				(pts
					(arc
						(start 126.731014 -91.34983)
						(mid 125.969014 -91.34983)
						(end 126.731014 -91.34983)
					)
				)
			)
		)
		(zone
			(layer "F.Cu")
			(hatch none 0.5)
			(connect_pads
				(clearance 0)
			)
			(min_thickness 0.25)
			(keepout
				(tracks allowed)
				(vias not_allowed)
				(pads allowed)
				(copperpour not_allowed)
				(footprints allowed)
			)
			(placement
				(enabled no)
				(sheetname "")
			)
			(fill
				(thermal_gap 0.5)
				(thermal_bridge_width 0.5)
				(island_removal_mode 0)
			)
			(polygon
				(pts
					(arc
						(start 126.731014 -90.349832)
						(mid 125.969014 -90.349832)
						(end 126.731014 -90.349832)
					)
				)
			)
		)
		(zone
			(layer "F.Cu")
			(hatch none 0.5)
			(connect_pads
				(clearance 0)
			)
			(min_thickness 0.25)
			(keepout
				(tracks allowed)
				(vias not_allowed)
				(pads allowed)
				(copperpour not_allowed)
				(footprints allowed)
			)
			(placement
				(enabled no)
				(sheetname "")
			)
			(fill
				(thermal_gap 0.5)
				(thermal_bridge_width 0.5)
				(island_removal_mode 0)
			)
			(polygon
				(pts
					(arc
						(start 126.731014 -89.349834)
						(mid 125.969014 -89.349834)
						(end 126.731014 -89.349834)
					)
				)
			)
		)
		(zone
			(layer "F.Cu")
			(hatch none 0.5)
			(connect_pads
				(clearance 0)
			)
			(min_thickness 0.25)
			(keepout
				(tracks allowed)
				(vias not_allowed)
				(pads allowed)
				(copperpour not_allowed)
				(footprints allowed)
			)
			(placement
				(enabled no)
				(sheetname "")
			)
			(fill
				(thermal_gap 0.5)
				(thermal_bridge_width 0.5)
				(island_removal_mode 0)
			)
			(polygon
				(pts
					(arc
						(start 126.731014 -88.349836)
						(mid 125.969014 -88.349836)
						(end 126.731014 -88.349836)
					)
				)
			)
		)
		(zone
			(layer "F.Cu")
			(hatch none 0.5)
			(connect_pads
				(clearance 0)
			)
			(min_thickness 0.25)
			(keepout
				(tracks allowed)
				(vias not_allowed)
				(pads allowed)
				(copperpour not_allowed)
				(footprints allowed)
			)
			(placement
				(enabled no)
				(sheetname "")
			)
			(fill
				(thermal_gap 0.5)
				(thermal_bridge_width 0.5)
				(island_removal_mode 0)
			)
			(polygon
				(pts
					(arc
						(start 126.731014 -87.349838)
						(mid 125.969014 -87.349838)
						(end 126.731014 -87.349838)
					)
				)
			)
		)
		(zone
			(layer "F.Cu")
			(hatch none 0.5)
			(connect_pads
				(clearance 0)
			)
			(min_thickness 0.25)
			(keepout
				(tracks allowed)
				(vias not_allowed)
				(pads allowed)
				(copperpour not_allowed)
				(footprints allowed)
			)
			(placement
				(enabled no)
				(sheetname "")
			)
			(fill
				(thermal_gap 0.5)
				(thermal_bridge_width 0.5)
				(island_removal_mode 0)
			)
			(polygon
				(pts
					(arc
						(start 126.731014 -86.34984)
						(mid 125.969014 -86.34984)
						(end 126.731014 -86.34984)
					)
				)
			)
		)
		(zone
			(layer "F.Cu")
			(hatch none 0.5)
			(connect_pads
				(clearance 0)
			)
			(min_thickness 0.25)
			(keepout
				(tracks allowed)
				(vias not_allowed)
				(pads allowed)
				(copperpour not_allowed)
				(footprints allowed)
			)
			(placement
				(enabled no)
				(sheetname "")
			)
			(fill
				(thermal_gap 0.5)
				(thermal_bridge_width 0.5)
				(island_removal_mode 0)
			)
			(polygon
				(pts
					(arc
						(start 126.731014 -85.349842)
						(mid 125.969014 -85.349842)
						(end 126.731014 -85.349842)
					)
				)
			)
		)
		(zone
			(layer "F.Cu")
			(hatch none 0.5)
			(connect_pads
				(clearance 0)
			)
			(min_thickness 0.25)
			(keepout
				(tracks allowed)
				(vias not_allowed)
				(pads allowed)
				(copperpour not_allowed)
				(footprints allowed)
			)
			(placement
				(enabled no)
				(sheetname "")
			)
			(fill
				(thermal_gap 0.5)
				(thermal_bridge_width 0.5)
				(island_removal_mode 0)
			)
			(polygon
				(pts
					(arc
						(start 127.731012 -104.350058)
						(mid 126.969012 -104.350058)
						(end 127.731012 -104.350058)
					)
				)
			)
		)
		(zone
			(layer "F.Cu")
			(hatch none 0.5)
			(connect_pads
				(clearance 0)
			)
			(min_thickness 0.25)
			(keepout
				(tracks allowed)
				(vias not_allowed)
				(pads allowed)
				(copperpour not_allowed)
				(footprints allowed)
			)
			(placement
				(enabled no)
				(sheetname "")
			)
			(fill
				(thermal_gap 0.5)
				(thermal_bridge_width 0.5)
				(island_removal_mode 0)
			)
			(polygon
				(pts
					(arc
						(start 127.731012 -103.35006)
						(mid 126.969012 -103.35006)
						(end 127.731012 -103.35006)
					)
				)
			)
		)
		(zone
			(layer "F.Cu")
			(hatch none 0.5)
			(connect_pads
				(clearance 0)
			)
			(min_thickness 0.25)
			(keepout
				(tracks allowed)
				(vias not_allowed)
				(pads allowed)
				(copperpour not_allowed)
				(footprints allowed)
			)
			(placement
				(enabled no)
				(sheetname "")
			)
			(fill
				(thermal_gap 0.5)
				(thermal_bridge_width 0.5)
				(island_removal_mode 0)
			)
			(polygon
				(pts
					(arc
						(start 127.731012 -102.350062)
						(mid 126.969012 -102.350062)
						(end 127.731012 -102.350062)
					)
				)
			)
		)
		(zone
			(layer "F.Cu")
			(hatch none 0.5)
			(connect_pads
				(clearance 0)
			)
			(min_thickness 0.25)
			(keepout
				(tracks allowed)
				(vias not_allowed)
				(pads allowed)
				(copperpour not_allowed)
				(footprints allowed)
			)
			(placement
				(enabled no)
				(sheetname "")
			)
			(fill
				(thermal_gap 0.5)
				(thermal_bridge_width 0.5)
				(island_removal_mode 0)
			)
			(polygon
				(pts
					(arc
						(start 127.731012 -101.350064)
						(mid 126.969012 -101.350064)
						(end 127.731012 -101.350064)
					)
				)
			)
		)
		(zone
			(layer "F.Cu")
			(hatch none 0.5)
			(connect_pads
				(clearance 0)
			)
			(min_thickness 0.25)
			(keepout
				(tracks allowed)
				(vias not_allowed)
				(pads allowed)
				(copperpour not_allowed)
				(footprints allowed)
			)
			(placement
				(enabled no)
				(sheetname "")
			)
			(fill
				(thermal_gap 0.5)
				(thermal_bridge_width 0.5)
				(island_removal_mode 0)
			)
			(polygon
				(pts
					(arc
						(start 127.731012 -100.350066)
						(mid 126.969012 -100.350066)
						(end 127.731012 -100.350066)
					)
				)
			)
		)
		(zone
			(layer "F.Cu")
			(hatch none 0.5)
			(connect_pads
				(clearance 0)
			)
			(min_thickness 0.25)
			(keepout
				(tracks allowed)
				(vias not_allowed)
				(pads allowed)
				(copperpour not_allowed)
				(footprints allowed)
			)
			(placement
				(enabled no)
				(sheetname "")
			)
			(fill
				(thermal_gap 0.5)
				(thermal_bridge_width 0.5)
				(island_removal_mode 0)
			)
			(polygon
				(pts
					(arc
						(start 127.731012 -99.350068)
						(mid 126.969012 -99.350068)
						(end 127.731012 -99.350068)
					)
				)
			)
		)
		(zone
			(layer "F.Cu")
			(hatch none 0.5)
			(connect_pads
				(clearance 0)
			)
			(min_thickness 0.25)
			(keepout
				(tracks allowed)
				(vias not_allowed)
				(pads allowed)
				(copperpour not_allowed)
				(footprints allowed)
			)
			(placement
				(enabled no)
				(sheetname "")
			)
			(fill
				(thermal_gap 0.5)
				(thermal_bridge_width 0.5)
				(island_removal_mode 0)
			)
			(polygon
				(pts
					(arc
						(start 127.731012 -98.35007)
						(mid 126.969012 -98.35007)
						(end 127.731012 -98.35007)
					)
				)
			)
		)
		(zone
			(layer "F.Cu")
			(hatch none 0.5)
			(connect_pads
				(clearance 0)
			)
			(min_thickness 0.25)
			(keepout
				(tracks allowed)
				(vias not_allowed)
				(pads allowed)
				(copperpour not_allowed)
				(footprints allowed)
			)
			(placement
				(enabled no)
				(sheetname "")
			)
			(fill
				(thermal_gap 0.5)
				(thermal_bridge_width 0.5)
				(island_removal_mode 0)
			)
			(polygon
				(pts
					(arc
						(start 127.731012 -97.350072)
						(mid 126.969012 -97.350072)
						(end 127.731012 -97.350072)
					)
				)
			)
		)
		(zone
			(layer "F.Cu")
			(hatch none 0.5)
			(connect_pads
				(clearance 0)
			)
			(min_thickness 0.25)
			(keepout
				(tracks allowed)
				(vias not_allowed)
				(pads allowed)
				(copperpour not_allowed)
				(footprints allowed)
			)
			(placement
				(enabled no)
				(sheetname "")
			)
			(fill
				(thermal_gap 0.5)
				(thermal_bridge_width 0.5)
				(island_removal_mode 0)
			)
			(polygon
				(pts
					(arc
						(start 127.731012 -96.350074)
						(mid 126.969012 -96.350074)
						(end 127.731012 -96.350074)
					)
				)
			)
		)
		(zone
			(layer "F.Cu")
			(hatch none 0.5)
			(connect_pads
				(clearance 0)
			)
			(min_thickness 0.25)
			(keepout
				(tracks allowed)
				(vias not_allowed)
				(pads allowed)
				(copperpour not_allowed)
				(footprints allowed)
			)
			(placement
				(enabled no)
				(sheetname "")
			)
			(fill
				(thermal_gap 0.5)
				(thermal_bridge_width 0.5)
				(island_removal_mode 0)
			)
			(polygon
				(pts
					(arc
						(start 127.731012 -95.350076)
						(mid 126.969012 -95.350076)
						(end 127.731012 -95.350076)
					)
				)
			)
		)
		(zone
			(layer "F.Cu")
			(hatch none 0.5)
			(connect_pads
				(clearance 0)
			)
			(min_thickness 0.25)
			(keepout
				(tracks allowed)
				(vias not_allowed)
				(pads allowed)
				(copperpour not_allowed)
				(footprints allowed)
			)
			(placement
				(enabled no)
				(sheetname "")
			)
			(fill
				(thermal_gap 0.5)
				(thermal_bridge_width 0.5)
				(island_removal_mode 0)
			)
			(polygon
				(pts
					(arc
						(start 127.731012 -94.349824)
						(mid 126.969012 -94.349824)
						(end 127.731012 -94.349824)
					)
				)
			)
		)
		(zone
			(layer "F.Cu")
			(hatch none 0.5)
			(connect_pads
				(clearance 0)
			)
			(min_thickness 0.25)
			(keepout
				(tracks allowed)
				(vias not_allowed)
				(pads allowed)
				(copperpour not_allowed)
				(footprints allowed)
			)
			(placement
				(enabled no)
				(sheetname "")
			)
			(fill
				(thermal_gap 0.5)
				(thermal_bridge_width 0.5)
				(island_removal_mode 0)
			)
			(polygon
				(pts
					(arc
						(start 127.731012 -93.349826)
						(mid 126.969012 -93.349826)
						(end 127.731012 -93.349826)
					)
				)
			)
		)
		(zone
			(layer "F.Cu")
			(hatch none 0.5)
			(connect_pads
				(clearance 0)
			)
			(min_thickness 0.25)
			(keepout
				(tracks allowed)
				(vias not_allowed)
				(pads allowed)
				(copperpour not_allowed)
				(footprints allowed)
			)
			(placement
				(enabled no)
				(sheetname "")
			)
			(fill
				(thermal_gap 0.5)
				(thermal_bridge_width 0.5)
				(island_removal_mode 0)
			)
			(polygon
				(pts
					(arc
						(start 127.731012 -92.349828)
						(mid 126.969012 -92.349828)
						(end 127.731012 -92.349828)
					)
				)
			)
		)
		(zone
			(layer "F.Cu")
			(hatch none 0.5)
			(connect_pads
				(clearance 0)
			)
			(min_thickness 0.25)
			(keepout
				(tracks allowed)
				(vias not_allowed)
				(pads allowed)
				(copperpour not_allowed)
				(footprints allowed)
			)
			(placement
				(enabled no)
				(sheetname "")
			)
			(fill
				(thermal_gap 0.5)
				(thermal_bridge_width 0.5)
				(island_removal_mode 0)
			)
			(polygon
				(pts
					(arc
						(start 127.731012 -91.34983)
						(mid 126.969012 -91.34983)
						(end 127.731012 -91.34983)
					)
				)
			)
		)
		(zone
			(layer "F.Cu")
			(hatch none 0.5)
			(connect_pads
				(clearance 0)
			)
			(min_thickness 0.25)
			(keepout
				(tracks allowed)
				(vias not_allowed)
				(pads allowed)
				(copperpour not_allowed)
				(footprints allowed)
			)
			(placement
				(enabled no)
				(sheetname "")
			)
			(fill
				(thermal_gap 0.5)
				(thermal_bridge_width 0.5)
				(island_removal_mode 0)
			)
			(polygon
				(pts
					(arc
						(start 127.731012 -90.349832)
						(mid 126.969012 -90.349832)
						(end 127.731012 -90.349832)
					)
				)
			)
		)
		(zone
			(layer "F.Cu")
			(hatch none 0.5)
			(connect_pads
				(clearance 0)
			)
			(min_thickness 0.25)
			(keepout
				(tracks allowed)
				(vias not_allowed)
				(pads allowed)
				(copperpour not_allowed)
				(footprints allowed)
			)
			(placement
				(enabled no)
				(sheetname "")
			)
			(fill
				(thermal_gap 0.5)
				(thermal_bridge_width 0.5)
				(island_removal_mode 0)
			)
			(polygon
				(pts
					(arc
						(start 127.731012 -89.349834)
						(mid 126.969012 -89.349834)
						(end 127.731012 -89.349834)
					)
				)
			)
		)
		(zone
			(layer "F.Cu")
			(hatch none 0.5)
			(connect_pads
				(clearance 0)
			)
			(min_thickness 0.25)
			(keepout
				(tracks allowed)
				(vias not_allowed)
				(pads allowed)
				(copperpour not_allowed)
				(footprints allowed)
			)
			(placement
				(enabled no)
				(sheetname "")
			)
			(fill
				(thermal_gap 0.5)
				(thermal_bridge_width 0.5)
				(island_removal_mode 0)
			)
			(polygon
				(pts
					(arc
						(start 127.731012 -88.349836)
						(mid 126.969012 -88.349836)
						(end 127.731012 -88.349836)
					)
				)
			)
		)
		(zone
			(layer "F.Cu")
			(hatch none 0.5)
			(connect_pads
				(clearance 0)
			)
			(min_thickness 0.25)
			(keepout
				(tracks allowed)
				(vias not_allowed)
				(pads allowed)
				(copperpour not_allowed)
				(footprints allowed)
			)
			(placement
				(enabled no)
				(sheetname "")
			)
			(fill
				(thermal_gap 0.5)
				(thermal_bridge_width 0.5)
				(island_removal_mode 0)
			)
			(polygon
				(pts
					(arc
						(start 127.731012 -87.349838)
						(mid 126.969012 -87.349838)
						(end 127.731012 -87.349838)
					)
				)
			)
		)
		(zone
			(layer "F.Cu")
			(hatch none 0.5)
			(connect_pads
				(clearance 0)
			)
			(min_thickness 0.25)
			(keepout
				(tracks allowed)
				(vias not_allowed)
				(pads allowed)
				(copperpour not_allowed)
				(footprints allowed)
			)
			(placement
				(enabled no)
				(sheetname "")
			)
			(fill
				(thermal_gap 0.5)
				(thermal_bridge_width 0.5)
				(island_removal_mode 0)
			)
			(polygon
				(pts
					(arc
						(start 127.731012 -86.34984)
						(mid 126.969012 -86.34984)
						(end 127.731012 -86.34984)
					)
				)
			)
		)
		(zone
			(layer "F.Cu")
			(hatch none 0.5)
			(connect_pads
				(clearance 0)
			)
			(min_thickness 0.25)
			(keepout
				(tracks allowed)
				(vias not_allowed)
				(pads allowed)
				(copperpour not_allowed)
				(footprints allowed)
			)
			(placement
				(enabled no)
				(sheetname "")
			)
			(fill
				(thermal_gap 0.5)
				(thermal_bridge_width 0.5)
				(island_removal_mode 0)
			)
			(polygon
				(pts
					(arc
						(start 127.731012 -85.349842)
						(mid 126.969012 -85.349842)
						(end 127.731012 -85.349842)
					)
				)
			)
		)
		(zone
			(layer "F.Cu")
			(hatch none 0.5)
			(connect_pads
				(clearance 0)
			)
			(min_thickness 0.25)
			(keepout
				(tracks allowed)
				(vias not_allowed)
				(pads allowed)
				(copperpour not_allowed)
				(footprints allowed)
			)
			(placement
				(enabled no)
				(sheetname "")
			)
			(fill
				(thermal_gap 0.5)
				(thermal_bridge_width 0.5)
				(island_removal_mode 0)
			)
			(polygon
				(pts
					(arc
						(start 102.756208 -106.350054)
						(mid 101.943408 -106.350054)
						(end 102.756208 -106.350054)
					)
				)
			)
		)
		(zone
			(layer "F.Cu")
			(hatch none 0.5)
			(connect_pads
				(clearance 0)
			)
			(min_thickness 0.25)
			(keepout
				(tracks allowed)
				(vias not_allowed)
				(pads allowed)
				(copperpour not_allowed)
				(footprints allowed)
			)
			(placement
				(enabled no)
				(sheetname "")
			)
			(fill
				(thermal_gap 0.5)
				(thermal_bridge_width 0.5)
				(island_removal_mode 0)
			)
			(polygon
				(pts
					(arc
						(start 102.756208 -105.350056)
						(mid 101.943408 -105.350056)
						(end 102.756208 -105.350056)
					)
				)
			)
		)
		(zone
			(layer "F.Cu")
			(hatch none 0.5)
			(connect_pads
				(clearance 0)
			)
			(min_thickness 0.25)
			(keepout
				(tracks allowed)
				(vias not_allowed)
				(pads allowed)
				(copperpour not_allowed)
				(footprints allowed)
			)
			(placement
				(enabled no)
				(sheetname "")
			)
			(fill
				(thermal_gap 0.5)
				(thermal_bridge_width 0.5)
				(island_removal_mode 0)
			)
			(polygon
				(pts
					(arc
						(start 102.756208 -84.349844)
						(mid 101.943408 -84.349844)
						(end 102.756208 -84.349844)
					)
				)
			)
		)
		(zone
			(layer "F.Cu")
			(hatch none 0.5)
			(connect_pads
				(clearance 0)
			)
			(min_thickness 0.25)
			(keepout
				(tracks allowed)
				(vias not_allowed)
				(pads allowed)
				(copperpour not_allowed)
				(footprints allowed)
			)
			(placement
				(enabled no)
				(sheetname "")
			)
			(fill
				(thermal_gap 0.5)
				(thermal_bridge_width 0.5)
				(island_removal_mode 0)
			)
			(polygon
				(pts
					(arc
						(start 102.756208 -83.349846)
						(mid 101.943408 -83.349846)
						(end 102.756208 -83.349846)
					)
				)
			)
		)
		(zone
			(layer "F.Cu")
			(hatch none 0.5)
			(connect_pads
				(clearance 0)
			)
			(min_thickness 0.25)
			(keepout
				(tracks allowed)
				(vias not_allowed)
				(pads allowed)
				(copperpour not_allowed)
				(footprints allowed)
			)
			(placement
				(enabled no)
				(sheetname "")
			)
			(fill
				(thermal_gap 0.5)
				(thermal_bridge_width 0.5)
				(island_removal_mode 0)
			)
			(polygon
				(pts
					(arc
						(start 103.756206 -107.350052)
						(mid 102.943406 -107.350052)
						(end 103.756206 -107.350052)
					)
				)
			)
		)
		(zone
			(layer "F.Cu")
			(hatch none 0.5)
			(connect_pads
				(clearance 0)
			)
			(min_thickness 0.25)
			(keepout
				(tracks allowed)
				(vias not_allowed)
				(pads allowed)
				(copperpour not_allowed)
				(footprints allowed)
			)
			(placement
				(enabled no)
				(sheetname "")
			)
			(fill
				(thermal_gap 0.5)
				(thermal_bridge_width 0.5)
				(island_removal_mode 0)
			)
			(polygon
				(pts
					(arc
						(start 103.756206 -106.350054)
						(mid 102.943406 -106.350054)
						(end 103.756206 -106.350054)
					)
				)
			)
		)
		(zone
			(layer "F.Cu")
			(hatch none 0.5)
			(connect_pads
				(clearance 0)
			)
			(min_thickness 0.25)
			(keepout
				(tracks allowed)
				(vias not_allowed)
				(pads allowed)
				(copperpour not_allowed)
				(footprints allowed)
			)
			(placement
				(enabled no)
				(sheetname "")
			)
			(fill
				(thermal_gap 0.5)
				(thermal_bridge_width 0.5)
				(island_removal_mode 0)
			)
			(polygon
				(pts
					(arc
						(start 103.756206 -105.350056)
						(mid 102.943406 -105.350056)
						(end 103.756206 -105.350056)
					)
				)
			)
		)
		(zone
			(layer "F.Cu")
			(hatch none 0.5)
			(connect_pads
				(clearance 0)
			)
			(min_thickness 0.25)
			(keepout
				(tracks allowed)
				(vias not_allowed)
				(pads allowed)
				(copperpour not_allowed)
				(footprints allowed)
			)
			(placement
				(enabled no)
				(sheetname "")
			)
			(fill
				(thermal_gap 0.5)
				(thermal_bridge_width 0.5)
				(island_removal_mode 0)
			)
			(polygon
				(pts
					(arc
						(start 103.756206 -84.349844)
						(mid 102.943406 -84.349844)
						(end 103.756206 -84.349844)
					)
				)
			)
		)
		(zone
			(layer "F.Cu")
			(hatch none 0.5)
			(connect_pads
				(clearance 0)
			)
			(min_thickness 0.25)
			(keepout
				(tracks allowed)
				(vias not_allowed)
				(pads allowed)
				(copperpour not_allowed)
				(footprints allowed)
			)
			(placement
				(enabled no)
				(sheetname "")
			)
			(fill
				(thermal_gap 0.5)
				(thermal_bridge_width 0.5)
				(island_removal_mode 0)
			)
			(polygon
				(pts
					(arc
						(start 103.756206 -83.349846)
						(mid 102.943406 -83.349846)
						(end 103.756206 -83.349846)
					)
				)
			)
		)
		(zone
			(layer "F.Cu")
			(hatch none 0.5)
			(connect_pads
				(clearance 0)
			)
			(min_thickness 0.25)
			(keepout
				(tracks allowed)
				(vias not_allowed)
				(pads allowed)
				(copperpour not_allowed)
				(footprints allowed)
			)
			(placement
				(enabled no)
				(sheetname "")
			)
			(fill
				(thermal_gap 0.5)
				(thermal_bridge_width 0.5)
				(island_removal_mode 0)
			)
			(polygon
				(pts
					(arc
						(start 103.756206 -82.349848)
						(mid 102.943406 -82.349848)
						(end 103.756206 -82.349848)
					)
				)
			)
		)
		(zone
			(layer "F.Cu")
			(hatch none 0.5)
			(connect_pads
				(clearance 0)
			)
			(min_thickness 0.25)
			(keepout
				(tracks allowed)
				(vias not_allowed)
				(pads allowed)
				(copperpour not_allowed)
				(footprints allowed)
			)
			(placement
				(enabled no)
				(sheetname "")
			)
			(fill
				(thermal_gap 0.5)
				(thermal_bridge_width 0.5)
				(island_removal_mode 0)
			)
			(polygon
				(pts
					(arc
						(start 104.756204 -107.350052)
						(mid 103.943404 -107.350052)
						(end 104.756204 -107.350052)
					)
				)
			)
		)
		(zone
			(layer "F.Cu")
			(hatch none 0.5)
			(connect_pads
				(clearance 0)
			)
			(min_thickness 0.25)
			(keepout
				(tracks allowed)
				(vias not_allowed)
				(pads allowed)
				(copperpour not_allowed)
				(footprints allowed)
			)
			(placement
				(enabled no)
				(sheetname "")
			)
			(fill
				(thermal_gap 0.5)
				(thermal_bridge_width 0.5)
				(island_removal_mode 0)
			)
			(polygon
				(pts
					(arc
						(start 104.756204 -106.350054)
						(mid 103.943404 -106.350054)
						(end 104.756204 -106.350054)
					)
				)
			)
		)
		(zone
			(layer "F.Cu")
			(hatch none 0.5)
			(connect_pads
				(clearance 0)
			)
			(min_thickness 0.25)
			(keepout
				(tracks allowed)
				(vias not_allowed)
				(pads allowed)
				(copperpour not_allowed)
				(footprints allowed)
			)
			(placement
				(enabled no)
				(sheetname "")
			)
			(fill
				(thermal_gap 0.5)
				(thermal_bridge_width 0.5)
				(island_removal_mode 0)
			)
			(polygon
				(pts
					(arc
						(start 104.756204 -105.350056)
						(mid 103.943404 -105.350056)
						(end 104.756204 -105.350056)
					)
				)
			)
		)
		(zone
			(layer "F.Cu")
			(hatch none 0.5)
			(connect_pads
				(clearance 0)
			)
			(min_thickness 0.25)
			(keepout
				(tracks allowed)
				(vias not_allowed)
				(pads allowed)
				(copperpour not_allowed)
				(footprints allowed)
			)
			(placement
				(enabled no)
				(sheetname "")
			)
			(fill
				(thermal_gap 0.5)
				(thermal_bridge_width 0.5)
				(island_removal_mode 0)
			)
			(polygon
				(pts
					(arc
						(start 104.756204 -84.349844)
						(mid 103.943404 -84.349844)
						(end 104.756204 -84.349844)
					)
				)
			)
		)
		(zone
			(layer "F.Cu")
			(hatch none 0.5)
			(connect_pads
				(clearance 0)
			)
			(min_thickness 0.25)
			(keepout
				(tracks allowed)
				(vias not_allowed)
				(pads allowed)
				(copperpour not_allowed)
				(footprints allowed)
			)
			(placement
				(enabled no)
				(sheetname "")
			)
			(fill
				(thermal_gap 0.5)
				(thermal_bridge_width 0.5)
				(island_removal_mode 0)
			)
			(polygon
				(pts
					(arc
						(start 104.756204 -83.349846)
						(mid 103.943404 -83.349846)
						(end 104.756204 -83.349846)
					)
				)
			)
		)
		(zone
			(layer "F.Cu")
			(hatch none 0.5)
			(connect_pads
				(clearance 0)
			)
			(min_thickness 0.25)
			(keepout
				(tracks allowed)
				(vias not_allowed)
				(pads allowed)
				(copperpour not_allowed)
				(footprints allowed)
			)
			(placement
				(enabled no)
				(sheetname "")
			)
			(fill
				(thermal_gap 0.5)
				(thermal_bridge_width 0.5)
				(island_removal_mode 0)
			)
			(polygon
				(pts
					(arc
						(start 104.756204 -82.349848)
						(mid 103.943404 -82.349848)
						(end 104.756204 -82.349848)
					)
				)
			)
		)
		(zone
			(layer "F.Cu")
			(hatch none 0.5)
			(connect_pads
				(clearance 0)
			)
			(min_thickness 0.25)
			(keepout
				(tracks allowed)
				(vias not_allowed)
				(pads allowed)
				(copperpour not_allowed)
				(footprints allowed)
			)
			(placement
				(enabled no)
				(sheetname "")
			)
			(fill
				(thermal_gap 0.5)
				(thermal_bridge_width 0.5)
				(island_removal_mode 0)
			)
			(polygon
				(pts
					(arc
						(start 125.756416 -107.350052)
						(mid 124.943616 -107.350052)
						(end 125.756416 -107.350052)
					)
				)
			)
		)
		(zone
			(layer "F.Cu")
			(hatch none 0.5)
			(connect_pads
				(clearance 0)
			)
			(min_thickness 0.25)
			(keepout
				(tracks allowed)
				(vias not_allowed)
				(pads allowed)
				(copperpour not_allowed)
				(footprints allowed)
			)
			(placement
				(enabled no)
				(sheetname "")
			)
			(fill
				(thermal_gap 0.5)
				(thermal_bridge_width 0.5)
				(island_removal_mode 0)
			)
			(polygon
				(pts
					(arc
						(start 125.756416 -106.350054)
						(mid 124.943616 -106.350054)
						(end 125.756416 -106.350054)
					)
				)
			)
		)
		(zone
			(layer "F.Cu")
			(hatch none 0.5)
			(connect_pads
				(clearance 0)
			)
			(min_thickness 0.25)
			(keepout
				(tracks allowed)
				(vias not_allowed)
				(pads allowed)
				(copperpour not_allowed)
				(footprints allowed)
			)
			(placement
				(enabled no)
				(sheetname "")
			)
			(fill
				(thermal_gap 0.5)
				(thermal_bridge_width 0.5)
				(island_removal_mode 0)
			)
			(polygon
				(pts
					(arc
						(start 125.756416 -105.350056)
						(mid 124.943616 -105.350056)
						(end 125.756416 -105.350056)
					)
				)
			)
		)
		(zone
			(layer "F.Cu")
			(hatch none 0.5)
			(connect_pads
				(clearance 0)
			)
			(min_thickness 0.25)
			(keepout
				(tracks allowed)
				(vias not_allowed)
				(pads allowed)
				(copperpour not_allowed)
				(footprints allowed)
			)
			(placement
				(enabled no)
				(sheetname "")
			)
			(fill
				(thermal_gap 0.5)
				(thermal_bridge_width 0.5)
				(island_removal_mode 0)
			)
			(polygon
				(pts
					(arc
						(start 125.756416 -84.349844)
						(mid 124.943616 -84.349844)
						(end 125.756416 -84.349844)
					)
				)
			)
		)
		(zone
			(layer "F.Cu")
			(hatch none 0.5)
			(connect_pads
				(clearance 0)
			)
			(min_thickness 0.25)
			(keepout
				(tracks allowed)
				(vias not_allowed)
				(pads allowed)
				(copperpour not_allowed)
				(footprints allowed)
			)
			(placement
				(enabled no)
				(sheetname "")
			)
			(fill
				(thermal_gap 0.5)
				(thermal_bridge_width 0.5)
				(island_removal_mode 0)
			)
			(polygon
				(pts
					(arc
						(start 125.756416 -83.349846)
						(mid 124.943616 -83.349846)
						(end 125.756416 -83.349846)
					)
				)
			)
		)
		(zone
			(layer "F.Cu")
			(hatch none 0.5)
			(connect_pads
				(clearance 0)
			)
			(min_thickness 0.25)
			(keepout
				(tracks allowed)
				(vias not_allowed)
				(pads allowed)
				(copperpour not_allowed)
				(footprints allowed)
			)
			(placement
				(enabled no)
				(sheetname "")
			)
			(fill
				(thermal_gap 0.5)
				(thermal_bridge_width 0.5)
				(island_removal_mode 0)
			)
			(polygon
				(pts
					(arc
						(start 125.756416 -82.349848)
						(mid 124.943616 -82.349848)
						(end 125.756416 -82.349848)
					)
				)
			)
		)
		(zone
			(layer "F.Cu")
			(hatch none 0.5)
			(connect_pads
				(clearance 0)
			)
			(min_thickness 0.25)
			(keepout
				(tracks allowed)
				(vias not_allowed)
				(pads allowed)
				(copperpour not_allowed)
				(footprints allowed)
			)
			(placement
				(enabled no)
				(sheetname "")
			)
			(fill
				(thermal_gap 0.5)
				(thermal_bridge_width 0.5)
				(island_removal_mode 0)
			)
			(polygon
				(pts
					(arc
						(start 126.756414 -107.350052)
						(mid 125.943614 -107.350052)
						(end 126.756414 -107.350052)
					)
				)
			)
		)
		(zone
			(layer "F.Cu")
			(hatch none 0.5)
			(connect_pads
				(clearance 0)
			)
			(min_thickness 0.25)
			(keepout
				(tracks allowed)
				(vias not_allowed)
				(pads allowed)
				(copperpour not_allowed)
				(footprints allowed)
			)
			(placement
				(enabled no)
				(sheetname "")
			)
			(fill
				(thermal_gap 0.5)
				(thermal_bridge_width 0.5)
				(island_removal_mode 0)
			)
			(polygon
				(pts
					(arc
						(start 126.756414 -106.350054)
						(mid 125.943614 -106.350054)
						(end 126.756414 -106.350054)
					)
				)
			)
		)
		(zone
			(layer "F.Cu")
			(hatch none 0.5)
			(connect_pads
				(clearance 0)
			)
			(min_thickness 0.25)
			(keepout
				(tracks allowed)
				(vias not_allowed)
				(pads allowed)
				(copperpour not_allowed)
				(footprints allowed)
			)
			(placement
				(enabled no)
				(sheetname "")
			)
			(fill
				(thermal_gap 0.5)
				(thermal_bridge_width 0.5)
				(island_removal_mode 0)
			)
			(polygon
				(pts
					(arc
						(start 126.756414 -105.350056)
						(mid 125.943614 -105.350056)
						(end 126.756414 -105.350056)
					)
				)
			)
		)
		(zone
			(layer "F.Cu")
			(hatch none 0.5)
			(connect_pads
				(clearance 0)
			)
			(min_thickness 0.25)
			(keepout
				(tracks allowed)
				(vias not_allowed)
				(pads allowed)
				(copperpour not_allowed)
				(footprints allowed)
			)
			(placement
				(enabled no)
				(sheetname "")
			)
			(fill
				(thermal_gap 0.5)
				(thermal_bridge_width 0.5)
				(island_removal_mode 0)
			)
			(polygon
				(pts
					(arc
						(start 126.756414 -84.349844)
						(mid 125.943614 -84.349844)
						(end 126.756414 -84.349844)
					)
				)
			)
		)
		(zone
			(layer "F.Cu")
			(hatch none 0.5)
			(connect_pads
				(clearance 0)
			)
			(min_thickness 0.25)
			(keepout
				(tracks allowed)
				(vias not_allowed)
				(pads allowed)
				(copperpour not_allowed)
				(footprints allowed)
			)
			(placement
				(enabled no)
				(sheetname "")
			)
			(fill
				(thermal_gap 0.5)
				(thermal_bridge_width 0.5)
				(island_removal_mode 0)
			)
			(polygon
				(pts
					(arc
						(start 126.756414 -83.349846)
						(mid 125.943614 -83.349846)
						(end 126.756414 -83.349846)
					)
				)
			)
		)
		(zone
			(layer "F.Cu")
			(hatch none 0.5)
			(connect_pads
				(clearance 0)
			)
			(min_thickness 0.25)
			(keepout
				(tracks allowed)
				(vias not_allowed)
				(pads allowed)
				(copperpour not_allowed)
				(footprints allowed)
			)
			(placement
				(enabled no)
				(sheetname "")
			)
			(fill
				(thermal_gap 0.5)
				(thermal_bridge_width 0.5)
				(island_removal_mode 0)
			)
			(polygon
				(pts
					(arc
						(start 126.756414 -82.349848)
						(mid 125.943614 -82.349848)
						(end 126.756414 -82.349848)
					)
				)
			)
		)
		(zone
			(layer "F.Cu")
			(hatch none 0.5)
			(connect_pads
				(clearance 0)
			)
			(min_thickness 0.25)
			(keepout
				(tracks allowed)
				(vias not_allowed)
				(pads allowed)
				(copperpour not_allowed)
				(footprints allowed)
			)
			(placement
				(enabled no)
				(sheetname "")
			)
			(fill
				(thermal_gap 0.5)
				(thermal_bridge_width 0.5)
				(island_removal_mode 0)
			)
			(polygon
				(pts
					(arc
						(start 127.756412 -106.350054)
						(mid 126.943612 -106.350054)
						(end 127.756412 -106.350054)
					)
				)
			)
		)
		(zone
			(layer "F.Cu")
			(hatch none 0.5)
			(connect_pads
				(clearance 0)
			)
			(min_thickness 0.25)
			(keepout
				(tracks allowed)
				(vias not_allowed)
				(pads allowed)
				(copperpour not_allowed)
				(footprints allowed)
			)
			(placement
				(enabled no)
				(sheetname "")
			)
			(fill
				(thermal_gap 0.5)
				(thermal_bridge_width 0.5)
				(island_removal_mode 0)
			)
			(polygon
				(pts
					(arc
						(start 127.756412 -105.350056)
						(mid 126.943612 -105.350056)
						(end 127.756412 -105.350056)
					)
				)
			)
		)
		(zone
			(layer "F.Cu")
			(hatch none 0.5)
			(connect_pads
				(clearance 0)
			)
			(min_thickness 0.25)
			(keepout
				(tracks allowed)
				(vias not_allowed)
				(pads allowed)
				(copperpour not_allowed)
				(footprints allowed)
			)
			(placement
				(enabled no)
				(sheetname "")
			)
			(fill
				(thermal_gap 0.5)
				(thermal_bridge_width 0.5)
				(island_removal_mode 0)
			)
			(polygon
				(pts
					(arc
						(start 127.756412 -84.349844)
						(mid 126.943612 -84.349844)
						(end 127.756412 -84.349844)
					)
				)
			)
		)
		(zone
			(layer "F.Cu")
			(hatch none 0.5)
			(connect_pads
				(clearance 0)
			)
			(min_thickness 0.25)
			(keepout
				(tracks allowed)
				(vias not_allowed)
				(pads allowed)
				(copperpour not_allowed)
				(footprints allowed)
			)
			(placement
				(enabled no)
				(sheetname "")
			)
			(fill
				(thermal_gap 0.5)
				(thermal_bridge_width 0.5)
				(island_removal_mode 0)
			)
			(polygon
				(pts
					(arc
						(start 127.756412 -83.349846)
						(mid 126.943612 -83.349846)
						(end 127.756412 -83.349846)
					)
				)
			)
		)
	)
	(footprint ""
		(layer "F.Cu")
		(at 295.529 -161.544 180)
		(property "Reference" "R286"
			(at 0 0 180)
			(layer "F.SilkS")
			(hide yes)
			(effects
				(font
					(size 1.27 1.27)
				)
			)
		)
		(property "Value" "0R2J-2-GP"
			(at 0.064008 -3.993896 180)
			(unlocked yes)
			(layer "F.Fab")
			(hide yes)
			(effects
				(font
					(size 1.016 1.016)
					(thickness 0.1524)
				)
			)
		)
		(property "Device Type" "R402H16"
			(at 0.064008 -5.517896 180)
			(unlocked yes)
			(layer "F.Fab")
			(hide yes)
			(effects
				(font
					(size 1.016 1.016)
					(thickness 0.1524)
				)
			)
		)
		(duplicate_pad_numbers_are_jumpers no)
		(fp_line
			(start 0.508 -0.9398)
			(end -0.508 -0.9398)
			(stroke
				(width 0.1524)
				(type default)
			)
			(layer "F.SilkS")
		)
		(fp_line
			(start -0.508 -0.9398)
			(end -0.508 0.9398)
			(stroke
				(width 0.1524)
				(type default)
			)
			(layer "F.SilkS")
		)
		(fp_rect
			(start -0.508 0.9398)
			(end 0.508 -0.9398)
			(stroke
				(width 0)
				(type default)
			)
			(fill no)
			(layer "F.CrtYd")
		)
		(fp_rect
			(start -0.508 0.9398)
			(end 0.508 -0.9398)
			(stroke
				(width 0)
				(type default)
			)
			(fill no)
			(layer "F.Fab")
		)
		(pad "1" smd custom
			(at 0 -0.4445 180)
			(size 0.1397 0.1397)
			(layers "F.Cu" "F.Mask" "F.Paste")
			(net "RMII_BMC_CRS_DV")
			(options
				(clearance outline)
				(anchor circle)
			)
			(primitives
				(gr_poly
					(pts
						(arc
							(start -0.1778 -0.2794)
							(mid -0.249642 -0.249642)
							(end -0.2794 -0.1778)
						)
						(arc
							(start -0.2794 0.1778)
							(mid -0.249642 0.249642)
							(end -0.1778 0.2794)
						)
						(arc
							(start 0.1778 0.2794)
							(mid 0.249642 0.249642)
							(end 0.2794 0.1778)
						)
						(arc
							(start 0.2794 -0.1778)
							(mid 0.249642 -0.249642)
							(end 0.1778 -0.2794)
						)
					)
					(width 0)
					(fill yes)
				)
			)
		)
		(pad "2" smd custom
			(at 0 0.4445 180)
			(size 0.1397 0.1397)
			(layers "F.Cu" "F.Mask" "F.Paste")
			(net "RMII0_BMC_C_CRS_DV")
			(options
				(clearance outline)
				(anchor circle)
			)
			(primitives
				(gr_poly
					(pts
						(arc
							(start -0.1778 -0.2794)
							(mid -0.249642 -0.249642)
							(end -0.2794 -0.1778)
						)
						(arc
							(start -0.2794 0.1778)
							(mid -0.249642 0.249642)
							(end -0.1778 0.2794)
						)
						(arc
							(start 0.1778 0.2794)
							(mid 0.249642 0.249642)
							(end 0.2794 0.1778)
						)
						(arc
							(start 0.2794 -0.1778)
							(mid 0.249642 -0.249642)
							(end 0.1778 -0.2794)
						)
					)
					(width 0)
					(fill yes)
				)
			)
		)
	)
	(footprint ""
		(layer "F.Cu")
		(at 53.848 -224.917)
		(property "Reference" "R2107"
			(at 0 0 0)
			(layer "F.SilkS")
			(hide yes)
			(effects
				(font
					(size 1.27 1.27)
				)
			)
		)
		(property "Value" "49K9R2F-L-GP"
			(at 0.064008 -3.993896 0)
			(unlocked yes)
			(layer "F.Fab")
			(hide yes)
			(effects
				(font
					(size 1.016 1.016)
					(thickness 0.1524)
				)
			)
		)
		(property "Device Type" "R402H16"
			(at 0.064008 -5.517896 0)
			(unlocked yes)
			(layer "F.Fab")
			(hide yes)
			(effects
				(font
					(size 1.016 1.016)
					(thickness 0.1524)
				)
			)
		)
		(duplicate_pad_numbers_are_jumpers no)
		(fp_line
			(start -0.508 -0.9398)
			(end -0.508 0.9398)
			(stroke
				(width 0.1524)
				(type default)
			)
			(layer "F.SilkS")
		)
		(fp_line
			(start 0.508 -0.9398)
			(end -0.508 -0.9398)
			(stroke
				(width 0.1524)
				(type default)
			)
			(layer "F.SilkS")
		)
		(fp_rect
			(start -0.508 0.9398)
			(end 0.508 -0.9398)
			(stroke
				(width 0)
				(type default)
			)
			(fill no)
			(layer "F.CrtYd")
		)
		(fp_rect
			(start -0.508 0.9398)
			(end 0.508 -0.9398)
			(stroke
				(width 0)
				(type default)
			)
			(fill no)
			(layer "F.Fab")
		)
		(pad "1" smd custom
			(at 0 -0.4445)
			(size 0.1397 0.1397)
			(layers "F.Cu" "F.Mask" "F.Paste")
			(net "P12V_PCIE")
			(options
				(clearance outline)
				(anchor circle)
			)
			(primitives
				(gr_poly
					(pts
						(arc
							(start -0.1778 -0.2794)
							(mid -0.249642 -0.249642)
							(end -0.2794 -0.1778)
						)
						(arc
							(start -0.2794 0.1778)
							(mid -0.249642 0.249642)
							(end -0.1778 0.2794)
						)
						(arc
							(start 0.1778 0.2794)
							(mid 0.249642 0.249642)
							(end 0.2794 0.1778)
						)
						(arc
							(start 0.2794 -0.1778)
							(mid 0.249642 -0.249642)
							(end 0.1778 -0.2794)
						)
					)
					(width 0)
					(fill yes)
				)
			)
		)
		(pad "2" smd custom
			(at 0 0.4445)
			(size 0.1397 0.1397)
			(layers "F.Cu" "F.Mask" "F.Paste")
			(net "MB0_CM_UV_R")
			(options
				(clearance outline)
				(anchor circle)
			)
			(primitives
				(gr_poly
					(pts
						(arc
							(start -0.1778 -0.2794)
							(mid -0.249642 -0.249642)
							(end -0.2794 -0.1778)
						)
						(arc
							(start -0.2794 0.1778)
							(mid -0.249642 0.249642)
							(end -0.1778 0.2794)
						)
						(arc
							(start 0.1778 0.2794)
							(mid 0.249642 0.249642)
							(end 0.2794 0.1778)
						)
						(arc
							(start 0.2794 -0.1778)
							(mid 0.249642 -0.249642)
							(end 0.1778 -0.2794)
						)
					)
					(width 0)
					(fill yes)
				)
			)
		)
	)
	(footprint ""
		(layer "F.Cu")
		(at 305.308 -153.797 -90)
		(property "Reference" "R7888"
			(at 0 0 270)
			(layer "F.SilkS")
			(hide yes)
			(effects
				(font
					(size 1.27 1.27)
				)
			)
		)
		(property "Value" "47R2F-GP"
			(at 0.064008 -3.993896 270)
			(unlocked yes)
			(layer "F.Fab")
			(hide yes)
			(effects
				(font
					(size 1.016 1.016)
					(thickness 0.1524)
				)
			)
		)
		(property "Device Type" "R402H16"
			(at 0.064008 -5.517896 270)
			(unlocked yes)
			(layer "F.Fab")
			(hide yes)
			(effects
				(font
					(size 1.016 1.016)
					(thickness 0.1524)
				)
			)
		)
		(duplicate_pad_numbers_are_jumpers no)
		(fp_line
			(start -0.508 -0.9398)
			(end -0.508 0.9398)
			(stroke
				(width 0.1524)
				(type default)
			)
			(layer "F.SilkS")
		)
		(fp_line
			(start 0.508 -0.9398)
			(end -0.508 -0.9398)
			(stroke
				(width 0.1524)
				(type default)
			)
			(layer "F.SilkS")
		)
		(fp_rect
			(start -0.508 0.9398)
			(end 0.508 -0.9398)
			(stroke
				(width 0)
				(type default)
			)
			(fill no)
			(layer "F.CrtYd")
		)
		(fp_rect
			(start -0.508 0.9398)
			(end 0.508 -0.9398)
			(stroke
				(width 0)
				(type default)
			)
			(fill no)
			(layer "F.Fab")
		)
		(pad "1" smd custom
			(at 0 -0.4445 270)
			(size 0.1397 0.1397)
			(layers "F.Cu" "F.Mask" "F.Paste")
			(net "125_GTX")
			(options
				(clearance outline)
				(anchor circle)
			)
			(primitives
				(gr_poly
					(pts
						(arc
							(start -0.1778 -0.2794)
							(mid -0.249642 -0.249642)
							(end -0.2794 -0.1778)
						)
						(arc
							(start -0.2794 0.1778)
							(mid -0.249642 0.249642)
							(end -0.1778 0.2794)
						)
						(arc
							(start 0.1778 0.2794)
							(mid 0.249642 0.249642)
							(end 0.2794 0.1778)
						)
						(arc
							(start 0.2794 -0.1778)
							(mid 0.249642 -0.249642)
							(end 0.1778 -0.2794)
						)
					)
					(width 0)
					(fill yes)
				)
			)
		)
		(pad "2" smd custom
			(at 0 0.4445 270)
			(size 0.1397 0.1397)
			(layers "F.Cu" "F.Mask" "F.Paste")
			(net "BMC_MAC2_RGMIICK")
			(options
				(clearance outline)
				(anchor circle)
			)
			(primitives
				(gr_poly
					(pts
						(arc
							(start -0.1778 -0.2794)
							(mid -0.249642 -0.249642)
							(end -0.2794 -0.1778)
						)
						(arc
							(start -0.2794 0.1778)
							(mid -0.249642 0.249642)
							(end -0.1778 0.2794)
						)
						(arc
							(start 0.1778 0.2794)
							(mid 0.249642 0.249642)
							(end 0.2794 0.1778)
						)
						(arc
							(start 0.2794 -0.1778)
							(mid 0.249642 -0.249642)
							(end 0.1778 -0.2794)
						)
					)
					(width 0)
					(fill yes)
				)
			)
		)
	)
	(footprint ""
		(layer "F.Cu")
		(at 94.361 -221.361)
		(property "Reference" "SR314"
			(at 0 0 0)
			(layer "F.SilkS")
			(hide yes)
			(effects
				(font
					(size 1.27 1.27)
				)
			)
		)
		(property "Value" "0R2J-2-GP"
			(at 0.064008 -3.993896 0)
			(unlocked yes)
			(layer "F.Fab")
			(hide yes)
			(effects
				(font
					(size 1.016 1.016)
					(thickness 0.1524)
				)
			)
		)
		(property "Device Type" "R402H16"
			(at 0.064008 -5.517896 0)
			(unlocked yes)
			(layer "F.Fab")
			(hide yes)
			(effects
				(font
					(size 1.016 1.016)
					(thickness 0.1524)
				)
			)
		)
		(duplicate_pad_numbers_are_jumpers no)
		(fp_line
			(start -0.508 -0.9398)
			(end -0.508 0.9398)
			(stroke
				(width 0.1524)
				(type default)
			)
			(layer "F.SilkS")
		)
		(fp_line
			(start 0.508 -0.9398)
			(end -0.508 -0.9398)
			(stroke
				(width 0.1524)
				(type default)
			)
			(layer "F.SilkS")
		)
		(fp_rect
			(start -0.508 0.9398)
			(end 0.508 -0.9398)
			(stroke
				(width 0)
				(type default)
			)
			(fill no)
			(layer "F.CrtYd")
		)
		(fp_rect
			(start -0.508 0.9398)
			(end 0.508 -0.9398)
			(stroke
				(width 0)
				(type default)
			)
			(fill no)
			(layer "F.Fab")
		)
		(pad "1" smd custom
			(at 0 -0.4445)
			(size 0.1397 0.1397)
			(layers "F.Cu" "F.Mask" "F.Paste")
			(net "FAULT_SDA")
			(options
				(clearance outline)
				(anchor circle)
			)
			(primitives
				(gr_poly
					(pts
						(arc
							(start -0.1778 -0.2794)
							(mid -0.249642 -0.249642)
							(end -0.2794 -0.1778)
						)
						(arc
							(start -0.2794 0.1778)
							(mid -0.249642 0.249642)
							(end -0.1778 0.2794)
						)
						(arc
							(start 0.1778 0.2794)
							(mid 0.249642 0.249642)
							(end 0.2794 0.1778)
						)
						(arc
							(start 0.2794 -0.1778)
							(mid 0.249642 -0.249642)
							(end 0.1778 -0.2794)
						)
					)
					(width 0)
					(fill yes)
				)
			)
		)
		(pad "2" smd custom
			(at 0 0.4445)
			(size 0.1397 0.1397)
			(layers "F.Cu" "F.Mask" "F.Paste")
			(net "BMC_I2C_SDA_10")
			(options
				(clearance outline)
				(anchor circle)
			)
			(primitives
				(gr_poly
					(pts
						(arc
							(start -0.1778 -0.2794)
							(mid -0.249642 -0.249642)
							(end -0.2794 -0.1778)
						)
						(arc
							(start -0.2794 0.1778)
							(mid -0.249642 0.249642)
							(end -0.1778 0.2794)
						)
						(arc
							(start 0.1778 0.2794)
							(mid 0.249642 0.249642)
							(end 0.2794 0.1778)
						)
						(arc
							(start 0.2794 -0.1778)
							(mid 0.249642 -0.249642)
							(end 0.1778 -0.2794)
						)
					)
					(width 0)
					(fill yes)
				)
			)
		)
	)
	(footprint ""
		(layer "F.Cu")
		(at 297.688 -191.897)
		(property "Reference" "R670"
			(at 0 0 0)
			(layer "F.SilkS")
			(hide yes)
			(effects
				(font
					(size 1.27 1.27)
				)
			)
		)
		(property "Value" "0R2J-2-GP"
			(at 0.064008 -3.993896 0)
			(unlocked yes)
			(layer "F.Fab")
			(hide yes)
			(effects
				(font
					(size 1.016 1.016)
					(thickness 0.1524)
				)
			)
		)
		(property "Device Type" "R402H16"
			(at 0.064008 -5.517896 0)
			(unlocked yes)
			(layer "F.Fab")
			(hide yes)
			(effects
				(font
					(size 1.016 1.016)
					(thickness 0.1524)
				)
			)
		)
		(duplicate_pad_numbers_are_jumpers no)
		(fp_line
			(start -0.508 -0.9398)
			(end -0.508 0.9398)
			(stroke
				(width 0.1524)
				(type default)
			)
			(layer "F.SilkS")
		)
		(fp_line
			(start 0.508 -0.9398)
			(end -0.508 -0.9398)
			(stroke
				(width 0.1524)
				(type default)
			)
			(layer "F.SilkS")
		)
		(fp_rect
			(start -0.508 0.9398)
			(end 0.508 -0.9398)
			(stroke
				(width 0)
				(type default)
			)
			(fill no)
			(layer "F.CrtYd")
		)
		(fp_rect
			(start -0.508 0.9398)
			(end 0.508 -0.9398)
			(stroke
				(width 0)
				(type default)
			)
			(fill no)
			(layer "F.Fab")
		)
		(pad "1" smd custom
			(at 0 -0.4445)
			(size 0.1397 0.1397)
			(layers "F.Cu" "F.Mask" "F.Paste")
			(net "BMC_ENCLOSURE_LED")
			(options
				(clearance outline)
				(anchor circle)
			)
			(primitives
				(gr_poly
					(pts
						(arc
							(start -0.1778 -0.2794)
							(mid -0.249642 -0.249642)
							(end -0.2794 -0.1778)
						)
						(arc
							(start -0.2794 0.1778)
							(mid -0.249642 0.249642)
							(end -0.1778 0.2794)
						)
						(arc
							(start 0.1778 0.2794)
							(mid 0.249642 0.249642)
							(end 0.2794 0.1778)
						)
						(arc
							(start 0.2794 -0.1778)
							(mid 0.249642 -0.249642)
							(end 0.1778 -0.2794)
						)
					)
					(width 0)
					(fill yes)
				)
			)
		)
		(pad "2" smd custom
			(at 0 0.4445)
			(size 0.1397 0.1397)
			(layers "F.Cu" "F.Mask" "F.Paste")
			(net "BMC0_TACH15")
			(options
				(clearance outline)
				(anchor circle)
			)
			(primitives
				(gr_poly
					(pts
						(arc
							(start -0.1778 -0.2794)
							(mid -0.249642 -0.249642)
							(end -0.2794 -0.1778)
						)
						(arc
							(start -0.2794 0.1778)
							(mid -0.249642 0.249642)
							(end -0.1778 0.2794)
						)
						(arc
							(start 0.1778 0.2794)
							(mid 0.249642 0.249642)
							(end 0.2794 0.1778)
						)
						(arc
							(start 0.2794 -0.1778)
							(mid 0.249642 -0.249642)
							(end 0.1778 -0.2794)
						)
					)
					(width 0)
					(fill yes)
				)
			)
		)
	)
	(footprint ""
		(layer "F.Cu")
		(at 274.240752 -190.940436 180)
		(property "Reference" "R317"
			(at 0 0 180)
			(layer "F.SilkS")
			(hide yes)
			(effects
				(font
					(size 1.27 1.27)
				)
			)
		)
		(property "Value" "8K2R2J-3-GP"
			(at 0.064008 -3.993896 180)
			(unlocked yes)
			(layer "F.Fab")
			(hide yes)
			(effects
				(font
					(size 1.016 1.016)
					(thickness 0.1524)
				)
			)
		)
		(property "Device Type" "R402H16"
			(at 0.064008 -5.517896 180)
			(unlocked yes)
			(layer "F.Fab")
			(hide yes)
			(effects
				(font
					(size 1.016 1.016)
					(thickness 0.1524)
				)
			)
		)
		(duplicate_pad_numbers_are_jumpers no)
		(fp_line
			(start 0.508 -0.9398)
			(end -0.508 -0.9398)
			(stroke
				(width 0.1524)
				(type default)
			)
			(layer "F.SilkS")
		)
		(fp_line
			(start -0.508 -0.9398)
			(end -0.508 0.9398)
			(stroke
				(width 0.1524)
				(type default)
			)
			(layer "F.SilkS")
		)
		(fp_rect
			(start -0.508 0.9398)
			(end 0.508 -0.9398)
			(stroke
				(width 0)
				(type default)
			)
			(fill no)
			(layer "F.CrtYd")
		)
		(fp_rect
			(start -0.508 0.9398)
			(end 0.508 -0.9398)
			(stroke
				(width 0)
				(type default)
			)
			(fill no)
			(layer "F.Fab")
		)
		(pad "1" smd custom
			(at 0 -0.4445 180)
			(size 0.1397 0.1397)
			(layers "F.Cu" "F.Mask" "F.Paste")
			(net "PD_USB2VRES")
			(options
				(clearance outline)
				(anchor circle)
			)
			(primitives
				(gr_poly
					(pts
						(arc
							(start -0.1778 -0.2794)
							(mid -0.249642 -0.249642)
							(end -0.2794 -0.1778)
						)
						(arc
							(start -0.2794 0.1778)
							(mid -0.249642 0.249642)
							(end -0.1778 0.2794)
						)
						(arc
							(start 0.1778 0.2794)
							(mid 0.249642 0.249642)
							(end 0.2794 0.1778)
						)
						(arc
							(start 0.2794 -0.1778)
							(mid 0.249642 -0.249642)
							(end 0.1778 -0.2794)
						)
					)
					(width 0)
					(fill yes)
				)
			)
		)
		(pad "2" smd custom
			(at 0 0.4445 180)
			(size 0.1397 0.1397)
			(layers "F.Cu" "F.Mask" "F.Paste")
			(net "GND")
			(options
				(clearance outline)
				(anchor circle)
			)
			(primitives
				(gr_poly
					(pts
						(arc
							(start -0.1778 -0.2794)
							(mid -0.249642 -0.249642)
							(end -0.2794 -0.1778)
						)
						(arc
							(start -0.2794 0.1778)
							(mid -0.249642 0.249642)
							(end -0.1778 0.2794)
						)
						(arc
							(start 0.1778 0.2794)
							(mid 0.249642 0.249642)
							(end 0.2794 0.1778)
						)
						(arc
							(start 0.2794 -0.1778)
							(mid 0.249642 -0.249642)
							(end 0.1778 -0.2794)
						)
					)
					(width 0)
					(fill yes)
				)
			)
		)
	)
	(footprint ""
		(layer "F.Cu")
		(at 59.817 -225.933 180)
		(property "Reference" "PQ33"
			(at 0 0 180)
			(layer "F.SilkS")
			(hide yes)
			(effects
				(font
					(size 1.27 1.27)
				)
			)
		)
		(property "Value" "NST3904F3T5G-GP-U"
			(at -9.8552 -5.2451 180)
			(unlocked yes)
			(layer "F.Fab")
			(hide yes)
			(effects
				(font
					(size 1.016 1.016)
					(thickness 0.1524)
				)
			)
		)
		(property "Device Type" "SOT-1123CBE1006H16"
			(at -9.8552 -6.7691 180)
			(unlocked yes)
			(layer "F.Fab")
			(hide yes)
			(effects
				(font
					(size 1.016 1.016)
					(thickness 0.1524)
				)
			)
		)
		(duplicate_pad_numbers_are_jumpers no)
		(fp_line
			(start 0.6096 0.889)
			(end -0.6096 0.889)
			(stroke
				(width 0.1524)
				(type default)
			)
			(layer "F.SilkS")
		)
		(fp_line
			(start 0.6096 -0.8636)
			(end 0.6096 0.889)
			(stroke
				(width 0.1524)
				(type default)
			)
			(layer "F.SilkS")
		)
		(fp_line
			(start -0.6096 0.889)
			(end -0.6096 -0.8636)
			(stroke
				(width 0.1524)
				(type default)
			)
			(layer "F.SilkS")
		)
		(fp_line
			(start -0.6096 -0.8636)
			(end 0.6096 -0.8636)
			(stroke
				(width 0.1524)
				(type default)
			)
			(layer "F.SilkS")
		)
		(fp_rect
			(start -0.3048 0.4953)
			(end 0.3048 -0.4953)
			(stroke
				(width 0)
				(type default)
			)
			(fill no)
			(layer "F.CrtYd")
		)
		(fp_poly
			(pts
				(xy -0.8636 1.143) (xy -0.8636 -1.1176) (xy 0.8636 -1.1176) (xy 0.8636 -0.00635) (xy 0.3048 -0.00635)
				(xy 0.3048 -0.4953) (xy -0.3048 -0.4953) (xy -0.3048 0.4953) (xy 0.3048 0.4953) (xy 0.3048 0.00635)
				(xy 0.8636 0.00635) (xy 0.8636 1.143)
			)
			(stroke
				(width 0)
				(type default)
			)
			(fill no)
			(layer "F.CrtYd")
		)
		(fp_rect
			(start -0.8636 1.143)
			(end 0.8636 -1.1176)
			(stroke
				(width 0)
				(type default)
			)
			(fill no)
			(layer "F.Fab")
		)
		(pad "B" smd rect
			(at -0.225044 0.450088 180)
			(size 0.254 0.3556)
			(layers "F.Cu" "F.Mask" "F.Paste")
			(net "MB0_TEMP")
		)
		(pad "C" smd rect
			(at 0 -0.450088 180)
			(size 0.4064 0.3048)
			(layers "F.Cu" "F.Mask" "F.Paste")
			(net "MB0_TEMP")
		)
		(pad "E" smd rect
			(at 0.225044 0.450088 180)
			(size 0.254 0.3556)
			(layers "F.Cu" "F.Mask" "F.Paste")
			(net "GND")
		)
	)
	(footprint ""
		(layer "F.Cu")
		(at 333.828136 -200.033128)
		(property "Reference" "R199"
			(at 0 0 0)
			(layer "F.SilkS")
			(hide yes)
			(effects
				(font
					(size 1.27 1.27)
				)
			)
		)
		(property "Value" "8K2R2J-3-GP"
			(at 0.064008 -3.993896 0)
			(unlocked yes)
			(layer "F.Fab")
			(hide yes)
			(effects
				(font
					(size 1.016 1.016)
					(thickness 0.1524)
				)
			)
		)
		(property "Device Type" "R402H16"
			(at 0.064008 -5.517896 0)
			(unlocked yes)
			(layer "F.Fab")
			(hide yes)
			(effects
				(font
					(size 1.016 1.016)
					(thickness 0.1524)
				)
			)
		)
		(duplicate_pad_numbers_are_jumpers no)
		(fp_line
			(start -0.508 -0.9398)
			(end -0.508 0.9398)
			(stroke
				(width 0.1524)
				(type default)
			)
			(layer "F.SilkS")
		)
		(fp_line
			(start 0.508 -0.9398)
			(end -0.508 -0.9398)
			(stroke
				(width 0.1524)
				(type default)
			)
			(layer "F.SilkS")
		)
		(fp_rect
			(start -0.508 0.9398)
			(end 0.508 -0.9398)
			(stroke
				(width 0)
				(type default)
			)
			(fill no)
			(layer "F.CrtYd")
		)
		(fp_rect
			(start -0.508 0.9398)
			(end 0.508 -0.9398)
			(stroke
				(width 0)
				(type default)
			)
			(fill no)
			(layer "F.Fab")
		)
		(pad "1" smd custom
			(at 0 -0.4445)
			(size 0.1397 0.1397)
			(layers "F.Cu" "F.Mask" "F.Paste")
			(net "EEPROM_A2_R")
			(options
				(clearance outline)
				(anchor circle)
			)
			(primitives
				(gr_poly
					(pts
						(arc
							(start -0.1778 -0.2794)
							(mid -0.249642 -0.249642)
							(end -0.2794 -0.1778)
						)
						(arc
							(start -0.2794 0.1778)
							(mid -0.249642 0.249642)
							(end -0.1778 0.2794)
						)
						(arc
							(start 0.1778 0.2794)
							(mid 0.249642 0.249642)
							(end 0.2794 0.1778)
						)
						(arc
							(start 0.2794 -0.1778)
							(mid 0.249642 -0.249642)
							(end 0.1778 -0.2794)
						)
					)
					(width 0)
					(fill yes)
				)
			)
		)
		(pad "2" smd custom
			(at 0 0.4445)
			(size 0.1397 0.1397)
			(layers "F.Cu" "F.Mask" "F.Paste")
			(net "GND")
			(options
				(clearance outline)
				(anchor circle)
			)
			(primitives
				(gr_poly
					(pts
						(arc
							(start -0.1778 -0.2794)
							(mid -0.249642 -0.249642)
							(end -0.2794 -0.1778)
						)
						(arc
							(start -0.2794 0.1778)
							(mid -0.249642 0.249642)
							(end -0.1778 0.2794)
						)
						(arc
							(start 0.1778 0.2794)
							(mid 0.249642 0.249642)
							(end 0.2794 0.1778)
						)
						(arc
							(start 0.2794 -0.1778)
							(mid 0.249642 -0.249642)
							(end 0.1778 -0.2794)
						)
					)
					(width 0)
					(fill yes)
				)
			)
		)
	)
	(footprint ""
		(layer "F.Cu")
		(at 265.049 -25.019 -90)
		(property "Reference" "PC57"
			(at 0 0 270)
			(layer "F.SilkS")
			(hide yes)
			(effects
				(font
					(size 1.27 1.27)
				)
			)
		)
		(property "Value" "SC100U6D3V6MX-GP"
			(at -0.0762 -5.1308 270)
			(unlocked yes)
			(layer "F.Fab")
			(hide yes)
			(effects
				(font
					(size 1.016 1.016)
					(thickness 0.1524)
				)
			)
		)
		(property "Device Type" "C1206H71"
			(at -0.127 -6.6548 270)
			(unlocked yes)
			(layer "F.Fab")
			(hide yes)
			(effects
				(font
					(size 1.016 1.016)
					(thickness 0.1524)
				)
			)
		)
		(duplicate_pad_numbers_are_jumpers no)
		(fp_line
			(start -1.016 2.2352)
			(end -1.016 0.8382)
			(stroke
				(width 0.1524)
				(type default)
			)
			(layer "F.SilkS")
		)
		(fp_line
			(start 1.016 2.2352)
			(end -1.016 2.2352)
			(stroke
				(width 0.1524)
				(type default)
			)
			(layer "F.SilkS")
		)
		(fp_line
			(start 1.016 0.8382)
			(end 1.016 2.2352)
			(stroke
				(width 0.1524)
				(type default)
			)
			(layer "F.SilkS")
		)
		(fp_line
			(start -1.016 -0.8382)
			(end -1.016 -2.2352)
			(stroke
				(width 0.1524)
				(type default)
			)
			(layer "F.SilkS")
		)
		(fp_line
			(start -1.016 -2.2352)
			(end 1.016 -2.2352)
			(stroke
				(width 0.1524)
				(type default)
			)
			(layer "F.SilkS")
		)
		(fp_line
			(start 1.016 -2.2352)
			(end 1.016 -0.8382)
			(stroke
				(width 0.1524)
				(type default)
			)
			(layer "F.SilkS")
		)
		(fp_rect
			(start -1.0922 2.3114)
			(end 1.0922 -2.3114)
			(stroke
				(width 0)
				(type default)
			)
			(fill no)
			(layer "F.CrtYd")
		)
		(fp_poly
			(pts
				(xy 1.0922 -2.3114) (xy 1.0922 2.3114) (xy -1.0922 2.3114) (xy -1.0922 -2.3114)
			)
			(stroke
				(width 0)
				(type default)
			)
			(fill no)
			(layer "F.Fab")
		)
		(pad "1" smd rect
			(at 0 -1.397 270)
			(size 1.651 1.27)
			(layers "F.Cu" "F.Mask" "F.Paste")
			(net "P1V8_STBY")
		)
		(pad "2" smd rect
			(at 0 1.397 270)
			(size 1.651 1.27)
			(layers "F.Cu" "F.Mask" "F.Paste")
			(net "GND")
		)
	)
	(footprint ""
		(layer "F.Cu")
		(at 308.991 -186.817 -90)
		(property "Reference" "SR847"
			(at 0 0 270)
			(layer "F.SilkS")
			(hide yes)
			(effects
				(font
					(size 1.27 1.27)
				)
			)
		)
		(property "Value" "4K75R2F-1-GP"
			(at 0.064008 -3.993896 270)
			(unlocked yes)
			(layer "F.Fab")
			(hide yes)
			(effects
				(font
					(size 1.016 1.016)
					(thickness 0.1524)
				)
			)
		)
		(property "Device Type" "R402H16"
			(at 0.064008 -5.517896 270)
			(unlocked yes)
			(layer "F.Fab")
			(hide yes)
			(effects
				(font
					(size 1.016 1.016)
					(thickness 0.1524)
				)
			)
		)
		(duplicate_pad_numbers_are_jumpers no)
		(fp_line
			(start -0.508 -0.9398)
			(end -0.508 0.9398)
			(stroke
				(width 0.1524)
				(type default)
			)
			(layer "F.SilkS")
		)
		(fp_line
			(start 0.508 -0.9398)
			(end -0.508 -0.9398)
			(stroke
				(width 0.1524)
				(type default)
			)
			(layer "F.SilkS")
		)
		(fp_rect
			(start -0.508 0.9398)
			(end 0.508 -0.9398)
			(stroke
				(width 0)
				(type default)
			)
			(fill no)
			(layer "F.CrtYd")
		)
		(fp_rect
			(start -0.508 0.9398)
			(end 0.508 -0.9398)
			(stroke
				(width 0)
				(type default)
			)
			(fill no)
			(layer "F.Fab")
		)
		(pad "1" smd custom
			(at 0 -0.4445 270)
			(size 0.1397 0.1397)
			(layers "F.Cu" "F.Mask" "F.Paste")
			(net "BMC_FW_DET_BOARD_VER_2")
			(options
				(clearance outline)
				(anchor circle)
			)
			(primitives
				(gr_poly
					(pts
						(arc
							(start -0.1778 -0.2794)
							(mid -0.249642 -0.249642)
							(end -0.2794 -0.1778)
						)
						(arc
							(start -0.2794 0.1778)
							(mid -0.249642 0.249642)
							(end -0.1778 0.2794)
						)
						(arc
							(start 0.1778 0.2794)
							(mid 0.249642 0.249642)
							(end 0.2794 0.1778)
						)
						(arc
							(start 0.2794 -0.1778)
							(mid 0.249642 -0.249642)
							(end 0.1778 -0.2794)
						)
					)
					(width 0)
					(fill yes)
				)
			)
		)
		(pad "2" smd custom
			(at 0 0.4445 270)
			(size 0.1397 0.1397)
			(layers "F.Cu" "F.Mask" "F.Paste")
			(net "GND")
			(options
				(clearance outline)
				(anchor circle)
			)
			(primitives
				(gr_poly
					(pts
						(arc
							(start -0.1778 -0.2794)
							(mid -0.249642 -0.249642)
							(end -0.2794 -0.1778)
						)
						(arc
							(start -0.2794 0.1778)
							(mid -0.249642 0.249642)
							(end -0.1778 0.2794)
						)
						(arc
							(start 0.1778 0.2794)
							(mid 0.249642 0.249642)
							(end 0.2794 0.1778)
						)
						(arc
							(start 0.2794 -0.1778)
							(mid 0.249642 -0.249642)
							(end 0.1778 -0.2794)
						)
					)
					(width 0)
					(fill yes)
				)
			)
		)
	)
	(footprint ""
		(layer "F.Cu")
		(at 173.628304 -24.113236 90)
		(property "Reference" "R404"
			(at 0 0 90)
			(layer "F.SilkS")
			(hide yes)
			(effects
				(font
					(size 1.27 1.27)
				)
			)
		)
		(property "Value" "49D9R2F-GP"
			(at 0.064008 -3.993896 90)
			(unlocked yes)
			(layer "F.Fab")
			(hide yes)
			(effects
				(font
					(size 1.016 1.016)
					(thickness 0.1524)
				)
			)
		)
		(property "Device Type" "R402H16"
			(at 0.064008 -5.517896 90)
			(unlocked yes)
			(layer "F.Fab")
			(hide yes)
			(effects
				(font
					(size 1.016 1.016)
					(thickness 0.1524)
				)
			)
		)
		(duplicate_pad_numbers_are_jumpers no)
		(fp_line
			(start 0.508 -0.9398)
			(end -0.508 -0.9398)
			(stroke
				(width 0.1524)
				(type default)
			)
			(layer "F.SilkS")
		)
		(fp_line
			(start -0.508 -0.9398)
			(end -0.508 0.9398)
			(stroke
				(width 0.1524)
				(type default)
			)
			(layer "F.SilkS")
		)
		(fp_rect
			(start -0.508 0.9398)
			(end 0.508 -0.9398)
			(stroke
				(width 0)
				(type default)
			)
			(fill no)
			(layer "F.CrtYd")
		)
		(fp_rect
			(start -0.508 0.9398)
			(end 0.508 -0.9398)
			(stroke
				(width 0)
				(type default)
			)
			(fill no)
			(layer "F.Fab")
		)
		(pad "1" smd custom
			(at 0 -0.4445 90)
			(size 0.1397 0.1397)
			(layers "F.Cu" "F.Mask" "F.Paste")
			(net "MOD_IMC_FAB_D_COP")
			(options
				(clearance outline)
				(anchor circle)
			)
			(primitives
				(gr_poly
					(pts
						(arc
							(start -0.1778 -0.2794)
							(mid -0.249642 -0.249642)
							(end -0.2794 -0.1778)
						)
						(arc
							(start -0.2794 0.1778)
							(mid -0.249642 0.249642)
							(end -0.1778 0.2794)
						)
						(arc
							(start 0.1778 0.2794)
							(mid 0.249642 0.249642)
							(end 0.2794 0.1778)
						)
						(arc
							(start 0.2794 -0.1778)
							(mid 0.249642 -0.249642)
							(end 0.1778 -0.2794)
						)
					)
					(width 0)
					(fill yes)
				)
			)
		)
		(pad "2" smd custom
			(at 0 0.4445 90)
			(size 0.1397 0.1397)
			(layers "F.Cu" "F.Mask" "F.Paste")
			(net "BCM5221_TX_C_DP")
			(options
				(clearance outline)
				(anchor circle)
			)
			(primitives
				(gr_poly
					(pts
						(arc
							(start -0.1778 -0.2794)
							(mid -0.249642 -0.249642)
							(end -0.2794 -0.1778)
						)
						(arc
							(start -0.2794 0.1778)
							(mid -0.249642 0.249642)
							(end -0.1778 0.2794)
						)
						(arc
							(start 0.1778 0.2794)
							(mid 0.249642 0.249642)
							(end 0.2794 0.1778)
						)
						(arc
							(start 0.2794 -0.1778)
							(mid 0.249642 -0.249642)
							(end 0.1778 -0.2794)
						)
					)
					(width 0)
					(fill yes)
				)
			)
		)
	)
	(footprint ""
		(layer "F.Cu")
		(at 332.431136 -197.366128 180)
		(property "Reference" "R193"
			(at 0 0 180)
			(layer "F.SilkS")
			(hide yes)
			(effects
				(font
					(size 1.27 1.27)
				)
			)
		)
		(property "Value" "8K2R2J-3-GP"
			(at 0.064008 -3.993896 180)
			(unlocked yes)
			(layer "F.Fab")
			(hide yes)
			(effects
				(font
					(size 1.016 1.016)
					(thickness 0.1524)
				)
			)
		)
		(property "Device Type" "R402H16"
			(at 0.064008 -5.517896 180)
			(unlocked yes)
			(layer "F.Fab")
			(hide yes)
			(effects
				(font
					(size 1.016 1.016)
					(thickness 0.1524)
				)
			)
		)
		(duplicate_pad_numbers_are_jumpers no)
		(fp_line
			(start 0.508 -0.9398)
			(end -0.508 -0.9398)
			(stroke
				(width 0.1524)
				(type default)
			)
			(layer "F.SilkS")
		)
		(fp_line
			(start -0.508 -0.9398)
			(end -0.508 0.9398)
			(stroke
				(width 0.1524)
				(type default)
			)
			(layer "F.SilkS")
		)
		(fp_rect
			(start -0.508 0.9398)
			(end 0.508 -0.9398)
			(stroke
				(width 0)
				(type default)
			)
			(fill no)
			(layer "F.CrtYd")
		)
		(fp_rect
			(start -0.508 0.9398)
			(end 0.508 -0.9398)
			(stroke
				(width 0)
				(type default)
			)
			(fill no)
			(layer "F.Fab")
		)
		(pad "1" smd custom
			(at 0 -0.4445 180)
			(size 0.1397 0.1397)
			(layers "F.Cu" "F.Mask" "F.Paste")
			(net "P3V3_STBY")
			(options
				(clearance outline)
				(anchor circle)
			)
			(primitives
				(gr_poly
					(pts
						(arc
							(start -0.1778 -0.2794)
							(mid -0.249642 -0.249642)
							(end -0.2794 -0.1778)
						)
						(arc
							(start -0.2794 0.1778)
							(mid -0.249642 0.249642)
							(end -0.1778 0.2794)
						)
						(arc
							(start 0.1778 0.2794)
							(mid 0.249642 0.249642)
							(end 0.2794 0.1778)
						)
						(arc
							(start 0.2794 -0.1778)
							(mid 0.249642 -0.249642)
							(end 0.1778 -0.2794)
						)
					)
					(width 0)
					(fill yes)
				)
			)
		)
		(pad "2" smd custom
			(at 0 0.4445 180)
			(size 0.1397 0.1397)
			(layers "F.Cu" "F.Mask" "F.Paste")
			(net "EEPROM_A1_R")
			(options
				(clearance outline)
				(anchor circle)
			)
			(primitives
				(gr_poly
					(pts
						(arc
							(start -0.1778 -0.2794)
							(mid -0.249642 -0.249642)
							(end -0.2794 -0.1778)
						)
						(arc
							(start -0.2794 0.1778)
							(mid -0.249642 0.249642)
							(end -0.1778 0.2794)
						)
						(arc
							(start 0.1778 0.2794)
							(mid 0.249642 0.249642)
							(end 0.2794 0.1778)
						)
						(arc
							(start 0.2794 -0.1778)
							(mid 0.249642 -0.249642)
							(end 0.1778 -0.2794)
						)
					)
					(width 0)
					(fill yes)
				)
			)
		)
	)
	(footprint ""
		(layer "F.Cu")
		(at 222.123 -96.393 -90)
		(property "Reference" "PR120"
			(at 0 0 270)
			(layer "F.SilkS")
			(hide yes)
			(effects
				(font
					(size 1.27 1.27)
				)
			)
		)
		(property "Value" "0R6J-3-GP"
			(at -0.0508 -4.8514 270)
			(unlocked yes)
			(layer "F.Fab")
			(hide yes)
			(effects
				(font
					(size 1.016 1.016)
					(thickness 0.1524)
				)
			)
		)
		(property "Device Type" "R1206H28"
			(at 0 -6.3754 270)
			(unlocked yes)
			(layer "F.Fab")
			(hide yes)
			(effects
				(font
					(size 1.016 1.016)
					(thickness 0.1524)
				)
			)
		)
		(duplicate_pad_numbers_are_jumpers no)
		(fp_line
			(start -1.016 2.2352)
			(end -1.016 -2.2352)
			(stroke
				(width 0.1524)
				(type default)
			)
			(layer "F.SilkS")
		)
		(fp_line
			(start 1.016 2.2352)
			(end -1.016 2.2352)
			(stroke
				(width 0.1524)
				(type default)
			)
			(layer "F.SilkS")
		)
		(fp_line
			(start -1.016 -2.2352)
			(end 1.016 -2.2352)
			(stroke
				(width 0.1524)
				(type default)
			)
			(layer "F.SilkS")
		)
		(fp_line
			(start 1.016 -2.2352)
			(end 1.016 2.2352)
			(stroke
				(width 0.1524)
				(type default)
			)
			(layer "F.SilkS")
		)
		(fp_rect
			(start -1.0922 2.3114)
			(end 1.0922 -2.3114)
			(stroke
				(width 0)
				(type default)
			)
			(fill no)
			(layer "F.CrtYd")
		)
		(fp_poly
			(pts
				(xy -1.0922 -2.3114) (xy 1.0922 -2.3114) (xy 1.0922 2.3114) (xy -1.0922 2.3114)
			)
			(stroke
				(width 0)
				(type default)
			)
			(fill no)
			(layer "F.Fab")
		)
		(pad "1" smd rect
			(at 0 -1.397 270)
			(size 1.651 1.27)
			(layers "F.Cu" "F.Mask" "F.Paste")
			(net "P1V8_STBY")
		)
		(pad "2" smd rect
			(at 0 1.397 270)
			(size 1.651 1.27)
			(layers "F.Cu" "F.Mask" "F.Paste")
			(net "TPS74801_P1V5_C_IN")
		)
	)
	(footprint ""
		(layer "F.Cu")
		(at 95.89897 -80.518 -90)
		(property "Reference" "SR800"
			(at 0 0 270)
			(layer "F.SilkS")
			(hide yes)
			(effects
				(font
					(size 1.27 1.27)
				)
			)
		)
		(property "Value" "4K75R2F-1-GP"
			(at 0.064008 -3.993896 270)
			(unlocked yes)
			(layer "F.Fab")
			(hide yes)
			(effects
				(font
					(size 1.016 1.016)
					(thickness 0.1524)
				)
			)
		)
		(property "Device Type" "R402H16"
			(at 0.064008 -5.517896 270)
			(unlocked yes)
			(layer "F.Fab")
			(hide yes)
			(effects
				(font
					(size 1.016 1.016)
					(thickness 0.1524)
				)
			)
		)
		(duplicate_pad_numbers_are_jumpers no)
		(fp_line
			(start -0.508 -0.9398)
			(end -0.508 0.9398)
			(stroke
				(width 0.1524)
				(type default)
			)
			(layer "F.SilkS")
		)
		(fp_line
			(start 0.508 -0.9398)
			(end -0.508 -0.9398)
			(stroke
				(width 0.1524)
				(type default)
			)
			(layer "F.SilkS")
		)
		(fp_rect
			(start -0.508 0.9398)
			(end 0.508 -0.9398)
			(stroke
				(width 0)
				(type default)
			)
			(fill no)
			(layer "F.CrtYd")
		)
		(fp_rect
			(start -0.508 0.9398)
			(end 0.508 -0.9398)
			(stroke
				(width 0)
				(type default)
			)
			(fill no)
			(layer "F.Fab")
		)
		(pad "1" smd custom
			(at 0 -0.4445 270)
			(size 0.1397 0.1397)
			(layers "F.Cu" "F.Mask" "F.Paste")
			(net "TMUX_EN")
			(options
				(clearance outline)
				(anchor circle)
			)
			(primitives
				(gr_poly
					(pts
						(arc
							(start -0.1778 -0.2794)
							(mid -0.249642 -0.249642)
							(end -0.2794 -0.1778)
						)
						(arc
							(start -0.2794 0.1778)
							(mid -0.249642 0.249642)
							(end -0.1778 0.2794)
						)
						(arc
							(start 0.1778 0.2794)
							(mid 0.249642 0.249642)
							(end 0.2794 0.1778)
						)
						(arc
							(start 0.2794 -0.1778)
							(mid 0.249642 -0.249642)
							(end 0.1778 -0.2794)
						)
					)
					(width 0)
					(fill yes)
				)
			)
		)
		(pad "2" smd custom
			(at 0 0.4445 270)
			(size 0.1397 0.1397)
			(layers "F.Cu" "F.Mask" "F.Paste")
			(net "GND")
			(options
				(clearance outline)
				(anchor circle)
			)
			(primitives
				(gr_poly
					(pts
						(arc
							(start -0.1778 -0.2794)
							(mid -0.249642 -0.249642)
							(end -0.2794 -0.1778)
						)
						(arc
							(start -0.2794 0.1778)
							(mid -0.249642 0.249642)
							(end -0.1778 0.2794)
						)
						(arc
							(start 0.1778 0.2794)
							(mid 0.249642 0.249642)
							(end 0.2794 0.1778)
						)
						(arc
							(start 0.2794 -0.1778)
							(mid 0.249642 -0.249642)
							(end 0.1778 -0.2794)
						)
					)
					(width 0)
					(fill yes)
				)
			)
		)
	)
	(footprint ""
		(layer "F.Cu")
		(at 220.091 -26.035)
		(property "Reference" "R7890"
			(at 0 0 0)
			(layer "F.SilkS")
			(hide yes)
			(effects
				(font
					(size 1.27 1.27)
				)
			)
		)
		(property "Value" "0R2J-2-GP"
			(at 0.064008 -3.993896 0)
			(unlocked yes)
			(layer "F.Fab")
			(hide yes)
			(effects
				(font
					(size 1.016 1.016)
					(thickness 0.1524)
				)
			)
		)
		(property "Device Type" "R402H16"
			(at 0.064008 -5.517896 0)
			(unlocked yes)
			(layer "F.Fab")
			(hide yes)
			(effects
				(font
					(size 1.016 1.016)
					(thickness 0.1524)
				)
			)
		)
		(duplicate_pad_numbers_are_jumpers no)
		(fp_line
			(start -0.508 -0.9398)
			(end -0.508 0.9398)
			(stroke
				(width 0.1524)
				(type default)
			)
			(layer "F.SilkS")
		)
		(fp_line
			(start 0.508 -0.9398)
			(end -0.508 -0.9398)
			(stroke
				(width 0.1524)
				(type default)
			)
			(layer "F.SilkS")
		)
		(fp_rect
			(start -0.508 0.9398)
			(end 0.508 -0.9398)
			(stroke
				(width 0)
				(type default)
			)
			(fill no)
			(layer "F.CrtYd")
		)
		(fp_rect
			(start -0.508 0.9398)
			(end 0.508 -0.9398)
			(stroke
				(width 0)
				(type default)
			)
			(fill no)
			(layer "F.Fab")
		)
		(pad "1" smd custom
			(at 0 -0.4445)
			(size 0.1397 0.1397)
			(layers "F.Cu" "F.Mask" "F.Paste")
			(net "PMU_PLTRST_N")
			(options
				(clearance outline)
				(anchor circle)
			)
			(primitives
				(gr_poly
					(pts
						(arc
							(start -0.1778 -0.2794)
							(mid -0.249642 -0.249642)
							(end -0.2794 -0.1778)
						)
						(arc
							(start -0.2794 0.1778)
							(mid -0.249642 0.249642)
							(end -0.1778 0.2794)
						)
						(arc
							(start 0.1778 0.2794)
							(mid 0.249642 0.249642)
							(end 0.2794 0.1778)
						)
						(arc
							(start 0.2794 -0.1778)
							(mid 0.249642 -0.249642)
							(end 0.1778 -0.2794)
						)
					)
					(width 0)
					(fill yes)
				)
			)
		)
		(pad "2" smd custom
			(at 0 0.4445)
			(size 0.1397 0.1397)
			(layers "F.Cu" "F.Mask" "F.Paste")
			(net "BMC_ID_LED_R")
			(options
				(clearance outline)
				(anchor circle)
			)
			(primitives
				(gr_poly
					(pts
						(arc
							(start -0.1778 -0.2794)
							(mid -0.249642 -0.249642)
							(end -0.2794 -0.1778)
						)
						(arc
							(start -0.2794 0.1778)
							(mid -0.249642 0.249642)
							(end -0.1778 0.2794)
						)
						(arc
							(start 0.1778 0.2794)
							(mid 0.249642 0.249642)
							(end 0.2794 0.1778)
						)
						(arc
							(start 0.2794 -0.1778)
							(mid 0.249642 -0.249642)
							(end 0.1778 -0.2794)
						)
					)
					(width 0)
					(fill yes)
				)
			)
		)
	)
	(footprint ""
		(layer "F.Cu")
		(at 258.699 -70.485 -90)
		(property "Reference" "C309"
			(at 0 0 270)
			(layer "F.SilkS")
			(hide yes)
			(effects
				(font
					(size 1.27 1.27)
				)
			)
		)
		(property "Value" "SCD1U25V2KX-2-GP"
			(at 1.1811 -2.7051 270)
			(unlocked yes)
			(layer "F.Fab")
			(hide yes)
			(effects
				(font
					(size 1.016 1.016)
					(thickness 0.1524)
				)
			)
		)
		(property "Device Type" "C402H22"
			(at 1.1811 -4.2291 270)
			(unlocked yes)
			(layer "F.Fab")
			(hide yes)
			(effects
				(font
					(size 1.016 1.016)
					(thickness 0.1524)
				)
			)
		)
		(duplicate_pad_numbers_are_jumpers no)
		(fp_rect
			(start -0.4318 0.9525)
			(end 0.4318 -0.9525)
			(stroke
				(width 0)
				(type default)
			)
			(fill no)
			(layer "F.CrtYd")
		)
		(fp_rect
			(start -0.4318 0.9525)
			(end 0.4318 -0.9525)
			(stroke
				(width 0)
				(type default)
			)
			(fill no)
			(layer "F.Fab")
		)
		(pad "1" smd custom
			(at 0 -0.4445 270)
			(size 0.1524 0.1524)
			(layers "F.Cu" "F.Mask" "F.Paste")
			(net "P12V_MSB")
			(options
				(clearance outline)
				(anchor circle)
			)
			(primitives
				(gr_poly
					(pts
						(arc
							(start 0.3048 -0.2032)
							(mid 0.275042 -0.275042)
							(end 0.2032 -0.3048)
						)
						(arc
							(start -0.2032 -0.3048)
							(mid -0.275042 -0.275042)
							(end -0.3048 -0.2032)
						)
						(arc
							(start -0.3048 0.2032)
							(mid -0.275042 0.275042)
							(end -0.2032 0.3048)
						)
						(arc
							(start 0.2032 0.3048)
							(mid 0.275042 0.275042)
							(end 0.3048 0.2032)
						)
					)
					(width 0)
					(fill yes)
				)
			)
		)
		(pad "2" smd custom
			(at 0 0.4445 270)
			(size 0.1524 0.1524)
			(layers "F.Cu" "F.Mask" "F.Paste")
			(net "GND")
			(options
				(clearance outline)
				(anchor circle)
			)
			(primitives
				(gr_poly
					(pts
						(arc
							(start 0.3048 -0.2032)
							(mid 0.275042 -0.275042)
							(end 0.2032 -0.3048)
						)
						(arc
							(start -0.2032 -0.3048)
							(mid -0.275042 -0.275042)
							(end -0.3048 -0.2032)
						)
						(arc
							(start -0.3048 0.2032)
							(mid -0.275042 0.275042)
							(end -0.2032 0.3048)
						)
						(arc
							(start 0.2032 0.3048)
							(mid 0.275042 0.275042)
							(end 0.3048 0.2032)
						)
					)
					(width 0)
					(fill yes)
				)
			)
		)
	)
	(footprint ""
		(layer "F.Cu")
		(at 119.64797 -74.6252 -90)
		(property "Reference" "SR597"
			(at 0 0 270)
			(layer "F.SilkS")
			(hide yes)
			(effects
				(font
					(size 1.27 1.27)
				)
			)
		)
		(property "Value" "0R2J-2-GP"
			(at 0.064008 -3.993896 270)
			(unlocked yes)
			(layer "F.Fab")
			(hide yes)
			(effects
				(font
					(size 1.016 1.016)
					(thickness 0.1524)
				)
			)
		)
		(property "Device Type" "R402H16"
			(at 0.064008 -5.517896 270)
			(unlocked yes)
			(layer "F.Fab")
			(hide yes)
			(effects
				(font
					(size 1.016 1.016)
					(thickness 0.1524)
				)
			)
		)
		(duplicate_pad_numbers_are_jumpers no)
		(fp_line
			(start -0.508 -0.9398)
			(end -0.508 0.9398)
			(stroke
				(width 0.1524)
				(type default)
			)
			(layer "F.SilkS")
		)
		(fp_line
			(start 0.508 -0.9398)
			(end -0.508 -0.9398)
			(stroke
				(width 0.1524)
				(type default)
			)
			(layer "F.SilkS")
		)
		(fp_rect
			(start -0.508 0.9398)
			(end 0.508 -0.9398)
			(stroke
				(width 0)
				(type default)
			)
			(fill no)
			(layer "F.CrtYd")
		)
		(fp_rect
			(start -0.508 0.9398)
			(end 0.508 -0.9398)
			(stroke
				(width 0)
				(type default)
			)
			(fill no)
			(layer "F.Fab")
		)
		(pad "1" smd custom
			(at 0 -0.4445 270)
			(size 0.1397 0.1397)
			(layers "F.Cu" "F.Mask" "F.Paste")
			(net "EXP_REF_CLK_N_R")
			(options
				(clearance outline)
				(anchor circle)
			)
			(primitives
				(gr_poly
					(pts
						(arc
							(start -0.1778 -0.2794)
							(mid -0.249642 -0.249642)
							(end -0.2794 -0.1778)
						)
						(arc
							(start -0.2794 0.1778)
							(mid -0.249642 0.249642)
							(end -0.1778 0.2794)
						)
						(arc
							(start 0.1778 0.2794)
							(mid 0.249642 0.249642)
							(end 0.2794 0.1778)
						)
						(arc
							(start 0.2794 -0.1778)
							(mid 0.249642 -0.249642)
							(end 0.1778 -0.2794)
						)
					)
					(width 0)
					(fill yes)
				)
			)
		)
		(pad "2" smd custom
			(at 0 0.4445 270)
			(size 0.1397 0.1397)
			(layers "F.Cu" "F.Mask" "F.Paste")
			(net "EXP_REF_CLK_N")
			(options
				(clearance outline)
				(anchor circle)
			)
			(primitives
				(gr_poly
					(pts
						(arc
							(start -0.1778 -0.2794)
							(mid -0.249642 -0.249642)
							(end -0.2794 -0.1778)
						)
						(arc
							(start -0.2794 0.1778)
							(mid -0.249642 0.249642)
							(end -0.1778 0.2794)
						)
						(arc
							(start 0.1778 0.2794)
							(mid 0.249642 0.249642)
							(end 0.2794 0.1778)
						)
						(arc
							(start 0.2794 -0.1778)
							(mid 0.249642 -0.249642)
							(end 0.1778 -0.2794)
						)
					)
					(width 0)
					(fill yes)
				)
			)
		)
	)
	(footprint ""
		(layer "F.Cu")
		(at 307.594 -216.789 180)
		(property "Reference" "R657"
			(at 0 0 180)
			(layer "F.SilkS")
			(hide yes)
			(effects
				(font
					(size 1.27 1.27)
				)
			)
		)
		(property "Value" "4K7R2F-GP"
			(at 0.064008 -3.993896 180)
			(unlocked yes)
			(layer "F.Fab")
			(hide yes)
			(effects
				(font
					(size 1.016 1.016)
					(thickness 0.1524)
				)
			)
		)
		(property "Device Type" "R402H16"
			(at 0.064008 -5.517896 180)
			(unlocked yes)
			(layer "F.Fab")
			(hide yes)
			(effects
				(font
					(size 1.016 1.016)
					(thickness 0.1524)
				)
			)
		)
		(duplicate_pad_numbers_are_jumpers no)
		(fp_line
			(start 0.508 -0.9398)
			(end -0.508 -0.9398)
			(stroke
				(width 0.1524)
				(type default)
			)
			(layer "F.SilkS")
		)
		(fp_line
			(start -0.508 -0.9398)
			(end -0.508 0.9398)
			(stroke
				(width 0.1524)
				(type default)
			)
			(layer "F.SilkS")
		)
		(fp_rect
			(start -0.508 0.9398)
			(end 0.508 -0.9398)
			(stroke
				(width 0)
				(type default)
			)
			(fill no)
			(layer "F.CrtYd")
		)
		(fp_rect
			(start -0.508 0.9398)
			(end 0.508 -0.9398)
			(stroke
				(width 0)
				(type default)
			)
			(fill no)
			(layer "F.Fab")
		)
		(pad "1" smd custom
			(at 0 -0.4445 180)
			(size 0.1397 0.1397)
			(layers "F.Cu" "F.Mask" "F.Paste")
			(net "P3V3_STBY")
			(options
				(clearance outline)
				(anchor circle)
			)
			(primitives
				(gr_poly
					(pts
						(arc
							(start -0.1778 -0.2794)
							(mid -0.249642 -0.249642)
							(end -0.2794 -0.1778)
						)
						(arc
							(start -0.2794 0.1778)
							(mid -0.249642 0.249642)
							(end -0.1778 0.2794)
						)
						(arc
							(start 0.1778 0.2794)
							(mid 0.249642 0.249642)
							(end 0.2794 0.1778)
						)
						(arc
							(start 0.2794 -0.1778)
							(mid 0.249642 -0.249642)
							(end 0.1778 -0.2794)
						)
					)
					(width 0)
					(fill yes)
				)
			)
		)
		(pad "2" smd custom
			(at 0 0.4445 180)
			(size 0.1397 0.1397)
			(layers "F.Cu" "F.Mask" "F.Paste")
			(net "BMC_DEBUG_OE_2_N")
			(options
				(clearance outline)
				(anchor circle)
			)
			(primitives
				(gr_poly
					(pts
						(arc
							(start -0.1778 -0.2794)
							(mid -0.249642 -0.249642)
							(end -0.2794 -0.1778)
						)
						(arc
							(start -0.2794 0.1778)
							(mid -0.249642 0.249642)
							(end -0.1778 0.2794)
						)
						(arc
							(start 0.1778 0.2794)
							(mid 0.249642 0.249642)
							(end 0.2794 0.1778)
						)
						(arc
							(start 0.2794 -0.1778)
							(mid 0.249642 -0.249642)
							(end 0.1778 -0.2794)
						)
					)
					(width 0)
					(fill yes)
				)
			)
		)
	)
	(footprint ""
		(layer "F.Cu")
		(at 103.867966 -63.8556 90)
		(property "Reference" "SC915"
			(at 0 0 90)
			(layer "F.SilkS")
			(hide yes)
			(effects
				(font
					(size 1.27 1.27)
				)
			)
		)
		(property "Value" "SC22U6D3V5MX-2GP"
			(at -0.0762 -6.1214 90)
			(unlocked yes)
			(layer "F.Fab")
			(hide yes)
			(effects
				(font
					(size 1.016 1.016)
					(thickness 0.1524)
				)
			)
		)
		(property "Device Type" "C805H58"
			(at -0.0762 -8.1534 90)
			(unlocked yes)
			(layer "F.Fab")
			(hide yes)
			(effects
				(font
					(size 1.016 1.016)
					(thickness 0.1524)
				)
			)
		)
		(duplicate_pad_numbers_are_jumpers no)
		(fp_line
			(start 0.635 0)
			(end -0.635 0)
			(stroke
				(width 0.508)
				(type default)
			)
			(layer "F.SilkS")
		)
		(fp_rect
			(start -0.9652 1.778)
			(end 0.9652 -1.778)
			(stroke
				(width 0)
				(type default)
			)
			(fill no)
			(layer "F.CrtYd")
		)
		(fp_poly
			(pts
				(xy -0.9652 -1.778) (xy 0.9652 -1.778) (xy 0.9652 1.778) (xy -0.9652 1.778)
			)
			(stroke
				(width 0)
				(type default)
			)
			(fill no)
			(layer "F.Fab")
		)
		(pad "1" smd rect
			(at 0 -0.9652 90)
			(size 1.397 1.143)
			(layers "F.Cu" "F.Mask" "F.Paste")
			(net "HM40ADC_VDDA")
		)
		(pad "2" smd rect
			(at 0 0.9652 90)
			(size 1.397 1.143)
			(layers "F.Cu" "F.Mask" "F.Paste")
			(net "GND")
		)
	)
	(footprint ""
		(layer "F.Cu")
		(at 103.51897 -114.3 180)
		(property "Reference" "SC1087"
			(at 0 0 180)
			(layer "F.SilkS")
			(hide yes)
			(effects
				(font
					(size 1.27 1.27)
				)
			)
		)
		(property "Value" "SCD01U10V1KX-GP"
			(at -2.8321 -1.7399 180)
			(unlocked yes)
			(layer "F.Fab")
			(hide yes)
			(effects
				(font
					(size 1.016 1.016)
					(thickness 0.1524)
				)
			)
		)
		(property "Device Type" "C0201H13"
			(at -2.8321 -3.2639 180)
			(unlocked yes)
			(layer "F.Fab")
			(hide yes)
			(effects
				(font
					(size 1.016 1.016)
					(thickness 0.1524)
				)
			)
		)
		(duplicate_pad_numbers_are_jumpers no)
		(fp_rect
			(start -0.2794 0.6477)
			(end 0.2794 -0.6477)
			(stroke
				(width 0)
				(type default)
			)
			(fill no)
			(layer "F.CrtYd")
		)
		(fp_rect
			(start -0.2794 0.6477)
			(end 0.2794 -0.6477)
			(stroke
				(width 0)
				(type default)
			)
			(fill no)
			(layer "F.Fab")
		)
		(pad "1" smd custom
			(at 0 -0.2794 180)
			(size 0.0762 0.0762)
			(layers "F.Cu" "F.Mask" "F.Paste")
			(net "SAS_HDD_TX10_N")
			(options
				(clearance outline)
				(anchor circle)
			)
			(primitives
				(gr_poly
					(pts
						(arc
							(start 0.1524 -0.127)
							(mid 0.137521 -0.162921)
							(end 0.1016 -0.1778)
						)
						(arc
							(start -0.1016 -0.1778)
							(mid -0.137521 -0.162921)
							(end -0.1524 -0.127)
						)
						(arc
							(start -0.1524 0.127)
							(mid -0.137521 0.162921)
							(end -0.1016 0.1778)
						)
						(arc
							(start 0.1016 0.1778)
							(mid 0.137521 0.162921)
							(end 0.1524 0.127)
						)
					)
					(width 0)
					(fill yes)
				)
			)
		)
		(pad "2" smd custom
			(at 0 0.2794 180)
			(size 0.0762 0.0762)
			(layers "F.Cu" "F.Mask" "F.Paste")
			(net "SAS_EXP_GF_TX_DN14")
			(options
				(clearance outline)
				(anchor circle)
			)
			(primitives
				(gr_poly
					(pts
						(arc
							(start 0.1524 -0.127)
							(mid 0.137521 -0.162921)
							(end 0.1016 -0.1778)
						)
						(arc
							(start -0.1016 -0.1778)
							(mid -0.137521 -0.162921)
							(end -0.1524 -0.127)
						)
						(arc
							(start -0.1524 0.127)
							(mid -0.137521 0.162921)
							(end -0.1016 0.1778)
						)
						(arc
							(start 0.1016 0.1778)
							(mid 0.137521 0.162921)
							(end 0.1524 0.127)
						)
					)
					(width 0)
					(fill yes)
				)
			)
		)
	)
	(footprint ""
		(layer "F.Cu")
		(at 281.051 -212.217)
		(property "Reference" "R125"
			(at 0 0 0)
			(layer "F.SilkS")
			(hide yes)
			(effects
				(font
					(size 1.27 1.27)
				)
			)
		)
		(property "Value" "0R2J-2-GP"
			(at 0.064008 -3.993896 0)
			(unlocked yes)
			(layer "F.Fab")
			(hide yes)
			(effects
				(font
					(size 1.016 1.016)
					(thickness 0.1524)
				)
			)
		)
		(property "Device Type" "R402H16"
			(at 0.064008 -5.517896 0)
			(unlocked yes)
			(layer "F.Fab")
			(hide yes)
			(effects
				(font
					(size 1.016 1.016)
					(thickness 0.1524)
				)
			)
		)
		(duplicate_pad_numbers_are_jumpers no)
		(fp_line
			(start -0.508 -0.9398)
			(end -0.508 0.9398)
			(stroke
				(width 0.1524)
				(type default)
			)
			(layer "F.SilkS")
		)
		(fp_line
			(start 0.508 -0.9398)
			(end -0.508 -0.9398)
			(stroke
				(width 0.1524)
				(type default)
			)
			(layer "F.SilkS")
		)
		(fp_rect
			(start -0.508 0.9398)
			(end 0.508 -0.9398)
			(stroke
				(width 0)
				(type default)
			)
			(fill no)
			(layer "F.CrtYd")
		)
		(fp_rect
			(start -0.508 0.9398)
			(end 0.508 -0.9398)
			(stroke
				(width 0)
				(type default)
			)
			(fill no)
			(layer "F.Fab")
		)
		(pad "1" smd custom
			(at 0 -0.4445)
			(size 0.1397 0.1397)
			(layers "F.Cu" "F.Mask" "F.Paste")
			(net "P1V26_STBY_PG")
			(options
				(clearance outline)
				(anchor circle)
			)
			(primitives
				(gr_poly
					(pts
						(arc
							(start -0.1778 -0.2794)
							(mid -0.249642 -0.249642)
							(end -0.2794 -0.1778)
						)
						(arc
							(start -0.2794 0.1778)
							(mid -0.249642 0.249642)
							(end -0.1778 0.2794)
						)
						(arc
							(start 0.1778 0.2794)
							(mid 0.249642 0.249642)
							(end 0.2794 0.1778)
						)
						(arc
							(start 0.2794 -0.1778)
							(mid 0.249642 -0.249642)
							(end 0.1778 -0.2794)
						)
					)
					(width 0)
					(fill yes)
				)
			)
		)
		(pad "2" smd custom
			(at 0 0.4445)
			(size 0.1397 0.1397)
			(layers "F.Cu" "F.Mask" "F.Paste")
			(net "FM_BMC_RESET_N")
			(options
				(clearance outline)
				(anchor circle)
			)
			(primitives
				(gr_poly
					(pts
						(arc
							(start -0.1778 -0.2794)
							(mid -0.249642 -0.249642)
							(end -0.2794 -0.1778)
						)
						(arc
							(start -0.2794 0.1778)
							(mid -0.249642 0.249642)
							(end -0.1778 0.2794)
						)
						(arc
							(start 0.1778 0.2794)
							(mid 0.249642 0.249642)
							(end 0.2794 0.1778)
						)
						(arc
							(start 0.2794 -0.1778)
							(mid 0.249642 -0.249642)
							(end 0.1778 -0.2794)
						)
					)
					(width 0)
					(fill yes)
				)
			)
		)
	)
	(footprint ""
		(layer "F.Cu")
		(at 97.663 -240.538 -90)
		(property "Reference" "SC435"
			(at 0 0 270)
			(layer "F.SilkS")
			(hide yes)
			(effects
				(font
					(size 1.27 1.27)
				)
			)
		)
		(property "Value" "SCD1U16V2KX-3GP"
			(at 1.1811 -2.7051 270)
			(unlocked yes)
			(layer "F.Fab")
			(hide yes)
			(effects
				(font
					(size 1.016 1.016)
					(thickness 0.1524)
				)
			)
		)
		(property "Device Type" "C402H22"
			(at 1.1811 -4.2291 270)
			(unlocked yes)
			(layer "F.Fab")
			(hide yes)
			(effects
				(font
					(size 1.016 1.016)
					(thickness 0.1524)
				)
			)
		)
		(duplicate_pad_numbers_are_jumpers no)
		(fp_rect
			(start -0.4318 0.9525)
			(end 0.4318 -0.9525)
			(stroke
				(width 0)
				(type default)
			)
			(fill no)
			(layer "F.CrtYd")
		)
		(fp_rect
			(start -0.4318 0.9525)
			(end 0.4318 -0.9525)
			(stroke
				(width 0)
				(type default)
			)
			(fill no)
			(layer "F.Fab")
		)
		(pad "1" smd custom
			(at 0 -0.4445 270)
			(size 0.1524 0.1524)
			(layers "F.Cu" "F.Mask" "F.Paste")
			(net "P3V3_STBY")
			(options
				(clearance outline)
				(anchor circle)
			)
			(primitives
				(gr_poly
					(pts
						(arc
							(start 0.3048 -0.2032)
							(mid 0.275042 -0.275042)
							(end 0.2032 -0.3048)
						)
						(arc
							(start -0.2032 -0.3048)
							(mid -0.275042 -0.275042)
							(end -0.3048 -0.2032)
						)
						(arc
							(start -0.3048 0.2032)
							(mid -0.275042 0.275042)
							(end -0.2032 0.3048)
						)
						(arc
							(start 0.2032 0.3048)
							(mid 0.275042 0.275042)
							(end 0.3048 0.2032)
						)
					)
					(width 0)
					(fill yes)
				)
			)
		)
		(pad "2" smd custom
			(at 0 0.4445 270)
			(size 0.1524 0.1524)
			(layers "F.Cu" "F.Mask" "F.Paste")
			(net "GND")
			(options
				(clearance outline)
				(anchor circle)
			)
			(primitives
				(gr_poly
					(pts
						(arc
							(start 0.3048 -0.2032)
							(mid 0.275042 -0.275042)
							(end 0.2032 -0.3048)
						)
						(arc
							(start -0.2032 -0.3048)
							(mid -0.275042 -0.275042)
							(end -0.3048 -0.2032)
						)
						(arc
							(start -0.3048 0.2032)
							(mid -0.275042 0.275042)
							(end -0.2032 0.3048)
						)
						(arc
							(start 0.2032 0.3048)
							(mid 0.275042 0.275042)
							(end 0.3048 0.2032)
						)
					)
					(width 0)
					(fill yes)
				)
			)
		)
	)
	(footprint ""
		(layer "F.Cu")
		(at 95.70847 -104.902 -90)
		(property "Reference" "SR793"
			(at 0 0 270)
			(layer "F.SilkS")
			(hide yes)
			(effects
				(font
					(size 1.27 1.27)
				)
			)
		)
		(property "Value" "0R2J-2-GP"
			(at 0.064008 -3.993896 270)
			(unlocked yes)
			(layer "F.Fab")
			(hide yes)
			(effects
				(font
					(size 1.016 1.016)
					(thickness 0.1524)
				)
			)
		)
		(property "Device Type" "R402H16"
			(at 0.064008 -5.517896 270)
			(unlocked yes)
			(layer "F.Fab")
			(hide yes)
			(effects
				(font
					(size 1.016 1.016)
					(thickness 0.1524)
				)
			)
		)
		(duplicate_pad_numbers_are_jumpers no)
		(fp_line
			(start -0.508 -0.9398)
			(end -0.508 0.9398)
			(stroke
				(width 0.1524)
				(type default)
			)
			(layer "F.SilkS")
		)
		(fp_line
			(start 0.508 -0.9398)
			(end -0.508 -0.9398)
			(stroke
				(width 0.1524)
				(type default)
			)
			(layer "F.SilkS")
		)
		(fp_rect
			(start -0.508 0.9398)
			(end 0.508 -0.9398)
			(stroke
				(width 0)
				(type default)
			)
			(fill no)
			(layer "F.CrtYd")
		)
		(fp_rect
			(start -0.508 0.9398)
			(end 0.508 -0.9398)
			(stroke
				(width 0)
				(type default)
			)
			(fill no)
			(layer "F.Fab")
		)
		(pad "1" smd custom
			(at 0 -0.4445 270)
			(size 0.1397 0.1397)
			(layers "F.Cu" "F.Mask" "F.Paste")
			(net "SMART_TX")
			(options
				(clearance outline)
				(anchor circle)
			)
			(primitives
				(gr_poly
					(pts
						(arc
							(start -0.1778 -0.2794)
							(mid -0.249642 -0.249642)
							(end -0.2794 -0.1778)
						)
						(arc
							(start -0.2794 0.1778)
							(mid -0.249642 0.249642)
							(end -0.1778 0.2794)
						)
						(arc
							(start 0.1778 0.2794)
							(mid 0.249642 0.249642)
							(end 0.2794 0.1778)
						)
						(arc
							(start 0.2794 -0.1778)
							(mid 0.249642 -0.249642)
							(end 0.1778 -0.2794)
						)
					)
					(width 0)
					(fill yes)
				)
			)
		)
		(pad "2" smd custom
			(at 0 0.4445 270)
			(size 0.1397 0.1397)
			(layers "F.Cu" "F.Mask" "F.Paste")
			(net "SAS_SMART_TX")
			(options
				(clearance outline)
				(anchor circle)
			)
			(primitives
				(gr_poly
					(pts
						(arc
							(start -0.1778 -0.2794)
							(mid -0.249642 -0.249642)
							(end -0.2794 -0.1778)
						)
						(arc
							(start -0.2794 0.1778)
							(mid -0.249642 0.249642)
							(end -0.1778 0.2794)
						)
						(arc
							(start 0.1778 0.2794)
							(mid 0.249642 0.249642)
							(end 0.2794 0.1778)
						)
						(arc
							(start 0.2794 -0.1778)
							(mid 0.249642 -0.249642)
							(end 0.1778 -0.2794)
						)
					)
					(width 0)
					(fill yes)
				)
			)
		)
	)
	(footprint ""
		(layer "F.Cu")
		(at 298.494958 -58.166 180)
		(property "Reference" "C284"
			(at 0 0 180)
			(layer "F.SilkS")
			(hide yes)
			(effects
				(font
					(size 1.27 1.27)
				)
			)
		)
		(property "Value" "SC1U25V3KX-GP"
			(at 0 -2.8194 180)
			(unlocked yes)
			(layer "F.Fab")
			(hide yes)
			(effects
				(font
					(size 1.016 1.016)
					(thickness 0.1524)
				)
			)
		)
		(property "Device Type" "C603H36"
			(at 0 -4.3434 180)
			(unlocked yes)
			(layer "F.Fab")
			(hide yes)
			(effects
				(font
					(size 1.016 1.016)
					(thickness 0.1524)
				)
			)
		)
		(duplicate_pad_numbers_are_jumpers no)
		(fp_line
			(start 0.508 0)
			(end -0.508 0)
			(stroke
				(width 0.2032)
				(type default)
			)
			(layer "F.SilkS")
		)
		(fp_rect
			(start -0.5842 1.3335)
			(end 0.5842 -1.3335)
			(stroke
				(width 0)
				(type default)
			)
			(fill no)
			(layer "F.CrtYd")
		)
		(fp_rect
			(start -0.5842 1.3335)
			(end 0.5842 -1.3335)
			(stroke
				(width 0)
				(type default)
			)
			(fill no)
			(layer "F.Fab")
		)
		(pad "1" smd custom
			(at 0 -0.762 180)
			(size 0.2159 0.2159)
			(layers "F.Cu" "F.Mask" "F.Paste")
			(net "P3V3_STBY")
			(options
				(clearance outline)
				(anchor circle)
			)
			(primitives
				(gr_poly
					(pts
						(arc
							(start -0.3302 -0.4318)
							(mid -0.402042 -0.402042)
							(end -0.4318 -0.3302)
						)
						(arc
							(start -0.4318 0.3302)
							(mid -0.402042 0.402042)
							(end -0.3302 0.4318)
						)
						(arc
							(start 0.3302 0.4318)
							(mid 0.402042 0.402042)
							(end 0.4318 0.3302)
						)
						(arc
							(start 0.4318 -0.3302)
							(mid 0.402042 -0.402042)
							(end 0.3302 -0.4318)
						)
					)
					(width 0)
					(fill yes)
				)
			)
		)
		(pad "2" smd custom
			(at 0 0.762 180)
			(size 0.2159 0.2159)
			(layers "F.Cu" "F.Mask" "F.Paste")
			(net "GND")
			(options
				(clearance outline)
				(anchor circle)
			)
			(primitives
				(gr_poly
					(pts
						(arc
							(start -0.3302 -0.4318)
							(mid -0.402042 -0.402042)
							(end -0.4318 -0.3302)
						)
						(arc
							(start -0.4318 0.3302)
							(mid -0.402042 0.402042)
							(end -0.3302 0.4318)
						)
						(arc
							(start 0.3302 0.4318)
							(mid 0.402042 0.402042)
							(end 0.4318 0.3302)
						)
						(arc
							(start 0.4318 -0.3302)
							(mid 0.402042 -0.402042)
							(end 0.3302 -0.4318)
						)
					)
					(width 0)
					(fill yes)
				)
			)
		)
	)
	(footprint ""
		(layer "F.Cu")
		(at 39.51097 -134.62 90)
		(property "Reference" "SR857"
			(at 0 0 90)
			(layer "F.SilkS")
			(hide yes)
			(effects
				(font
					(size 1.27 1.27)
				)
			)
		)
		(property "Value" "4K7R2F-GP"
			(at 0.064008 -3.993896 90)
			(unlocked yes)
			(layer "F.Fab")
			(hide yes)
			(effects
				(font
					(size 1.016 1.016)
					(thickness 0.1524)
				)
			)
		)
		(property "Device Type" "R402H16"
			(at 0.064008 -5.517896 90)
			(unlocked yes)
			(layer "F.Fab")
			(hide yes)
			(effects
				(font
					(size 1.016 1.016)
					(thickness 0.1524)
				)
			)
		)
		(duplicate_pad_numbers_are_jumpers no)
		(fp_line
			(start 0.508 -0.9398)
			(end -0.508 -0.9398)
			(stroke
				(width 0.1524)
				(type default)
			)
			(layer "F.SilkS")
		)
		(fp_line
			(start -0.508 -0.9398)
			(end -0.508 0.9398)
			(stroke
				(width 0.1524)
				(type default)
			)
			(layer "F.SilkS")
		)
		(fp_rect
			(start -0.508 0.9398)
			(end 0.508 -0.9398)
			(stroke
				(width 0)
				(type default)
			)
			(fill no)
			(layer "F.CrtYd")
		)
		(fp_rect
			(start -0.508 0.9398)
			(end 0.508 -0.9398)
			(stroke
				(width 0)
				(type default)
			)
			(fill no)
			(layer "F.Fab")
		)
		(pad "1" smd custom
			(at 0 -0.4445 90)
			(size 0.1397 0.1397)
			(layers "F.Cu" "F.Mask" "F.Paste")
			(net "P3V3_STBY")
			(options
				(clearance outline)
				(anchor circle)
			)
			(primitives
				(gr_poly
					(pts
						(arc
							(start -0.1778 -0.2794)
							(mid -0.249642 -0.249642)
							(end -0.2794 -0.1778)
						)
						(arc
							(start -0.2794 0.1778)
							(mid -0.249642 0.249642)
							(end -0.1778 0.2794)
						)
						(arc
							(start 0.1778 0.2794)
							(mid 0.249642 0.249642)
							(end 0.2794 0.1778)
						)
						(arc
							(start 0.2794 -0.1778)
							(mid 0.249642 -0.249642)
							(end 0.1778 -0.2794)
						)
					)
					(width 0)
					(fill yes)
				)
			)
		)
		(pad "2" smd custom
			(at 0 0.4445 90)
			(size 0.1397 0.1397)
			(layers "F.Cu" "F.Mask" "F.Paste")
			(net "P3V3_STBY_R5")
			(options
				(clearance outline)
				(anchor circle)
			)
			(primitives
				(gr_poly
					(pts
						(arc
							(start -0.1778 -0.2794)
							(mid -0.249642 -0.249642)
							(end -0.2794 -0.1778)
						)
						(arc
							(start -0.2794 0.1778)
							(mid -0.249642 0.249642)
							(end -0.1778 0.2794)
						)
						(arc
							(start 0.1778 0.2794)
							(mid 0.249642 0.249642)
							(end 0.2794 0.1778)
						)
						(arc
							(start 0.2794 -0.1778)
							(mid 0.249642 -0.249642)
							(end 0.1778 -0.2794)
						)
					)
					(width 0)
					(fill yes)
				)
			)
		)
	)
	(footprint ""
		(layer "F.Cu")
		(at 345.596718 -157.838648 180)
		(property "Reference" "R553"
			(at 0 0 180)
			(layer "F.SilkS")
			(hide yes)
			(effects
				(font
					(size 1.27 1.27)
				)
			)
		)
		(property "Value" "4K7R2F-GP"
			(at 0.064008 -3.993896 180)
			(unlocked yes)
			(layer "F.Fab")
			(hide yes)
			(effects
				(font
					(size 1.016 1.016)
					(thickness 0.1524)
				)
			)
		)
		(property "Device Type" "R402H16"
			(at 0.064008 -5.517896 180)
			(unlocked yes)
			(layer "F.Fab")
			(hide yes)
			(effects
				(font
					(size 1.016 1.016)
					(thickness 0.1524)
				)
			)
		)
		(duplicate_pad_numbers_are_jumpers no)
		(fp_line
			(start 0.508 -0.9398)
			(end -0.508 -0.9398)
			(stroke
				(width 0.1524)
				(type default)
			)
			(layer "F.SilkS")
		)
		(fp_line
			(start -0.508 -0.9398)
			(end -0.508 0.9398)
			(stroke
				(width 0.1524)
				(type default)
			)
			(layer "F.SilkS")
		)
		(fp_rect
			(start -0.508 0.9398)
			(end 0.508 -0.9398)
			(stroke
				(width 0)
				(type default)
			)
			(fill no)
			(layer "F.CrtYd")
		)
		(fp_rect
			(start -0.508 0.9398)
			(end 0.508 -0.9398)
			(stroke
				(width 0)
				(type default)
			)
			(fill no)
			(layer "F.Fab")
		)
		(pad "1" smd custom
			(at 0 -0.4445 180)
			(size 0.1397 0.1397)
			(layers "F.Cu" "F.Mask" "F.Paste")
			(net "USB_EN_1")
			(options
				(clearance outline)
				(anchor circle)
			)
			(primitives
				(gr_poly
					(pts
						(arc
							(start -0.1778 -0.2794)
							(mid -0.249642 -0.249642)
							(end -0.2794 -0.1778)
						)
						(arc
							(start -0.2794 0.1778)
							(mid -0.249642 0.249642)
							(end -0.1778 0.2794)
						)
						(arc
							(start 0.1778 0.2794)
							(mid 0.249642 0.249642)
							(end 0.2794 0.1778)
						)
						(arc
							(start 0.2794 -0.1778)
							(mid 0.249642 -0.249642)
							(end 0.1778 -0.2794)
						)
					)
					(width 0)
					(fill yes)
				)
			)
		)
		(pad "2" smd custom
			(at 0 0.4445 180)
			(size 0.1397 0.1397)
			(layers "F.Cu" "F.Mask" "F.Paste")
			(net "GND")
			(options
				(clearance outline)
				(anchor circle)
			)
			(primitives
				(gr_poly
					(pts
						(arc
							(start -0.1778 -0.2794)
							(mid -0.249642 -0.249642)
							(end -0.2794 -0.1778)
						)
						(arc
							(start -0.2794 0.1778)
							(mid -0.249642 0.249642)
							(end -0.1778 0.2794)
						)
						(arc
							(start 0.1778 0.2794)
							(mid 0.249642 0.249642)
							(end 0.2794 0.1778)
						)
						(arc
							(start 0.2794 -0.1778)
							(mid 0.249642 -0.249642)
							(end 0.1778 -0.2794)
						)
					)
					(width 0)
					(fill yes)
				)
			)
		)
	)
	(footprint ""
		(layer "F.Cu")
		(at 223.647 -84.963 90)
		(property "Reference" "SR926"
			(at 0 0 90)
			(layer "F.SilkS")
			(hide yes)
			(effects
				(font
					(size 1.27 1.27)
				)
			)
		)
		(property "Value" "0R2J-2-GP"
			(at 0.064008 -3.993896 90)
			(unlocked yes)
			(layer "F.Fab")
			(hide yes)
			(effects
				(font
					(size 1.016 1.016)
					(thickness 0.1524)
				)
			)
		)
		(property "Device Type" "R402H16"
			(at 0.064008 -5.517896 90)
			(unlocked yes)
			(layer "F.Fab")
			(hide yes)
			(effects
				(font
					(size 1.016 1.016)
					(thickness 0.1524)
				)
			)
		)
		(duplicate_pad_numbers_are_jumpers no)
		(fp_line
			(start 0.508 -0.9398)
			(end -0.508 -0.9398)
			(stroke
				(width 0.1524)
				(type default)
			)
			(layer "F.SilkS")
		)
		(fp_line
			(start -0.508 -0.9398)
			(end -0.508 0.9398)
			(stroke
				(width 0.1524)
				(type default)
			)
			(layer "F.SilkS")
		)
		(fp_rect
			(start -0.508 0.9398)
			(end 0.508 -0.9398)
			(stroke
				(width 0)
				(type default)
			)
			(fill no)
			(layer "F.CrtYd")
		)
		(fp_rect
			(start -0.508 0.9398)
			(end 0.508 -0.9398)
			(stroke
				(width 0)
				(type default)
			)
			(fill no)
			(layer "F.Fab")
		)
		(pad "1" smd custom
			(at 0 -0.4445 90)
			(size 0.1397 0.1397)
			(layers "F.Cu" "F.Mask" "F.Paste")
			(net "IOC_UART_0_RX_R")
			(options
				(clearance outline)
				(anchor circle)
			)
			(primitives
				(gr_poly
					(pts
						(arc
							(start -0.1778 -0.2794)
							(mid -0.249642 -0.249642)
							(end -0.2794 -0.1778)
						)
						(arc
							(start -0.2794 0.1778)
							(mid -0.249642 0.249642)
							(end -0.1778 0.2794)
						)
						(arc
							(start 0.1778 0.2794)
							(mid 0.249642 0.249642)
							(end 0.2794 0.1778)
						)
						(arc
							(start 0.2794 -0.1778)
							(mid 0.249642 -0.249642)
							(end 0.1778 -0.2794)
						)
					)
					(width 0)
					(fill yes)
				)
			)
		)
		(pad "2" smd custom
			(at 0 0.4445 90)
			(size 0.1397 0.1397)
			(layers "F.Cu" "F.Mask" "F.Paste")
			(net "IOC_UART_0_RX")
			(options
				(clearance outline)
				(anchor circle)
			)
			(primitives
				(gr_poly
					(pts
						(arc
							(start -0.1778 -0.2794)
							(mid -0.249642 -0.249642)
							(end -0.2794 -0.1778)
						)
						(arc
							(start -0.2794 0.1778)
							(mid -0.249642 0.249642)
							(end -0.1778 0.2794)
						)
						(arc
							(start 0.1778 0.2794)
							(mid 0.249642 0.249642)
							(end 0.2794 0.1778)
						)
						(arc
							(start 0.2794 -0.1778)
							(mid 0.249642 -0.249642)
							(end 0.1778 -0.2794)
						)
					)
					(width 0)
					(fill yes)
				)
			)
		)
	)
	(footprint ""
		(layer "F.Cu")
		(at 86.49716 -35.306 -90)
		(property "Reference" "SC881"
			(at 0 0 270)
			(layer "F.SilkS")
			(hide yes)
			(effects
				(font
					(size 1.27 1.27)
				)
			)
		)
		(property "Value" "SCD01U10V1KX-GP"
			(at -2.8321 -1.7399 270)
			(unlocked yes)
			(layer "F.Fab")
			(hide yes)
			(effects
				(font
					(size 1.016 1.016)
					(thickness 0.1524)
				)
			)
		)
		(property "Device Type" "C0201H13"
			(at -2.8321 -3.2639 270)
			(unlocked yes)
			(layer "F.Fab")
			(hide yes)
			(effects
				(font
					(size 1.016 1.016)
					(thickness 0.1524)
				)
			)
		)
		(duplicate_pad_numbers_are_jumpers no)
		(fp_rect
			(start -0.2794 0.6477)
			(end 0.2794 -0.6477)
			(stroke
				(width 0)
				(type default)
			)
			(fill no)
			(layer "F.CrtYd")
		)
		(fp_rect
			(start -0.2794 0.6477)
			(end 0.2794 -0.6477)
			(stroke
				(width 0)
				(type default)
			)
			(fill no)
			(layer "F.Fab")
		)
		(pad "1" smd custom
			(at 0 -0.2794 270)
			(size 0.0762 0.0762)
			(layers "F.Cu" "F.Mask" "F.Paste")
			(net "SAS3008_RAID_TX_C_P1")
			(options
				(clearance outline)
				(anchor circle)
			)
			(primitives
				(gr_poly
					(pts
						(arc
							(start 0.1524 -0.127)
							(mid 0.137521 -0.162921)
							(end 0.1016 -0.1778)
						)
						(arc
							(start -0.1016 -0.1778)
							(mid -0.137521 -0.162921)
							(end -0.1524 -0.127)
						)
						(arc
							(start -0.1524 0.127)
							(mid -0.137521 0.162921)
							(end -0.1016 0.1778)
						)
						(arc
							(start 0.1016 0.1778)
							(mid 0.137521 0.162921)
							(end 0.1524 0.127)
						)
					)
					(width 0)
					(fill yes)
				)
			)
		)
		(pad "2" smd custom
			(at 0 0.2794 270)
			(size 0.0762 0.0762)
			(layers "F.Cu" "F.Mask" "F.Paste")
			(net "SAS3008_RAID_TX_P1")
			(options
				(clearance outline)
				(anchor circle)
			)
			(primitives
				(gr_poly
					(pts
						(arc
							(start 0.1524 -0.127)
							(mid 0.137521 -0.162921)
							(end 0.1016 -0.1778)
						)
						(arc
							(start -0.1016 -0.1778)
							(mid -0.137521 -0.162921)
							(end -0.1524 -0.127)
						)
						(arc
							(start -0.1524 0.127)
							(mid -0.137521 0.162921)
							(end -0.1016 0.1778)
						)
						(arc
							(start 0.1016 0.1778)
							(mid 0.137521 0.162921)
							(end 0.1524 0.127)
						)
					)
					(width 0)
					(fill yes)
				)
			)
		)
	)
	(footprint ""
		(layer "F.Cu")
		(at 99.45497 -118.3005 180)
		(property "Reference" "SR747"
			(at 0 0 180)
			(layer "F.SilkS")
			(hide yes)
			(effects
				(font
					(size 1.27 1.27)
				)
			)
		)
		(property "Value" "4K7R2F-GP"
			(at 0.064008 -3.993896 180)
			(unlocked yes)
			(layer "F.Fab")
			(hide yes)
			(effects
				(font
					(size 1.016 1.016)
					(thickness 0.1524)
				)
			)
		)
		(property "Device Type" "R402H16"
			(at 0.064008 -5.517896 180)
			(unlocked yes)
			(layer "F.Fab")
			(hide yes)
			(effects
				(font
					(size 1.016 1.016)
					(thickness 0.1524)
				)
			)
		)
		(duplicate_pad_numbers_are_jumpers no)
		(fp_line
			(start 0.508 -0.9398)
			(end -0.508 -0.9398)
			(stroke
				(width 0.1524)
				(type default)
			)
			(layer "F.SilkS")
		)
		(fp_line
			(start -0.508 -0.9398)
			(end -0.508 0.9398)
			(stroke
				(width 0.1524)
				(type default)
			)
			(layer "F.SilkS")
		)
		(fp_rect
			(start -0.508 0.9398)
			(end 0.508 -0.9398)
			(stroke
				(width 0)
				(type default)
			)
			(fill no)
			(layer "F.CrtYd")
		)
		(fp_rect
			(start -0.508 0.9398)
			(end 0.508 -0.9398)
			(stroke
				(width 0)
				(type default)
			)
			(fill no)
			(layer "F.Fab")
		)
		(pad "1" smd custom
			(at 0 -0.4445 180)
			(size 0.1397 0.1397)
			(layers "F.Cu" "F.Mask" "F.Paste")
			(net "SIO_D_IN")
			(options
				(clearance outline)
				(anchor circle)
			)
			(primitives
				(gr_poly
					(pts
						(arc
							(start -0.1778 -0.2794)
							(mid -0.249642 -0.249642)
							(end -0.2794 -0.1778)
						)
						(arc
							(start -0.2794 0.1778)
							(mid -0.249642 0.249642)
							(end -0.1778 0.2794)
						)
						(arc
							(start 0.1778 0.2794)
							(mid 0.249642 0.249642)
							(end 0.2794 0.1778)
						)
						(arc
							(start 0.2794 -0.1778)
							(mid 0.249642 -0.249642)
							(end 0.1778 -0.2794)
						)
					)
					(width 0)
					(fill yes)
				)
			)
		)
		(pad "2" smd custom
			(at 0 0.4445 180)
			(size 0.1397 0.1397)
			(layers "F.Cu" "F.Mask" "F.Paste")
			(net "P1V8_E")
			(options
				(clearance outline)
				(anchor circle)
			)
			(primitives
				(gr_poly
					(pts
						(arc
							(start -0.1778 -0.2794)
							(mid -0.249642 -0.249642)
							(end -0.2794 -0.1778)
						)
						(arc
							(start -0.2794 0.1778)
							(mid -0.249642 0.249642)
							(end -0.1778 0.2794)
						)
						(arc
							(start 0.1778 0.2794)
							(mid 0.249642 0.249642)
							(end 0.2794 0.1778)
						)
						(arc
							(start 0.2794 -0.1778)
							(mid 0.249642 -0.249642)
							(end 0.1778 -0.2794)
						)
					)
					(width 0)
					(fill yes)
				)
			)
		)
	)
	(footprint ""
		(layer "F.Cu")
		(at 97.54997 -86.233)
		(property "Reference" "STP144"
			(at 0 0 0)
			(layer "F.SilkS")
			(hide yes)
			(effects
				(font
					(size 1.27 1.27)
				)
			)
		)
		(property "Value" "TPAD28"
			(at 0.0127 -1.8034 0)
			(unlocked yes)
			(layer "F.Fab")
			(hide yes)
			(effects
				(font
					(size 1.016 1.016)
					(thickness 0.1524)
				)
			)
		)
		(property "Device Type" "TPAD28"
			(at 0.0127 -3.3274 0)
			(unlocked yes)
			(layer "F.Fab")
			(hide yes)
			(effects
				(font
					(size 1.016 1.016)
					(thickness 0.1524)
				)
			)
		)
		(duplicate_pad_numbers_are_jumpers no)
		(fp_poly
			(pts
				(arc
					(start 0.3556 0)
					(mid -0.3556 0)
					(end 0.3556 0)
				)
			)
			(stroke
				(width 0)
				(type default)
			)
			(fill no)
			(layer "F.CrtYd")
		)
		(fp_poly
			(pts
				(arc
					(start 0.6096 0)
					(mid -0.6096 0)
					(end 0.6096 0)
				)
			)
			(stroke
				(width 0)
				(type default)
			)
			(fill no)
			(layer "F.Fab")
		)
		(pad "1" smd circle
			(at 0 0)
			(size 0.7112 0.7112)
			(layers "F.Cu" "F.Mask" "F.Paste")
			(net "SXP_ACTIVE_1")
		)
	)
	(footprint ""
		(layer "F.Cu")
		(at 82.43697 -129.159)
		(property "Reference" "SC307"
			(at 0 0 0)
			(layer "F.SilkS")
			(hide yes)
			(effects
				(font
					(size 1.27 1.27)
				)
			)
		)
		(property "Value" "SCD1U16V2KX-3GP"
			(at 1.1811 -2.7051 0)
			(unlocked yes)
			(layer "F.Fab")
			(hide yes)
			(effects
				(font
					(size 1.016 1.016)
					(thickness 0.1524)
				)
			)
		)
		(property "Device Type" "C402H22"
			(at 1.1811 -4.2291 0)
			(unlocked yes)
			(layer "F.Fab")
			(hide yes)
			(effects
				(font
					(size 1.016 1.016)
					(thickness 0.1524)
				)
			)
		)
		(duplicate_pad_numbers_are_jumpers no)
		(fp_rect
			(start -0.4318 0.9525)
			(end 0.4318 -0.9525)
			(stroke
				(width 0)
				(type default)
			)
			(fill no)
			(layer "F.CrtYd")
		)
		(fp_rect
			(start -0.4318 0.9525)
			(end 0.4318 -0.9525)
			(stroke
				(width 0)
				(type default)
			)
			(fill no)
			(layer "F.Fab")
		)
		(pad "1" smd custom
			(at 0 -0.4445)
			(size 0.1524 0.1524)
			(layers "F.Cu" "F.Mask" "F.Paste")
			(net "P1V8_E")
			(options
				(clearance outline)
				(anchor circle)
			)
			(primitives
				(gr_poly
					(pts
						(arc
							(start 0.3048 -0.2032)
							(mid 0.275042 -0.275042)
							(end 0.2032 -0.3048)
						)
						(arc
							(start -0.2032 -0.3048)
							(mid -0.275042 -0.275042)
							(end -0.3048 -0.2032)
						)
						(arc
							(start -0.3048 0.2032)
							(mid -0.275042 0.275042)
							(end -0.2032 0.3048)
						)
						(arc
							(start 0.2032 0.3048)
							(mid 0.275042 0.275042)
							(end 0.3048 0.2032)
						)
					)
					(width 0)
					(fill yes)
				)
			)
		)
		(pad "2" smd custom
			(at 0 0.4445)
			(size 0.1524 0.1524)
			(layers "F.Cu" "F.Mask" "F.Paste")
			(net "GND")
			(options
				(clearance outline)
				(anchor circle)
			)
			(primitives
				(gr_poly
					(pts
						(arc
							(start 0.3048 -0.2032)
							(mid 0.275042 -0.275042)
							(end 0.2032 -0.3048)
						)
						(arc
							(start -0.2032 -0.3048)
							(mid -0.275042 -0.275042)
							(end -0.3048 -0.2032)
						)
						(arc
							(start -0.3048 0.2032)
							(mid -0.275042 0.275042)
							(end -0.2032 0.3048)
						)
						(arc
							(start 0.2032 0.3048)
							(mid 0.275042 0.275042)
							(end 0.3048 0.2032)
						)
					)
					(width 0)
					(fill yes)
				)
			)
		)
	)
	(footprint ""
		(layer "F.Cu")
		(at 107.07497 -114.3 180)
		(property "Reference" "SC1084"
			(at 0 0 180)
			(layer "F.SilkS")
			(hide yes)
			(effects
				(font
					(size 1.27 1.27)
				)
			)
		)
		(property "Value" "SCD01U10V1KX-GP"
			(at -2.8321 -1.7399 180)
			(unlocked yes)
			(layer "F.Fab")
			(hide yes)
			(effects
				(font
					(size 1.016 1.016)
					(thickness 0.1524)
				)
			)
		)
		(property "Device Type" "C0201H13"
			(at -2.8321 -3.2639 180)
			(unlocked yes)
			(layer "F.Fab")
			(hide yes)
			(effects
				(font
					(size 1.016 1.016)
					(thickness 0.1524)
				)
			)
		)
		(duplicate_pad_numbers_are_jumpers no)
		(fp_rect
			(start -0.2794 0.6477)
			(end 0.2794 -0.6477)
			(stroke
				(width 0)
				(type default)
			)
			(fill no)
			(layer "F.CrtYd")
		)
		(fp_rect
			(start -0.2794 0.6477)
			(end 0.2794 -0.6477)
			(stroke
				(width 0)
				(type default)
			)
			(fill no)
			(layer "F.Fab")
		)
		(pad "1" smd custom
			(at 0 -0.2794 180)
			(size 0.0762 0.0762)
			(layers "F.Cu" "F.Mask" "F.Paste")
			(net "SAS_HDD_TX8_N")
			(options
				(clearance outline)
				(anchor circle)
			)
			(primitives
				(gr_poly
					(pts
						(arc
							(start 0.1524 -0.127)
							(mid 0.137521 -0.162921)
							(end 0.1016 -0.1778)
						)
						(arc
							(start -0.1016 -0.1778)
							(mid -0.137521 -0.162921)
							(end -0.1524 -0.127)
						)
						(arc
							(start -0.1524 0.127)
							(mid -0.137521 0.162921)
							(end -0.1016 0.1778)
						)
						(arc
							(start 0.1016 0.1778)
							(mid 0.137521 0.162921)
							(end 0.1524 0.127)
						)
					)
					(width 0)
					(fill yes)
				)
			)
		)
		(pad "2" smd custom
			(at 0 0.2794 180)
			(size 0.0762 0.0762)
			(layers "F.Cu" "F.Mask" "F.Paste")
			(net "SAS_EXP_GF_TX_DN12")
			(options
				(clearance outline)
				(anchor circle)
			)
			(primitives
				(gr_poly
					(pts
						(arc
							(start 0.1524 -0.127)
							(mid 0.137521 -0.162921)
							(end 0.1016 -0.1778)
						)
						(arc
							(start -0.1016 -0.1778)
							(mid -0.137521 -0.162921)
							(end -0.1524 -0.127)
						)
						(arc
							(start -0.1524 0.127)
							(mid -0.137521 0.162921)
							(end -0.1016 0.1778)
						)
						(arc
							(start 0.1016 0.1778)
							(mid 0.137521 0.162921)
							(end 0.1524 0.127)
						)
					)
					(width 0)
					(fill yes)
				)
			)
		)
	)
	(footprint ""
		(layer "F.Cu")
		(at 274.193 -184.531 90)
		(property "Reference" "R358"
			(at 0 0 90)
			(layer "F.SilkS")
			(hide yes)
			(effects
				(font
					(size 1.27 1.27)
				)
			)
		)
		(property "Value" "3K3R2F-2-GP"
			(at 0.064008 -3.993896 90)
			(unlocked yes)
			(layer "F.Fab")
			(hide yes)
			(effects
				(font
					(size 1.016 1.016)
					(thickness 0.1524)
				)
			)
		)
		(property "Device Type" "R402H16"
			(at 0.064008 -5.517896 90)
			(unlocked yes)
			(layer "F.Fab")
			(hide yes)
			(effects
				(font
					(size 1.016 1.016)
					(thickness 0.1524)
				)
			)
		)
		(duplicate_pad_numbers_are_jumpers no)
		(fp_line
			(start 0.508 -0.9398)
			(end -0.508 -0.9398)
			(stroke
				(width 0.1524)
				(type default)
			)
			(layer "F.SilkS")
		)
		(fp_line
			(start -0.508 -0.9398)
			(end -0.508 0.9398)
			(stroke
				(width 0.1524)
				(type default)
			)
			(layer "F.SilkS")
		)
		(fp_rect
			(start -0.508 0.9398)
			(end 0.508 -0.9398)
			(stroke
				(width 0)
				(type default)
			)
			(fill no)
			(layer "F.CrtYd")
		)
		(fp_rect
			(start -0.508 0.9398)
			(end 0.508 -0.9398)
			(stroke
				(width 0)
				(type default)
			)
			(fill no)
			(layer "F.Fab")
		)
		(pad "1" smd custom
			(at 0 -0.4445 90)
			(size 0.1397 0.1397)
			(layers "F.Cu" "F.Mask" "F.Paste")
			(net "P3V3_STBY")
			(options
				(clearance outline)
				(anchor circle)
			)
			(primitives
				(gr_poly
					(pts
						(arc
							(start -0.1778 -0.2794)
							(mid -0.249642 -0.249642)
							(end -0.2794 -0.1778)
						)
						(arc
							(start -0.2794 0.1778)
							(mid -0.249642 0.249642)
							(end -0.1778 0.2794)
						)
						(arc
							(start 0.1778 0.2794)
							(mid 0.249642 0.249642)
							(end 0.2794 0.1778)
						)
						(arc
							(start 0.2794 -0.1778)
							(mid 0.249642 -0.249642)
							(end 0.1778 -0.2794)
						)
					)
					(width 0)
					(fill yes)
				)
			)
		)
		(pad "2" smd custom
			(at 0 0.4445 90)
			(size 0.1397 0.1397)
			(layers "F.Cu" "F.Mask" "F.Paste")
			(net "ROMD4")
			(options
				(clearance outline)
				(anchor circle)
			)
			(primitives
				(gr_poly
					(pts
						(arc
							(start -0.1778 -0.2794)
							(mid -0.249642 -0.249642)
							(end -0.2794 -0.1778)
						)
						(arc
							(start -0.2794 0.1778)
							(mid -0.249642 0.249642)
							(end -0.1778 0.2794)
						)
						(arc
							(start 0.1778 0.2794)
							(mid 0.249642 0.249642)
							(end 0.2794 0.1778)
						)
						(arc
							(start 0.2794 -0.1778)
							(mid 0.249642 -0.249642)
							(end 0.1778 -0.2794)
						)
					)
					(width 0)
					(fill yes)
				)
			)
		)
	)
	(footprint ""
		(layer "F.Cu")
		(at 187.198 -22.86)
		(property "Reference" "TP130"
			(at 0 0 0)
			(layer "F.SilkS")
			(hide yes)
			(effects
				(font
					(size 1.27 1.27)
				)
			)
		)
		(property "Value" "TPAD28"
			(at 0.0127 -1.8034 0)
			(unlocked yes)
			(layer "F.Fab")
			(hide yes)
			(effects
				(font
					(size 1.016 1.016)
					(thickness 0.1524)
				)
			)
		)
		(property "Device Type" "TPAD28"
			(at 0.0127 -3.3274 0)
			(unlocked yes)
			(layer "F.Fab")
			(hide yes)
			(effects
				(font
					(size 1.016 1.016)
					(thickness 0.1524)
				)
			)
		)
		(duplicate_pad_numbers_are_jumpers no)
		(fp_poly
			(pts
				(arc
					(start 0.3556 0)
					(mid -0.3556 0)
					(end 0.3556 0)
				)
			)
			(stroke
				(width 0)
				(type default)
			)
			(fill no)
			(layer "F.CrtYd")
		)
		(fp_poly
			(pts
				(arc
					(start 0.6096 0)
					(mid -0.6096 0)
					(end 0.6096 0)
				)
			)
			(stroke
				(width 0)
				(type default)
			)
			(fill no)
			(layer "F.Fab")
		)
		(pad "1" smd circle
			(at 0 0)
			(size 0.7112 0.7112)
			(layers "F.Cu" "F.Mask" "F.Paste")
			(net "RMII_BMC_MDC_R")
		)
	)
	(footprint ""
		(layer "F.Cu")
		(at 48.514 -221.996 -90)
		(property "Reference" "C7316"
			(at 0 0 270)
			(layer "F.SilkS")
			(hide yes)
			(effects
				(font
					(size 1.27 1.27)
				)
			)
		)
		(property "Value" "SCD1U25V3JX-GP"
			(at 0 -2.8194 270)
			(unlocked yes)
			(layer "F.Fab")
			(hide yes)
			(effects
				(font
					(size 1.016 1.016)
					(thickness 0.1524)
				)
			)
		)
		(property "Device Type" "C603H36"
			(at 0 -4.3434 270)
			(unlocked yes)
			(layer "F.Fab")
			(hide yes)
			(effects
				(font
					(size 1.016 1.016)
					(thickness 0.1524)
				)
			)
		)
		(duplicate_pad_numbers_are_jumpers no)
		(fp_line
			(start 0.508 0)
			(end -0.508 0)
			(stroke
				(width 0.2032)
				(type default)
			)
			(layer "F.SilkS")
		)
		(fp_rect
			(start -0.5842 1.3335)
			(end 0.5842 -1.3335)
			(stroke
				(width 0)
				(type default)
			)
			(fill no)
			(layer "F.CrtYd")
		)
		(fp_rect
			(start -0.5842 1.3335)
			(end 0.5842 -1.3335)
			(stroke
				(width 0)
				(type default)
			)
			(fill no)
			(layer "F.Fab")
		)
		(pad "1" smd custom
			(at 0 -0.762 270)
			(size 0.2159 0.2159)
			(layers "F.Cu" "F.Mask" "F.Paste")
			(net "MB0_PSET_R")
			(options
				(clearance outline)
				(anchor circle)
			)
			(primitives
				(gr_poly
					(pts
						(arc
							(start -0.3302 -0.4318)
							(mid -0.402042 -0.402042)
							(end -0.4318 -0.3302)
						)
						(arc
							(start -0.4318 0.3302)
							(mid -0.402042 0.402042)
							(end -0.3302 0.4318)
						)
						(arc
							(start 0.3302 0.4318)
							(mid 0.402042 0.402042)
							(end 0.4318 0.3302)
						)
						(arc
							(start 0.4318 -0.3302)
							(mid 0.402042 -0.402042)
							(end 0.3302 -0.4318)
						)
					)
					(width 0)
					(fill yes)
				)
			)
		)
		(pad "2" smd custom
			(at 0 0.762 270)
			(size 0.2159 0.2159)
			(layers "F.Cu" "F.Mask" "F.Paste")
			(net "AGND_CURRENT_MON")
			(options
				(clearance outline)
				(anchor circle)
			)
			(primitives
				(gr_poly
					(pts
						(arc
							(start -0.3302 -0.4318)
							(mid -0.402042 -0.402042)
							(end -0.4318 -0.3302)
						)
						(arc
							(start -0.4318 0.3302)
							(mid -0.402042 0.402042)
							(end -0.3302 0.4318)
						)
						(arc
							(start 0.3302 0.4318)
							(mid 0.402042 0.402042)
							(end 0.4318 0.3302)
						)
						(arc
							(start 0.4318 -0.3302)
							(mid 0.402042 -0.402042)
							(end 0.3302 -0.4318)
						)
					)
					(width 0)
					(fill yes)
				)
			)
		)
	)
	(footprint ""
		(layer "F.Cu")
		(at 23.064216 -204.90688 90)
		(property "Reference" "R567"
			(at 0 0 90)
			(layer "F.SilkS")
			(hide yes)
			(effects
				(font
					(size 1.27 1.27)
				)
			)
		)
		(property "Value" "4K7R2F-GP"
			(at 0.064008 -3.993896 90)
			(unlocked yes)
			(layer "F.Fab")
			(hide yes)
			(effects
				(font
					(size 1.016 1.016)
					(thickness 0.1524)
				)
			)
		)
		(property "Device Type" "R402H16"
			(at 0.064008 -5.517896 90)
			(unlocked yes)
			(layer "F.Fab")
			(hide yes)
			(effects
				(font
					(size 1.016 1.016)
					(thickness 0.1524)
				)
			)
		)
		(duplicate_pad_numbers_are_jumpers no)
		(fp_line
			(start 0.508 -0.9398)
			(end -0.508 -0.9398)
			(stroke
				(width 0.1524)
				(type default)
			)
			(layer "F.SilkS")
		)
		(fp_line
			(start -0.508 -0.9398)
			(end -0.508 0.9398)
			(stroke
				(width 0.1524)
				(type default)
			)
			(layer "F.SilkS")
		)
		(fp_rect
			(start -0.508 0.9398)
			(end 0.508 -0.9398)
			(stroke
				(width 0)
				(type default)
			)
			(fill no)
			(layer "F.CrtYd")
		)
		(fp_rect
			(start -0.508 0.9398)
			(end 0.508 -0.9398)
			(stroke
				(width 0)
				(type default)
			)
			(fill no)
			(layer "F.Fab")
		)
		(pad "1" smd custom
			(at 0 -0.4445 90)
			(size 0.1397 0.1397)
			(layers "F.Cu" "F.Mask" "F.Paste")
			(net "P3V3_STBY")
			(options
				(clearance outline)
				(anchor circle)
			)
			(primitives
				(gr_poly
					(pts
						(arc
							(start -0.1778 -0.2794)
							(mid -0.249642 -0.249642)
							(end -0.2794 -0.1778)
						)
						(arc
							(start -0.2794 0.1778)
							(mid -0.249642 0.249642)
							(end -0.1778 0.2794)
						)
						(arc
							(start 0.1778 0.2794)
							(mid 0.249642 0.249642)
							(end 0.2794 0.1778)
						)
						(arc
							(start 0.2794 -0.1778)
							(mid 0.249642 -0.249642)
							(end 0.1778 -0.2794)
						)
					)
					(width 0)
					(fill yes)
				)
			)
		)
		(pad "2" smd custom
			(at 0 0.4445 90)
			(size 0.1397 0.1397)
			(layers "F.Cu" "F.Mask" "F.Paste")
			(net "VOL_SEN_ALERT_U17")
			(options
				(clearance outline)
				(anchor circle)
			)
			(primitives
				(gr_poly
					(pts
						(arc
							(start -0.1778 -0.2794)
							(mid -0.249642 -0.249642)
							(end -0.2794 -0.1778)
						)
						(arc
							(start -0.2794 0.1778)
							(mid -0.249642 0.249642)
							(end -0.1778 0.2794)
						)
						(arc
							(start 0.1778 0.2794)
							(mid 0.249642 0.249642)
							(end 0.2794 0.1778)
						)
						(arc
							(start 0.2794 -0.1778)
							(mid 0.249642 -0.249642)
							(end 0.1778 -0.2794)
						)
					)
					(width 0)
					(fill yes)
				)
			)
		)
	)
	(footprint ""
		(layer "F.Cu")
		(at 48.387 -225.298 180)
		(property "Reference" "C7275"
			(at 0 0 180)
			(layer "F.SilkS")
			(hide yes)
			(effects
				(font
					(size 1.27 1.27)
				)
			)
		)
		(property "Value" "SC1U16V3KX-5GP"
			(at 0 -2.8194 180)
			(unlocked yes)
			(layer "F.Fab")
			(hide yes)
			(effects
				(font
					(size 1.016 1.016)
					(thickness 0.1524)
				)
			)
		)
		(property "Device Type" "C603H36"
			(at 0 -4.3434 180)
			(unlocked yes)
			(layer "F.Fab")
			(hide yes)
			(effects
				(font
					(size 1.016 1.016)
					(thickness 0.1524)
				)
			)
		)
		(duplicate_pad_numbers_are_jumpers no)
		(fp_line
			(start 0.508 0)
			(end -0.508 0)
			(stroke
				(width 0.2032)
				(type default)
			)
			(layer "F.SilkS")
		)
		(fp_rect
			(start -0.5842 1.3335)
			(end 0.5842 -1.3335)
			(stroke
				(width 0)
				(type default)
			)
			(fill no)
			(layer "F.CrtYd")
		)
		(fp_rect
			(start -0.5842 1.3335)
			(end 0.5842 -1.3335)
			(stroke
				(width 0)
				(type default)
			)
			(fill no)
			(layer "F.Fab")
		)
		(pad "1" smd custom
			(at 0 -0.762 180)
			(size 0.2159 0.2159)
			(layers "F.Cu" "F.Mask" "F.Paste")
			(net "MB0_CM_OV_R")
			(options
				(clearance outline)
				(anchor circle)
			)
			(primitives
				(gr_poly
					(pts
						(arc
							(start -0.3302 -0.4318)
							(mid -0.402042 -0.402042)
							(end -0.4318 -0.3302)
						)
						(arc
							(start -0.4318 0.3302)
							(mid -0.402042 0.402042)
							(end -0.3302 0.4318)
						)
						(arc
							(start 0.3302 0.4318)
							(mid 0.402042 0.402042)
							(end 0.4318 0.3302)
						)
						(arc
							(start 0.4318 -0.3302)
							(mid 0.402042 -0.402042)
							(end 0.3302 -0.4318)
						)
					)
					(width 0)
					(fill yes)
				)
			)
		)
		(pad "2" smd custom
			(at 0 0.762 180)
			(size 0.2159 0.2159)
			(layers "F.Cu" "F.Mask" "F.Paste")
			(net "AGND_CURRENT_MON")
			(options
				(clearance outline)
				(anchor circle)
			)
			(primitives
				(gr_poly
					(pts
						(arc
							(start -0.3302 -0.4318)
							(mid -0.402042 -0.402042)
							(end -0.4318 -0.3302)
						)
						(arc
							(start -0.4318 0.3302)
							(mid -0.402042 0.402042)
							(end -0.3302 0.4318)
						)
						(arc
							(start 0.3302 0.4318)
							(mid 0.402042 0.402042)
							(end 0.4318 0.3302)
						)
						(arc
							(start 0.4318 -0.3302)
							(mid 0.402042 -0.402042)
							(end 0.3302 -0.4318)
						)
					)
					(width 0)
					(fill yes)
				)
			)
		)
	)
	(footprint ""
		(layer "F.Cu")
		(at 86.49716 -42.926 -90)
		(property "Reference" "SC890"
			(at 0 0 270)
			(layer "F.SilkS")
			(hide yes)
			(effects
				(font
					(size 1.27 1.27)
				)
			)
		)
		(property "Value" "SCD01U10V1KX-GP"
			(at -2.8321 -1.7399 270)
			(unlocked yes)
			(layer "F.Fab")
			(hide yes)
			(effects
				(font
					(size 1.016 1.016)
					(thickness 0.1524)
				)
			)
		)
		(property "Device Type" "C0201H13"
			(at -2.8321 -3.2639 270)
			(unlocked yes)
			(layer "F.Fab")
			(hide yes)
			(effects
				(font
					(size 1.016 1.016)
					(thickness 0.1524)
				)
			)
		)
		(duplicate_pad_numbers_are_jumpers no)
		(fp_rect
			(start -0.2794 0.6477)
			(end 0.2794 -0.6477)
			(stroke
				(width 0)
				(type default)
			)
			(fill no)
			(layer "F.CrtYd")
		)
		(fp_rect
			(start -0.2794 0.6477)
			(end 0.2794 -0.6477)
			(stroke
				(width 0)
				(type default)
			)
			(fill no)
			(layer "F.Fab")
		)
		(pad "1" smd custom
			(at 0 -0.2794 270)
			(size 0.0762 0.0762)
			(layers "F.Cu" "F.Mask" "F.Paste")
			(net "SAS3008_RAID_TX_C_N5")
			(options
				(clearance outline)
				(anchor circle)
			)
			(primitives
				(gr_poly
					(pts
						(arc
							(start 0.1524 -0.127)
							(mid 0.137521 -0.162921)
							(end 0.1016 -0.1778)
						)
						(arc
							(start -0.1016 -0.1778)
							(mid -0.137521 -0.162921)
							(end -0.1524 -0.127)
						)
						(arc
							(start -0.1524 0.127)
							(mid -0.137521 0.162921)
							(end -0.1016 0.1778)
						)
						(arc
							(start 0.1016 0.1778)
							(mid 0.137521 0.162921)
							(end 0.1524 0.127)
						)
					)
					(width 0)
					(fill yes)
				)
			)
		)
		(pad "2" smd custom
			(at 0 0.2794 270)
			(size 0.0762 0.0762)
			(layers "F.Cu" "F.Mask" "F.Paste")
			(net "IOC_RAID_TX_N5")
			(options
				(clearance outline)
				(anchor circle)
			)
			(primitives
				(gr_poly
					(pts
						(arc
							(start 0.1524 -0.127)
							(mid 0.137521 -0.162921)
							(end 0.1016 -0.1778)
						)
						(arc
							(start -0.1016 -0.1778)
							(mid -0.137521 -0.162921)
							(end -0.1524 -0.127)
						)
						(arc
							(start -0.1524 0.127)
							(mid -0.137521 0.162921)
							(end -0.1016 0.1778)
						)
						(arc
							(start 0.1016 0.1778)
							(mid 0.137521 0.162921)
							(end 0.1524 0.127)
						)
					)
					(width 0)
					(fill yes)
				)
			)
		)
	)
	(footprint ""
		(layer "F.Cu")
		(at 216.29497 -69.088)
		(property "Reference" "R16"
			(at 0 0 0)
			(layer "F.SilkS")
			(hide yes)
			(effects
				(font
					(size 1.27 1.27)
				)
			)
		)
		(property "Value" "100R2F-L1-GP-U"
			(at 0.064008 -3.993896 0)
			(unlocked yes)
			(layer "F.Fab")
			(hide yes)
			(effects
				(font
					(size 1.016 1.016)
					(thickness 0.1524)
				)
			)
		)
		(property "Device Type" "R402H14"
			(at 0.064008 -5.517896 0)
			(unlocked yes)
			(layer "F.Fab")
			(hide yes)
			(effects
				(font
					(size 1.016 1.016)
					(thickness 0.1524)
				)
			)
		)
		(duplicate_pad_numbers_are_jumpers no)
		(fp_line
			(start -0.508 -0.9398)
			(end -0.508 0.9398)
			(stroke
				(width 0.1524)
				(type default)
			)
			(layer "F.SilkS")
		)
		(fp_line
			(start 0.508 -0.9398)
			(end -0.508 -0.9398)
			(stroke
				(width 0.1524)
				(type default)
			)
			(layer "F.SilkS")
		)
		(fp_rect
			(start -0.508 0.9398)
			(end 0.508 -0.9398)
			(stroke
				(width 0)
				(type default)
			)
			(fill no)
			(layer "F.CrtYd")
		)
		(fp_rect
			(start -0.508 0.9398)
			(end 0.508 -0.9398)
			(stroke
				(width 0)
				(type default)
			)
			(fill no)
			(layer "F.Fab")
		)
		(pad "1" smd custom
			(at 0 -0.4445)
			(size 0.1397 0.1397)
			(layers "F.Cu" "F.Mask" "F.Paste")
			(net "SVR_ID1")
			(options
				(clearance outline)
				(anchor circle)
			)
			(primitives
				(gr_poly
					(pts
						(arc
							(start -0.1778 -0.2794)
							(mid -0.249642 -0.249642)
							(end -0.2794 -0.1778)
						)
						(arc
							(start -0.2794 0.1778)
							(mid -0.249642 0.249642)
							(end -0.1778 0.2794)
						)
						(arc
							(start 0.1778 0.2794)
							(mid 0.249642 0.249642)
							(end 0.2794 0.1778)
						)
						(arc
							(start 0.2794 -0.1778)
							(mid 0.249642 -0.249642)
							(end 0.1778 -0.2794)
						)
					)
					(width 0)
					(fill yes)
				)
			)
		)
		(pad "2" smd custom
			(at 0 0.4445)
			(size 0.1397 0.1397)
			(layers "F.Cu" "F.Mask" "F.Paste")
			(net "GND")
			(options
				(clearance outline)
				(anchor circle)
			)
			(primitives
				(gr_poly
					(pts
						(arc
							(start -0.1778 -0.2794)
							(mid -0.249642 -0.249642)
							(end -0.2794 -0.1778)
						)
						(arc
							(start -0.2794 0.1778)
							(mid -0.249642 0.249642)
							(end -0.1778 0.2794)
						)
						(arc
							(start 0.1778 0.2794)
							(mid 0.249642 0.249642)
							(end 0.2794 0.1778)
						)
						(arc
							(start 0.2794 -0.1778)
							(mid 0.249642 -0.249642)
							(end 0.1778 -0.2794)
						)
					)
					(width 0)
					(fill yes)
				)
			)
		)
	)
	(footprint ""
		(layer "F.Cu")
		(at 195.707 -169.672 90)
		(property "Reference" "PR58"
			(at 0 0 90)
			(layer "F.SilkS")
			(hide yes)
			(effects
				(font
					(size 1.27 1.27)
				)
			)
		)
		(property "Value" "0R2J-2-GP"
			(at 0.064008 -3.993896 90)
			(unlocked yes)
			(layer "F.Fab")
			(hide yes)
			(effects
				(font
					(size 1.016 1.016)
					(thickness 0.1524)
				)
			)
		)
		(property "Device Type" "R402H16"
			(at 0.064008 -5.517896 90)
			(unlocked yes)
			(layer "F.Fab")
			(hide yes)
			(effects
				(font
					(size 1.016 1.016)
					(thickness 0.1524)
				)
			)
		)
		(duplicate_pad_numbers_are_jumpers no)
		(fp_line
			(start 0.508 -0.9398)
			(end -0.508 -0.9398)
			(stroke
				(width 0.1524)
				(type default)
			)
			(layer "F.SilkS")
		)
		(fp_line
			(start -0.508 -0.9398)
			(end -0.508 0.9398)
			(stroke
				(width 0.1524)
				(type default)
			)
			(layer "F.SilkS")
		)
		(fp_rect
			(start -0.508 0.9398)
			(end 0.508 -0.9398)
			(stroke
				(width 0)
				(type default)
			)
			(fill no)
			(layer "F.CrtYd")
		)
		(fp_rect
			(start -0.508 0.9398)
			(end 0.508 -0.9398)
			(stroke
				(width 0)
				(type default)
			)
			(fill no)
			(layer "F.Fab")
		)
		(pad "1" smd custom
			(at 0 -0.4445 90)
			(size 0.1397 0.1397)
			(layers "F.Cu" "F.Mask" "F.Paste")
			(net "P3V3_STBY_B1")
			(options
				(clearance outline)
				(anchor circle)
			)
			(primitives
				(gr_poly
					(pts
						(arc
							(start -0.1778 -0.2794)
							(mid -0.249642 -0.249642)
							(end -0.2794 -0.1778)
						)
						(arc
							(start -0.2794 0.1778)
							(mid -0.249642 0.249642)
							(end -0.1778 0.2794)
						)
						(arc
							(start 0.1778 0.2794)
							(mid 0.249642 0.249642)
							(end 0.2794 0.1778)
						)
						(arc
							(start 0.2794 -0.1778)
							(mid 0.249642 -0.249642)
							(end 0.1778 -0.2794)
						)
					)
					(width 0)
					(fill yes)
				)
			)
		)
		(pad "2" smd custom
			(at 0 0.4445 90)
			(size 0.1397 0.1397)
			(layers "F.Cu" "F.Mask" "F.Paste")
			(net "P3V3_STBY_R1")
			(options
				(clearance outline)
				(anchor circle)
			)
			(primitives
				(gr_poly
					(pts
						(arc
							(start -0.1778 -0.2794)
							(mid -0.249642 -0.249642)
							(end -0.2794 -0.1778)
						)
						(arc
							(start -0.2794 0.1778)
							(mid -0.249642 0.249642)
							(end -0.1778 0.2794)
						)
						(arc
							(start 0.1778 0.2794)
							(mid 0.249642 0.249642)
							(end 0.2794 0.1778)
						)
						(arc
							(start 0.2794 -0.1778)
							(mid 0.249642 -0.249642)
							(end 0.1778 -0.2794)
						)
					)
					(width 0)
					(fill yes)
				)
			)
		)
	)
	(footprint ""
		(layer "F.Cu")
		(at 107.88777 -72.9488 -90)
		(property "Reference" "R177"
			(at 0 0 270)
			(layer "F.SilkS")
			(hide yes)
			(effects
				(font
					(size 1.27 1.27)
				)
			)
		)
		(property "Value" "4K7R2F-GP"
			(at 0.064008 -3.993896 270)
			(unlocked yes)
			(layer "F.Fab")
			(hide yes)
			(effects
				(font
					(size 1.016 1.016)
					(thickness 0.1524)
				)
			)
		)
		(property "Device Type" "R402H16"
			(at 0.064008 -5.517896 270)
			(unlocked yes)
			(layer "F.Fab")
			(hide yes)
			(effects
				(font
					(size 1.016 1.016)
					(thickness 0.1524)
				)
			)
		)
		(duplicate_pad_numbers_are_jumpers no)
		(fp_line
			(start -0.508 -0.9398)
			(end -0.508 0.9398)
			(stroke
				(width 0.1524)
				(type default)
			)
			(layer "F.SilkS")
		)
		(fp_line
			(start 0.508 -0.9398)
			(end -0.508 -0.9398)
			(stroke
				(width 0.1524)
				(type default)
			)
			(layer "F.SilkS")
		)
		(fp_rect
			(start -0.508 0.9398)
			(end 0.508 -0.9398)
			(stroke
				(width 0)
				(type default)
			)
			(fill no)
			(layer "F.CrtYd")
		)
		(fp_rect
			(start -0.508 0.9398)
			(end 0.508 -0.9398)
			(stroke
				(width 0)
				(type default)
			)
			(fill no)
			(layer "F.Fab")
		)
		(pad "1" smd custom
			(at 0 -0.4445 270)
			(size 0.1397 0.1397)
			(layers "F.Cu" "F.Mask" "F.Paste")
			(net "TEMP_4_A1")
			(options
				(clearance outline)
				(anchor circle)
			)
			(primitives
				(gr_poly
					(pts
						(arc
							(start -0.1778 -0.2794)
							(mid -0.249642 -0.249642)
							(end -0.2794 -0.1778)
						)
						(arc
							(start -0.2794 0.1778)
							(mid -0.249642 0.249642)
							(end -0.1778 0.2794)
						)
						(arc
							(start 0.1778 0.2794)
							(mid 0.249642 0.249642)
							(end 0.2794 0.1778)
						)
						(arc
							(start 0.2794 -0.1778)
							(mid 0.249642 -0.249642)
							(end 0.1778 -0.2794)
						)
					)
					(width 0)
					(fill yes)
				)
			)
		)
		(pad "2" smd custom
			(at 0 0.4445 270)
			(size 0.1397 0.1397)
			(layers "F.Cu" "F.Mask" "F.Paste")
			(net "GND")
			(options
				(clearance outline)
				(anchor circle)
			)
			(primitives
				(gr_poly
					(pts
						(arc
							(start -0.1778 -0.2794)
							(mid -0.249642 -0.249642)
							(end -0.2794 -0.1778)
						)
						(arc
							(start -0.2794 0.1778)
							(mid -0.249642 0.249642)
							(end -0.1778 0.2794)
						)
						(arc
							(start 0.1778 0.2794)
							(mid 0.249642 0.249642)
							(end 0.2794 0.1778)
						)
						(arc
							(start 0.2794 -0.1778)
							(mid 0.249642 -0.249642)
							(end 0.1778 -0.2794)
						)
					)
					(width 0)
					(fill yes)
				)
			)
		)
	)
	(footprint ""
		(layer "F.Cu")
		(at 289.433 -163.703)
		(property "Reference" "TP139"
			(at 0 0 0)
			(layer "F.SilkS")
			(hide yes)
			(effects
				(font
					(size 1.27 1.27)
				)
			)
		)
		(property "Value" "TPAD28"
			(at 0.0127 -1.8034 0)
			(unlocked yes)
			(layer "F.Fab")
			(hide yes)
			(effects
				(font
					(size 1.016 1.016)
					(thickness 0.1524)
				)
			)
		)
		(property "Device Type" "TPAD28"
			(at 0.0127 -3.3274 0)
			(unlocked yes)
			(layer "F.Fab")
			(hide yes)
			(effects
				(font
					(size 1.016 1.016)
					(thickness 0.1524)
				)
			)
		)
		(duplicate_pad_numbers_are_jumpers no)
		(fp_poly
			(pts
				(arc
					(start 0.3556 0)
					(mid -0.3556 0)
					(end 0.3556 0)
				)
			)
			(stroke
				(width 0)
				(type default)
			)
			(fill no)
			(layer "F.CrtYd")
		)
		(fp_poly
			(pts
				(arc
					(start 0.6096 0)
					(mid -0.6096 0)
					(end 0.6096 0)
				)
			)
			(stroke
				(width 0)
				(type default)
			)
			(fill no)
			(layer "F.Fab")
		)
		(pad "1" smd circle
			(at 0 0)
			(size 0.7112 0.7112)
			(layers "F.Cu" "F.Mask" "F.Paste")
			(net "TP_BMC_GPIOE2")
		)
	)
	(footprint ""
		(layer "F.Cu")
		(at 83.420966 -87.757 180)
		(property "Reference" "SC1147"
			(at 0 0 180)
			(layer "F.SilkS")
			(hide yes)
			(effects
				(font
					(size 1.27 1.27)
				)
			)
		)
		(property "Value" "SC10U6D3V5KX-4GP"
			(at -0.0762 -6.1214 180)
			(unlocked yes)
			(layer "F.Fab")
			(hide yes)
			(effects
				(font
					(size 1.016 1.016)
					(thickness 0.1524)
				)
			)
		)
		(property "Device Type" "C805H58"
			(at -0.0762 -8.1534 180)
			(unlocked yes)
			(layer "F.Fab")
			(hide yes)
			(effects
				(font
					(size 1.016 1.016)
					(thickness 0.1524)
				)
			)
		)
		(duplicate_pad_numbers_are_jumpers no)
		(fp_line
			(start 0.635 0)
			(end -0.635 0)
			(stroke
				(width 0.508)
				(type default)
			)
			(layer "F.SilkS")
		)
		(fp_rect
			(start -0.9652 1.778)
			(end 0.9652 -1.778)
			(stroke
				(width 0)
				(type default)
			)
			(fill no)
			(layer "F.CrtYd")
		)
		(fp_poly
			(pts
				(xy -0.9652 -1.778) (xy 0.9652 -1.778) (xy 0.9652 1.778) (xy -0.9652 1.778)
			)
			(stroke
				(width 0)
				(type default)
			)
			(fill no)
			(layer "F.Fab")
		)
		(pad "1" smd rect
			(at 0 -0.9652 180)
			(size 1.397 1.143)
			(layers "F.Cu" "F.Mask" "F.Paste")
			(net "SYSPLL_VDDA18")
		)
		(pad "2" smd rect
			(at 0 0.9652 180)
			(size 1.397 1.143)
			(layers "F.Cu" "F.Mask" "F.Paste")
			(net "GND")
		)
	)
	(footprint ""
		(layer "F.Cu")
		(at 85.452966 -87.757 180)
		(property "Reference" "SC1146"
			(at 0 0 180)
			(layer "F.SilkS")
			(hide yes)
			(effects
				(font
					(size 1.27 1.27)
				)
			)
		)
		(property "Value" "SC22U6D3V5MX-2GP"
			(at -0.0762 -6.1214 180)
			(unlocked yes)
			(layer "F.Fab")
			(hide yes)
			(effects
				(font
					(size 1.016 1.016)
					(thickness 0.1524)
				)
			)
		)
		(property "Device Type" "C805H58"
			(at -0.0762 -8.1534 180)
			(unlocked yes)
			(layer "F.Fab")
			(hide yes)
			(effects
				(font
					(size 1.016 1.016)
					(thickness 0.1524)
				)
			)
		)
		(duplicate_pad_numbers_are_jumpers no)
		(fp_line
			(start 0.635 0)
			(end -0.635 0)
			(stroke
				(width 0.508)
				(type default)
			)
			(layer "F.SilkS")
		)
		(fp_rect
			(start -0.9652 1.778)
			(end 0.9652 -1.778)
			(stroke
				(width 0)
				(type default)
			)
			(fill no)
			(layer "F.CrtYd")
		)
		(fp_poly
			(pts
				(xy -0.9652 -1.778) (xy 0.9652 -1.778) (xy 0.9652 1.778) (xy -0.9652 1.778)
			)
			(stroke
				(width 0)
				(type default)
			)
			(fill no)
			(layer "F.Fab")
		)
		(pad "1" smd rect
			(at 0 -0.9652 180)
			(size 1.397 1.143)
			(layers "F.Cu" "F.Mask" "F.Paste")
			(net "SYSPLL_VDDA18")
		)
		(pad "2" smd rect
			(at 0 0.9652 180)
			(size 1.397 1.143)
			(layers "F.Cu" "F.Mask" "F.Paste")
			(net "GND")
		)
	)
	(footprint ""
		(layer "F.Cu")
		(at 261.239 -42.799 90)
		(property "Reference" "PR52"
			(at 0 0 90)
			(layer "F.SilkS")
			(hide yes)
			(effects
				(font
					(size 1.27 1.27)
				)
			)
		)
		(property "Value" "866KR2F-GP"
			(at 0.064008 -3.993896 90)
			(unlocked yes)
			(layer "F.Fab")
			(hide yes)
			(effects
				(font
					(size 1.016 1.016)
					(thickness 0.1524)
				)
			)
		)
		(property "Device Type" "R402H16"
			(at 0.064008 -5.517896 90)
			(unlocked yes)
			(layer "F.Fab")
			(hide yes)
			(effects
				(font
					(size 1.016 1.016)
					(thickness 0.1524)
				)
			)
		)
		(duplicate_pad_numbers_are_jumpers no)
		(fp_line
			(start 0.508 -0.9398)
			(end -0.508 -0.9398)
			(stroke
				(width 0.1524)
				(type default)
			)
			(layer "F.SilkS")
		)
		(fp_line
			(start -0.508 -0.9398)
			(end -0.508 0.9398)
			(stroke
				(width 0.1524)
				(type default)
			)
			(layer "F.SilkS")
		)
		(fp_rect
			(start -0.508 0.9398)
			(end 0.508 -0.9398)
			(stroke
				(width 0)
				(type default)
			)
			(fill no)
			(layer "F.CrtYd")
		)
		(fp_rect
			(start -0.508 0.9398)
			(end 0.508 -0.9398)
			(stroke
				(width 0)
				(type default)
			)
			(fill no)
			(layer "F.Fab")
		)
		(pad "1" smd custom
			(at 0 -0.4445 90)
			(size 0.1397 0.1397)
			(layers "F.Cu" "F.Mask" "F.Paste")
			(net "P1V8_STBY_VREG")
			(options
				(clearance outline)
				(anchor circle)
			)
			(primitives
				(gr_poly
					(pts
						(arc
							(start -0.1778 -0.2794)
							(mid -0.249642 -0.249642)
							(end -0.2794 -0.1778)
						)
						(arc
							(start -0.2794 0.1778)
							(mid -0.249642 0.249642)
							(end -0.1778 0.2794)
						)
						(arc
							(start 0.1778 0.2794)
							(mid 0.249642 0.249642)
							(end 0.2794 0.1778)
						)
						(arc
							(start 0.2794 -0.1778)
							(mid 0.249642 -0.249642)
							(end 0.1778 -0.2794)
						)
					)
					(width 0)
					(fill yes)
				)
			)
		)
		(pad "2" smd custom
			(at 0 0.4445 90)
			(size 0.1397 0.1397)
			(layers "F.Cu" "F.Mask" "F.Paste")
			(net "P1V8_STBY_RF")
			(options
				(clearance outline)
				(anchor circle)
			)
			(primitives
				(gr_poly
					(pts
						(arc
							(start -0.1778 -0.2794)
							(mid -0.249642 -0.249642)
							(end -0.2794 -0.1778)
						)
						(arc
							(start -0.2794 0.1778)
							(mid -0.249642 0.249642)
							(end -0.1778 0.2794)
						)
						(arc
							(start 0.1778 0.2794)
							(mid 0.249642 0.249642)
							(end 0.2794 0.1778)
						)
						(arc
							(start 0.2794 -0.1778)
							(mid 0.249642 -0.249642)
							(end 0.1778 -0.2794)
						)
					)
					(width 0)
					(fill yes)
				)
			)
		)
	)
	(footprint ""
		(layer "F.Cu")
		(at 346.612718 -157.838648 180)
		(property "Reference" "C166"
			(at 0 0 180)
			(layer "F.SilkS")
			(hide yes)
			(effects
				(font
					(size 1.27 1.27)
				)
			)
		)
		(property "Value" "SC1U10V2KX-4-GP"
			(at 1.1811 -2.7051 180)
			(unlocked yes)
			(layer "F.Fab")
			(hide yes)
			(effects
				(font
					(size 1.016 1.016)
					(thickness 0.1524)
				)
			)
		)
		(property "Device Type" "C402H22"
			(at 1.1811 -4.2291 180)
			(unlocked yes)
			(layer "F.Fab")
			(hide yes)
			(effects
				(font
					(size 1.016 1.016)
					(thickness 0.1524)
				)
			)
		)
		(duplicate_pad_numbers_are_jumpers no)
		(fp_rect
			(start -0.4318 0.9525)
			(end 0.4318 -0.9525)
			(stroke
				(width 0)
				(type default)
			)
			(fill no)
			(layer "F.CrtYd")
		)
		(fp_rect
			(start -0.4318 0.9525)
			(end 0.4318 -0.9525)
			(stroke
				(width 0)
				(type default)
			)
			(fill no)
			(layer "F.Fab")
		)
		(pad "1" smd custom
			(at 0 -0.4445 180)
			(size 0.1524 0.1524)
			(layers "F.Cu" "F.Mask" "F.Paste")
			(net "P3V3_STBY")
			(options
				(clearance outline)
				(anchor circle)
			)
			(primitives
				(gr_poly
					(pts
						(arc
							(start 0.3048 -0.2032)
							(mid 0.275042 -0.275042)
							(end 0.2032 -0.3048)
						)
						(arc
							(start -0.2032 -0.3048)
							(mid -0.275042 -0.275042)
							(end -0.3048 -0.2032)
						)
						(arc
							(start -0.3048 0.2032)
							(mid -0.275042 0.275042)
							(end -0.2032 0.3048)
						)
						(arc
							(start 0.2032 0.3048)
							(mid 0.275042 0.275042)
							(end 0.3048 0.2032)
						)
					)
					(width 0)
					(fill yes)
				)
			)
		)
		(pad "2" smd custom
			(at 0 0.4445 180)
			(size 0.1524 0.1524)
			(layers "F.Cu" "F.Mask" "F.Paste")
			(net "GND")
			(options
				(clearance outline)
				(anchor circle)
			)
			(primitives
				(gr_poly
					(pts
						(arc
							(start 0.3048 -0.2032)
							(mid 0.275042 -0.275042)
							(end 0.2032 -0.3048)
						)
						(arc
							(start -0.2032 -0.3048)
							(mid -0.275042 -0.275042)
							(end -0.3048 -0.2032)
						)
						(arc
							(start -0.3048 0.2032)
							(mid -0.275042 0.275042)
							(end -0.2032 0.3048)
						)
						(arc
							(start 0.2032 0.3048)
							(mid 0.275042 0.275042)
							(end 0.3048 0.2032)
						)
					)
					(width 0)
					(fill yes)
				)
			)
		)
	)
	(footprint ""
		(layer "F.Cu")
		(at 274.193 -185.547 90)
		(property "Reference" "R366"
			(at 0 0 90)
			(layer "F.SilkS")
			(hide yes)
			(effects
				(font
					(size 1.27 1.27)
				)
			)
		)
		(property "Value" "3K3R2F-2-GP"
			(at 0.064008 -3.993896 90)
			(unlocked yes)
			(layer "F.Fab")
			(hide yes)
			(effects
				(font
					(size 1.016 1.016)
					(thickness 0.1524)
				)
			)
		)
		(property "Device Type" "R402H16"
			(at 0.064008 -5.517896 90)
			(unlocked yes)
			(layer "F.Fab")
			(hide yes)
			(effects
				(font
					(size 1.016 1.016)
					(thickness 0.1524)
				)
			)
		)
		(duplicate_pad_numbers_are_jumpers no)
		(fp_line
			(start 0.508 -0.9398)
			(end -0.508 -0.9398)
			(stroke
				(width 0.1524)
				(type default)
			)
			(layer "F.SilkS")
		)
		(fp_line
			(start -0.508 -0.9398)
			(end -0.508 0.9398)
			(stroke
				(width 0.1524)
				(type default)
			)
			(layer "F.SilkS")
		)
		(fp_rect
			(start -0.508 0.9398)
			(end 0.508 -0.9398)
			(stroke
				(width 0)
				(type default)
			)
			(fill no)
			(layer "F.CrtYd")
		)
		(fp_rect
			(start -0.508 0.9398)
			(end 0.508 -0.9398)
			(stroke
				(width 0)
				(type default)
			)
			(fill no)
			(layer "F.Fab")
		)
		(pad "1" smd custom
			(at 0 -0.4445 90)
			(size 0.1397 0.1397)
			(layers "F.Cu" "F.Mask" "F.Paste")
			(net "P3V3_STBY")
			(options
				(clearance outline)
				(anchor circle)
			)
			(primitives
				(gr_poly
					(pts
						(arc
							(start -0.1778 -0.2794)
							(mid -0.249642 -0.249642)
							(end -0.2794 -0.1778)
						)
						(arc
							(start -0.2794 0.1778)
							(mid -0.249642 0.249642)
							(end -0.1778 0.2794)
						)
						(arc
							(start 0.1778 0.2794)
							(mid 0.249642 0.249642)
							(end 0.2794 0.1778)
						)
						(arc
							(start 0.2794 -0.1778)
							(mid 0.249642 -0.249642)
							(end 0.1778 -0.2794)
						)
					)
					(width 0)
					(fill yes)
				)
			)
		)
		(pad "2" smd custom
			(at 0 0.4445 90)
			(size 0.1397 0.1397)
			(layers "F.Cu" "F.Mask" "F.Paste")
			(net "ROMD6")
			(options
				(clearance outline)
				(anchor circle)
			)
			(primitives
				(gr_poly
					(pts
						(arc
							(start -0.1778 -0.2794)
							(mid -0.249642 -0.249642)
							(end -0.2794 -0.1778)
						)
						(arc
							(start -0.2794 0.1778)
							(mid -0.249642 0.249642)
							(end -0.1778 0.2794)
						)
						(arc
							(start 0.1778 0.2794)
							(mid 0.249642 0.249642)
							(end 0.2794 0.1778)
						)
						(arc
							(start 0.2794 -0.1778)
							(mid 0.249642 -0.249642)
							(end 0.1778 -0.2794)
						)
					)
					(width 0)
					(fill yes)
				)
			)
		)
	)
	(footprint ""
		(layer "F.Cu")
		(at 198.755 -91.821 -90)
		(property "Reference" "PC235"
			(at 0 0 270)
			(layer "F.SilkS")
			(hide yes)
			(effects
				(font
					(size 1.27 1.27)
				)
			)
		)
		(property "Value" "SC22U6D3V5MX-2GP"
			(at -0.0762 -6.1214 270)
			(unlocked yes)
			(layer "F.Fab")
			(hide yes)
			(effects
				(font
					(size 1.016 1.016)
					(thickness 0.1524)
				)
			)
		)
		(property "Device Type" "C805H58"
			(at -0.0762 -8.1534 270)
			(unlocked yes)
			(layer "F.Fab")
			(hide yes)
			(effects
				(font
					(size 1.016 1.016)
					(thickness 0.1524)
				)
			)
		)
		(duplicate_pad_numbers_are_jumpers no)
		(fp_line
			(start 0.635 0)
			(end -0.635 0)
			(stroke
				(width 0.508)
				(type default)
			)
			(layer "F.SilkS")
		)
		(fp_rect
			(start -0.9652 1.778)
			(end 0.9652 -1.778)
			(stroke
				(width 0)
				(type default)
			)
			(fill no)
			(layer "F.CrtYd")
		)
		(fp_poly
			(pts
				(xy -0.9652 -1.778) (xy 0.9652 -1.778) (xy 0.9652 1.778) (xy -0.9652 1.778)
			)
			(stroke
				(width 0)
				(type default)
			)
			(fill no)
			(layer "F.Fab")
		)
		(pad "1" smd rect
			(at 0 -0.9652 270)
			(size 1.397 1.143)
			(layers "F.Cu" "F.Mask" "F.Paste")
			(net "P1V5_E")
		)
		(pad "2" smd rect
			(at 0 0.9652 270)
			(size 1.397 1.143)
			(layers "F.Cu" "F.Mask" "F.Paste")
			(net "GND")
		)
	)
	(footprint ""
		(layer "F.Cu")
		(at 219.41028 -91.02852)
		(property "Reference" "SR928"
			(at 0 0 0)
			(layer "F.SilkS")
			(hide yes)
			(effects
				(font
					(size 1.27 1.27)
				)
			)
		)
		(property "Value" "0R2J-2-GP"
			(at 0.064008 -3.993896 0)
			(unlocked yes)
			(layer "F.Fab")
			(hide yes)
			(effects
				(font
					(size 1.016 1.016)
					(thickness 0.1524)
				)
			)
		)
		(property "Device Type" "R402H16"
			(at 0.064008 -5.517896 0)
			(unlocked yes)
			(layer "F.Fab")
			(hide yes)
			(effects
				(font
					(size 1.016 1.016)
					(thickness 0.1524)
				)
			)
		)
		(duplicate_pad_numbers_are_jumpers no)
		(fp_line
			(start -0.508 -0.9398)
			(end -0.508 0.9398)
			(stroke
				(width 0.1524)
				(type default)
			)
			(layer "F.SilkS")
		)
		(fp_line
			(start 0.508 -0.9398)
			(end -0.508 -0.9398)
			(stroke
				(width 0.1524)
				(type default)
			)
			(layer "F.SilkS")
		)
		(fp_rect
			(start -0.508 0.9398)
			(end 0.508 -0.9398)
			(stroke
				(width 0)
				(type default)
			)
			(fill no)
			(layer "F.CrtYd")
		)
		(fp_rect
			(start -0.508 0.9398)
			(end 0.508 -0.9398)
			(stroke
				(width 0)
				(type default)
			)
			(fill no)
			(layer "F.Fab")
		)
		(pad "1" smd custom
			(at 0 -0.4445)
			(size 0.1397 0.1397)
			(layers "F.Cu" "F.Mask" "F.Paste")
			(net "IOC_UART_RX")
			(options
				(clearance outline)
				(anchor circle)
			)
			(primitives
				(gr_poly
					(pts
						(arc
							(start -0.1778 -0.2794)
							(mid -0.249642 -0.249642)
							(end -0.2794 -0.1778)
						)
						(arc
							(start -0.2794 0.1778)
							(mid -0.249642 0.249642)
							(end -0.1778 0.2794)
						)
						(arc
							(start 0.1778 0.2794)
							(mid 0.249642 0.249642)
							(end 0.2794 0.1778)
						)
						(arc
							(start 0.2794 -0.1778)
							(mid 0.249642 -0.249642)
							(end 0.1778 -0.2794)
						)
					)
					(width 0)
					(fill yes)
				)
			)
		)
		(pad "2" smd custom
			(at 0 0.4445)
			(size 0.1397 0.1397)
			(layers "F.Cu" "F.Mask" "F.Paste")
			(net "IOC_UART_R_RX")
			(options
				(clearance outline)
				(anchor circle)
			)
			(primitives
				(gr_poly
					(pts
						(arc
							(start -0.1778 -0.2794)
							(mid -0.249642 -0.249642)
							(end -0.2794 -0.1778)
						)
						(arc
							(start -0.2794 0.1778)
							(mid -0.249642 0.249642)
							(end -0.1778 0.2794)
						)
						(arc
							(start 0.1778 0.2794)
							(mid 0.249642 0.249642)
							(end 0.2794 0.1778)
						)
						(arc
							(start 0.2794 -0.1778)
							(mid 0.249642 -0.249642)
							(end 0.1778 -0.2794)
						)
					)
					(width 0)
					(fill yes)
				)
			)
		)
	)
	(footprint ""
		(layer "F.Cu")
		(at 233.426 -13.589)
		(property "Reference" "R544"
			(at 0 0 0)
			(layer "F.SilkS")
			(hide yes)
			(effects
				(font
					(size 1.27 1.27)
				)
			)
		)
		(property "Value" "1KR2F-3-GP"
			(at 0.064008 -3.993896 0)
			(unlocked yes)
			(layer "F.Fab")
			(hide yes)
			(effects
				(font
					(size 1.016 1.016)
					(thickness 0.1524)
				)
			)
		)
		(property "Device Type" "R402H16"
			(at 0.064008 -5.517896 0)
			(unlocked yes)
			(layer "F.Fab")
			(hide yes)
			(effects
				(font
					(size 1.016 1.016)
					(thickness 0.1524)
				)
			)
		)
		(duplicate_pad_numbers_are_jumpers no)
		(fp_line
			(start -0.508 -0.9398)
			(end -0.508 0.9398)
			(stroke
				(width 0.1524)
				(type default)
			)
			(layer "F.SilkS")
		)
		(fp_line
			(start 0.508 -0.9398)
			(end -0.508 -0.9398)
			(stroke
				(width 0.1524)
				(type default)
			)
			(layer "F.SilkS")
		)
		(fp_rect
			(start -0.508 0.9398)
			(end 0.508 -0.9398)
			(stroke
				(width 0)
				(type default)
			)
			(fill no)
			(layer "F.CrtYd")
		)
		(fp_rect
			(start -0.508 0.9398)
			(end 0.508 -0.9398)
			(stroke
				(width 0)
				(type default)
			)
			(fill no)
			(layer "F.Fab")
		)
		(pad "1" smd custom
			(at 0 -0.4445)
			(size 0.1397 0.1397)
			(layers "F.Cu" "F.Mask" "F.Paste")
			(net "ENCLO_LED_RED_D")
			(options
				(clearance outline)
				(anchor circle)
			)
			(primitives
				(gr_poly
					(pts
						(arc
							(start -0.1778 -0.2794)
							(mid -0.249642 -0.249642)
							(end -0.2794 -0.1778)
						)
						(arc
							(start -0.2794 0.1778)
							(mid -0.249642 0.249642)
							(end -0.1778 0.2794)
						)
						(arc
							(start 0.1778 0.2794)
							(mid 0.249642 0.249642)
							(end 0.2794 0.1778)
						)
						(arc
							(start 0.2794 -0.1778)
							(mid 0.249642 -0.249642)
							(end 0.1778 -0.2794)
						)
					)
					(width 0)
					(fill yes)
				)
			)
		)
		(pad "2" smd custom
			(at 0 0.4445)
			(size 0.1397 0.1397)
			(layers "F.Cu" "F.Mask" "F.Paste")
			(net "P3V3_STBY")
			(options
				(clearance outline)
				(anchor circle)
			)
			(primitives
				(gr_poly
					(pts
						(arc
							(start -0.1778 -0.2794)
							(mid -0.249642 -0.249642)
							(end -0.2794 -0.1778)
						)
						(arc
							(start -0.2794 0.1778)
							(mid -0.249642 0.249642)
							(end -0.1778 0.2794)
						)
						(arc
							(start 0.1778 0.2794)
							(mid 0.249642 0.249642)
							(end 0.2794 0.1778)
						)
						(arc
							(start 0.2794 -0.1778)
							(mid 0.249642 -0.249642)
							(end 0.1778 -0.2794)
						)
					)
					(width 0)
					(fill yes)
				)
			)
		)
	)
	(footprint ""
		(layer "F.Cu")
		(at 216.272872 -175.586136 90)
		(property "Reference" "R495"
			(at 0 0 90)
			(layer "F.SilkS")
			(hide yes)
			(effects
				(font
					(size 1.27 1.27)
				)
			)
		)
		(property "Value" "51R2010F-GP"
			(at 0.254 -8.0772 90)
			(unlocked yes)
			(layer "F.Fab")
			(hide yes)
			(effects
				(font
					(size 1.016 1.016)
					(thickness 0.1524)
				)
			)
		)
		(property "Device Type" "R2010H28"
			(at 0.254 -9.6774 90)
			(unlocked yes)
			(layer "F.Fab")
			(hide yes)
			(effects
				(font
					(size 1.016 1.016)
					(thickness 0.1524)
				)
			)
		)
		(duplicate_pad_numbers_are_jumpers no)
		(fp_line
			(start 1.651 -3.302)
			(end -1.651 -3.302)
			(stroke
				(width 0.1524)
				(type default)
			)
			(layer "F.SilkS")
		)
		(fp_line
			(start -1.651 -3.302)
			(end -1.651 3.302)
			(stroke
				(width 0.1524)
				(type default)
			)
			(layer "F.SilkS")
		)
		(fp_line
			(start 1.651 3.302)
			(end 1.651 -3.302)
			(stroke
				(width 0.1524)
				(type default)
			)
			(layer "F.SilkS")
		)
		(fp_line
			(start -1.651 3.302)
			(end 1.651 3.302)
			(stroke
				(width 0.1524)
				(type default)
			)
			(layer "F.SilkS")
		)
		(fp_rect
			(start -1.7272 -3.3782)
			(end 1.7272 3.3782)
			(stroke
				(width 0)
				(type default)
			)
			(fill no)
			(layer "F.CrtYd")
		)
		(fp_poly
			(pts
				(xy 1.7272 3.3782) (xy 1.7272 -3.3782) (xy -1.7272 -3.3782) (xy -1.7272 3.3782)
			)
			(stroke
				(width 0)
				(type default)
			)
			(fill no)
			(layer "F.Fab")
		)
		(pad "1" smd rect
			(at 0 -2.3495 90)
			(size 2.794 1.143)
			(layers "F.Cu" "F.Mask" "F.Paste")
			(net "P3V3_STBY")
		)
		(pad "2" smd rect
			(at 0 2.3495 90)
			(size 2.794 1.143)
			(layers "F.Cu" "F.Mask" "F.Paste")
			(net "HB_EXP_TO_BMC")
		)
	)
	(footprint ""
		(layer "F.Cu")
		(at 184.404 -219.456 -90)
		(property "Reference" "R2054"
			(at 0 0 270)
			(layer "F.SilkS")
			(hide yes)
			(effects
				(font
					(size 1.27 1.27)
				)
			)
		)
		(property "Value" "4K7R2F-GP"
			(at 0.064008 -3.993896 270)
			(unlocked yes)
			(layer "F.Fab")
			(hide yes)
			(effects
				(font
					(size 1.016 1.016)
					(thickness 0.1524)
				)
			)
		)
		(property "Device Type" "R402H16"
			(at 0.064008 -5.517896 270)
			(unlocked yes)
			(layer "F.Fab")
			(hide yes)
			(effects
				(font
					(size 1.016 1.016)
					(thickness 0.1524)
				)
			)
		)
		(duplicate_pad_numbers_are_jumpers no)
		(fp_line
			(start -0.508 -0.9398)
			(end -0.508 0.9398)
			(stroke
				(width 0.1524)
				(type default)
			)
			(layer "F.SilkS")
		)
		(fp_line
			(start 0.508 -0.9398)
			(end -0.508 -0.9398)
			(stroke
				(width 0.1524)
				(type default)
			)
			(layer "F.SilkS")
		)
		(fp_rect
			(start -0.508 0.9398)
			(end 0.508 -0.9398)
			(stroke
				(width 0)
				(type default)
			)
			(fill no)
			(layer "F.CrtYd")
		)
		(fp_rect
			(start -0.508 0.9398)
			(end 0.508 -0.9398)
			(stroke
				(width 0)
				(type default)
			)
			(fill no)
			(layer "F.Fab")
		)
		(pad "1" smd custom
			(at 0 -0.4445 270)
			(size 0.1397 0.1397)
			(layers "F.Cu" "F.Mask" "F.Paste")
			(net "FM_BMC_READY_N")
			(options
				(clearance outline)
				(anchor circle)
			)
			(primitives
				(gr_poly
					(pts
						(arc
							(start -0.1778 -0.2794)
							(mid -0.249642 -0.249642)
							(end -0.2794 -0.1778)
						)
						(arc
							(start -0.2794 0.1778)
							(mid -0.249642 0.249642)
							(end -0.1778 0.2794)
						)
						(arc
							(start 0.1778 0.2794)
							(mid 0.249642 0.249642)
							(end 0.2794 0.1778)
						)
						(arc
							(start 0.2794 -0.1778)
							(mid 0.249642 -0.249642)
							(end 0.1778 -0.2794)
						)
					)
					(width 0)
					(fill yes)
				)
			)
		)
		(pad "2" smd custom
			(at 0 0.4445 270)
			(size 0.1397 0.1397)
			(layers "F.Cu" "F.Mask" "F.Paste")
			(net "P3V3_STBY")
			(options
				(clearance outline)
				(anchor circle)
			)
			(primitives
				(gr_poly
					(pts
						(arc
							(start -0.1778 -0.2794)
							(mid -0.249642 -0.249642)
							(end -0.2794 -0.1778)
						)
						(arc
							(start -0.2794 0.1778)
							(mid -0.249642 0.249642)
							(end -0.1778 0.2794)
						)
						(arc
							(start 0.1778 0.2794)
							(mid 0.249642 0.249642)
							(end 0.2794 0.1778)
						)
						(arc
							(start 0.2794 -0.1778)
							(mid 0.249642 -0.249642)
							(end 0.1778 -0.2794)
						)
					)
					(width 0)
					(fill yes)
				)
			)
		)
	)
	(footprint ""
		(layer "F.Cu")
		(at 315.468 -151.892 -90)
		(property "Reference" "R5201"
			(at 0 0 270)
			(layer "F.SilkS")
			(hide yes)
			(effects
				(font
					(size 1.27 1.27)
				)
			)
		)
		(property "Value" "0R2J-2-GP"
			(at 0.064008 -3.993896 270)
			(unlocked yes)
			(layer "F.Fab")
			(hide yes)
			(effects
				(font
					(size 1.016 1.016)
					(thickness 0.1524)
				)
			)
		)
		(property "Device Type" "R402H16"
			(at 0.064008 -5.517896 270)
			(unlocked yes)
			(layer "F.Fab")
			(hide yes)
			(effects
				(font
					(size 1.016 1.016)
					(thickness 0.1524)
				)
			)
		)
		(duplicate_pad_numbers_are_jumpers no)
		(fp_line
			(start -0.508 -0.9398)
			(end -0.508 0.9398)
			(stroke
				(width 0.1524)
				(type default)
			)
			(layer "F.SilkS")
		)
		(fp_line
			(start 0.508 -0.9398)
			(end -0.508 -0.9398)
			(stroke
				(width 0.1524)
				(type default)
			)
			(layer "F.SilkS")
		)
		(fp_rect
			(start -0.508 0.9398)
			(end 0.508 -0.9398)
			(stroke
				(width 0)
				(type default)
			)
			(fill no)
			(layer "F.CrtYd")
		)
		(fp_rect
			(start -0.508 0.9398)
			(end 0.508 -0.9398)
			(stroke
				(width 0)
				(type default)
			)
			(fill no)
			(layer "F.Fab")
		)
		(pad "1" smd custom
			(at 0 -0.4445 270)
			(size 0.1397 0.1397)
			(layers "F.Cu" "F.Mask" "F.Paste")
			(net "RTC_I2C_SDA")
			(options
				(clearance outline)
				(anchor circle)
			)
			(primitives
				(gr_poly
					(pts
						(arc
							(start -0.1778 -0.2794)
							(mid -0.249642 -0.249642)
							(end -0.2794 -0.1778)
						)
						(arc
							(start -0.2794 0.1778)
							(mid -0.249642 0.249642)
							(end -0.1778 0.2794)
						)
						(arc
							(start 0.1778 0.2794)
							(mid 0.249642 0.249642)
							(end 0.2794 0.1778)
						)
						(arc
							(start 0.2794 -0.1778)
							(mid 0.249642 -0.249642)
							(end 0.1778 -0.2794)
						)
					)
					(width 0)
					(fill yes)
				)
			)
		)
		(pad "2" smd custom
			(at 0 0.4445 270)
			(size 0.1397 0.1397)
			(layers "F.Cu" "F.Mask" "F.Paste")
			(net "BMC_I2C_A_SDA")
			(options
				(clearance outline)
				(anchor circle)
			)
			(primitives
				(gr_poly
					(pts
						(arc
							(start -0.1778 -0.2794)
							(mid -0.249642 -0.249642)
							(end -0.2794 -0.1778)
						)
						(arc
							(start -0.2794 0.1778)
							(mid -0.249642 0.249642)
							(end -0.1778 0.2794)
						)
						(arc
							(start 0.1778 0.2794)
							(mid 0.249642 0.249642)
							(end 0.2794 0.1778)
						)
						(arc
							(start 0.2794 -0.1778)
							(mid 0.249642 -0.249642)
							(end 0.1778 -0.2794)
						)
					)
					(width 0)
					(fill yes)
				)
			)
		)
	)
	(footprint ""
		(layer "F.Cu")
		(at 133.736842 -83.891882 90)
		(property "Reference" "SC1095"
			(at 0 0 90)
			(layer "F.SilkS")
			(hide yes)
			(effects
				(font
					(size 1.27 1.27)
				)
			)
		)
		(property "Value" "SCD01U10V1KX-GP"
			(at -2.8321 -1.7399 90)
			(unlocked yes)
			(layer "F.Fab")
			(hide yes)
			(effects
				(font
					(size 1.016 1.016)
					(thickness 0.1524)
				)
			)
		)
		(property "Device Type" "C0201H13"
			(at -2.8321 -3.2639 90)
			(unlocked yes)
			(layer "F.Fab")
			(hide yes)
			(effects
				(font
					(size 1.016 1.016)
					(thickness 0.1524)
				)
			)
		)
		(duplicate_pad_numbers_are_jumpers no)
		(fp_rect
			(start -0.2794 0.6477)
			(end 0.2794 -0.6477)
			(stroke
				(width 0)
				(type default)
			)
			(fill no)
			(layer "F.CrtYd")
		)
		(fp_rect
			(start -0.2794 0.6477)
			(end 0.2794 -0.6477)
			(stroke
				(width 0)
				(type default)
			)
			(fill no)
			(layer "F.Fab")
		)
		(pad "1" smd custom
			(at 0 -0.2794 90)
			(size 0.0762 0.0762)
			(layers "F.Cu" "F.Mask" "F.Paste")
			(net "SAS_HDD_TX14_N")
			(options
				(clearance outline)
				(anchor circle)
			)
			(primitives
				(gr_poly
					(pts
						(arc
							(start 0.1524 -0.127)
							(mid 0.137521 -0.162921)
							(end 0.1016 -0.1778)
						)
						(arc
							(start -0.1016 -0.1778)
							(mid -0.137521 -0.162921)
							(end -0.1524 -0.127)
						)
						(arc
							(start -0.1524 0.127)
							(mid -0.137521 0.162921)
							(end -0.1016 0.1778)
						)
						(arc
							(start 0.1016 0.1778)
							(mid 0.137521 0.162921)
							(end 0.1524 0.127)
						)
					)
					(width 0)
					(fill yes)
				)
			)
		)
		(pad "2" smd custom
			(at 0 0.2794 90)
			(size 0.0762 0.0762)
			(layers "F.Cu" "F.Mask" "F.Paste")
			(net "3008_SAS_RX_N2")
			(options
				(clearance outline)
				(anchor circle)
			)
			(primitives
				(gr_poly
					(pts
						(arc
							(start 0.1524 -0.127)
							(mid 0.137521 -0.162921)
							(end 0.1016 -0.1778)
						)
						(arc
							(start -0.1016 -0.1778)
							(mid -0.137521 -0.162921)
							(end -0.1524 -0.127)
						)
						(arc
							(start -0.1524 0.127)
							(mid -0.137521 0.162921)
							(end -0.1016 0.1778)
						)
						(arc
							(start 0.1016 0.1778)
							(mid 0.137521 0.162921)
							(end 0.1524 0.127)
						)
					)
					(width 0)
					(fill yes)
				)
			)
		)
	)
	(footprint ""
		(layer "F.Cu")
		(at 91.186 -10.033 180)
		(property "Reference" "PC201"
			(at 0 0 180)
			(layer "F.SilkS")
			(hide yes)
			(effects
				(font
					(size 1.27 1.27)
				)
			)
		)
		(property "Value" "SC22U6D3V6KX-2-GP"
			(at -0.0762 -5.1308 180)
			(unlocked yes)
			(layer "F.Fab")
			(hide yes)
			(effects
				(font
					(size 1.016 1.016)
					(thickness 0.1524)
				)
			)
		)
		(property "Device Type" "C1206H71"
			(at -0.127 -6.6548 180)
			(unlocked yes)
			(layer "F.Fab")
			(hide yes)
			(effects
				(font
					(size 1.016 1.016)
					(thickness 0.1524)
				)
			)
		)
		(duplicate_pad_numbers_are_jumpers no)
		(fp_line
			(start 1.016 2.2352)
			(end -1.016 2.2352)
			(stroke
				(width 0.1524)
				(type default)
			)
			(layer "F.SilkS")
		)
		(fp_line
			(start 1.016 0.8382)
			(end 1.016 2.2352)
			(stroke
				(width 0.1524)
				(type default)
			)
			(layer "F.SilkS")
		)
		(fp_line
			(start 1.016 -2.2352)
			(end 1.016 -0.8382)
			(stroke
				(width 0.1524)
				(type default)
			)
			(layer "F.SilkS")
		)
		(fp_line
			(start -1.016 2.2352)
			(end -1.016 0.8382)
			(stroke
				(width 0.1524)
				(type default)
			)
			(layer "F.SilkS")
		)
		(fp_line
			(start -1.016 -0.8382)
			(end -1.016 -2.2352)
			(stroke
				(width 0.1524)
				(type default)
			)
			(layer "F.SilkS")
		)
		(fp_line
			(start -1.016 -2.2352)
			(end 1.016 -2.2352)
			(stroke
				(width 0.1524)
				(type default)
			)
			(layer "F.SilkS")
		)
		(fp_rect
			(start -1.0922 2.3114)
			(end 1.0922 -2.3114)
			(stroke
				(width 0)
				(type default)
			)
			(fill no)
			(layer "F.CrtYd")
		)
		(fp_poly
			(pts
				(xy 1.0922 -2.3114) (xy 1.0922 2.3114) (xy -1.0922 2.3114) (xy -1.0922 -2.3114)
			)
			(stroke
				(width 0)
				(type default)
			)
			(fill no)
			(layer "F.Fab")
		)
		(pad "1" smd rect
			(at 0 -1.397 180)
			(size 1.651 1.27)
			(layers "F.Cu" "F.Mask" "F.Paste")
			(net "P0V955_C")
		)
		(pad "2" smd rect
			(at 0 1.397 180)
			(size 1.651 1.27)
			(layers "F.Cu" "F.Mask" "F.Paste")
			(net "GND")
		)
	)
	(footprint ""
		(layer "F.Cu")
		(at 333.912718 -152.377648 -90)
		(property "Reference" "R536"
			(at 0 0 270)
			(layer "F.SilkS")
			(hide yes)
			(effects
				(font
					(size 1.27 1.27)
				)
			)
		)
		(property "Value" "0R2J-2-GP"
			(at 0.064008 -3.993896 270)
			(unlocked yes)
			(layer "F.Fab")
			(hide yes)
			(effects
				(font
					(size 1.016 1.016)
					(thickness 0.1524)
				)
			)
		)
		(property "Device Type" "R402H16"
			(at 0.064008 -5.517896 270)
			(unlocked yes)
			(layer "F.Fab")
			(hide yes)
			(effects
				(font
					(size 1.016 1.016)
					(thickness 0.1524)
				)
			)
		)
		(duplicate_pad_numbers_are_jumpers no)
		(fp_line
			(start -0.508 -0.9398)
			(end -0.508 0.9398)
			(stroke
				(width 0.1524)
				(type default)
			)
			(layer "F.SilkS")
		)
		(fp_line
			(start 0.508 -0.9398)
			(end -0.508 -0.9398)
			(stroke
				(width 0.1524)
				(type default)
			)
			(layer "F.SilkS")
		)
		(fp_rect
			(start -0.508 0.9398)
			(end 0.508 -0.9398)
			(stroke
				(width 0)
				(type default)
			)
			(fill no)
			(layer "F.CrtYd")
		)
		(fp_rect
			(start -0.508 0.9398)
			(end 0.508 -0.9398)
			(stroke
				(width 0)
				(type default)
			)
			(fill no)
			(layer "F.Fab")
		)
		(pad "1" smd custom
			(at 0 -0.4445 270)
			(size 0.1397 0.1397)
			(layers "F.Cu" "F.Mask" "F.Paste")
			(net "CFG_SEL0")
			(options
				(clearance outline)
				(anchor circle)
			)
			(primitives
				(gr_poly
					(pts
						(arc
							(start -0.1778 -0.2794)
							(mid -0.249642 -0.249642)
							(end -0.2794 -0.1778)
						)
						(arc
							(start -0.2794 0.1778)
							(mid -0.249642 0.249642)
							(end -0.1778 0.2794)
						)
						(arc
							(start 0.1778 0.2794)
							(mid 0.249642 0.249642)
							(end 0.2794 0.1778)
						)
						(arc
							(start 0.2794 -0.1778)
							(mid 0.249642 -0.249642)
							(end 0.1778 -0.2794)
						)
					)
					(width 0)
					(fill yes)
				)
			)
		)
		(pad "2" smd custom
			(at 0 0.4445 270)
			(size 0.1397 0.1397)
			(layers "F.Cu" "F.Mask" "F.Paste")
			(net "BMC_I2C_D_SCL")
			(options
				(clearance outline)
				(anchor circle)
			)
			(primitives
				(gr_poly
					(pts
						(arc
							(start -0.1778 -0.2794)
							(mid -0.249642 -0.249642)
							(end -0.2794 -0.1778)
						)
						(arc
							(start -0.2794 0.1778)
							(mid -0.249642 0.249642)
							(end -0.1778 0.2794)
						)
						(arc
							(start 0.1778 0.2794)
							(mid 0.249642 0.249642)
							(end 0.2794 0.1778)
						)
						(arc
							(start 0.2794 -0.1778)
							(mid 0.249642 -0.249642)
							(end 0.1778 -0.2794)
						)
					)
					(width 0)
					(fill yes)
				)
			)
		)
	)
	(footprint ""
		(layer "F.Cu")
		(at 280.162 -191.77 180)
		(property "Reference" "C203"
			(at 0 0 180)
			(layer "F.SilkS")
			(hide yes)
			(effects
				(font
					(size 1.27 1.27)
				)
			)
		)
		(property "Value" "SC100P50V2JN-3GP"
			(at 1.1811 -2.7051 180)
			(unlocked yes)
			(layer "F.Fab")
			(hide yes)
			(effects
				(font
					(size 1.016 1.016)
					(thickness 0.1524)
				)
			)
		)
		(property "Device Type" "C402H22"
			(at 1.1811 -4.2291 180)
			(unlocked yes)
			(layer "F.Fab")
			(hide yes)
			(effects
				(font
					(size 1.016 1.016)
					(thickness 0.1524)
				)
			)
		)
		(duplicate_pad_numbers_are_jumpers no)
		(fp_rect
			(start -0.4318 0.9525)
			(end 0.4318 -0.9525)
			(stroke
				(width 0)
				(type default)
			)
			(fill no)
			(layer "F.CrtYd")
		)
		(fp_rect
			(start -0.4318 0.9525)
			(end 0.4318 -0.9525)
			(stroke
				(width 0)
				(type default)
			)
			(fill no)
			(layer "F.Fab")
		)
		(pad "1" smd custom
			(at 0 -0.4445 180)
			(size 0.1524 0.1524)
			(layers "F.Cu" "F.Mask" "F.Paste")
			(net "V1PLLAV12")
			(options
				(clearance outline)
				(anchor circle)
			)
			(primitives
				(gr_poly
					(pts
						(arc
							(start 0.3048 -0.2032)
							(mid 0.275042 -0.275042)
							(end 0.2032 -0.3048)
						)
						(arc
							(start -0.2032 -0.3048)
							(mid -0.275042 -0.275042)
							(end -0.3048 -0.2032)
						)
						(arc
							(start -0.3048 0.2032)
							(mid -0.275042 0.275042)
							(end -0.2032 0.3048)
						)
						(arc
							(start 0.2032 0.3048)
							(mid 0.275042 0.275042)
							(end 0.3048 0.2032)
						)
					)
					(width 0)
					(fill yes)
				)
			)
		)
		(pad "2" smd custom
			(at 0 0.4445 180)
			(size 0.1524 0.1524)
			(layers "F.Cu" "F.Mask" "F.Paste")
			(net "GND")
			(options
				(clearance outline)
				(anchor circle)
			)
			(primitives
				(gr_poly
					(pts
						(arc
							(start 0.3048 -0.2032)
							(mid 0.275042 -0.275042)
							(end 0.2032 -0.3048)
						)
						(arc
							(start -0.2032 -0.3048)
							(mid -0.275042 -0.275042)
							(end -0.3048 -0.2032)
						)
						(arc
							(start -0.3048 0.2032)
							(mid -0.275042 0.275042)
							(end -0.2032 0.3048)
						)
						(arc
							(start 0.2032 0.3048)
							(mid 0.275042 0.275042)
							(end 0.3048 0.2032)
						)
					)
					(width 0)
					(fill yes)
				)
			)
		)
	)
	(footprint ""
		(layer "F.Cu")
		(at 34.036 -170.942 180)
		(property "Reference" "SR1278"
			(at 0 0 180)
			(layer "F.SilkS")
			(hide yes)
			(effects
				(font
					(size 1.27 1.27)
				)
			)
		)
		(property "Value" "4K7R2F-GP"
			(at 0.064008 -3.993896 180)
			(unlocked yes)
			(layer "F.Fab")
			(hide yes)
			(effects
				(font
					(size 1.016 1.016)
					(thickness 0.1524)
				)
			)
		)
		(property "Device Type" "R402H16"
			(at 0.064008 -5.517896 180)
			(unlocked yes)
			(layer "F.Fab")
			(hide yes)
			(effects
				(font
					(size 1.016 1.016)
					(thickness 0.1524)
				)
			)
		)
		(duplicate_pad_numbers_are_jumpers no)
		(fp_line
			(start 0.508 -0.9398)
			(end -0.508 -0.9398)
			(stroke
				(width 0.1524)
				(type default)
			)
			(layer "F.SilkS")
		)
		(fp_line
			(start -0.508 -0.9398)
			(end -0.508 0.9398)
			(stroke
				(width 0.1524)
				(type default)
			)
			(layer "F.SilkS")
		)
		(fp_rect
			(start -0.508 0.9398)
			(end 0.508 -0.9398)
			(stroke
				(width 0)
				(type default)
			)
			(fill no)
			(layer "F.CrtYd")
		)
		(fp_rect
			(start -0.508 0.9398)
			(end 0.508 -0.9398)
			(stroke
				(width 0)
				(type default)
			)
			(fill no)
			(layer "F.Fab")
		)
		(pad "1" smd custom
			(at 0 -0.4445 180)
			(size 0.1397 0.1397)
			(layers "F.Cu" "F.Mask" "F.Paste")
			(net "P3V3_STBY")
			(options
				(clearance outline)
				(anchor circle)
			)
			(primitives
				(gr_poly
					(pts
						(arc
							(start -0.1778 -0.2794)
							(mid -0.249642 -0.249642)
							(end -0.2794 -0.1778)
						)
						(arc
							(start -0.2794 0.1778)
							(mid -0.249642 0.249642)
							(end -0.1778 0.2794)
						)
						(arc
							(start 0.1778 0.2794)
							(mid 0.249642 0.249642)
							(end 0.2794 0.1778)
						)
						(arc
							(start 0.2794 -0.1778)
							(mid 0.249642 -0.249642)
							(end 0.1778 -0.2794)
						)
					)
					(width 0)
					(fill yes)
				)
			)
		)
		(pad "2" smd custom
			(at 0 0.4445 180)
			(size 0.1397 0.1397)
			(layers "F.Cu" "F.Mask" "F.Paste")
			(net "P3V3_STBY_R8")
			(options
				(clearance outline)
				(anchor circle)
			)
			(primitives
				(gr_poly
					(pts
						(arc
							(start -0.1778 -0.2794)
							(mid -0.249642 -0.249642)
							(end -0.2794 -0.1778)
						)
						(arc
							(start -0.2794 0.1778)
							(mid -0.249642 0.249642)
							(end -0.1778 0.2794)
						)
						(arc
							(start 0.1778 0.2794)
							(mid 0.249642 0.249642)
							(end 0.2794 0.1778)
						)
						(arc
							(start 0.2794 -0.1778)
							(mid 0.249642 -0.249642)
							(end 0.1778 -0.2794)
						)
					)
					(width 0)
					(fill yes)
				)
			)
		)
	)
	(footprint ""
		(layer "F.Cu")
		(at 302.387 -58.547 180)
		(property "Reference" "C287"
			(at 0 0 180)
			(layer "F.SilkS")
			(hide yes)
			(effects
				(font
					(size 1.27 1.27)
				)
			)
		)
		(property "Value" "SC1U25V3KX-GP"
			(at 0 -2.8194 180)
			(unlocked yes)
			(layer "F.Fab")
			(hide yes)
			(effects
				(font
					(size 1.016 1.016)
					(thickness 0.1524)
				)
			)
		)
		(property "Device Type" "C603H36"
			(at 0 -4.3434 180)
			(unlocked yes)
			(layer "F.Fab")
			(hide yes)
			(effects
				(font
					(size 1.016 1.016)
					(thickness 0.1524)
				)
			)
		)
		(duplicate_pad_numbers_are_jumpers no)
		(fp_line
			(start 0.508 0)
			(end -0.508 0)
			(stroke
				(width 0.2032)
				(type default)
			)
			(layer "F.SilkS")
		)
		(fp_rect
			(start -0.5842 1.3335)
			(end 0.5842 -1.3335)
			(stroke
				(width 0)
				(type default)
			)
			(fill no)
			(layer "F.CrtYd")
		)
		(fp_rect
			(start -0.5842 1.3335)
			(end 0.5842 -1.3335)
			(stroke
				(width 0)
				(type default)
			)
			(fill no)
			(layer "F.Fab")
		)
		(pad "1" smd custom
			(at 0 -0.762 180)
			(size 0.2159 0.2159)
			(layers "F.Cu" "F.Mask" "F.Paste")
			(net "P3V3")
			(options
				(clearance outline)
				(anchor circle)
			)
			(primitives
				(gr_poly
					(pts
						(arc
							(start -0.3302 -0.4318)
							(mid -0.402042 -0.402042)
							(end -0.4318 -0.3302)
						)
						(arc
							(start -0.4318 0.3302)
							(mid -0.402042 0.402042)
							(end -0.3302 0.4318)
						)
						(arc
							(start 0.3302 0.4318)
							(mid 0.402042 0.402042)
							(end 0.4318 0.3302)
						)
						(arc
							(start 0.4318 -0.3302)
							(mid 0.402042 -0.402042)
							(end 0.3302 -0.4318)
						)
					)
					(width 0)
					(fill yes)
				)
			)
		)
		(pad "2" smd custom
			(at 0 0.762 180)
			(size 0.2159 0.2159)
			(layers "F.Cu" "F.Mask" "F.Paste")
			(net "GND")
			(options
				(clearance outline)
				(anchor circle)
			)
			(primitives
				(gr_poly
					(pts
						(arc
							(start -0.3302 -0.4318)
							(mid -0.402042 -0.402042)
							(end -0.4318 -0.3302)
						)
						(arc
							(start -0.4318 0.3302)
							(mid -0.402042 0.402042)
							(end -0.3302 0.4318)
						)
						(arc
							(start 0.3302 0.4318)
							(mid 0.402042 0.402042)
							(end 0.4318 0.3302)
						)
						(arc
							(start 0.4318 -0.3302)
							(mid 0.402042 -0.402042)
							(end 0.3302 -0.4318)
						)
					)
					(width 0)
					(fill yes)
				)
			)
		)
	)
	(footprint ""
		(layer "F.Cu")
		(at 35.779456 -73.70826 -90)
		(property "Reference" "R659"
			(at 0 0 270)
			(layer "F.SilkS")
			(hide yes)
			(effects
				(font
					(size 1.27 1.27)
				)
			)
		)
		(property "Value" "1K8R6J-GP"
			(at -0.0508 -4.8514 270)
			(unlocked yes)
			(layer "F.Fab")
			(hide yes)
			(effects
				(font
					(size 1.016 1.016)
					(thickness 0.1524)
				)
			)
		)
		(property "Device Type" "R1206H28"
			(at 0 -6.3754 270)
			(unlocked yes)
			(layer "F.Fab")
			(hide yes)
			(effects
				(font
					(size 1.016 1.016)
					(thickness 0.1524)
				)
			)
		)
		(duplicate_pad_numbers_are_jumpers no)
		(fp_line
			(start -1.016 2.2352)
			(end -1.016 -2.2352)
			(stroke
				(width 0.1524)
				(type default)
			)
			(layer "F.SilkS")
		)
		(fp_line
			(start 1.016 2.2352)
			(end -1.016 2.2352)
			(stroke
				(width 0.1524)
				(type default)
			)
			(layer "F.SilkS")
		)
		(fp_line
			(start -1.016 -2.2352)
			(end 1.016 -2.2352)
			(stroke
				(width 0.1524)
				(type default)
			)
			(layer "F.SilkS")
		)
		(fp_line
			(start 1.016 -2.2352)
			(end 1.016 2.2352)
			(stroke
				(width 0.1524)
				(type default)
			)
			(layer "F.SilkS")
		)
		(fp_rect
			(start -1.0922 2.3114)
			(end 1.0922 -2.3114)
			(stroke
				(width 0)
				(type default)
			)
			(fill no)
			(layer "F.CrtYd")
		)
		(fp_poly
			(pts
				(xy -1.0922 -2.3114) (xy 1.0922 -2.3114) (xy 1.0922 2.3114) (xy -1.0922 2.3114)
			)
			(stroke
				(width 0)
				(type default)
			)
			(fill no)
			(layer "F.Fab")
		)
		(pad "1" smd rect
			(at 0 -1.397 270)
			(size 1.651 1.27)
			(layers "F.Cu" "F.Mask" "F.Paste")
			(net "P12V")
		)
		(pad "2" smd rect
			(at 0 1.397 270)
			(size 1.651 1.27)
			(layers "F.Cu" "F.Mask" "F.Paste")
			(net "INTA_LED_BLUE_C")
		)
	)
	(footprint ""
		(layer "F.Cu")
		(at 281.296872 -205.253336)
		(property "Reference" "R489"
			(at 0 0 0)
			(layer "F.SilkS")
			(hide yes)
			(effects
				(font
					(size 1.27 1.27)
				)
			)
		)
		(property "Value" "4K7R2F-GP"
			(at 0.064008 -3.993896 0)
			(unlocked yes)
			(layer "F.Fab")
			(hide yes)
			(effects
				(font
					(size 1.016 1.016)
					(thickness 0.1524)
				)
			)
		)
		(property "Device Type" "R402H16"
			(at 0.064008 -5.517896 0)
			(unlocked yes)
			(layer "F.Fab")
			(hide yes)
			(effects
				(font
					(size 1.016 1.016)
					(thickness 0.1524)
				)
			)
		)
		(duplicate_pad_numbers_are_jumpers no)
		(fp_line
			(start -0.508 -0.9398)
			(end -0.508 0.9398)
			(stroke
				(width 0.1524)
				(type default)
			)
			(layer "F.SilkS")
		)
		(fp_line
			(start 0.508 -0.9398)
			(end -0.508 -0.9398)
			(stroke
				(width 0.1524)
				(type default)
			)
			(layer "F.SilkS")
		)
		(fp_rect
			(start -0.508 0.9398)
			(end 0.508 -0.9398)
			(stroke
				(width 0)
				(type default)
			)
			(fill no)
			(layer "F.CrtYd")
		)
		(fp_rect
			(start -0.508 0.9398)
			(end 0.508 -0.9398)
			(stroke
				(width 0)
				(type default)
			)
			(fill no)
			(layer "F.Fab")
		)
		(pad "1" smd custom
			(at 0 -0.4445)
			(size 0.1397 0.1397)
			(layers "F.Cu" "F.Mask" "F.Paste")
			(net "P1V53_STBY")
			(options
				(clearance outline)
				(anchor circle)
			)
			(primitives
				(gr_poly
					(pts
						(arc
							(start -0.1778 -0.2794)
							(mid -0.249642 -0.249642)
							(end -0.2794 -0.1778)
						)
						(arc
							(start -0.2794 0.1778)
							(mid -0.249642 0.249642)
							(end -0.1778 0.2794)
						)
						(arc
							(start 0.1778 0.2794)
							(mid 0.249642 0.249642)
							(end 0.2794 0.1778)
						)
						(arc
							(start 0.2794 -0.1778)
							(mid 0.249642 -0.249642)
							(end 0.1778 -0.2794)
						)
					)
					(width 0)
					(fill yes)
				)
			)
		)
		(pad "2" smd custom
			(at 0 0.4445)
			(size 0.1397 0.1397)
			(layers "F.Cu" "F.Mask" "F.Paste")
			(net "BMC_DDR3_RST_N")
			(options
				(clearance outline)
				(anchor circle)
			)
			(primitives
				(gr_poly
					(pts
						(arc
							(start -0.1778 -0.2794)
							(mid -0.249642 -0.249642)
							(end -0.2794 -0.1778)
						)
						(arc
							(start -0.2794 0.1778)
							(mid -0.249642 0.249642)
							(end -0.1778 0.2794)
						)
						(arc
							(start 0.1778 0.2794)
							(mid 0.249642 0.249642)
							(end 0.2794 0.1778)
						)
						(arc
							(start 0.2794 -0.1778)
							(mid 0.249642 -0.249642)
							(end 0.1778 -0.2794)
						)
					)
					(width 0)
					(fill yes)
				)
			)
		)
	)
	(footprint ""
		(layer "F.Cu")
		(at 87.865966 -91.44 180)
		(property "Reference" "SC1200"
			(at 0 0 180)
			(layer "F.SilkS")
			(hide yes)
			(effects
				(font
					(size 1.27 1.27)
				)
			)
		)
		(property "Value" "SC1U6D3V1MX-GP"
			(at 1.9177 2.0193 180)
			(unlocked yes)
			(layer "F.Fab")
			(hide yes)
			(effects
				(font
					(size 1.016 1.016)
					(thickness 0.1524)
				)
			)
		)
		(property "Device Type" "C0201H14"
			(at 1.9177 0.4953 180)
			(unlocked yes)
			(layer "F.Fab")
			(hide yes)
			(effects
				(font
					(size 1.016 1.016)
					(thickness 0.1524)
				)
			)
		)
		(duplicate_pad_numbers_are_jumpers no)
		(fp_rect
			(start -0.1524 0.3048)
			(end 0.1524 -0.3048)
			(stroke
				(width 0)
				(type default)
			)
			(fill no)
			(layer "F.CrtYd")
		)
		(fp_poly
			(pts
				(xy -0.2794 0.6477) (xy -0.2794 -0.6477) (xy 0.2794 -0.6477) (xy 0.2794 -0.1905) (xy 0.1524 -0.1905)
				(xy 0.1524 -0.3048) (xy -0.1524 -0.3048) (xy -0.1524 0.3048) (xy 0.1524 0.3048) (xy 0.1524 -0.1778)
				(xy 0.2794 -0.1778) (xy 0.2794 0.6477)
			)
			(stroke
				(width 0)
				(type default)
			)
			(fill no)
			(layer "F.CrtYd")
		)
		(fp_rect
			(start -0.2794 0.6477)
			(end 0.2794 -0.6477)
			(stroke
				(width 0)
				(type default)
			)
			(fill no)
			(layer "F.Fab")
		)
		(pad "1" smd custom
			(at 0 -0.2794 180)
			(size 0.0762 0.0762)
			(layers "F.Cu" "F.Mask" "F.Paste")
			(net "SYSPLL_VDDA09")
			(options
				(clearance outline)
				(anchor circle)
			)
			(primitives
				(gr_poly
					(pts
						(arc
							(start 0.1524 -0.127)
							(mid 0.137521 -0.162921)
							(end 0.1016 -0.1778)
						)
						(arc
							(start -0.1016 -0.1778)
							(mid -0.137521 -0.162921)
							(end -0.1524 -0.127)
						)
						(arc
							(start -0.1524 0.127)
							(mid -0.137521 0.162921)
							(end -0.1016 0.1778)
						)
						(arc
							(start 0.1016 0.1778)
							(mid 0.137521 0.162921)
							(end 0.1524 0.127)
						)
					)
					(width 0)
					(fill yes)
				)
			)
		)
		(pad "2" smd custom
			(at 0 0.2794 180)
			(size 0.0762 0.0762)
			(layers "F.Cu" "F.Mask" "F.Paste")
			(net "GND")
			(options
				(clearance outline)
				(anchor circle)
			)
			(primitives
				(gr_poly
					(pts
						(arc
							(start 0.1524 -0.127)
							(mid 0.137521 -0.162921)
							(end 0.1016 -0.1778)
						)
						(arc
							(start -0.1016 -0.1778)
							(mid -0.137521 -0.162921)
							(end -0.1524 -0.127)
						)
						(arc
							(start -0.1524 0.127)
							(mid -0.137521 0.162921)
							(end -0.1016 0.1778)
						)
						(arc
							(start 0.1016 0.1778)
							(mid 0.137521 0.162921)
							(end 0.1524 0.127)
						)
					)
					(width 0)
					(fill yes)
				)
			)
		)
	)
	(footprint ""
		(layer "F.Cu")
		(at 12.650216 -214.05088 90)
		(property "Reference" "R624"
			(at 0 0 90)
			(layer "F.SilkS")
			(hide yes)
			(effects
				(font
					(size 1.27 1.27)
				)
			)
		)
		(property "Value" "10KR2F-2-GP"
			(at 0.064008 -3.993896 90)
			(unlocked yes)
			(layer "F.Fab")
			(hide yes)
			(effects
				(font
					(size 1.016 1.016)
					(thickness 0.1524)
				)
			)
		)
		(property "Device Type" "R402H16"
			(at 0.064008 -5.517896 90)
			(unlocked yes)
			(layer "F.Fab")
			(hide yes)
			(effects
				(font
					(size 1.016 1.016)
					(thickness 0.1524)
				)
			)
		)
		(duplicate_pad_numbers_are_jumpers no)
		(fp_line
			(start 0.508 -0.9398)
			(end -0.508 -0.9398)
			(stroke
				(width 0.1524)
				(type default)
			)
			(layer "F.SilkS")
		)
		(fp_line
			(start -0.508 -0.9398)
			(end -0.508 0.9398)
			(stroke
				(width 0.1524)
				(type default)
			)
			(layer "F.SilkS")
		)
		(fp_rect
			(start -0.508 0.9398)
			(end 0.508 -0.9398)
			(stroke
				(width 0)
				(type default)
			)
			(fill no)
			(layer "F.CrtYd")
		)
		(fp_rect
			(start -0.508 0.9398)
			(end 0.508 -0.9398)
			(stroke
				(width 0)
				(type default)
			)
			(fill no)
			(layer "F.Fab")
		)
		(pad "1" smd custom
			(at 0 -0.4445 90)
			(size 0.1397 0.1397)
			(layers "F.Cu" "F.Mask" "F.Paste")
			(net "PCIE_MATED#")
			(options
				(clearance outline)
				(anchor circle)
			)
			(primitives
				(gr_poly
					(pts
						(arc
							(start -0.1778 -0.2794)
							(mid -0.249642 -0.249642)
							(end -0.2794 -0.1778)
						)
						(arc
							(start -0.2794 0.1778)
							(mid -0.249642 0.249642)
							(end -0.1778 0.2794)
						)
						(arc
							(start 0.1778 0.2794)
							(mid 0.249642 0.249642)
							(end 0.2794 0.1778)
						)
						(arc
							(start 0.2794 -0.1778)
							(mid 0.249642 -0.249642)
							(end 0.1778 -0.2794)
						)
					)
					(width 0)
					(fill yes)
				)
			)
		)
		(pad "2" smd custom
			(at 0 0.4445 90)
			(size 0.1397 0.1397)
			(layers "F.Cu" "F.Mask" "F.Paste")
			(net "P3V3_STBY")
			(options
				(clearance outline)
				(anchor circle)
			)
			(primitives
				(gr_poly
					(pts
						(arc
							(start -0.1778 -0.2794)
							(mid -0.249642 -0.249642)
							(end -0.2794 -0.1778)
						)
						(arc
							(start -0.2794 0.1778)
							(mid -0.249642 0.249642)
							(end -0.1778 0.2794)
						)
						(arc
							(start 0.1778 0.2794)
							(mid 0.249642 0.249642)
							(end 0.2794 0.1778)
						)
						(arc
							(start 0.2794 -0.1778)
							(mid 0.249642 -0.249642)
							(end 0.1778 -0.2794)
						)
					)
					(width 0)
					(fill yes)
				)
			)
		)
	)
	(footprint ""
		(layer "F.Cu")
		(at 184.339992 -46.355)
		(property "Reference" "R525"
			(at 0 0 0)
			(layer "F.SilkS")
			(hide yes)
			(effects
				(font
					(size 1.27 1.27)
				)
			)
		)
		(property "Value" "10KR2F-2-GP"
			(at 0.064008 -3.993896 0)
			(unlocked yes)
			(layer "F.Fab")
			(hide yes)
			(effects
				(font
					(size 1.016 1.016)
					(thickness 0.1524)
				)
			)
		)
		(property "Device Type" "R402H16"
			(at 0.064008 -5.517896 0)
			(unlocked yes)
			(layer "F.Fab")
			(hide yes)
			(effects
				(font
					(size 1.016 1.016)
					(thickness 0.1524)
				)
			)
		)
		(duplicate_pad_numbers_are_jumpers no)
		(fp_line
			(start -0.508 -0.9398)
			(end -0.508 0.9398)
			(stroke
				(width 0.1524)
				(type default)
			)
			(layer "F.SilkS")
		)
		(fp_line
			(start 0.508 -0.9398)
			(end -0.508 -0.9398)
			(stroke
				(width 0.1524)
				(type default)
			)
			(layer "F.SilkS")
		)
		(fp_rect
			(start -0.508 0.9398)
			(end 0.508 -0.9398)
			(stroke
				(width 0)
				(type default)
			)
			(fill no)
			(layer "F.CrtYd")
		)
		(fp_rect
			(start -0.508 0.9398)
			(end 0.508 -0.9398)
			(stroke
				(width 0)
				(type default)
			)
			(fill no)
			(layer "F.Fab")
		)
		(pad "1" smd custom
			(at 0 -0.4445)
			(size 0.1397 0.1397)
			(layers "F.Cu" "F.Mask" "F.Paste")
			(net "P3V3_STBY")
			(options
				(clearance outline)
				(anchor circle)
			)
			(primitives
				(gr_poly
					(pts
						(arc
							(start -0.1778 -0.2794)
							(mid -0.249642 -0.249642)
							(end -0.2794 -0.1778)
						)
						(arc
							(start -0.2794 0.1778)
							(mid -0.249642 0.249642)
							(end -0.1778 0.2794)
						)
						(arc
							(start 0.1778 0.2794)
							(mid 0.249642 0.249642)
							(end 0.2794 0.1778)
						)
						(arc
							(start 0.2794 -0.1778)
							(mid 0.249642 -0.249642)
							(end 0.1778 -0.2794)
						)
					)
					(width 0)
					(fill yes)
				)
			)
		)
		(pad "2" smd custom
			(at 0 0.4445)
			(size 0.1397 0.1397)
			(layers "F.Cu" "F.Mask" "F.Paste")
			(net "PRSNT_MSB_A1")
			(options
				(clearance outline)
				(anchor circle)
			)
			(primitives
				(gr_poly
					(pts
						(arc
							(start -0.1778 -0.2794)
							(mid -0.249642 -0.249642)
							(end -0.2794 -0.1778)
						)
						(arc
							(start -0.2794 0.1778)
							(mid -0.249642 0.249642)
							(end -0.1778 0.2794)
						)
						(arc
							(start 0.1778 0.2794)
							(mid 0.249642 0.249642)
							(end 0.2794 0.1778)
						)
						(arc
							(start 0.2794 -0.1778)
							(mid 0.249642 -0.249642)
							(end 0.1778 -0.2794)
						)
					)
					(width 0)
					(fill yes)
				)
			)
		)
	)
	(footprint ""
		(layer "F.Cu")
		(at 343.945718 -146.027648 -90)
		(property "Reference" "TP167"
			(at 0 0 270)
			(layer "F.SilkS")
			(hide yes)
			(effects
				(font
					(size 1.27 1.27)
				)
			)
		)
		(property "Value" "TPAD28"
			(at 0.0127 -1.8034 270)
			(unlocked yes)
			(layer "F.Fab")
			(hide yes)
			(effects
				(font
					(size 1.016 1.016)
					(thickness 0.1524)
				)
			)
		)
		(property "Device Type" "TPAD28"
			(at 0.0127 -3.3274 270)
			(unlocked yes)
			(layer "F.Fab")
			(hide yes)
			(effects
				(font
					(size 1.016 1.016)
					(thickness 0.1524)
				)
			)
		)
		(duplicate_pad_numbers_are_jumpers no)
		(fp_poly
			(pts
				(arc
					(start 0 -0.3556)
					(mid 0 0.3556)
					(end 0 -0.3556)
				)
			)
			(stroke
				(width 0)
				(type default)
			)
			(fill no)
			(layer "F.CrtYd")
		)
		(fp_poly
			(pts
				(arc
					(start 0 -0.6096)
					(mid 0 0.6096)
					(end 0 -0.6096)
				)
			)
			(stroke
				(width 0)
				(type default)
			)
			(fill no)
			(layer "F.Fab")
		)
		(pad "1" smd circle
			(at 0 0 270)
			(size 0.7112 0.7112)
			(layers "F.Cu" "F.Mask" "F.Paste")
			(net "PLLFILT")
		)
	)
	(footprint ""
		(layer "F.Cu")
		(at 14.682216 -220.52788 -90)
		(property "Reference" "SR299"
			(at 0 0 270)
			(layer "F.SilkS")
			(hide yes)
			(effects
				(font
					(size 1.27 1.27)
				)
			)
		)
		(property "Value" "0R2J-2-GP"
			(at 0.064008 -3.993896 270)
			(unlocked yes)
			(layer "F.Fab")
			(hide yes)
			(effects
				(font
					(size 1.016 1.016)
					(thickness 0.1524)
				)
			)
		)
		(property "Device Type" "R402H16"
			(at 0.064008 -5.517896 270)
			(unlocked yes)
			(layer "F.Fab")
			(hide yes)
			(effects
				(font
					(size 1.016 1.016)
					(thickness 0.1524)
				)
			)
		)
		(duplicate_pad_numbers_are_jumpers no)
		(fp_line
			(start -0.508 -0.9398)
			(end -0.508 0.9398)
			(stroke
				(width 0.1524)
				(type default)
			)
			(layer "F.SilkS")
		)
		(fp_line
			(start 0.508 -0.9398)
			(end -0.508 -0.9398)
			(stroke
				(width 0.1524)
				(type default)
			)
			(layer "F.SilkS")
		)
		(fp_rect
			(start -0.508 0.9398)
			(end 0.508 -0.9398)
			(stroke
				(width 0)
				(type default)
			)
			(fill no)
			(layer "F.CrtYd")
		)
		(fp_rect
			(start -0.508 0.9398)
			(end 0.508 -0.9398)
			(stroke
				(width 0)
				(type default)
			)
			(fill no)
			(layer "F.Fab")
		)
		(pad "1" smd custom
			(at 0 -0.4445 270)
			(size 0.1397 0.1397)
			(layers "F.Cu" "F.Mask" "F.Paste")
			(net "PWR_SDA")
			(options
				(clearance outline)
				(anchor circle)
			)
			(primitives
				(gr_poly
					(pts
						(arc
							(start -0.1778 -0.2794)
							(mid -0.249642 -0.249642)
							(end -0.2794 -0.1778)
						)
						(arc
							(start -0.2794 0.1778)
							(mid -0.249642 0.249642)
							(end -0.1778 0.2794)
						)
						(arc
							(start 0.1778 0.2794)
							(mid 0.249642 0.249642)
							(end 0.2794 0.1778)
						)
						(arc
							(start 0.2794 -0.1778)
							(mid 0.249642 -0.249642)
							(end 0.1778 -0.2794)
						)
					)
					(width 0)
					(fill yes)
				)
			)
		)
		(pad "2" smd custom
			(at 0 0.4445 270)
			(size 0.1397 0.1397)
			(layers "F.Cu" "F.Mask" "F.Paste")
			(net "BMC_IOEXP_SDA_10")
			(options
				(clearance outline)
				(anchor circle)
			)
			(primitives
				(gr_poly
					(pts
						(arc
							(start -0.1778 -0.2794)
							(mid -0.249642 -0.249642)
							(end -0.2794 -0.1778)
						)
						(arc
							(start -0.2794 0.1778)
							(mid -0.249642 0.249642)
							(end -0.1778 0.2794)
						)
						(arc
							(start 0.1778 0.2794)
							(mid 0.249642 0.249642)
							(end 0.2794 0.1778)
						)
						(arc
							(start 0.2794 -0.1778)
							(mid 0.249642 -0.249642)
							(end 0.1778 -0.2794)
						)
					)
					(width 0)
					(fill yes)
				)
			)
		)
	)
	(footprint ""
		(layer "F.Cu")
		(at 83.18119 -55.466488 90)
		(property "Reference" "SC922"
			(at 0 0 90)
			(layer "F.SilkS")
			(hide yes)
			(effects
				(font
					(size 1.27 1.27)
				)
			)
		)
		(property "Value" "SCD1U6D3V1KX-GP"
			(at -2.8321 -1.7399 90)
			(unlocked yes)
			(layer "F.Fab")
			(hide yes)
			(effects
				(font
					(size 1.016 1.016)
					(thickness 0.1524)
				)
			)
		)
		(property "Device Type" "C0201H13"
			(at -2.8321 -3.2639 90)
			(unlocked yes)
			(layer "F.Fab")
			(hide yes)
			(effects
				(font
					(size 1.016 1.016)
					(thickness 0.1524)
				)
			)
		)
		(duplicate_pad_numbers_are_jumpers no)
		(fp_rect
			(start -0.2794 0.6477)
			(end 0.2794 -0.6477)
			(stroke
				(width 0)
				(type default)
			)
			(fill no)
			(layer "F.CrtYd")
		)
		(fp_rect
			(start -0.2794 0.6477)
			(end 0.2794 -0.6477)
			(stroke
				(width 0)
				(type default)
			)
			(fill no)
			(layer "F.Fab")
		)
		(pad "1" smd custom
			(at 0 -0.2794 90)
			(size 0.0762 0.0762)
			(layers "F.Cu" "F.Mask" "F.Paste")
			(net "SYS_PLL_VDD")
			(options
				(clearance outline)
				(anchor circle)
			)
			(primitives
				(gr_poly
					(pts
						(arc
							(start 0.1524 -0.127)
							(mid 0.137521 -0.162921)
							(end 0.1016 -0.1778)
						)
						(arc
							(start -0.1016 -0.1778)
							(mid -0.137521 -0.162921)
							(end -0.1524 -0.127)
						)
						(arc
							(start -0.1524 0.127)
							(mid -0.137521 0.162921)
							(end -0.1016 0.1778)
						)
						(arc
							(start 0.1016 0.1778)
							(mid 0.137521 0.162921)
							(end 0.1524 0.127)
						)
					)
					(width 0)
					(fill yes)
				)
			)
		)
		(pad "2" smd custom
			(at 0 0.2794 90)
			(size 0.0762 0.0762)
			(layers "F.Cu" "F.Mask" "F.Paste")
			(net "GND")
			(options
				(clearance outline)
				(anchor circle)
			)
			(primitives
				(gr_poly
					(pts
						(arc
							(start 0.1524 -0.127)
							(mid 0.137521 -0.162921)
							(end 0.1016 -0.1778)
						)
						(arc
							(start -0.1016 -0.1778)
							(mid -0.137521 -0.162921)
							(end -0.1524 -0.127)
						)
						(arc
							(start -0.1524 0.127)
							(mid -0.137521 0.162921)
							(end -0.1016 0.1778)
						)
						(arc
							(start 0.1016 0.1778)
							(mid 0.137521 0.162921)
							(end 0.1524 0.127)
						)
					)
					(width 0)
					(fill yes)
				)
			)
		)
	)
	(footprint ""
		(layer "F.Cu")
		(at 179.324 -15.113 90)
		(property "Reference" "R203"
			(at 0 0 90)
			(layer "F.SilkS")
			(hide yes)
			(effects
				(font
					(size 1.27 1.27)
				)
			)
		)
		(property "Value" "0R2J-2-GP"
			(at 0.064008 -3.993896 90)
			(unlocked yes)
			(layer "F.Fab")
			(hide yes)
			(effects
				(font
					(size 1.016 1.016)
					(thickness 0.1524)
				)
			)
		)
		(property "Device Type" "R402H16"
			(at 0.064008 -5.517896 90)
			(unlocked yes)
			(layer "F.Fab")
			(hide yes)
			(effects
				(font
					(size 1.016 1.016)
					(thickness 0.1524)
				)
			)
		)
		(duplicate_pad_numbers_are_jumpers no)
		(fp_line
			(start 0.508 -0.9398)
			(end -0.508 -0.9398)
			(stroke
				(width 0.1524)
				(type default)
			)
			(layer "F.SilkS")
		)
		(fp_line
			(start -0.508 -0.9398)
			(end -0.508 0.9398)
			(stroke
				(width 0.1524)
				(type default)
			)
			(layer "F.SilkS")
		)
		(fp_rect
			(start -0.508 0.9398)
			(end 0.508 -0.9398)
			(stroke
				(width 0)
				(type default)
			)
			(fill no)
			(layer "F.CrtYd")
		)
		(fp_rect
			(start -0.508 0.9398)
			(end 0.508 -0.9398)
			(stroke
				(width 0)
				(type default)
			)
			(fill no)
			(layer "F.Fab")
		)
		(pad "1" smd custom
			(at 0 -0.4445 90)
			(size 0.1397 0.1397)
			(layers "F.Cu" "F.Mask" "F.Paste")
			(net "GND")
			(options
				(clearance outline)
				(anchor circle)
			)
			(primitives
				(gr_poly
					(pts
						(arc
							(start -0.1778 -0.2794)
							(mid -0.249642 -0.249642)
							(end -0.2794 -0.1778)
						)
						(arc
							(start -0.2794 0.1778)
							(mid -0.249642 0.249642)
							(end -0.1778 0.2794)
						)
						(arc
							(start 0.1778 0.2794)
							(mid 0.249642 0.249642)
							(end 0.2794 0.1778)
						)
						(arc
							(start 0.2794 -0.1778)
							(mid 0.249642 -0.249642)
							(end 0.1778 -0.2794)
						)
					)
					(width 0)
					(fill yes)
				)
			)
		)
		(pad "2" smd custom
			(at 0 0.4445 90)
			(size 0.1397 0.1397)
			(layers "F.Cu" "F.Mask" "F.Paste")
			(net "TEMP_SENSOR_C")
			(options
				(clearance outline)
				(anchor circle)
			)
			(primitives
				(gr_poly
					(pts
						(arc
							(start -0.1778 -0.2794)
							(mid -0.249642 -0.249642)
							(end -0.2794 -0.1778)
						)
						(arc
							(start -0.2794 0.1778)
							(mid -0.249642 0.249642)
							(end -0.1778 0.2794)
						)
						(arc
							(start 0.1778 0.2794)
							(mid 0.249642 0.249642)
							(end 0.2794 0.1778)
						)
						(arc
							(start 0.2794 -0.1778)
							(mid 0.249642 -0.249642)
							(end 0.1778 -0.2794)
						)
					)
					(width 0)
					(fill yes)
				)
			)
		)
	)
	(footprint ""
		(layer "F.Cu")
		(at 315.849 -172.466)
		(property "Reference" "TP173"
			(at 0 0 0)
			(layer "F.SilkS")
			(hide yes)
			(effects
				(font
					(size 1.27 1.27)
				)
			)
		)
		(property "Value" "TPAD28"
			(at -0.0127 -1.6637 0)
			(unlocked yes)
			(layer "F.Fab")
			(hide yes)
			(effects
				(font
					(size 1.016 1.016)
					(thickness 0.1524)
				)
			)
		)
		(property "Device Type" "TPAD28"
			(at -0.0127 -3.1877 0)
			(unlocked yes)
			(layer "F.Fab")
			(hide yes)
			(effects
				(font
					(size 1.016 1.016)
					(thickness 0.1524)
				)
			)
		)
		(duplicate_pad_numbers_are_jumpers no)
		(fp_poly
			(pts
				(arc
					(start 0.3556 0)
					(mid -0.3556 0)
					(end 0.3556 0)
				)
			)
			(stroke
				(width 0)
				(type default)
			)
			(fill no)
			(layer "F.CrtYd")
		)
		(fp_poly
			(pts
				(arc
					(start 0.6096 0)
					(mid -0.6096 0)
					(end 0.6096 0)
				)
			)
			(stroke
				(width 0)
				(type default)
			)
			(fill no)
			(layer "F.Fab")
		)
		(pad "1" smd circle
			(at 0 0)
			(size 0.7112 0.7112)
			(layers "F.Cu" "F.Mask" "F.Paste")
			(net "JTAG_BMC_TDI")
		)
	)
	(footprint ""
		(layer "F.Cu")
		(at 87.992966 -84.328 180)
		(property "Reference" "SC1157"
			(at 0 0 180)
			(layer "F.SilkS")
			(hide yes)
			(effects
				(font
					(size 1.27 1.27)
				)
			)
		)
		(property "Value" "SCD1U6D3V1KX-GP"
			(at -2.8321 -1.7399 180)
			(unlocked yes)
			(layer "F.Fab")
			(hide yes)
			(effects
				(font
					(size 1.016 1.016)
					(thickness 0.1524)
				)
			)
		)
		(property "Device Type" "C0201H13"
			(at -2.8321 -3.2639 180)
			(unlocked yes)
			(layer "F.Fab")
			(hide yes)
			(effects
				(font
					(size 1.016 1.016)
					(thickness 0.1524)
				)
			)
		)
		(duplicate_pad_numbers_are_jumpers no)
		(fp_rect
			(start -0.2794 0.6477)
			(end 0.2794 -0.6477)
			(stroke
				(width 0)
				(type default)
			)
			(fill no)
			(layer "F.CrtYd")
		)
		(fp_rect
			(start -0.2794 0.6477)
			(end 0.2794 -0.6477)
			(stroke
				(width 0)
				(type default)
			)
			(fill no)
			(layer "F.Fab")
		)
		(pad "1" smd custom
			(at 0 -0.2794 180)
			(size 0.0762 0.0762)
			(layers "F.Cu" "F.Mask" "F.Paste")
			(net "PLLDDR_VDDA18")
			(options
				(clearance outline)
				(anchor circle)
			)
			(primitives
				(gr_poly
					(pts
						(arc
							(start 0.1524 -0.127)
							(mid 0.137521 -0.162921)
							(end 0.1016 -0.1778)
						)
						(arc
							(start -0.1016 -0.1778)
							(mid -0.137521 -0.162921)
							(end -0.1524 -0.127)
						)
						(arc
							(start -0.1524 0.127)
							(mid -0.137521 0.162921)
							(end -0.1016 0.1778)
						)
						(arc
							(start 0.1016 0.1778)
							(mid 0.137521 0.162921)
							(end 0.1524 0.127)
						)
					)
					(width 0)
					(fill yes)
				)
			)
		)
		(pad "2" smd custom
			(at 0 0.2794 180)
			(size 0.0762 0.0762)
			(layers "F.Cu" "F.Mask" "F.Paste")
			(net "GND")
			(options
				(clearance outline)
				(anchor circle)
			)
			(primitives
				(gr_poly
					(pts
						(arc
							(start 0.1524 -0.127)
							(mid 0.137521 -0.162921)
							(end 0.1016 -0.1778)
						)
						(arc
							(start -0.1016 -0.1778)
							(mid -0.137521 -0.162921)
							(end -0.1524 -0.127)
						)
						(arc
							(start -0.1524 0.127)
							(mid -0.137521 0.162921)
							(end -0.1016 0.1778)
						)
						(arc
							(start 0.1016 0.1778)
							(mid 0.137521 0.162921)
							(end 0.1524 0.127)
						)
					)
					(width 0)
					(fill yes)
				)
			)
		)
	)
	(footprint ""
		(layer "F.Cu")
		(at 289.941 -218.948 -90)
		(property "Reference" "PC81"
			(at 0 0 270)
			(layer "F.SilkS")
			(hide yes)
			(effects
				(font
					(size 1.27 1.27)
				)
			)
		)
		(property "Value" "SC1KP50V2KX-1GP"
			(at 1.1811 -2.7051 270)
			(unlocked yes)
			(layer "F.Fab")
			(hide yes)
			(effects
				(font
					(size 1.016 1.016)
					(thickness 0.1524)
				)
			)
		)
		(property "Device Type" "C402H22"
			(at 1.1811 -4.2291 270)
			(unlocked yes)
			(layer "F.Fab")
			(hide yes)
			(effects
				(font
					(size 1.016 1.016)
					(thickness 0.1524)
				)
			)
		)
		(duplicate_pad_numbers_are_jumpers no)
		(fp_rect
			(start -0.4318 0.9525)
			(end 0.4318 -0.9525)
			(stroke
				(width 0)
				(type default)
			)
			(fill no)
			(layer "F.CrtYd")
		)
		(fp_rect
			(start -0.4318 0.9525)
			(end 0.4318 -0.9525)
			(stroke
				(width 0)
				(type default)
			)
			(fill no)
			(layer "F.Fab")
		)
		(pad "1" smd custom
			(at 0 -0.4445 270)
			(size 0.1524 0.1524)
			(layers "F.Cu" "F.Mask" "F.Paste")
			(net "TPS74801_1V53_STBY_OUT")
			(options
				(clearance outline)
				(anchor circle)
			)
			(primitives
				(gr_poly
					(pts
						(arc
							(start 0.3048 -0.2032)
							(mid 0.275042 -0.275042)
							(end 0.2032 -0.3048)
						)
						(arc
							(start -0.2032 -0.3048)
							(mid -0.275042 -0.275042)
							(end -0.3048 -0.2032)
						)
						(arc
							(start -0.3048 0.2032)
							(mid -0.275042 0.275042)
							(end -0.2032 0.3048)
						)
						(arc
							(start 0.2032 0.3048)
							(mid 0.275042 0.275042)
							(end 0.3048 0.2032)
						)
					)
					(width 0)
					(fill yes)
				)
			)
		)
		(pad "2" smd custom
			(at 0 0.4445 270)
			(size 0.1524 0.1524)
			(layers "F.Cu" "F.Mask" "F.Paste")
			(net "TPS74801_1V53_STBY_FB")
			(options
				(clearance outline)
				(anchor circle)
			)
			(primitives
				(gr_poly
					(pts
						(arc
							(start 0.3048 -0.2032)
							(mid 0.275042 -0.275042)
							(end 0.2032 -0.3048)
						)
						(arc
							(start -0.2032 -0.3048)
							(mid -0.275042 -0.275042)
							(end -0.3048 -0.2032)
						)
						(arc
							(start -0.3048 0.2032)
							(mid -0.275042 0.275042)
							(end -0.2032 0.3048)
						)
						(arc
							(start 0.2032 0.3048)
							(mid 0.275042 0.275042)
							(end 0.3048 0.2032)
						)
					)
					(width 0)
					(fill yes)
				)
			)
		)
	)
	(footprint ""
		(layer "F.Cu")
		(at 78.73619 -55.339488 -90)
		(property "Reference" "SC930"
			(at 0 0 270)
			(layer "F.SilkS")
			(hide yes)
			(effects
				(font
					(size 1.27 1.27)
				)
			)
		)
		(property "Value" "SCD1U6D3V1KX-GP"
			(at -2.8321 -1.7399 270)
			(unlocked yes)
			(layer "F.Fab")
			(hide yes)
			(effects
				(font
					(size 1.016 1.016)
					(thickness 0.1524)
				)
			)
		)
		(property "Device Type" "C0201H13"
			(at -2.8321 -3.2639 270)
			(unlocked yes)
			(layer "F.Fab")
			(hide yes)
			(effects
				(font
					(size 1.016 1.016)
					(thickness 0.1524)
				)
			)
		)
		(duplicate_pad_numbers_are_jumpers no)
		(fp_rect
			(start -0.2794 0.6477)
			(end 0.2794 -0.6477)
			(stroke
				(width 0)
				(type default)
			)
			(fill no)
			(layer "F.CrtYd")
		)
		(fp_rect
			(start -0.2794 0.6477)
			(end 0.2794 -0.6477)
			(stroke
				(width 0)
				(type default)
			)
			(fill no)
			(layer "F.Fab")
		)
		(pad "1" smd custom
			(at 0 -0.2794 270)
			(size 0.0762 0.0762)
			(layers "F.Cu" "F.Mask" "F.Paste")
			(net "SHELL_PLL_VDD")
			(options
				(clearance outline)
				(anchor circle)
			)
			(primitives
				(gr_poly
					(pts
						(arc
							(start 0.1524 -0.127)
							(mid 0.137521 -0.162921)
							(end 0.1016 -0.1778)
						)
						(arc
							(start -0.1016 -0.1778)
							(mid -0.137521 -0.162921)
							(end -0.1524 -0.127)
						)
						(arc
							(start -0.1524 0.127)
							(mid -0.137521 0.162921)
							(end -0.1016 0.1778)
						)
						(arc
							(start 0.1016 0.1778)
							(mid 0.137521 0.162921)
							(end 0.1524 0.127)
						)
					)
					(width 0)
					(fill yes)
				)
			)
		)
		(pad "2" smd custom
			(at 0 0.2794 270)
			(size 0.0762 0.0762)
			(layers "F.Cu" "F.Mask" "F.Paste")
			(net "GND")
			(options
				(clearance outline)
				(anchor circle)
			)
			(primitives
				(gr_poly
					(pts
						(arc
							(start 0.1524 -0.127)
							(mid 0.137521 -0.162921)
							(end 0.1016 -0.1778)
						)
						(arc
							(start -0.1016 -0.1778)
							(mid -0.137521 -0.162921)
							(end -0.1524 -0.127)
						)
						(arc
							(start -0.1524 0.127)
							(mid -0.137521 0.162921)
							(end -0.1016 0.1778)
						)
						(arc
							(start 0.1016 0.1778)
							(mid 0.137521 0.162921)
							(end 0.1524 0.127)
						)
					)
					(width 0)
					(fill yes)
				)
			)
		)
	)
	(footprint ""
		(layer "F.Cu")
		(at 80.264 -28.194 90)
		(property "Reference" "SL9"
			(at 0 0 90)
			(layer "F.SilkS")
			(hide yes)
			(effects
				(font
					(size 1.27 1.27)
				)
			)
		)
		(property "Value" "28F0181-1SR-10-GP"
			(at -4.064 -3.5052 90)
			(unlocked yes)
			(layer "F.Fab")
			(hide yes)
			(effects
				(font
					(size 1.016 1.016)
					(thickness 0.1524)
				)
			)
		)
		(property "Device Type" "L9546-152127H121"
			(at -4.064 -5.0292 90)
			(unlocked yes)
			(layer "F.Fab")
			(hide yes)
			(effects
				(font
					(size 1.016 1.016)
					(thickness 0.1524)
				)
			)
		)
		(duplicate_pad_numbers_are_jumpers no)
		(fp_line
			(start 2.54 -5.6642)
			(end -2.54 -5.6642)
			(stroke
				(width 0.1524)
				(type default)
			)
			(layer "F.SilkS")
		)
		(fp_line
			(start -2.54 -5.6642)
			(end -2.54 5.6642)
			(stroke
				(width 0.1524)
				(type default)
			)
			(layer "F.SilkS")
		)
		(fp_line
			(start 2.54 5.6642)
			(end 2.54 -5.6642)
			(stroke
				(width 0.1524)
				(type default)
			)
			(layer "F.SilkS")
		)
		(fp_line
			(start -2.54 5.6642)
			(end 2.54 5.6642)
			(stroke
				(width 0.1524)
				(type default)
			)
			(layer "F.SilkS")
		)
		(fp_rect
			(start -2.286 4.7625)
			(end 2.286 -4.7625)
			(stroke
				(width 0)
				(type default)
			)
			(fill no)
			(layer "F.CrtYd")
		)
		(fp_poly
			(pts
				(xy -2.794 5.7404) (xy -2.794 -5.7404) (xy 2.794 -5.7404) (xy 2.794 5.7404) (xy 0.00254 5.7404)
				(xy 0.00254 4.7625) (xy 2.286 4.7625) (xy 2.286 -4.7625) (xy -2.286 -4.7625) (xy -2.286 4.7625)
				(xy -0.00254 4.7625) (xy -0.00254 5.7404)
			)
			(stroke
				(width 0)
				(type default)
			)
			(fill no)
			(layer "F.CrtYd")
		)
		(fp_rect
			(start -2.794 5.7404)
			(end 2.794 -5.7404)
			(stroke
				(width 0)
				(type default)
			)
			(fill no)
			(layer "F.Fab")
		)
		(pad "1" smd rect
			(at 0 -4.197604 90)
			(size 1.524 2.413)
			(layers "F.Cu" "F.Mask" "F.Paste")
			(net "P0V955_C")
		)
		(pad "2" smd rect
			(at 0 4.197604 90)
			(size 1.524 2.413)
			(layers "F.Cu" "F.Mask" "F.Paste")
			(net "SAS0_AVDD")
		)
	)
	(footprint ""
		(layer "F.Cu")
		(at 334.509872 -232.482136)
		(property "Reference" "R186"
			(at 0 0 0)
			(layer "F.SilkS")
			(hide yes)
			(effects
				(font
					(size 1.27 1.27)
				)
			)
		)
		(property "Value" "4K7R2F-GP"
			(at 0.064008 -3.993896 0)
			(unlocked yes)
			(layer "F.Fab")
			(hide yes)
			(effects
				(font
					(size 1.016 1.016)
					(thickness 0.1524)
				)
			)
		)
		(property "Device Type" "R402H16"
			(at 0.064008 -5.517896 0)
			(unlocked yes)
			(layer "F.Fab")
			(hide yes)
			(effects
				(font
					(size 1.016 1.016)
					(thickness 0.1524)
				)
			)
		)
		(duplicate_pad_numbers_are_jumpers no)
		(fp_line
			(start -0.508 -0.9398)
			(end -0.508 0.9398)
			(stroke
				(width 0.1524)
				(type default)
			)
			(layer "F.SilkS")
		)
		(fp_line
			(start 0.508 -0.9398)
			(end -0.508 -0.9398)
			(stroke
				(width 0.1524)
				(type default)
			)
			(layer "F.SilkS")
		)
		(fp_rect
			(start -0.508 0.9398)
			(end 0.508 -0.9398)
			(stroke
				(width 0)
				(type default)
			)
			(fill no)
			(layer "F.CrtYd")
		)
		(fp_rect
			(start -0.508 0.9398)
			(end 0.508 -0.9398)
			(stroke
				(width 0)
				(type default)
			)
			(fill no)
			(layer "F.Fab")
		)
		(pad "1" smd custom
			(at 0 -0.4445)
			(size 0.1397 0.1397)
			(layers "F.Cu" "F.Mask" "F.Paste")
			(net "P3V3_STBY")
			(options
				(clearance outline)
				(anchor circle)
			)
			(primitives
				(gr_poly
					(pts
						(arc
							(start -0.1778 -0.2794)
							(mid -0.249642 -0.249642)
							(end -0.2794 -0.1778)
						)
						(arc
							(start -0.2794 0.1778)
							(mid -0.249642 0.249642)
							(end -0.1778 0.2794)
						)
						(arc
							(start 0.1778 0.2794)
							(mid 0.249642 0.249642)
							(end 0.2794 0.1778)
						)
						(arc
							(start 0.2794 -0.1778)
							(mid 0.249642 -0.249642)
							(end 0.1778 -0.2794)
						)
					)
					(width 0)
					(fill yes)
				)
			)
		)
		(pad "2" smd custom
			(at 0 0.4445)
			(size 0.1397 0.1397)
			(layers "F.Cu" "F.Mask" "F.Paste")
			(net "VOL_SEN_ADDR")
			(options
				(clearance outline)
				(anchor circle)
			)
			(primitives
				(gr_poly
					(pts
						(arc
							(start -0.1778 -0.2794)
							(mid -0.249642 -0.249642)
							(end -0.2794 -0.1778)
						)
						(arc
							(start -0.2794 0.1778)
							(mid -0.249642 0.249642)
							(end -0.1778 0.2794)
						)
						(arc
							(start 0.1778 0.2794)
							(mid 0.249642 0.249642)
							(end 0.2794 0.1778)
						)
						(arc
							(start 0.2794 -0.1778)
							(mid 0.249642 -0.249642)
							(end 0.1778 -0.2794)
						)
					)
					(width 0)
					(fill yes)
				)
			)
		)
	)
	(footprint ""
		(layer "F.Cu")
		(at 310.896 -182.499 -90)
		(property "Reference" "R308"
			(at 0 0 270)
			(layer "F.SilkS")
			(hide yes)
			(effects
				(font
					(size 1.27 1.27)
				)
			)
		)
		(property "Value" "0R2J-2-GP"
			(at 0.064008 -3.993896 270)
			(unlocked yes)
			(layer "F.Fab")
			(hide yes)
			(effects
				(font
					(size 1.016 1.016)
					(thickness 0.1524)
				)
			)
		)
		(property "Device Type" "R402H16"
			(at 0.064008 -5.517896 270)
			(unlocked yes)
			(layer "F.Fab")
			(hide yes)
			(effects
				(font
					(size 1.016 1.016)
					(thickness 0.1524)
				)
			)
		)
		(duplicate_pad_numbers_are_jumpers no)
		(fp_line
			(start -0.508 -0.9398)
			(end -0.508 0.9398)
			(stroke
				(width 0.1524)
				(type default)
			)
			(layer "F.SilkS")
		)
		(fp_line
			(start 0.508 -0.9398)
			(end -0.508 -0.9398)
			(stroke
				(width 0.1524)
				(type default)
			)
			(layer "F.SilkS")
		)
		(fp_rect
			(start -0.508 0.9398)
			(end 0.508 -0.9398)
			(stroke
				(width 0)
				(type default)
			)
			(fill no)
			(layer "F.CrtYd")
		)
		(fp_rect
			(start -0.508 0.9398)
			(end 0.508 -0.9398)
			(stroke
				(width 0)
				(type default)
			)
			(fill no)
			(layer "F.Fab")
		)
		(pad "1" smd custom
			(at 0 -0.4445 270)
			(size 0.1397 0.1397)
			(layers "F.Cu" "F.Mask" "F.Paste")
			(net "FAN_PWM_PCIE")
			(options
				(clearance outline)
				(anchor circle)
			)
			(primitives
				(gr_poly
					(pts
						(arc
							(start -0.1778 -0.2794)
							(mid -0.249642 -0.249642)
							(end -0.2794 -0.1778)
						)
						(arc
							(start -0.2794 0.1778)
							(mid -0.249642 0.249642)
							(end -0.1778 0.2794)
						)
						(arc
							(start 0.1778 0.2794)
							(mid 0.249642 0.249642)
							(end 0.2794 0.1778)
						)
						(arc
							(start 0.2794 -0.1778)
							(mid 0.249642 -0.249642)
							(end 0.1778 -0.2794)
						)
					)
					(width 0)
					(fill yes)
				)
			)
		)
		(pad "2" smd custom
			(at 0 0.4445 270)
			(size 0.1397 0.1397)
			(layers "F.Cu" "F.Mask" "F.Paste")
			(net "FAN_PWM_PCIE_BMC")
			(options
				(clearance outline)
				(anchor circle)
			)
			(primitives
				(gr_poly
					(pts
						(arc
							(start -0.1778 -0.2794)
							(mid -0.249642 -0.249642)
							(end -0.2794 -0.1778)
						)
						(arc
							(start -0.2794 0.1778)
							(mid -0.249642 0.249642)
							(end -0.1778 0.2794)
						)
						(arc
							(start 0.1778 0.2794)
							(mid 0.249642 0.249642)
							(end 0.2794 0.1778)
						)
						(arc
							(start 0.2794 -0.1778)
							(mid 0.249642 -0.249642)
							(end 0.1778 -0.2794)
						)
					)
					(width 0)
					(fill yes)
				)
			)
		)
	)
	(footprint ""
		(layer "F.Cu")
		(at 296.545 -158.115 180)
		(property "Reference" "R291"
			(at 0 0 180)
			(layer "F.SilkS")
			(hide yes)
			(effects
				(font
					(size 1.27 1.27)
				)
			)
		)
		(property "Value" "0R2J-2-GP"
			(at 0.064008 -3.993896 180)
			(unlocked yes)
			(layer "F.Fab")
			(hide yes)
			(effects
				(font
					(size 1.016 1.016)
					(thickness 0.1524)
				)
			)
		)
		(property "Device Type" "R402H16"
			(at 0.064008 -5.517896 180)
			(unlocked yes)
			(layer "F.Fab")
			(hide yes)
			(effects
				(font
					(size 1.016 1.016)
					(thickness 0.1524)
				)
			)
		)
		(duplicate_pad_numbers_are_jumpers no)
		(fp_line
			(start 0.508 -0.9398)
			(end -0.508 -0.9398)
			(stroke
				(width 0.1524)
				(type default)
			)
			(layer "F.SilkS")
		)
		(fp_line
			(start -0.508 -0.9398)
			(end -0.508 0.9398)
			(stroke
				(width 0.1524)
				(type default)
			)
			(layer "F.SilkS")
		)
		(fp_rect
			(start -0.508 0.9398)
			(end 0.508 -0.9398)
			(stroke
				(width 0)
				(type default)
			)
			(fill no)
			(layer "F.CrtYd")
		)
		(fp_rect
			(start -0.508 0.9398)
			(end 0.508 -0.9398)
			(stroke
				(width 0)
				(type default)
			)
			(fill no)
			(layer "F.Fab")
		)
		(pad "1" smd custom
			(at 0 -0.4445 180)
			(size 0.1397 0.1397)
			(layers "F.Cu" "F.Mask" "F.Paste")
			(net "GND")
			(options
				(clearance outline)
				(anchor circle)
			)
			(primitives
				(gr_poly
					(pts
						(arc
							(start -0.1778 -0.2794)
							(mid -0.249642 -0.249642)
							(end -0.2794 -0.1778)
						)
						(arc
							(start -0.2794 0.1778)
							(mid -0.249642 0.249642)
							(end -0.1778 0.2794)
						)
						(arc
							(start 0.1778 0.2794)
							(mid 0.249642 0.249642)
							(end 0.2794 0.1778)
						)
						(arc
							(start 0.2794 -0.1778)
							(mid 0.249642 -0.249642)
							(end 0.1778 -0.2794)
						)
					)
					(width 0)
					(fill yes)
				)
			)
		)
		(pad "2" smd custom
			(at 0 0.4445 180)
			(size 0.1397 0.1397)
			(layers "F.Cu" "F.Mask" "F.Paste")
			(net "CLK_50M_BMC0")
			(options
				(clearance outline)
				(anchor circle)
			)
			(primitives
				(gr_poly
					(pts
						(arc
							(start -0.1778 -0.2794)
							(mid -0.249642 -0.249642)
							(end -0.2794 -0.1778)
						)
						(arc
							(start -0.2794 0.1778)
							(mid -0.249642 0.249642)
							(end -0.1778 0.2794)
						)
						(arc
							(start 0.1778 0.2794)
							(mid 0.249642 0.249642)
							(end 0.2794 0.1778)
						)
						(arc
							(start 0.2794 -0.1778)
							(mid 0.249642 -0.249642)
							(end 0.1778 -0.2794)
						)
					)
					(width 0)
					(fill yes)
				)
			)
		)
	)
	(footprint ""
		(layer "F.Cu")
		(at 35.354514 -76.795122 180)
		(property "Reference" "Q22"
			(at 0 0 180)
			(layer "F.SilkS")
			(hide yes)
			(effects
				(font
					(size 1.27 1.27)
				)
			)
		)
		(property "Value" "PMBS3904-1-GP"
			(at 0 -9.0932 180)
			(unlocked yes)
			(layer "F.Fab")
			(hide yes)
			(effects
				(font
					(size 1.016 1.016)
					(thickness 0.1524)
				)
			)
		)
		(property "Device Type" "SOT-23-10H44"
			(at 0 -10.6172 180)
			(unlocked yes)
			(layer "F.Fab")
			(hide yes)
			(effects
				(font
					(size 1.016 1.016)
					(thickness 0.1524)
				)
			)
		)
		(duplicate_pad_numbers_are_jumpers no)
		(fp_line
			(start 1.651 1.778)
			(end 1.651 -1.778)
			(stroke
				(width 0.1524)
				(type default)
			)
			(layer "F.SilkS")
		)
		(fp_line
			(start 1.651 -1.778)
			(end -1.651 -1.778)
			(stroke
				(width 0.1524)
				(type default)
			)
			(layer "F.SilkS")
		)
		(fp_line
			(start -0.635 1.8796)
			(end -1.7526 1.8796)
			(stroke
				(width 0.3302)
				(type default)
			)
			(layer "F.SilkS")
		)
		(fp_line
			(start -0.71628 2.15265)
			(end -1.26492 2.15265)
			(stroke
				(width 0.0127)
				(type default)
			)
			(layer "F.SilkS")
		)
		(fp_line
			(start -0.719074 2.145538)
			(end -1.265936 2.14122)
			(stroke
				(width 0.0127)
				(type default)
			)
			(layer "F.SilkS")
		)
		(fp_line
			(start -0.9906 1.86309)
			(end -0.701294 2.15265)
			(stroke
				(width 0.0127)
				(type default)
			)
			(layer "F.SilkS")
		)
		(fp_line
			(start -0.994156 1.8669)
			(end -0.987044 1.8669)
			(stroke
				(width 0.0127)
				(type default)
			)
			(layer "F.SilkS")
		)
		(fp_line
			(start -1.003808 1.876552)
			(end -0.977646 1.876552)
			(stroke
				(width 0.0127)
				(type default)
			)
			(layer "F.SilkS")
		)
		(fp_line
			(start -1.013206 1.88595)
			(end -0.967994 1.88595)
			(stroke
				(width 0.0127)
				(type default)
			)
			(layer "F.SilkS")
		)
		(fp_line
			(start -1.022858 1.895602)
			(end -0.958596 1.895602)
			(stroke
				(width 0.0127)
				(type default)
			)
			(layer "F.SilkS")
		)
		(fp_line
			(start -1.032256 1.905)
			(end -0.948944 1.905)
			(stroke
				(width 0.0127)
				(type default)
			)
			(layer "F.SilkS")
		)
		(fp_line
			(start -1.041908 1.914652)
			(end -0.939546 1.914652)
			(stroke
				(width 0.0127)
				(type default)
			)
			(layer "F.SilkS")
		)
		(fp_line
			(start -1.051306 1.92405)
			(end -0.929894 1.92405)
			(stroke
				(width 0.0127)
				(type default)
			)
			(layer "F.SilkS")
		)
		(fp_line
			(start -1.060958 1.933702)
			(end -0.920496 1.933702)
			(stroke
				(width 0.0127)
				(type default)
			)
			(layer "F.SilkS")
		)
		(fp_line
			(start -1.070356 1.9431)
			(end -0.910844 1.9431)
			(stroke
				(width 0.0127)
				(type default)
			)
			(layer "F.SilkS")
		)
		(fp_line
			(start -1.080008 1.952752)
			(end -0.901446 1.952752)
			(stroke
				(width 0.0127)
				(type default)
			)
			(layer "F.SilkS")
		)
		(fp_line
			(start -1.089406 1.96215)
			(end -0.891794 1.96215)
			(stroke
				(width 0.0127)
				(type default)
			)
			(layer "F.SilkS")
		)
		(fp_line
			(start -1.099058 1.971802)
			(end -0.882396 1.971802)
			(stroke
				(width 0.0127)
				(type default)
			)
			(layer "F.SilkS")
		)
		(fp_line
			(start -1.108456 1.9812)
			(end -0.872744 1.9812)
			(stroke
				(width 0.0127)
				(type default)
			)
			(layer "F.SilkS")
		)
		(fp_line
			(start -1.118108 1.990852)
			(end -0.863346 1.990852)
			(stroke
				(width 0.0127)
				(type default)
			)
			(layer "F.SilkS")
		)
		(fp_line
			(start -1.127506 2.00025)
			(end -0.853694 2.00025)
			(stroke
				(width 0.0127)
				(type default)
			)
			(layer "F.SilkS")
		)
		(fp_line
			(start -1.137158 2.009902)
			(end -0.844296 2.009902)
			(stroke
				(width 0.0127)
				(type default)
			)
			(layer "F.SilkS")
		)
		(fp_line
			(start -1.146556 2.0193)
			(end -0.834644 2.0193)
			(stroke
				(width 0.0127)
				(type default)
			)
			(layer "F.SilkS")
		)
		(fp_line
			(start -1.156208 2.028952)
			(end -0.825246 2.028952)
			(stroke
				(width 0.0127)
				(type default)
			)
			(layer "F.SilkS")
		)
		(fp_line
			(start -1.165606 2.03835)
			(end -0.815594 2.03835)
			(stroke
				(width 0.0127)
				(type default)
			)
			(layer "F.SilkS")
		)
		(fp_line
			(start -1.175258 2.048002)
			(end -0.806196 2.048002)
			(stroke
				(width 0.0127)
				(type default)
			)
			(layer "F.SilkS")
		)
		(fp_line
			(start -1.184656 2.0574)
			(end -0.796544 2.0574)
			(stroke
				(width 0.0127)
				(type default)
			)
			(layer "F.SilkS")
		)
		(fp_line
			(start -1.194308 2.067052)
			(end -0.787146 2.067052)
			(stroke
				(width 0.0127)
				(type default)
			)
			(layer "F.SilkS")
		)
		(fp_line
			(start -1.203706 2.07645)
			(end -0.777494 2.07645)
			(stroke
				(width 0.0127)
				(type default)
			)
			(layer "F.SilkS")
		)
		(fp_line
			(start -1.213358 2.086102)
			(end -0.768096 2.086102)
			(stroke
				(width 0.0127)
				(type default)
			)
			(layer "F.SilkS")
		)
		(fp_line
			(start -1.222756 2.0955)
			(end -0.758444 2.0955)
			(stroke
				(width 0.0127)
				(type default)
			)
			(layer "F.SilkS")
		)
		(fp_line
			(start -1.232408 2.105152)
			(end -0.749046 2.105152)
			(stroke
				(width 0.0127)
				(type default)
			)
			(layer "F.SilkS")
		)
		(fp_line
			(start -1.241806 2.11455)
			(end -0.739394 2.11455)
			(stroke
				(width 0.0127)
				(type default)
			)
			(layer "F.SilkS")
		)
		(fp_line
			(start -1.251458 2.124202)
			(end -0.729996 2.124202)
			(stroke
				(width 0.0127)
				(type default)
			)
			(layer "F.SilkS")
		)
		(fp_line
			(start -1.260856 2.1336)
			(end -0.720344 2.1336)
			(stroke
				(width 0.0127)
				(type default)
			)
			(layer "F.SilkS")
		)
		(fp_line
			(start -1.279144 2.15265)
			(end -0.701294 2.15265)
			(stroke
				(width 0.0127)
				(type default)
			)
			(layer "F.SilkS")
		)
		(fp_line
			(start -1.279398 2.152142)
			(end -0.9906 1.86309)
			(stroke
				(width 0.0127)
				(type default)
			)
			(layer "F.SilkS")
		)
		(fp_line
			(start -1.651 1.778)
			(end 1.651 1.778)
			(stroke
				(width 0.1524)
				(type default)
			)
			(layer "F.SilkS")
		)
		(fp_line
			(start -1.651 -1.778)
			(end -1.651 1.778)
			(stroke
				(width 0.1524)
				(type default)
			)
			(layer "F.SilkS")
		)
		(fp_line
			(start -1.7526 1.8796)
			(end -1.7526 0.9906)
			(stroke
				(width 0.3302)
				(type default)
			)
			(layer "F.SilkS")
		)
		(fp_poly
			(pts
				(xy -1.285748 2.159) (xy -1.285748 1.8796) (xy -1.778 1.8796) (xy -1.778 -1.8796) (xy 1.778 -1.8796)
				(xy 1.778 1.8796) (xy -0.694944 1.8796) (xy -0.694944 2.159)
			)
			(stroke
				(width 0)
				(type default)
			)
			(fill no)
			(layer "F.CrtYd")
		)
		(fp_poly
			(pts
				(xy -1.285748 2.159) (xy -1.285748 1.8796) (xy -1.778 1.8796) (xy -1.778 -1.8796) (xy 1.778 -1.8796)
				(xy 1.778 1.8796) (xy -0.694944 1.8796) (xy -0.694944 2.159)
			)
			(stroke
				(width 0)
				(type default)
			)
			(fill no)
			(layer "F.Fab")
		)
		(pad "1" smd rect
			(at -0.98425 0.9525 180)
			(size 0.762 1.143)
			(layers "F.Cu" "F.Mask" "F.Paste")
			(net "INTA_LED_BLUE_B")
		)
		(pad "2" smd rect
			(at 0.98425 0.9525 180)
			(size 0.762 1.143)
			(layers "F.Cu" "F.Mask" "F.Paste")
			(net "GND")
		)
		(pad "3" smd rect
			(at 0 -0.9525 180)
			(size 0.762 1.143)
			(layers "F.Cu" "F.Mask" "F.Paste")
			(net "INTA_LED_BLUE_C")
		)
	)
	(footprint ""
		(layer "F.Cu")
		(at 184.031128 -25.535128 -90)
		(property "Reference" "R455"
			(at 0 0 270)
			(layer "F.SilkS")
			(hide yes)
			(effects
				(font
					(size 1.27 1.27)
				)
			)
		)
		(property "Value" "4K75R2F-1-GP"
			(at 0.064008 -3.993896 270)
			(unlocked yes)
			(layer "F.Fab")
			(hide yes)
			(effects
				(font
					(size 1.016 1.016)
					(thickness 0.1524)
				)
			)
		)
		(property "Device Type" "R402H16"
			(at 0.064008 -5.517896 270)
			(unlocked yes)
			(layer "F.Fab")
			(hide yes)
			(effects
				(font
					(size 1.016 1.016)
					(thickness 0.1524)
				)
			)
		)
		(duplicate_pad_numbers_are_jumpers no)
		(fp_line
			(start -0.508 -0.9398)
			(end -0.508 0.9398)
			(stroke
				(width 0.1524)
				(type default)
			)
			(layer "F.SilkS")
		)
		(fp_line
			(start 0.508 -0.9398)
			(end -0.508 -0.9398)
			(stroke
				(width 0.1524)
				(type default)
			)
			(layer "F.SilkS")
		)
		(fp_rect
			(start -0.508 0.9398)
			(end 0.508 -0.9398)
			(stroke
				(width 0)
				(type default)
			)
			(fill no)
			(layer "F.CrtYd")
		)
		(fp_rect
			(start -0.508 0.9398)
			(end 0.508 -0.9398)
			(stroke
				(width 0)
				(type default)
			)
			(fill no)
			(layer "F.Fab")
		)
		(pad "1" smd custom
			(at 0 -0.4445 270)
			(size 0.1397 0.1397)
			(layers "F.Cu" "F.Mask" "F.Paste")
			(net "P3V3_STBY")
			(options
				(clearance outline)
				(anchor circle)
			)
			(primitives
				(gr_poly
					(pts
						(arc
							(start -0.1778 -0.2794)
							(mid -0.249642 -0.249642)
							(end -0.2794 -0.1778)
						)
						(arc
							(start -0.2794 0.1778)
							(mid -0.249642 0.249642)
							(end -0.1778 0.2794)
						)
						(arc
							(start 0.1778 0.2794)
							(mid 0.249642 0.249642)
							(end 0.2794 0.1778)
						)
						(arc
							(start 0.2794 -0.1778)
							(mid 0.249642 -0.249642)
							(end 0.1778 -0.2794)
						)
					)
					(width 0)
					(fill yes)
				)
			)
		)
		(pad "2" smd custom
			(at 0 0.4445 270)
			(size 0.1397 0.1397)
			(layers "F.Cu" "F.Mask" "F.Paste")
			(net "RMII_BMC_MDC_R")
			(options
				(clearance outline)
				(anchor circle)
			)
			(primitives
				(gr_poly
					(pts
						(arc
							(start -0.1778 -0.2794)
							(mid -0.249642 -0.249642)
							(end -0.2794 -0.1778)
						)
						(arc
							(start -0.2794 0.1778)
							(mid -0.249642 0.249642)
							(end -0.1778 0.2794)
						)
						(arc
							(start 0.1778 0.2794)
							(mid 0.249642 0.249642)
							(end 0.2794 0.1778)
						)
						(arc
							(start 0.2794 -0.1778)
							(mid 0.249642 -0.249642)
							(end 0.1778 -0.2794)
						)
					)
					(width 0)
					(fill yes)
				)
			)
		)
	)
	(footprint ""
		(layer "F.Cu")
		(at 90.17 -236.728)
		(property "Reference" "SU16"
			(at 0 0 0)
			(layer "F.SilkS")
			(hide yes)
			(effects
				(font
					(size 1.27 1.27)
				)
			)
		)
		(property "Value" "PI3C3861-AQE-GP"
			(at 0 -13.1572 0)
			(unlocked yes)
			(layer "F.Fab")
			(hide yes)
			(effects
				(font
					(size 1.016 1.016)
					(thickness 0.1524)
				)
			)
		)
		(property "Device Type" "QSOIC24H69"
			(at 0 -15.1892 0)
			(unlocked yes)
			(layer "F.Fab")
			(hide yes)
			(effects
				(font
					(size 1.016 1.016)
					(thickness 0.1524)
				)
			)
		)
		(duplicate_pad_numbers_are_jumpers no)
		(fp_line
			(start -4.4958 -1.5748)
			(end 3.5814 -1.5748)
			(stroke
				(width 0.1524)
				(type default)
			)
			(layer "F.SilkS")
		)
		(fp_line
			(start -4.4958 -0.4318)
			(end -4.4958 -1.5748)
			(stroke
				(width 0.1524)
				(type default)
			)
			(layer "F.SilkS")
		)
		(fp_line
			(start -4.4958 -0.4318)
			(end -4.064 0)
			(stroke
				(width 0.1524)
				(type default)
			)
			(layer "F.SilkS")
		)
		(fp_line
			(start -4.4958 0.4318)
			(end -4.4958 -0.4318)
			(stroke
				(width 0.1524)
				(type default)
			)
			(layer "F.SilkS")
		)
		(fp_line
			(start -4.4958 0.4318)
			(end -4.4958 1.5748)
			(stroke
				(width 0.1524)
				(type default)
			)
			(layer "F.SilkS")
		)
		(fp_line
			(start -4.318 1.5748)
			(end -4.318 3.556)
			(stroke
				(width 0.508)
				(type default)
			)
			(layer "F.SilkS")
		)
		(fp_line
			(start -4.064 0)
			(end -4.4958 0.4318)
			(stroke
				(width 0.1524)
				(type default)
			)
			(layer "F.SilkS")
		)
		(fp_line
			(start 3.5814 -1.5748)
			(end 3.5814 1.5748)
			(stroke
				(width 0.1524)
				(type default)
			)
			(layer "F.SilkS")
		)
		(fp_line
			(start 3.5814 1.5748)
			(end -4.4958 1.5748)
			(stroke
				(width 0.1524)
				(type default)
			)
			(layer "F.SilkS")
		)
		(fp_line
			(start 3.5814 1.5748)
			(end 3.5814 -1.5748)
			(stroke
				(width 0.1524)
				(type default)
			)
			(layer "F.SilkS")
		)
		(fp_poly
			(pts
				(xy -3.683 -1.5748) (xy 3.5814 -1.5748) (xy 3.5814 1.5748) (xy -3.683 1.5748)
			)
			(stroke
				(width 0)
				(type default)
			)
			(fill yes)
			(layer "F.SilkS")
		)
		(fp_rect
			(start -4.572 3.81)
			(end 4.572 -3.81)
			(stroke
				(width 0)
				(type default)
			)
			(fill no)
			(layer "F.CrtYd")
		)
		(fp_poly
			(pts
				(xy -4.572 -3.81) (xy 4.572 -3.81) (xy 4.572 3.81) (xy -4.572 3.81)
			)
			(stroke
				(width 0)
				(type default)
			)
			(fill no)
			(layer "F.Fab")
		)
		(pad "1" smd rect
			(at -3.4925 2.6162)
			(size 0.3556 1.524)
			(layers "F.Cu" "F.Mask" "F.Paste")
			(net "Net_172")
		)
		(pad "2" smd rect
			(at -2.8575 2.6162)
			(size 0.3556 1.524)
			(layers "F.Cu" "F.Mask" "F.Paste")
			(net "SAS_HDD_LED_10")
		)
		(pad "3" smd rect
			(at -2.2225 2.6162)
			(size 0.3556 1.524)
			(layers "F.Cu" "F.Mask" "F.Paste")
			(net "SAS_HDD_LED_11")
		)
		(pad "4" smd rect
			(at -1.5875 2.6162)
			(size 0.3556 1.524)
			(layers "F.Cu" "F.Mask" "F.Paste")
			(net "SAS_HDD_LED_12")
		)
		(pad "5" smd rect
			(at -0.9525 2.6162)
			(size 0.3556 1.524)
			(layers "F.Cu" "F.Mask" "F.Paste")
			(net "SAS_HDD_LED_13")
		)
		(pad "6" smd rect
			(at -0.3175 2.6162)
			(size 0.3556 1.524)
			(layers "F.Cu" "F.Mask" "F.Paste")
			(net "SAS_HDD_LED_14")
		)
		(pad "7" smd rect
			(at 0.3175 2.6162)
			(size 0.3556 1.524)
			(layers "F.Cu" "F.Mask" "F.Paste")
			(net "SAS_HDD_LED_15")
		)
		(pad "8" smd rect
			(at 0.9525 2.6162)
			(size 0.3556 1.524)
			(layers "F.Cu" "F.Mask" "F.Paste")
			(net "Net_170")
		)
		(pad "9" smd rect
			(at 1.5875 2.6162)
			(size 0.3556 1.524)
			(layers "F.Cu" "F.Mask" "F.Paste")
			(net "Net_171")
		)
		(pad "10" smd rect
			(at 2.2225 2.6162)
			(size 0.3556 1.524)
			(layers "F.Cu" "F.Mask" "F.Paste")
			(net "Net_167")
		)
		(pad "11" smd rect
			(at 2.8575 2.6162)
			(size 0.3556 1.524)
			(layers "F.Cu" "F.Mask" "F.Paste")
			(net "Net_168")
		)
		(pad "12" smd rect
			(at 3.4925 2.6162)
			(size 0.3556 1.524)
			(layers "F.Cu" "F.Mask" "F.Paste")
			(net "GND")
		)
		(pad "13" smd rect
			(at 3.4925 -2.6162)
			(size 0.3556 1.524)
			(layers "F.Cu" "F.Mask" "F.Paste")
			(net "Net_164")
		)
		(pad "14" smd rect
			(at 2.8575 -2.6162)
			(size 0.3556 1.524)
			(layers "F.Cu" "F.Mask" "F.Paste")
			(net "Net_165")
		)
		(pad "15" smd rect
			(at 2.2225 -2.6162)
			(size 0.3556 1.524)
			(layers "F.Cu" "F.Mask" "F.Paste")
			(net "Net_166")
		)
		(pad "16" smd rect
			(at 1.5875 -2.6162)
			(size 0.3556 1.524)
			(layers "F.Cu" "F.Mask" "F.Paste")
			(net "Net_169")
		)
		(pad "17" smd rect
			(at 0.9525 -2.6162)
			(size 0.3556 1.524)
			(layers "F.Cu" "F.Mask" "F.Paste")
			(net "SAS_FAULT_LED15")
		)
		(pad "18" smd rect
			(at 0.3175 -2.6162)
			(size 0.3556 1.524)
			(layers "F.Cu" "F.Mask" "F.Paste")
			(net "SAS_FAULT_LED14")
		)
		(pad "19" smd rect
			(at -0.3175 -2.6162)
			(size 0.3556 1.524)
			(layers "F.Cu" "F.Mask" "F.Paste")
			(net "SAS_FAULT_LED13")
		)
		(pad "20" smd rect
			(at -0.9525 -2.6162)
			(size 0.3556 1.524)
			(layers "F.Cu" "F.Mask" "F.Paste")
			(net "SAS_FAULT_LED12")
		)
		(pad "21" smd rect
			(at -1.5875 -2.6162)
			(size 0.3556 1.524)
			(layers "F.Cu" "F.Mask" "F.Paste")
			(net "SAS_FAULT_LED11")
		)
		(pad "22" smd rect
			(at -2.2225 -2.6162)
			(size 0.3556 1.524)
			(layers "F.Cu" "F.Mask" "F.Paste")
			(net "SAS_FAULT_LED10")
		)
		(pad "23" smd rect
			(at -2.8575 -2.6162)
			(size 0.3556 1.524)
			(layers "F.Cu" "F.Mask" "F.Paste")
			(net "PCIE_MATED#_LED_CD")
		)
		(pad "24" smd rect
			(at -3.4925 -2.6162)
			(size 0.3556 1.524)
			(layers "F.Cu" "F.Mask" "F.Paste")
			(net "P3V3_STBY")
		)
	)
	(footprint ""
		(layer "F.Cu")
		(at 181.356 -221.742 180)
		(property "Reference" "R219"
			(at 0 0 180)
			(layer "F.SilkS")
			(hide yes)
			(effects
				(font
					(size 1.27 1.27)
				)
			)
		)
		(property "Value" "10KR2F-2-GP"
			(at 0.064008 -3.993896 180)
			(unlocked yes)
			(layer "F.Fab")
			(hide yes)
			(effects
				(font
					(size 1.016 1.016)
					(thickness 0.1524)
				)
			)
		)
		(property "Device Type" "R402H16"
			(at 0.064008 -5.517896 180)
			(unlocked yes)
			(layer "F.Fab")
			(hide yes)
			(effects
				(font
					(size 1.016 1.016)
					(thickness 0.1524)
				)
			)
		)
		(duplicate_pad_numbers_are_jumpers no)
		(fp_line
			(start 0.508 -0.9398)
			(end -0.508 -0.9398)
			(stroke
				(width 0.1524)
				(type default)
			)
			(layer "F.SilkS")
		)
		(fp_line
			(start -0.508 -0.9398)
			(end -0.508 0.9398)
			(stroke
				(width 0.1524)
				(type default)
			)
			(layer "F.SilkS")
		)
		(fp_rect
			(start -0.508 0.9398)
			(end 0.508 -0.9398)
			(stroke
				(width 0)
				(type default)
			)
			(fill no)
			(layer "F.CrtYd")
		)
		(fp_rect
			(start -0.508 0.9398)
			(end 0.508 -0.9398)
			(stroke
				(width 0)
				(type default)
			)
			(fill no)
			(layer "F.Fab")
		)
		(pad "1" smd custom
			(at 0 -0.4445 180)
			(size 0.1397 0.1397)
			(layers "F.Cu" "F.Mask" "F.Paste")
			(net "P3V3_STBY")
			(options
				(clearance outline)
				(anchor circle)
			)
			(primitives
				(gr_poly
					(pts
						(arc
							(start -0.1778 -0.2794)
							(mid -0.249642 -0.249642)
							(end -0.2794 -0.1778)
						)
						(arc
							(start -0.2794 0.1778)
							(mid -0.249642 0.249642)
							(end -0.1778 0.2794)
						)
						(arc
							(start 0.1778 0.2794)
							(mid 0.249642 0.249642)
							(end 0.2794 0.1778)
						)
						(arc
							(start 0.2794 -0.1778)
							(mid 0.249642 -0.249642)
							(end 0.1778 -0.2794)
						)
					)
					(width 0)
					(fill yes)
				)
			)
		)
		(pad "2" smd custom
			(at 0 0.4445 180)
			(size 0.1397 0.1397)
			(layers "F.Cu" "F.Mask" "F.Paste")
			(net "PWRBTN_OUT_N")
			(options
				(clearance outline)
				(anchor circle)
			)
			(primitives
				(gr_poly
					(pts
						(arc
							(start -0.1778 -0.2794)
							(mid -0.249642 -0.249642)
							(end -0.2794 -0.1778)
						)
						(arc
							(start -0.2794 0.1778)
							(mid -0.249642 0.249642)
							(end -0.1778 0.2794)
						)
						(arc
							(start 0.1778 0.2794)
							(mid 0.249642 0.249642)
							(end 0.2794 0.1778)
						)
						(arc
							(start 0.2794 -0.1778)
							(mid 0.249642 -0.249642)
							(end 0.1778 -0.2794)
						)
					)
					(width 0)
					(fill yes)
				)
			)
		)
	)
	(footprint ""
		(layer "F.Cu")
		(at 188.149992 -38.227 180)
		(property "Reference" "R379"
			(at 0 0 180)
			(layer "F.SilkS")
			(hide yes)
			(effects
				(font
					(size 1.27 1.27)
				)
			)
		)
		(property "Value" "33R2J-2-GP"
			(at 0.064008 -3.993896 180)
			(unlocked yes)
			(layer "F.Fab")
			(hide yes)
			(effects
				(font
					(size 1.016 1.016)
					(thickness 0.1524)
				)
			)
		)
		(property "Device Type" "R402H16"
			(at 0.064008 -5.517896 180)
			(unlocked yes)
			(layer "F.Fab")
			(hide yes)
			(effects
				(font
					(size 1.016 1.016)
					(thickness 0.1524)
				)
			)
		)
		(duplicate_pad_numbers_are_jumpers no)
		(fp_line
			(start 0.508 -0.9398)
			(end -0.508 -0.9398)
			(stroke
				(width 0.1524)
				(type default)
			)
			(layer "F.SilkS")
		)
		(fp_line
			(start -0.508 -0.9398)
			(end -0.508 0.9398)
			(stroke
				(width 0.1524)
				(type default)
			)
			(layer "F.SilkS")
		)
		(fp_rect
			(start -0.508 0.9398)
			(end 0.508 -0.9398)
			(stroke
				(width 0)
				(type default)
			)
			(fill no)
			(layer "F.CrtYd")
		)
		(fp_rect
			(start -0.508 0.9398)
			(end 0.508 -0.9398)
			(stroke
				(width 0)
				(type default)
			)
			(fill no)
			(layer "F.Fab")
		)
		(pad "1" smd custom
			(at 0 -0.4445 180)
			(size 0.1397 0.1397)
			(layers "F.Cu" "F.Mask" "F.Paste")
			(net "RMII_BMC_CRS_DV_R")
			(options
				(clearance outline)
				(anchor circle)
			)
			(primitives
				(gr_poly
					(pts
						(arc
							(start -0.1778 -0.2794)
							(mid -0.249642 -0.249642)
							(end -0.2794 -0.1778)
						)
						(arc
							(start -0.2794 0.1778)
							(mid -0.249642 0.249642)
							(end -0.1778 0.2794)
						)
						(arc
							(start 0.1778 0.2794)
							(mid 0.249642 0.249642)
							(end 0.2794 0.1778)
						)
						(arc
							(start 0.2794 -0.1778)
							(mid 0.249642 -0.249642)
							(end 0.1778 -0.2794)
						)
					)
					(width 0)
					(fill yes)
				)
			)
		)
		(pad "2" smd custom
			(at 0 0.4445 180)
			(size 0.1397 0.1397)
			(layers "F.Cu" "F.Mask" "F.Paste")
			(net "RMII_BMC_CRS_DV")
			(options
				(clearance outline)
				(anchor circle)
			)
			(primitives
				(gr_poly
					(pts
						(arc
							(start -0.1778 -0.2794)
							(mid -0.249642 -0.249642)
							(end -0.2794 -0.1778)
						)
						(arc
							(start -0.2794 0.1778)
							(mid -0.249642 0.249642)
							(end -0.1778 0.2794)
						)
						(arc
							(start 0.1778 0.2794)
							(mid 0.249642 0.249642)
							(end 0.2794 0.1778)
						)
						(arc
							(start 0.2794 -0.1778)
							(mid 0.249642 -0.249642)
							(end 0.1778 -0.2794)
						)
					)
					(width 0)
					(fill yes)
				)
			)
		)
	)
	(footprint ""
		(layer "F.Cu")
		(at 25.858216 -237.29188 180)
		(property "Reference" "SC427"
			(at 0 0 180)
			(layer "F.SilkS")
			(hide yes)
			(effects
				(font
					(size 1.27 1.27)
				)
			)
		)
		(property "Value" "SCD1U16V2KX-3GP"
			(at 1.1811 -2.7051 180)
			(unlocked yes)
			(layer "F.Fab")
			(hide yes)
			(effects
				(font
					(size 1.016 1.016)
					(thickness 0.1524)
				)
			)
		)
		(property "Device Type" "C402H22"
			(at 1.1811 -4.2291 180)
			(unlocked yes)
			(layer "F.Fab")
			(hide yes)
			(effects
				(font
					(size 1.016 1.016)
					(thickness 0.1524)
				)
			)
		)
		(duplicate_pad_numbers_are_jumpers no)
		(fp_rect
			(start -0.4318 0.9525)
			(end 0.4318 -0.9525)
			(stroke
				(width 0)
				(type default)
			)
			(fill no)
			(layer "F.CrtYd")
		)
		(fp_rect
			(start -0.4318 0.9525)
			(end 0.4318 -0.9525)
			(stroke
				(width 0)
				(type default)
			)
			(fill no)
			(layer "F.Fab")
		)
		(pad "1" smd custom
			(at 0 -0.4445 180)
			(size 0.1524 0.1524)
			(layers "F.Cu" "F.Mask" "F.Paste")
			(net "P3V3_STBY")
			(options
				(clearance outline)
				(anchor circle)
			)
			(primitives
				(gr_poly
					(pts
						(arc
							(start 0.3048 -0.2032)
							(mid 0.275042 -0.275042)
							(end 0.2032 -0.3048)
						)
						(arc
							(start -0.2032 -0.3048)
							(mid -0.275042 -0.275042)
							(end -0.3048 -0.2032)
						)
						(arc
							(start -0.3048 0.2032)
							(mid -0.275042 0.275042)
							(end -0.2032 0.3048)
						)
						(arc
							(start 0.2032 0.3048)
							(mid 0.275042 0.275042)
							(end 0.3048 0.2032)
						)
					)
					(width 0)
					(fill yes)
				)
			)
		)
		(pad "2" smd custom
			(at 0 0.4445 180)
			(size 0.1524 0.1524)
			(layers "F.Cu" "F.Mask" "F.Paste")
			(net "GND")
			(options
				(clearance outline)
				(anchor circle)
			)
			(primitives
				(gr_poly
					(pts
						(arc
							(start 0.3048 -0.2032)
							(mid 0.275042 -0.275042)
							(end 0.2032 -0.3048)
						)
						(arc
							(start -0.2032 -0.3048)
							(mid -0.275042 -0.275042)
							(end -0.3048 -0.2032)
						)
						(arc
							(start -0.3048 0.2032)
							(mid -0.275042 0.275042)
							(end -0.2032 0.3048)
						)
						(arc
							(start 0.2032 0.3048)
							(mid 0.275042 0.275042)
							(end 0.3048 0.2032)
						)
					)
					(width 0)
					(fill yes)
				)
			)
		)
	)
	(footprint ""
		(layer "F.Cu")
		(at 53.848 -180.086 180)
		(property "Reference" "SR810"
			(at 0 0 180)
			(layer "F.SilkS")
			(hide yes)
			(effects
				(font
					(size 1.27 1.27)
				)
			)
		)
		(property "Value" "4K75R2F-1-GP"
			(at 0.064008 -3.993896 180)
			(unlocked yes)
			(layer "F.Fab")
			(hide yes)
			(effects
				(font
					(size 1.016 1.016)
					(thickness 0.1524)
				)
			)
		)
		(property "Device Type" "R402H16"
			(at 0.064008 -5.517896 180)
			(unlocked yes)
			(layer "F.Fab")
			(hide yes)
			(effects
				(font
					(size 1.016 1.016)
					(thickness 0.1524)
				)
			)
		)
		(duplicate_pad_numbers_are_jumpers no)
		(fp_line
			(start 0.508 -0.9398)
			(end -0.508 -0.9398)
			(stroke
				(width 0.1524)
				(type default)
			)
			(layer "F.SilkS")
		)
		(fp_line
			(start -0.508 -0.9398)
			(end -0.508 0.9398)
			(stroke
				(width 0.1524)
				(type default)
			)
			(layer "F.SilkS")
		)
		(fp_rect
			(start -0.508 0.9398)
			(end 0.508 -0.9398)
			(stroke
				(width 0)
				(type default)
			)
			(fill no)
			(layer "F.CrtYd")
		)
		(fp_rect
			(start -0.508 0.9398)
			(end 0.508 -0.9398)
			(stroke
				(width 0)
				(type default)
			)
			(fill no)
			(layer "F.Fab")
		)
		(pad "1" smd custom
			(at 0 -0.4445 180)
			(size 0.1397 0.1397)
			(layers "F.Cu" "F.Mask" "F.Paste")
			(net "P1V8_E")
			(options
				(clearance outline)
				(anchor circle)
			)
			(primitives
				(gr_poly
					(pts
						(arc
							(start -0.1778 -0.2794)
							(mid -0.249642 -0.249642)
							(end -0.2794 -0.1778)
						)
						(arc
							(start -0.2794 0.1778)
							(mid -0.249642 0.249642)
							(end -0.1778 0.2794)
						)
						(arc
							(start 0.1778 0.2794)
							(mid 0.249642 0.249642)
							(end 0.2794 0.1778)
						)
						(arc
							(start 0.2794 -0.1778)
							(mid 0.249642 -0.249642)
							(end 0.1778 -0.2794)
						)
					)
					(width 0)
					(fill yes)
				)
			)
		)
		(pad "2" smd custom
			(at 0 0.4445 180)
			(size 0.1397 0.1397)
			(layers "F.Cu" "F.Mask" "F.Paste")
			(net "ICE_TDI")
			(options
				(clearance outline)
				(anchor circle)
			)
			(primitives
				(gr_poly
					(pts
						(arc
							(start -0.1778 -0.2794)
							(mid -0.249642 -0.249642)
							(end -0.2794 -0.1778)
						)
						(arc
							(start -0.2794 0.1778)
							(mid -0.249642 0.249642)
							(end -0.1778 0.2794)
						)
						(arc
							(start 0.1778 0.2794)
							(mid 0.249642 0.249642)
							(end 0.2794 0.1778)
						)
						(arc
							(start 0.2794 -0.1778)
							(mid 0.249642 -0.249642)
							(end 0.1778 -0.2794)
						)
					)
					(width 0)
					(fill yes)
				)
			)
		)
	)
	(footprint ""
		(layer "F.Cu")
		(at 80.64627 -79.540608 90)
		(property "Reference" "SR837"
			(at 0 0 90)
			(layer "F.SilkS")
			(hide yes)
			(effects
				(font
					(size 1.27 1.27)
				)
			)
		)
		(property "Value" "10R2F-L-GP"
			(at 0.064008 -3.993896 90)
			(unlocked yes)
			(layer "F.Fab")
			(hide yes)
			(effects
				(font
					(size 1.016 1.016)
					(thickness 0.1524)
				)
			)
		)
		(property "Device Type" "R402H14"
			(at 0.064008 -5.517896 90)
			(unlocked yes)
			(layer "F.Fab")
			(hide yes)
			(effects
				(font
					(size 1.016 1.016)
					(thickness 0.1524)
				)
			)
		)
		(duplicate_pad_numbers_are_jumpers no)
		(fp_line
			(start 0.508 -0.9398)
			(end -0.508 -0.9398)
			(stroke
				(width 0.1524)
				(type default)
			)
			(layer "F.SilkS")
		)
		(fp_line
			(start -0.508 -0.9398)
			(end -0.508 0.9398)
			(stroke
				(width 0.1524)
				(type default)
			)
			(layer "F.SilkS")
		)
		(fp_rect
			(start -0.508 0.9398)
			(end 0.508 -0.9398)
			(stroke
				(width 0)
				(type default)
			)
			(fill no)
			(layer "F.CrtYd")
		)
		(fp_rect
			(start -0.508 0.9398)
			(end 0.508 -0.9398)
			(stroke
				(width 0)
				(type default)
			)
			(fill no)
			(layer "F.Fab")
		)
		(pad "1" smd custom
			(at 0 -0.4445 90)
			(size 0.1397 0.1397)
			(layers "F.Cu" "F.Mask" "F.Paste")
			(net "P0V9_E")
			(options
				(clearance outline)
				(anchor circle)
			)
			(primitives
				(gr_poly
					(pts
						(arc
							(start -0.1778 -0.2794)
							(mid -0.249642 -0.249642)
							(end -0.2794 -0.1778)
						)
						(arc
							(start -0.2794 0.1778)
							(mid -0.249642 0.249642)
							(end -0.1778 0.2794)
						)
						(arc
							(start 0.1778 0.2794)
							(mid 0.249642 0.249642)
							(end 0.2794 0.1778)
						)
						(arc
							(start 0.2794 -0.1778)
							(mid 0.249642 -0.249642)
							(end 0.1778 -0.2794)
						)
					)
					(width 0)
					(fill yes)
				)
			)
		)
		(pad "2" smd custom
			(at 0 0.4445 90)
			(size 0.1397 0.1397)
			(layers "F.Cu" "F.Mask" "F.Paste")
			(net "XTAL_VDDA09")
			(options
				(clearance outline)
				(anchor circle)
			)
			(primitives
				(gr_poly
					(pts
						(arc
							(start -0.1778 -0.2794)
							(mid -0.249642 -0.249642)
							(end -0.2794 -0.1778)
						)
						(arc
							(start -0.2794 0.1778)
							(mid -0.249642 0.249642)
							(end -0.1778 0.2794)
						)
						(arc
							(start 0.1778 0.2794)
							(mid 0.249642 0.249642)
							(end 0.2794 0.1778)
						)
						(arc
							(start 0.2794 -0.1778)
							(mid 0.249642 -0.249642)
							(end 0.1778 -0.2794)
						)
					)
					(width 0)
					(fill yes)
				)
			)
		)
	)
	(footprint ""
		(layer "F.Cu")
		(at 267.7668 -76.0984 90)
		(property "Reference" "C262"
			(at 0 0 90)
			(layer "F.SilkS")
			(hide yes)
			(effects
				(font
					(size 1.27 1.27)
				)
			)
		)
		(property "Value" "SCD1U25V2KX-2-GP"
			(at 1.1811 -2.7051 90)
			(unlocked yes)
			(layer "F.Fab")
			(hide yes)
			(effects
				(font
					(size 1.016 1.016)
					(thickness 0.1524)
				)
			)
		)
		(property "Device Type" "C402H22"
			(at 1.1811 -4.2291 90)
			(unlocked yes)
			(layer "F.Fab")
			(hide yes)
			(effects
				(font
					(size 1.016 1.016)
					(thickness 0.1524)
				)
			)
		)
		(duplicate_pad_numbers_are_jumpers no)
		(fp_rect
			(start -0.4318 0.9525)
			(end 0.4318 -0.9525)
			(stroke
				(width 0)
				(type default)
			)
			(fill no)
			(layer "F.CrtYd")
		)
		(fp_rect
			(start -0.4318 0.9525)
			(end 0.4318 -0.9525)
			(stroke
				(width 0)
				(type default)
			)
			(fill no)
			(layer "F.Fab")
		)
		(pad "1" smd custom
			(at 0 -0.4445 90)
			(size 0.1524 0.1524)
			(layers "F.Cu" "F.Mask" "F.Paste")
			(net "P12V_MSB")
			(options
				(clearance outline)
				(anchor circle)
			)
			(primitives
				(gr_poly
					(pts
						(arc
							(start 0.3048 -0.2032)
							(mid 0.275042 -0.275042)
							(end 0.2032 -0.3048)
						)
						(arc
							(start -0.2032 -0.3048)
							(mid -0.275042 -0.275042)
							(end -0.3048 -0.2032)
						)
						(arc
							(start -0.3048 0.2032)
							(mid -0.275042 0.275042)
							(end -0.2032 0.3048)
						)
						(arc
							(start 0.2032 0.3048)
							(mid 0.275042 0.275042)
							(end 0.3048 0.2032)
						)
					)
					(width 0)
					(fill yes)
				)
			)
		)
		(pad "2" smd custom
			(at 0 0.4445 90)
			(size 0.1524 0.1524)
			(layers "F.Cu" "F.Mask" "F.Paste")
			(net "GND")
			(options
				(clearance outline)
				(anchor circle)
			)
			(primitives
				(gr_poly
					(pts
						(arc
							(start 0.3048 -0.2032)
							(mid 0.275042 -0.275042)
							(end 0.2032 -0.3048)
						)
						(arc
							(start -0.2032 -0.3048)
							(mid -0.275042 -0.275042)
							(end -0.3048 -0.2032)
						)
						(arc
							(start -0.3048 0.2032)
							(mid -0.275042 0.275042)
							(end -0.2032 0.3048)
						)
						(arc
							(start 0.2032 0.3048)
							(mid 0.275042 0.275042)
							(end 0.3048 0.2032)
						)
					)
					(width 0)
					(fill yes)
				)
			)
		)
	)
	(footprint ""
		(layer "F.Cu")
		(at 171.131992 -14.351 -90)
		(property "Reference" "R415"
			(at 0 0 270)
			(layer "F.SilkS")
			(hide yes)
			(effects
				(font
					(size 1.27 1.27)
				)
			)
		)
		(property "Value" "150R3J-L-GP"
			(at -0.0254 -2.5146 270)
			(unlocked yes)
			(layer "F.Fab")
			(hide yes)
			(effects
				(font
					(size 1.016 1.016)
					(thickness 0.1524)
				)
			)
		)
		(property "Device Type" "R603H22"
			(at -0.0254 -4.0386 270)
			(unlocked yes)
			(layer "F.Fab")
			(hide yes)
			(effects
				(font
					(size 1.016 1.016)
					(thickness 0.1524)
				)
			)
		)
		(duplicate_pad_numbers_are_jumpers no)
		(fp_line
			(start -0.4826 0)
			(end -0.2032 0)
			(stroke
				(width 0.2032)
				(type default)
			)
			(layer "F.SilkS")
		)
		(fp_line
			(start 0.2032 0)
			(end 0.4826 0)
			(stroke
				(width 0.2032)
				(type default)
			)
			(layer "F.SilkS")
		)
		(fp_rect
			(start -0.5842 1.3335)
			(end 0.5842 -1.3335)
			(stroke
				(width 0)
				(type default)
			)
			(fill no)
			(layer "F.CrtYd")
		)
		(fp_rect
			(start -0.5842 1.3335)
			(end 0.5842 -1.3335)
			(stroke
				(width 0)
				(type default)
			)
			(fill no)
			(layer "F.Fab")
		)
		(pad "1" smd custom
			(at 0 -0.762 270)
			(size 0.2159 0.2159)
			(layers "F.Cu" "F.Mask" "F.Paste")
			(net "P3V3_STBY")
			(options
				(clearance outline)
				(anchor circle)
			)
			(primitives
				(gr_poly
					(pts
						(arc
							(start -0.3302 -0.4318)
							(mid -0.402042 -0.402042)
							(end -0.4318 -0.3302)
						)
						(arc
							(start -0.4318 0.3302)
							(mid -0.402042 0.402042)
							(end -0.3302 0.4318)
						)
						(arc
							(start 0.3302 0.4318)
							(mid 0.402042 0.402042)
							(end 0.4318 0.3302)
						)
						(arc
							(start 0.4318 -0.3302)
							(mid 0.402042 -0.402042)
							(end 0.3302 -0.4318)
						)
					)
					(width 0)
					(fill yes)
				)
			)
		)
		(pad "2" smd custom
			(at 0 0.762 270)
			(size 0.2159 0.2159)
			(layers "F.Cu" "F.Mask" "F.Paste")
			(net "LED_MDI0_LINK")
			(options
				(clearance outline)
				(anchor circle)
			)
			(primitives
				(gr_poly
					(pts
						(arc
							(start -0.3302 -0.4318)
							(mid -0.402042 -0.402042)
							(end -0.4318 -0.3302)
						)
						(arc
							(start -0.4318 0.3302)
							(mid -0.402042 0.402042)
							(end -0.3302 0.4318)
						)
						(arc
							(start 0.3302 0.4318)
							(mid 0.402042 0.402042)
							(end 0.4318 0.3302)
						)
						(arc
							(start 0.4318 -0.3302)
							(mid 0.402042 -0.402042)
							(end 0.3302 -0.4318)
						)
					)
					(width 0)
					(fill yes)
				)
			)
		)
	)
	(footprint ""
		(layer "F.Cu")
		(at 173.981872 -202.637136 90)
		(property "Reference" "R151"
			(at 0 0 90)
			(layer "F.SilkS")
			(hide yes)
			(effects
				(font
					(size 1.27 1.27)
				)
			)
		)
		(property "Value" "0R2J-2-GP"
			(at 0.064008 -3.993896 90)
			(unlocked yes)
			(layer "F.Fab")
			(hide yes)
			(effects
				(font
					(size 1.016 1.016)
					(thickness 0.1524)
				)
			)
		)
		(property "Device Type" "R402H16"
			(at 0.064008 -5.517896 90)
			(unlocked yes)
			(layer "F.Fab")
			(hide yes)
			(effects
				(font
					(size 1.016 1.016)
					(thickness 0.1524)
				)
			)
		)
		(duplicate_pad_numbers_are_jumpers no)
		(fp_line
			(start 0.508 -0.9398)
			(end -0.508 -0.9398)
			(stroke
				(width 0.1524)
				(type default)
			)
			(layer "F.SilkS")
		)
		(fp_line
			(start -0.508 -0.9398)
			(end -0.508 0.9398)
			(stroke
				(width 0.1524)
				(type default)
			)
			(layer "F.SilkS")
		)
		(fp_rect
			(start -0.508 0.9398)
			(end 0.508 -0.9398)
			(stroke
				(width 0)
				(type default)
			)
			(fill no)
			(layer "F.CrtYd")
		)
		(fp_rect
			(start -0.508 0.9398)
			(end 0.508 -0.9398)
			(stroke
				(width 0)
				(type default)
			)
			(fill no)
			(layer "F.Fab")
		)
		(pad "1" smd custom
			(at 0 -0.4445 90)
			(size 0.1397 0.1397)
			(layers "F.Cu" "F.Mask" "F.Paste")
			(net "SAS_I2C_B_BUF_SCL_R")
			(options
				(clearance outline)
				(anchor circle)
			)
			(primitives
				(gr_poly
					(pts
						(arc
							(start -0.1778 -0.2794)
							(mid -0.249642 -0.249642)
							(end -0.2794 -0.1778)
						)
						(arc
							(start -0.2794 0.1778)
							(mid -0.249642 0.249642)
							(end -0.1778 0.2794)
						)
						(arc
							(start 0.1778 0.2794)
							(mid 0.249642 0.249642)
							(end 0.2794 0.1778)
						)
						(arc
							(start 0.2794 -0.1778)
							(mid 0.249642 -0.249642)
							(end 0.1778 -0.2794)
						)
					)
					(width 0)
					(fill yes)
				)
			)
		)
		(pad "2" smd custom
			(at 0 0.4445 90)
			(size 0.1397 0.1397)
			(layers "F.Cu" "F.Mask" "F.Paste")
			(net "SAS_I2C_B_BUF_SCL")
			(options
				(clearance outline)
				(anchor circle)
			)
			(primitives
				(gr_poly
					(pts
						(arc
							(start -0.1778 -0.2794)
							(mid -0.249642 -0.249642)
							(end -0.2794 -0.1778)
						)
						(arc
							(start -0.2794 0.1778)
							(mid -0.249642 0.249642)
							(end -0.1778 0.2794)
						)
						(arc
							(start 0.1778 0.2794)
							(mid 0.249642 0.249642)
							(end 0.2794 0.1778)
						)
						(arc
							(start 0.2794 -0.1778)
							(mid 0.249642 -0.249642)
							(end 0.1778 -0.2794)
						)
					)
					(width 0)
					(fill yes)
				)
			)
		)
	)
	(footprint ""
		(layer "F.Cu")
		(at 198.247 -224.282)
		(property "Reference" "R1587"
			(at 0 0 0)
			(layer "F.SilkS")
			(hide yes)
			(effects
				(font
					(size 1.27 1.27)
				)
			)
		)
		(property "Value" "0R2J-2-GP"
			(at 0.064008 -3.993896 0)
			(unlocked yes)
			(layer "F.Fab")
			(hide yes)
			(effects
				(font
					(size 1.016 1.016)
					(thickness 0.1524)
				)
			)
		)
		(property "Device Type" "R402H16"
			(at 0.064008 -5.517896 0)
			(unlocked yes)
			(layer "F.Fab")
			(hide yes)
			(effects
				(font
					(size 1.016 1.016)
					(thickness 0.1524)
				)
			)
		)
		(duplicate_pad_numbers_are_jumpers no)
		(fp_line
			(start -0.508 -0.9398)
			(end -0.508 0.9398)
			(stroke
				(width 0.1524)
				(type default)
			)
			(layer "F.SilkS")
		)
		(fp_line
			(start 0.508 -0.9398)
			(end -0.508 -0.9398)
			(stroke
				(width 0.1524)
				(type default)
			)
			(layer "F.SilkS")
		)
		(fp_rect
			(start -0.508 0.9398)
			(end 0.508 -0.9398)
			(stroke
				(width 0)
				(type default)
			)
			(fill no)
			(layer "F.CrtYd")
		)
		(fp_rect
			(start -0.508 0.9398)
			(end 0.508 -0.9398)
			(stroke
				(width 0)
				(type default)
			)
			(fill no)
			(layer "F.Fab")
		)
		(pad "1" smd custom
			(at 0 -0.4445)
			(size 0.1397 0.1397)
			(layers "F.Cu" "F.Mask" "F.Paste")
			(net "SYS_RSTBTN_N")
			(options
				(clearance outline)
				(anchor circle)
			)
			(primitives
				(gr_poly
					(pts
						(arc
							(start -0.1778 -0.2794)
							(mid -0.249642 -0.249642)
							(end -0.2794 -0.1778)
						)
						(arc
							(start -0.2794 0.1778)
							(mid -0.249642 0.249642)
							(end -0.1778 0.2794)
						)
						(arc
							(start 0.1778 0.2794)
							(mid 0.249642 0.249642)
							(end 0.2794 0.1778)
						)
						(arc
							(start 0.2794 -0.1778)
							(mid 0.249642 -0.249642)
							(end 0.1778 -0.2794)
						)
					)
					(width 0)
					(fill yes)
				)
			)
		)
		(pad "2" smd custom
			(at 0 0.4445)
			(size 0.1397 0.1397)
			(layers "F.Cu" "F.Mask" "F.Paste")
			(net "RSTBTN_FP_N")
			(options
				(clearance outline)
				(anchor circle)
			)
			(primitives
				(gr_poly
					(pts
						(arc
							(start -0.1778 -0.2794)
							(mid -0.249642 -0.249642)
							(end -0.2794 -0.1778)
						)
						(arc
							(start -0.2794 0.1778)
							(mid -0.249642 0.249642)
							(end -0.1778 0.2794)
						)
						(arc
							(start 0.1778 0.2794)
							(mid 0.249642 0.249642)
							(end 0.2794 0.1778)
						)
						(arc
							(start 0.2794 -0.1778)
							(mid 0.249642 -0.249642)
							(end 0.1778 -0.2794)
						)
					)
					(width 0)
					(fill yes)
				)
			)
		)
	)
	(footprint ""
		(layer "F.Cu")
		(at 86.49716 -41.91 -90)
		(property "Reference" "SC892"
			(at 0 0 270)
			(layer "F.SilkS")
			(hide yes)
			(effects
				(font
					(size 1.27 1.27)
				)
			)
		)
		(property "Value" "SCD01U10V1KX-GP"
			(at -2.8321 -1.7399 270)
			(unlocked yes)
			(layer "F.Fab")
			(hide yes)
			(effects
				(font
					(size 1.016 1.016)
					(thickness 0.1524)
				)
			)
		)
		(property "Device Type" "C0201H13"
			(at -2.8321 -3.2639 270)
			(unlocked yes)
			(layer "F.Fab")
			(hide yes)
			(effects
				(font
					(size 1.016 1.016)
					(thickness 0.1524)
				)
			)
		)
		(duplicate_pad_numbers_are_jumpers no)
		(fp_rect
			(start -0.2794 0.6477)
			(end 0.2794 -0.6477)
			(stroke
				(width 0)
				(type default)
			)
			(fill no)
			(layer "F.CrtYd")
		)
		(fp_rect
			(start -0.2794 0.6477)
			(end 0.2794 -0.6477)
			(stroke
				(width 0)
				(type default)
			)
			(fill no)
			(layer "F.Fab")
		)
		(pad "1" smd custom
			(at 0 -0.2794 270)
			(size 0.0762 0.0762)
			(layers "F.Cu" "F.Mask" "F.Paste")
			(net "SAS3008_RAID_TX_C_P6")
			(options
				(clearance outline)
				(anchor circle)
			)
			(primitives
				(gr_poly
					(pts
						(arc
							(start 0.1524 -0.127)
							(mid 0.137521 -0.162921)
							(end 0.1016 -0.1778)
						)
						(arc
							(start -0.1016 -0.1778)
							(mid -0.137521 -0.162921)
							(end -0.1524 -0.127)
						)
						(arc
							(start -0.1524 0.127)
							(mid -0.137521 0.162921)
							(end -0.1016 0.1778)
						)
						(arc
							(start 0.1016 0.1778)
							(mid 0.137521 0.162921)
							(end 0.1524 0.127)
						)
					)
					(width 0)
					(fill yes)
				)
			)
		)
		(pad "2" smd custom
			(at 0 0.2794 270)
			(size 0.0762 0.0762)
			(layers "F.Cu" "F.Mask" "F.Paste")
			(net "IOC_RAID_TX_P6")
			(options
				(clearance outline)
				(anchor circle)
			)
			(primitives
				(gr_poly
					(pts
						(arc
							(start 0.1524 -0.127)
							(mid 0.137521 -0.162921)
							(end 0.1016 -0.1778)
						)
						(arc
							(start -0.1016 -0.1778)
							(mid -0.137521 -0.162921)
							(end -0.1524 -0.127)
						)
						(arc
							(start -0.1524 0.127)
							(mid -0.137521 0.162921)
							(end -0.1016 0.1778)
						)
						(arc
							(start 0.1016 0.1778)
							(mid 0.137521 0.162921)
							(end 0.1524 0.127)
						)
					)
					(width 0)
					(fill yes)
				)
			)
		)
	)
	(footprint ""
		(layer "F.Cu")
		(at 35.052 -80.772 180)
		(property "Reference" "R676"
			(at 0 0 180)
			(layer "F.SilkS")
			(hide yes)
			(effects
				(font
					(size 1.27 1.27)
				)
			)
		)
		(property "Value" "1KR2F-3-GP"
			(at 0.064008 -3.993896 180)
			(unlocked yes)
			(layer "F.Fab")
			(hide yes)
			(effects
				(font
					(size 1.016 1.016)
					(thickness 0.1524)
				)
			)
		)
		(property "Device Type" "R402H16"
			(at 0.064008 -5.517896 180)
			(unlocked yes)
			(layer "F.Fab")
			(hide yes)
			(effects
				(font
					(size 1.016 1.016)
					(thickness 0.1524)
				)
			)
		)
		(duplicate_pad_numbers_are_jumpers no)
		(fp_line
			(start 0.508 -0.9398)
			(end -0.508 -0.9398)
			(stroke
				(width 0.1524)
				(type default)
			)
			(layer "F.SilkS")
		)
		(fp_line
			(start -0.508 -0.9398)
			(end -0.508 0.9398)
			(stroke
				(width 0.1524)
				(type default)
			)
			(layer "F.SilkS")
		)
		(fp_rect
			(start -0.508 0.9398)
			(end 0.508 -0.9398)
			(stroke
				(width 0)
				(type default)
			)
			(fill no)
			(layer "F.CrtYd")
		)
		(fp_rect
			(start -0.508 0.9398)
			(end 0.508 -0.9398)
			(stroke
				(width 0)
				(type default)
			)
			(fill no)
			(layer "F.Fab")
		)
		(pad "1" smd custom
			(at 0 -0.4445 180)
			(size 0.1397 0.1397)
			(layers "F.Cu" "F.Mask" "F.Paste")
			(net "INTA_LED_BLUE_B")
			(options
				(clearance outline)
				(anchor circle)
			)
			(primitives
				(gr_poly
					(pts
						(arc
							(start -0.1778 -0.2794)
							(mid -0.249642 -0.249642)
							(end -0.2794 -0.1778)
						)
						(arc
							(start -0.2794 0.1778)
							(mid -0.249642 0.249642)
							(end -0.1778 0.2794)
						)
						(arc
							(start 0.1778 0.2794)
							(mid 0.249642 0.249642)
							(end 0.2794 0.1778)
						)
						(arc
							(start 0.2794 -0.1778)
							(mid 0.249642 -0.249642)
							(end 0.1778 -0.2794)
						)
					)
					(width 0)
					(fill yes)
				)
			)
		)
		(pad "2" smd custom
			(at 0 0.4445 180)
			(size 0.1397 0.1397)
			(layers "F.Cu" "F.Mask" "F.Paste")
			(net "SAS_STATUS_LED17")
			(options
				(clearance outline)
				(anchor circle)
			)
			(primitives
				(gr_poly
					(pts
						(arc
							(start -0.1778 -0.2794)
							(mid -0.249642 -0.249642)
							(end -0.2794 -0.1778)
						)
						(arc
							(start -0.2794 0.1778)
							(mid -0.249642 0.249642)
							(end -0.1778 0.2794)
						)
						(arc
							(start 0.1778 0.2794)
							(mid 0.249642 0.249642)
							(end 0.2794 0.1778)
						)
						(arc
							(start 0.2794 -0.1778)
							(mid 0.249642 -0.249642)
							(end 0.1778 -0.2794)
						)
					)
					(width 0)
					(fill yes)
				)
			)
		)
	)
	(footprint ""
		(layer "F.Cu")
		(at 300.75378 -197.358 90)
		(property "Reference" "C200"
			(at 0 0 90)
			(layer "F.SilkS")
			(hide yes)
			(effects
				(font
					(size 1.27 1.27)
				)
			)
		)
		(property "Value" "SC1U10V3KX-4GP-U"
			(at 0 -2.8194 90)
			(unlocked yes)
			(layer "F.Fab")
			(hide yes)
			(effects
				(font
					(size 1.016 1.016)
					(thickness 0.1524)
				)
			)
		)
		(property "Device Type" "C603H36"
			(at 0 -4.3434 90)
			(unlocked yes)
			(layer "F.Fab")
			(hide yes)
			(effects
				(font
					(size 1.016 1.016)
					(thickness 0.1524)
				)
			)
		)
		(duplicate_pad_numbers_are_jumpers no)
		(fp_line
			(start 0.508 0)
			(end -0.508 0)
			(stroke
				(width 0.2032)
				(type default)
			)
			(layer "F.SilkS")
		)
		(fp_rect
			(start -0.5842 1.3335)
			(end 0.5842 -1.3335)
			(stroke
				(width 0)
				(type default)
			)
			(fill no)
			(layer "F.CrtYd")
		)
		(fp_rect
			(start -0.5842 1.3335)
			(end 0.5842 -1.3335)
			(stroke
				(width 0)
				(type default)
			)
			(fill no)
			(layer "F.Fab")
		)
		(pad "1" smd custom
			(at 0 -0.762 90)
			(size 0.2159 0.2159)
			(layers "F.Cu" "F.Mask" "F.Paste")
			(net "P1V53_STBY")
			(options
				(clearance outline)
				(anchor circle)
			)
			(primitives
				(gr_poly
					(pts
						(arc
							(start -0.3302 -0.4318)
							(mid -0.402042 -0.402042)
							(end -0.4318 -0.3302)
						)
						(arc
							(start -0.4318 0.3302)
							(mid -0.402042 0.402042)
							(end -0.3302 0.4318)
						)
						(arc
							(start 0.3302 0.4318)
							(mid 0.402042 0.402042)
							(end 0.4318 0.3302)
						)
						(arc
							(start 0.4318 -0.3302)
							(mid 0.402042 -0.402042)
							(end 0.3302 -0.4318)
						)
					)
					(width 0)
					(fill yes)
				)
			)
		)
		(pad "2" smd custom
			(at 0 0.762 90)
			(size 0.2159 0.2159)
			(layers "F.Cu" "F.Mask" "F.Paste")
			(net "GND")
			(options
				(clearance outline)
				(anchor circle)
			)
			(primitives
				(gr_poly
					(pts
						(arc
							(start -0.3302 -0.4318)
							(mid -0.402042 -0.402042)
							(end -0.4318 -0.3302)
						)
						(arc
							(start -0.4318 0.3302)
							(mid -0.402042 0.402042)
							(end -0.3302 0.4318)
						)
						(arc
							(start 0.3302 0.4318)
							(mid 0.402042 0.402042)
							(end 0.4318 0.3302)
						)
						(arc
							(start 0.4318 -0.3302)
							(mid 0.402042 -0.402042)
							(end 0.3302 -0.4318)
						)
					)
					(width 0)
					(fill yes)
				)
			)
		)
	)
	(footprint ""
		(layer "F.Cu")
		(at 274.193 -159.385 90)
		(property "Reference" "R235"
			(at 0 0 90)
			(layer "F.SilkS")
			(hide yes)
			(effects
				(font
					(size 1.27 1.27)
				)
			)
		)
		(property "Value" "100KR2F-L1-GP"
			(at 0.064008 -3.993896 90)
			(unlocked yes)
			(layer "F.Fab")
			(hide yes)
			(effects
				(font
					(size 1.016 1.016)
					(thickness 0.1524)
				)
			)
		)
		(property "Device Type" "R402H16"
			(at 0.064008 -5.517896 90)
			(unlocked yes)
			(layer "F.Fab")
			(hide yes)
			(effects
				(font
					(size 1.016 1.016)
					(thickness 0.1524)
				)
			)
		)
		(duplicate_pad_numbers_are_jumpers no)
		(fp_line
			(start 0.508 -0.9398)
			(end -0.508 -0.9398)
			(stroke
				(width 0.1524)
				(type default)
			)
			(layer "F.SilkS")
		)
		(fp_line
			(start -0.508 -0.9398)
			(end -0.508 0.9398)
			(stroke
				(width 0.1524)
				(type default)
			)
			(layer "F.SilkS")
		)
		(fp_rect
			(start -0.508 0.9398)
			(end 0.508 -0.9398)
			(stroke
				(width 0)
				(type default)
			)
			(fill no)
			(layer "F.CrtYd")
		)
		(fp_rect
			(start -0.508 0.9398)
			(end 0.508 -0.9398)
			(stroke
				(width 0)
				(type default)
			)
			(fill no)
			(layer "F.Fab")
		)
		(pad "1" smd custom
			(at 0 -0.4445 90)
			(size 0.1397 0.1397)
			(layers "F.Cu" "F.Mask" "F.Paste")
			(net "GND")
			(options
				(clearance outline)
				(anchor circle)
			)
			(primitives
				(gr_poly
					(pts
						(arc
							(start -0.1778 -0.2794)
							(mid -0.249642 -0.249642)
							(end -0.2794 -0.1778)
						)
						(arc
							(start -0.2794 0.1778)
							(mid -0.249642 0.249642)
							(end -0.1778 0.2794)
						)
						(arc
							(start 0.1778 0.2794)
							(mid 0.249642 0.249642)
							(end 0.2794 0.1778)
						)
						(arc
							(start 0.2794 -0.1778)
							(mid 0.249642 -0.249642)
							(end 0.1778 -0.2794)
						)
					)
					(width 0)
					(fill yes)
				)
			)
		)
		(pad "2" smd custom
			(at 0 0.4445 90)
			(size 0.1397 0.1397)
			(layers "F.Cu" "F.Mask" "F.Paste")
			(net "TP_BMC0_LPC_LAD1")
			(options
				(clearance outline)
				(anchor circle)
			)
			(primitives
				(gr_poly
					(pts
						(arc
							(start -0.1778 -0.2794)
							(mid -0.249642 -0.249642)
							(end -0.2794 -0.1778)
						)
						(arc
							(start -0.2794 0.1778)
							(mid -0.249642 0.249642)
							(end -0.1778 0.2794)
						)
						(arc
							(start 0.1778 0.2794)
							(mid 0.249642 0.249642)
							(end 0.2794 0.1778)
						)
						(arc
							(start 0.2794 -0.1778)
							(mid 0.249642 -0.249642)
							(end 0.1778 -0.2794)
						)
					)
					(width 0)
					(fill yes)
				)
			)
		)
	)
	(footprint ""
		(layer "F.Cu")
		(at 324.358 -179.705 180)
		(property "Reference" "R3098"
			(at 0 0 180)
			(layer "F.SilkS")
			(hide yes)
			(effects
				(font
					(size 1.27 1.27)
				)
			)
		)
		(property "Value" "1KR2F-3-GP"
			(at 0.064008 -3.993896 180)
			(unlocked yes)
			(layer "F.Fab")
			(hide yes)
			(effects
				(font
					(size 1.016 1.016)
					(thickness 0.1524)
				)
			)
		)
		(property "Device Type" "R402H16"
			(at 0.064008 -5.517896 180)
			(unlocked yes)
			(layer "F.Fab")
			(hide yes)
			(effects
				(font
					(size 1.016 1.016)
					(thickness 0.1524)
				)
			)
		)
		(duplicate_pad_numbers_are_jumpers no)
		(fp_line
			(start 0.508 -0.9398)
			(end -0.508 -0.9398)
			(stroke
				(width 0.1524)
				(type default)
			)
			(layer "F.SilkS")
		)
		(fp_line
			(start -0.508 -0.9398)
			(end -0.508 0.9398)
			(stroke
				(width 0.1524)
				(type default)
			)
			(layer "F.SilkS")
		)
		(fp_rect
			(start -0.508 0.9398)
			(end 0.508 -0.9398)
			(stroke
				(width 0)
				(type default)
			)
			(fill no)
			(layer "F.CrtYd")
		)
		(fp_rect
			(start -0.508 0.9398)
			(end 0.508 -0.9398)
			(stroke
				(width 0)
				(type default)
			)
			(fill no)
			(layer "F.Fab")
		)
		(pad "1" smd custom
			(at 0 -0.4445 180)
			(size 0.1397 0.1397)
			(layers "F.Cu" "F.Mask" "F.Paste")
			(net "ADC_P1V5_C")
			(options
				(clearance outline)
				(anchor circle)
			)
			(primitives
				(gr_poly
					(pts
						(arc
							(start -0.1778 -0.2794)
							(mid -0.249642 -0.249642)
							(end -0.2794 -0.1778)
						)
						(arc
							(start -0.2794 0.1778)
							(mid -0.249642 0.249642)
							(end -0.1778 0.2794)
						)
						(arc
							(start 0.1778 0.2794)
							(mid 0.249642 0.249642)
							(end 0.2794 0.1778)
						)
						(arc
							(start 0.2794 -0.1778)
							(mid 0.249642 -0.249642)
							(end 0.1778 -0.2794)
						)
					)
					(width 0)
					(fill yes)
				)
			)
		)
		(pad "2" smd custom
			(at 0 0.4445 180)
			(size 0.1397 0.1397)
			(layers "F.Cu" "F.Mask" "F.Paste")
			(net "GND")
			(options
				(clearance outline)
				(anchor circle)
			)
			(primitives
				(gr_poly
					(pts
						(arc
							(start -0.1778 -0.2794)
							(mid -0.249642 -0.249642)
							(end -0.2794 -0.1778)
						)
						(arc
							(start -0.2794 0.1778)
							(mid -0.249642 0.249642)
							(end -0.1778 0.2794)
						)
						(arc
							(start 0.1778 0.2794)
							(mid 0.249642 0.249642)
							(end 0.2794 0.1778)
						)
						(arc
							(start 0.2794 -0.1778)
							(mid 0.249642 -0.249642)
							(end 0.1778 -0.2794)
						)
					)
					(width 0)
					(fill yes)
				)
			)
		)
	)
	(footprint ""
		(layer "F.Cu")
		(at 184.023 -221.742 -90)
		(property "Reference" "U171"
			(at 0 0 270)
			(layer "F.SilkS")
			(hide yes)
			(effects
				(font
					(size 1.27 1.27)
				)
			)
		)
		(property "Value" "SNLVC1G126DCKR-GP"
			(at -2.3368 -8.6868 270)
			(unlocked yes)
			(layer "F.Fab")
			(hide yes)
			(effects
				(font
					(size 1.016 1.016)
					(thickness 0.1524)
				)
			)
		)
		(property "Device Type" "SC70-5H44"
			(at -2.3114 -10.414 270)
			(unlocked yes)
			(layer "F.Fab")
			(hide yes)
			(effects
				(font
					(size 1.016 1.016)
					(thickness 0.1524)
				)
			)
		)
		(duplicate_pad_numbers_are_jumpers no)
		(fp_line
			(start -1.27 1.7018)
			(end -1.27 -1.7018)
			(stroke
				(width 0.1524)
				(type default)
			)
			(layer "F.SilkS")
		)
		(fp_line
			(start 1.27 1.7018)
			(end -1.27 1.7018)
			(stroke
				(width 0.1524)
				(type default)
			)
			(layer "F.SilkS")
		)
		(fp_line
			(start -1.27 -1.7018)
			(end 1.27 -1.7018)
			(stroke
				(width 0.1524)
				(type default)
			)
			(layer "F.SilkS")
		)
		(fp_line
			(start 1.27 -1.7018)
			(end 1.27 1.7018)
			(stroke
				(width 0.1524)
				(type default)
			)
			(layer "F.SilkS")
		)
		(fp_line
			(start 0.6604 -1.8034)
			(end 1.3843 -1.8034)
			(stroke
				(width 0.3302)
				(type default)
			)
			(layer "F.SilkS")
		)
		(fp_line
			(start 1.3843 -1.8034)
			(end 1.3843 -1.1176)
			(stroke
				(width 0.3302)
				(type default)
			)
			(layer "F.SilkS")
		)
		(fp_rect
			(start -1.524 1.9558)
			(end 1.524 -1.9558)
			(stroke
				(width 0)
				(type default)
			)
			(fill no)
			(layer "F.CrtYd")
		)
		(fp_poly
			(pts
				(xy -1.524 -1.9558) (xy 1.524 -1.9558) (xy 1.524 1.9558) (xy -1.524 1.9558)
			)
			(stroke
				(width 0)
				(type default)
			)
			(fill no)
			(layer "F.Fab")
		)
		(pad "1" smd rect
			(at 0.65024 -0.8255 270)
			(size 0.4064 1.2192)
			(layers "F.Cu" "F.Mask" "F.Paste")
			(net "FM_BMC_READY_N")
		)
		(pad "2" smd rect
			(at 0 -0.8255 270)
			(size 0.4064 1.2192)
			(layers "F.Cu" "F.Mask" "F.Paste")
			(net "PWRBTN_FP_N")
		)
		(pad "3" smd rect
			(at -0.65024 -0.8255 270)
			(size 0.4064 1.2192)
			(layers "F.Cu" "F.Mask" "F.Paste")
			(net "GND")
		)
		(pad "4" smd rect
			(at -0.65024 0.8255 270)
			(size 0.4064 1.2192)
			(layers "F.Cu" "F.Mask" "F.Paste")
			(net "PWRBTN_OUT_N")
		)
		(pad "5" smd rect
			(at 0.65024 0.8255 270)
			(size 0.4064 1.2192)
			(layers "F.Cu" "F.Mask" "F.Paste")
			(net "P3V3_STBY")
		)
	)
	(footprint ""
		(layer "F.Cu")
		(at 158.369 -104.902 90)
		(property "Reference" "SC1210"
			(at 0 0 90)
			(layer "F.SilkS")
			(hide yes)
			(effects
				(font
					(size 1.27 1.27)
				)
			)
		)
		(property "Value" "SC10U6D3V5KX-4GP"
			(at -0.0762 -6.1214 90)
			(unlocked yes)
			(layer "F.Fab")
			(hide yes)
			(effects
				(font
					(size 1.016 1.016)
					(thickness 0.1524)
				)
			)
		)
		(property "Device Type" "C805H58"
			(at -0.0762 -8.1534 90)
			(unlocked yes)
			(layer "F.Fab")
			(hide yes)
			(effects
				(font
					(size 1.016 1.016)
					(thickness 0.1524)
				)
			)
		)
		(duplicate_pad_numbers_are_jumpers no)
		(fp_line
			(start 0.635 0)
			(end -0.635 0)
			(stroke
				(width 0.508)
				(type default)
			)
			(layer "F.SilkS")
		)
		(fp_rect
			(start -0.9652 1.778)
			(end 0.9652 -1.778)
			(stroke
				(width 0)
				(type default)
			)
			(fill no)
			(layer "F.CrtYd")
		)
		(fp_poly
			(pts
				(xy -0.9652 -1.778) (xy 0.9652 -1.778) (xy 0.9652 1.778) (xy -0.9652 1.778)
			)
			(stroke
				(width 0)
				(type default)
			)
			(fill no)
			(layer "F.Fab")
		)
		(pad "1" smd rect
			(at 0 -0.9652 90)
			(size 1.397 1.143)
			(layers "F.Cu" "F.Mask" "F.Paste")
			(net "P0V9_E")
		)
		(pad "2" smd rect
			(at 0 0.9652 90)
			(size 1.397 1.143)
			(layers "F.Cu" "F.Mask" "F.Paste")
			(net "GND")
		)
	)
	(footprint ""
		(layer "F.Cu")
		(at 60.706 -107.442 90)
		(property "Reference" "SR824"
			(at 0 0 90)
			(layer "F.SilkS")
			(hide yes)
			(effects
				(font
					(size 1.27 1.27)
				)
			)
		)
		(property "Value" "4K75R2F-1-GP"
			(at 0.064008 -3.993896 90)
			(unlocked yes)
			(layer "F.Fab")
			(hide yes)
			(effects
				(font
					(size 1.016 1.016)
					(thickness 0.1524)
				)
			)
		)
		(property "Device Type" "R402H16"
			(at 0.064008 -5.517896 90)
			(unlocked yes)
			(layer "F.Fab")
			(hide yes)
			(effects
				(font
					(size 1.016 1.016)
					(thickness 0.1524)
				)
			)
		)
		(duplicate_pad_numbers_are_jumpers no)
		(fp_line
			(start 0.508 -0.9398)
			(end -0.508 -0.9398)
			(stroke
				(width 0.1524)
				(type default)
			)
			(layer "F.SilkS")
		)
		(fp_line
			(start -0.508 -0.9398)
			(end -0.508 0.9398)
			(stroke
				(width 0.1524)
				(type default)
			)
			(layer "F.SilkS")
		)
		(fp_rect
			(start -0.508 0.9398)
			(end 0.508 -0.9398)
			(stroke
				(width 0)
				(type default)
			)
			(fill no)
			(layer "F.CrtYd")
		)
		(fp_rect
			(start -0.508 0.9398)
			(end 0.508 -0.9398)
			(stroke
				(width 0)
				(type default)
			)
			(fill no)
			(layer "F.Fab")
		)
		(pad "1" smd custom
			(at 0 -0.4445 90)
			(size 0.1397 0.1397)
			(layers "F.Cu" "F.Mask" "F.Paste")
			(net "P1V8_E")
			(options
				(clearance outline)
				(anchor circle)
			)
			(primitives
				(gr_poly
					(pts
						(arc
							(start -0.1778 -0.2794)
							(mid -0.249642 -0.249642)
							(end -0.2794 -0.1778)
						)
						(arc
							(start -0.2794 0.1778)
							(mid -0.249642 0.249642)
							(end -0.1778 0.2794)
						)
						(arc
							(start 0.1778 0.2794)
							(mid 0.249642 0.249642)
							(end 0.2794 0.1778)
						)
						(arc
							(start 0.2794 -0.1778)
							(mid 0.249642 -0.249642)
							(end 0.1778 -0.2794)
						)
					)
					(width 0)
					(fill yes)
				)
			)
		)
		(pad "2" smd custom
			(at 0 0.4445 90)
			(size 0.1397 0.1397)
			(layers "F.Cu" "F.Mask" "F.Paste")
			(net "EXP_FW_DET_BOARD_VER_2")
			(options
				(clearance outline)
				(anchor circle)
			)
			(primitives
				(gr_poly
					(pts
						(arc
							(start -0.1778 -0.2794)
							(mid -0.249642 -0.249642)
							(end -0.2794 -0.1778)
						)
						(arc
							(start -0.2794 0.1778)
							(mid -0.249642 0.249642)
							(end -0.1778 0.2794)
						)
						(arc
							(start 0.1778 0.2794)
							(mid 0.249642 0.249642)
							(end 0.2794 0.1778)
						)
						(arc
							(start 0.2794 -0.1778)
							(mid 0.249642 -0.249642)
							(end 0.1778 -0.2794)
						)
					)
					(width 0)
					(fill yes)
				)
			)
		)
	)
	(footprint ""
		(layer "F.Cu")
		(at 304.038 -92.964)
		(property "Reference" "TP166"
			(at 0 0 0)
			(layer "F.SilkS")
			(hide yes)
			(effects
				(font
					(size 1.27 1.27)
				)
			)
		)
		(property "Value" "TPAD32-GP"
			(at 0 -3.166364 0)
			(unlocked yes)
			(layer "F.Fab")
			(hide yes)
			(effects
				(font
					(size 1.016 1.016)
					(thickness 0.1524)
				)
			)
		)
		(property "Device Type" "TPAD32"
			(at 0 -4.690618 0)
			(unlocked yes)
			(layer "F.Fab")
			(hide yes)
			(effects
				(font
					(size 1.016 1.016)
					(thickness 0.1524)
				)
			)
		)
		(duplicate_pad_numbers_are_jumpers no)
		(fp_poly
			(pts
				(arc
					(start 0.4064 0)
					(mid -0.4064 0)
					(end 0.4064 0)
				)
			)
			(stroke
				(width 0)
				(type default)
			)
			(fill no)
			(layer "F.CrtYd")
		)
		(fp_poly
			(pts
				(arc
					(start 0.7112 0)
					(mid -0.7112 0)
					(end 0.7112 0)
				)
			)
			(stroke
				(width 0)
				(type default)
			)
			(fill no)
			(layer "F.Fab")
		)
		(pad "1" smd circle
			(at 0 0)
			(size 0.8128 0.8128)
			(layers "F.Cu" "F.Mask" "F.Paste")
			(net "TEMP_2_ALERT")
		)
	)
	(footprint ""
		(layer "F.Cu")
		(at 131.02971 -98.92284 180)
		(property "Reference" "SC1273"
			(at 0 0 180)
			(layer "F.SilkS")
			(hide yes)
			(effects
				(font
					(size 1.27 1.27)
				)
			)
		)
		(property "Value" "SCD01U10V1KX-GP"
			(at -2.8321 -1.7399 180)
			(unlocked yes)
			(layer "F.Fab")
			(hide yes)
			(effects
				(font
					(size 1.016 1.016)
					(thickness 0.1524)
				)
			)
		)
		(property "Device Type" "C0201H13"
			(at -2.8321 -3.2639 180)
			(unlocked yes)
			(layer "F.Fab")
			(hide yes)
			(effects
				(font
					(size 1.016 1.016)
					(thickness 0.1524)
				)
			)
		)
		(duplicate_pad_numbers_are_jumpers no)
		(fp_rect
			(start -0.2794 0.6477)
			(end 0.2794 -0.6477)
			(stroke
				(width 0)
				(type default)
			)
			(fill no)
			(layer "F.CrtYd")
		)
		(fp_rect
			(start -0.2794 0.6477)
			(end 0.2794 -0.6477)
			(stroke
				(width 0)
				(type default)
			)
			(fill no)
			(layer "F.Fab")
		)
		(pad "1" smd custom
			(at 0 -0.2794 180)
			(size 0.0762 0.0762)
			(layers "F.Cu" "F.Mask" "F.Paste")
			(net "3X24_SAS_TX23_N")
			(options
				(clearance outline)
				(anchor circle)
			)
			(primitives
				(gr_poly
					(pts
						(arc
							(start 0.1524 -0.127)
							(mid 0.137521 -0.162921)
							(end 0.1016 -0.1778)
						)
						(arc
							(start -0.1016 -0.1778)
							(mid -0.137521 -0.162921)
							(end -0.1524 -0.127)
						)
						(arc
							(start -0.1524 0.127)
							(mid -0.137521 0.162921)
							(end -0.1016 0.1778)
						)
						(arc
							(start 0.1016 0.1778)
							(mid 0.137521 0.162921)
							(end 0.1524 0.127)
						)
					)
					(width 0)
					(fill yes)
				)
			)
		)
		(pad "2" smd custom
			(at 0 0.2794 180)
			(size 0.0762 0.0762)
			(layers "F.Cu" "F.Mask" "F.Paste")
			(net "SAS_EXP_GF_TX_DN3")
			(options
				(clearance outline)
				(anchor circle)
			)
			(primitives
				(gr_poly
					(pts
						(arc
							(start 0.1524 -0.127)
							(mid 0.137521 -0.162921)
							(end 0.1016 -0.1778)
						)
						(arc
							(start -0.1016 -0.1778)
							(mid -0.137521 -0.162921)
							(end -0.1524 -0.127)
						)
						(arc
							(start -0.1524 0.127)
							(mid -0.137521 0.162921)
							(end -0.1016 0.1778)
						)
						(arc
							(start 0.1016 0.1778)
							(mid 0.137521 0.162921)
							(end 0.1524 0.127)
						)
					)
					(width 0)
					(fill yes)
				)
			)
		)
	)
	(footprint ""
		(layer "F.Cu")
		(at 348.390718 -148.694648 -90)
		(property "Reference" "R450"
			(at 0 0 270)
			(layer "F.SilkS")
			(hide yes)
			(effects
				(font
					(size 1.27 1.27)
				)
			)
		)
		(property "Value" "0R2J-2-GP"
			(at 0.064008 -3.993896 270)
			(unlocked yes)
			(layer "F.Fab")
			(hide yes)
			(effects
				(font
					(size 1.016 1.016)
					(thickness 0.1524)
				)
			)
		)
		(property "Device Type" "R402H16"
			(at 0.064008 -5.517896 270)
			(unlocked yes)
			(layer "F.Fab")
			(hide yes)
			(effects
				(font
					(size 1.016 1.016)
					(thickness 0.1524)
				)
			)
		)
		(duplicate_pad_numbers_are_jumpers no)
		(fp_line
			(start -0.508 -0.9398)
			(end -0.508 0.9398)
			(stroke
				(width 0.1524)
				(type default)
			)
			(layer "F.SilkS")
		)
		(fp_line
			(start 0.508 -0.9398)
			(end -0.508 -0.9398)
			(stroke
				(width 0.1524)
				(type default)
			)
			(layer "F.SilkS")
		)
		(fp_rect
			(start -0.508 0.9398)
			(end 0.508 -0.9398)
			(stroke
				(width 0)
				(type default)
			)
			(fill no)
			(layer "F.CrtYd")
		)
		(fp_rect
			(start -0.508 0.9398)
			(end 0.508 -0.9398)
			(stroke
				(width 0)
				(type default)
			)
			(fill no)
			(layer "F.Fab")
		)
		(pad "1" smd custom
			(at 0 -0.4445 270)
			(size 0.1397 0.1397)
			(layers "F.Cu" "F.Mask" "F.Paste")
			(net "BMC_USB2_HDN")
			(options
				(clearance outline)
				(anchor circle)
			)
			(primitives
				(gr_poly
					(pts
						(arc
							(start -0.1778 -0.2794)
							(mid -0.249642 -0.249642)
							(end -0.2794 -0.1778)
						)
						(arc
							(start -0.2794 0.1778)
							(mid -0.249642 0.249642)
							(end -0.1778 0.2794)
						)
						(arc
							(start 0.1778 0.2794)
							(mid 0.249642 0.249642)
							(end 0.2794 0.1778)
						)
						(arc
							(start 0.2794 -0.1778)
							(mid 0.249642 -0.249642)
							(end 0.1778 -0.2794)
						)
					)
					(width 0)
					(fill yes)
				)
			)
		)
		(pad "2" smd custom
			(at 0 0.4445 270)
			(size 0.1397 0.1397)
			(layers "F.Cu" "F.Mask" "F.Paste")
			(net "USB_P2_DN")
			(options
				(clearance outline)
				(anchor circle)
			)
			(primitives
				(gr_poly
					(pts
						(arc
							(start -0.1778 -0.2794)
							(mid -0.249642 -0.249642)
							(end -0.2794 -0.1778)
						)
						(arc
							(start -0.2794 0.1778)
							(mid -0.249642 0.249642)
							(end -0.1778 0.2794)
						)
						(arc
							(start 0.1778 0.2794)
							(mid 0.249642 0.249642)
							(end 0.2794 0.1778)
						)
						(arc
							(start 0.2794 -0.1778)
							(mid 0.249642 -0.249642)
							(end 0.1778 -0.2794)
						)
					)
					(width 0)
					(fill yes)
				)
			)
		)
	)
	(footprint ""
		(layer "F.Cu")
		(at 295.266872 -63.953136 180)
		(property "Reference" "PR118"
			(at 0 0 180)
			(layer "F.SilkS")
			(hide yes)
			(effects
				(font
					(size 1.27 1.27)
				)
			)
		)
		(property "Value" "1KR2F-3-GP"
			(at 0.064008 -3.993896 180)
			(unlocked yes)
			(layer "F.Fab")
			(hide yes)
			(effects
				(font
					(size 1.016 1.016)
					(thickness 0.1524)
				)
			)
		)
		(property "Device Type" "R402H16"
			(at 0.064008 -5.517896 180)
			(unlocked yes)
			(layer "F.Fab")
			(hide yes)
			(effects
				(font
					(size 1.016 1.016)
					(thickness 0.1524)
				)
			)
		)
		(duplicate_pad_numbers_are_jumpers no)
		(fp_line
			(start 0.508 -0.9398)
			(end -0.508 -0.9398)
			(stroke
				(width 0.1524)
				(type default)
			)
			(layer "F.SilkS")
		)
		(fp_line
			(start -0.508 -0.9398)
			(end -0.508 0.9398)
			(stroke
				(width 0.1524)
				(type default)
			)
			(layer "F.SilkS")
		)
		(fp_rect
			(start -0.508 0.9398)
			(end 0.508 -0.9398)
			(stroke
				(width 0)
				(type default)
			)
			(fill no)
			(layer "F.CrtYd")
		)
		(fp_rect
			(start -0.508 0.9398)
			(end 0.508 -0.9398)
			(stroke
				(width 0)
				(type default)
			)
			(fill no)
			(layer "F.Fab")
		)
		(pad "1" smd custom
			(at 0 -0.4445 180)
			(size 0.1397 0.1397)
			(layers "F.Cu" "F.Mask" "F.Paste")
			(net "P3V3")
			(options
				(clearance outline)
				(anchor circle)
			)
			(primitives
				(gr_poly
					(pts
						(arc
							(start -0.1778 -0.2794)
							(mid -0.249642 -0.249642)
							(end -0.2794 -0.1778)
						)
						(arc
							(start -0.2794 0.1778)
							(mid -0.249642 0.249642)
							(end -0.1778 0.2794)
						)
						(arc
							(start 0.1778 0.2794)
							(mid 0.249642 0.249642)
							(end 0.2794 0.1778)
						)
						(arc
							(start 0.2794 -0.1778)
							(mid 0.249642 -0.249642)
							(end 0.1778 -0.2794)
						)
					)
					(width 0)
					(fill yes)
				)
			)
		)
		(pad "2" smd custom
			(at 0 0.4445 180)
			(size 0.1397 0.1397)
			(layers "F.Cu" "F.Mask" "F.Paste")
			(net "GND")
			(options
				(clearance outline)
				(anchor circle)
			)
			(primitives
				(gr_poly
					(pts
						(arc
							(start -0.1778 -0.2794)
							(mid -0.249642 -0.249642)
							(end -0.2794 -0.1778)
						)
						(arc
							(start -0.2794 0.1778)
							(mid -0.249642 0.249642)
							(end -0.1778 0.2794)
						)
						(arc
							(start 0.1778 0.2794)
							(mid 0.249642 0.249642)
							(end 0.2794 0.1778)
						)
						(arc
							(start 0.2794 -0.1778)
							(mid 0.249642 -0.249642)
							(end 0.1778 -0.2794)
						)
					)
					(width 0)
					(fill yes)
				)
			)
		)
	)
	(footprint ""
		(layer "F.Cu")
		(at 218.58097 -69.088)
		(property "Reference" "R11"
			(at 0 0 0)
			(layer "F.SilkS")
			(hide yes)
			(effects
				(font
					(size 1.27 1.27)
				)
			)
		)
		(property "Value" "10KR2F-2-GP"
			(at 0.064008 -3.993896 0)
			(unlocked yes)
			(layer "F.Fab")
			(hide yes)
			(effects
				(font
					(size 1.016 1.016)
					(thickness 0.1524)
				)
			)
		)
		(property "Device Type" "R402H16"
			(at 0.064008 -5.517896 0)
			(unlocked yes)
			(layer "F.Fab")
			(hide yes)
			(effects
				(font
					(size 1.016 1.016)
					(thickness 0.1524)
				)
			)
		)
		(duplicate_pad_numbers_are_jumpers no)
		(fp_line
			(start -0.508 -0.9398)
			(end -0.508 0.9398)
			(stroke
				(width 0.1524)
				(type default)
			)
			(layer "F.SilkS")
		)
		(fp_line
			(start 0.508 -0.9398)
			(end -0.508 -0.9398)
			(stroke
				(width 0.1524)
				(type default)
			)
			(layer "F.SilkS")
		)
		(fp_rect
			(start -0.508 0.9398)
			(end 0.508 -0.9398)
			(stroke
				(width 0)
				(type default)
			)
			(fill no)
			(layer "F.CrtYd")
		)
		(fp_rect
			(start -0.508 0.9398)
			(end 0.508 -0.9398)
			(stroke
				(width 0)
				(type default)
			)
			(fill no)
			(layer "F.Fab")
		)
		(pad "1" smd custom
			(at 0 -0.4445)
			(size 0.1397 0.1397)
			(layers "F.Cu" "F.Mask" "F.Paste")
			(net "SVR_ID0")
			(options
				(clearance outline)
				(anchor circle)
			)
			(primitives
				(gr_poly
					(pts
						(arc
							(start -0.1778 -0.2794)
							(mid -0.249642 -0.249642)
							(end -0.2794 -0.1778)
						)
						(arc
							(start -0.2794 0.1778)
							(mid -0.249642 0.249642)
							(end -0.1778 0.2794)
						)
						(arc
							(start 0.1778 0.2794)
							(mid 0.249642 0.249642)
							(end 0.2794 0.1778)
						)
						(arc
							(start 0.2794 -0.1778)
							(mid 0.249642 -0.249642)
							(end 0.1778 -0.2794)
						)
					)
					(width 0)
					(fill yes)
				)
			)
		)
		(pad "2" smd custom
			(at 0 0.4445)
			(size 0.1397 0.1397)
			(layers "F.Cu" "F.Mask" "F.Paste")
			(net "P3V3_STBY")
			(options
				(clearance outline)
				(anchor circle)
			)
			(primitives
				(gr_poly
					(pts
						(arc
							(start -0.1778 -0.2794)
							(mid -0.249642 -0.249642)
							(end -0.2794 -0.1778)
						)
						(arc
							(start -0.2794 0.1778)
							(mid -0.249642 0.249642)
							(end -0.1778 0.2794)
						)
						(arc
							(start 0.1778 0.2794)
							(mid 0.249642 0.249642)
							(end 0.2794 0.1778)
						)
						(arc
							(start 0.2794 -0.1778)
							(mid 0.249642 -0.249642)
							(end 0.1778 -0.2794)
						)
					)
					(width 0)
					(fill yes)
				)
			)
		)
	)
	(footprint ""
		(layer "F.Cu")
		(at 212.344 -215.646 -90)
		(property "Reference" "U177"
			(at 0 0 270)
			(layer "F.SilkS")
			(hide yes)
			(effects
				(font
					(size 1.27 1.27)
				)
			)
		)
		(property "Value" "SN74LVC1G08DCKR-GP"
			(at -2.3368 -8.6868 270)
			(unlocked yes)
			(layer "F.Fab")
			(hide yes)
			(effects
				(font
					(size 1.016 1.016)
					(thickness 0.1524)
				)
			)
		)
		(property "Device Type" "SC70-5H44"
			(at -2.3114 -10.414 270)
			(unlocked yes)
			(layer "F.Fab")
			(hide yes)
			(effects
				(font
					(size 1.016 1.016)
					(thickness 0.1524)
				)
			)
		)
		(duplicate_pad_numbers_are_jumpers no)
		(fp_line
			(start -1.27 1.7018)
			(end -1.27 -1.7018)
			(stroke
				(width 0.1524)
				(type default)
			)
			(layer "F.SilkS")
		)
		(fp_line
			(start 1.27 1.7018)
			(end -1.27 1.7018)
			(stroke
				(width 0.1524)
				(type default)
			)
			(layer "F.SilkS")
		)
		(fp_line
			(start -1.27 -1.7018)
			(end 1.27 -1.7018)
			(stroke
				(width 0.1524)
				(type default)
			)
			(layer "F.SilkS")
		)
		(fp_line
			(start 1.27 -1.7018)
			(end 1.27 1.7018)
			(stroke
				(width 0.1524)
				(type default)
			)
			(layer "F.SilkS")
		)
		(fp_line
			(start 0.6604 -1.8034)
			(end 1.3843 -1.8034)
			(stroke
				(width 0.3302)
				(type default)
			)
			(layer "F.SilkS")
		)
		(fp_line
			(start 1.3843 -1.8034)
			(end 1.3843 -1.1176)
			(stroke
				(width 0.3302)
				(type default)
			)
			(layer "F.SilkS")
		)
		(fp_rect
			(start -1.524 1.9558)
			(end 1.524 -1.9558)
			(stroke
				(width 0)
				(type default)
			)
			(fill no)
			(layer "F.CrtYd")
		)
		(fp_poly
			(pts
				(xy -1.524 -1.9558) (xy 1.524 -1.9558) (xy 1.524 1.9558) (xy -1.524 1.9558)
			)
			(stroke
				(width 0)
				(type default)
			)
			(fill no)
			(layer "F.Fab")
		)
		(pad "1" smd rect
			(at 0.65024 -0.8255 270)
			(size 0.4064 1.2192)
			(layers "F.Cu" "F.Mask" "F.Paste")
			(net "CPU_EXP_RESET_N")
		)
		(pad "2" smd rect
			(at 0 -0.8255 270)
			(size 0.4064 1.2192)
			(layers "F.Cu" "F.Mask" "F.Paste")
			(net "DP_BMC_CPU_RST_N")
		)
		(pad "3" smd rect
			(at -0.65024 -0.8255 270)
			(size 0.4064 1.2192)
			(layers "F.Cu" "F.Mask" "F.Paste")
			(net "GND")
		)
		(pad "4" smd rect
			(at -0.65024 0.8255 270)
			(size 0.4064 1.2192)
			(layers "F.Cu" "F.Mask" "F.Paste")
			(net "DP_BMC_CPU_RST_N_U177_OUT")
		)
		(pad "5" smd rect
			(at 0.65024 0.8255 270)
			(size 0.4064 1.2192)
			(layers "F.Cu" "F.Mask" "F.Paste")
			(net "P3V3_STBY")
		)
	)
	(footprint ""
		(layer "F.Cu")
		(at 191.897 -24.003 -90)
		(property "Reference" "R444"
			(at 0 0 270)
			(layer "F.SilkS")
			(hide yes)
			(effects
				(font
					(size 1.27 1.27)
				)
			)
		)
		(property "Value" "0R2J-2-GP"
			(at 0.064008 -3.993896 270)
			(unlocked yes)
			(layer "F.Fab")
			(hide yes)
			(effects
				(font
					(size 1.016 1.016)
					(thickness 0.1524)
				)
			)
		)
		(property "Device Type" "R402H16"
			(at 0.064008 -5.517896 270)
			(unlocked yes)
			(layer "F.Fab")
			(hide yes)
			(effects
				(font
					(size 1.016 1.016)
					(thickness 0.1524)
				)
			)
		)
		(duplicate_pad_numbers_are_jumpers no)
		(fp_line
			(start -0.508 -0.9398)
			(end -0.508 0.9398)
			(stroke
				(width 0.1524)
				(type default)
			)
			(layer "F.SilkS")
		)
		(fp_line
			(start 0.508 -0.9398)
			(end -0.508 -0.9398)
			(stroke
				(width 0.1524)
				(type default)
			)
			(layer "F.SilkS")
		)
		(fp_rect
			(start -0.508 0.9398)
			(end 0.508 -0.9398)
			(stroke
				(width 0)
				(type default)
			)
			(fill no)
			(layer "F.CrtYd")
		)
		(fp_rect
			(start -0.508 0.9398)
			(end 0.508 -0.9398)
			(stroke
				(width 0)
				(type default)
			)
			(fill no)
			(layer "F.Fab")
		)
		(pad "1" smd custom
			(at 0 -0.4445 270)
			(size 0.1397 0.1397)
			(layers "F.Cu" "F.Mask" "F.Paste")
			(net "GND")
			(options
				(clearance outline)
				(anchor circle)
			)
			(primitives
				(gr_poly
					(pts
						(arc
							(start -0.1778 -0.2794)
							(mid -0.249642 -0.249642)
							(end -0.2794 -0.1778)
						)
						(arc
							(start -0.2794 0.1778)
							(mid -0.249642 0.249642)
							(end -0.1778 0.2794)
						)
						(arc
							(start 0.1778 0.2794)
							(mid 0.249642 0.249642)
							(end 0.2794 0.1778)
						)
						(arc
							(start 0.2794 -0.1778)
							(mid 0.249642 -0.249642)
							(end 0.1778 -0.2794)
						)
					)
					(width 0)
					(fill yes)
				)
			)
		)
		(pad "2" smd custom
			(at 0 0.4445 270)
			(size 0.1397 0.1397)
			(layers "F.Cu" "F.Mask" "F.Paste")
			(net "RMII_PHY_BMC_RXD1")
			(options
				(clearance outline)
				(anchor circle)
			)
			(primitives
				(gr_poly
					(pts
						(arc
							(start -0.1778 -0.2794)
							(mid -0.249642 -0.249642)
							(end -0.2794 -0.1778)
						)
						(arc
							(start -0.2794 0.1778)
							(mid -0.249642 0.249642)
							(end -0.1778 0.2794)
						)
						(arc
							(start 0.1778 0.2794)
							(mid 0.249642 0.249642)
							(end 0.2794 0.1778)
						)
						(arc
							(start 0.2794 -0.1778)
							(mid 0.249642 -0.249642)
							(end 0.1778 -0.2794)
						)
					)
					(width 0)
					(fill yes)
				)
			)
		)
	)
	(footprint ""
		(layer "F.Cu")
		(at 117.456966 -33.909)
		(property "Reference" "STP25"
			(at 0 0 0)
			(layer "F.SilkS")
			(hide yes)
			(effects
				(font
					(size 1.27 1.27)
				)
			)
		)
		(property "Value" "TPAD28"
			(at 0.0127 -1.8034 0)
			(unlocked yes)
			(layer "F.Fab")
			(hide yes)
			(effects
				(font
					(size 1.016 1.016)
					(thickness 0.1524)
				)
			)
		)
		(property "Device Type" "TPAD28"
			(at 0.0127 -3.3274 0)
			(unlocked yes)
			(layer "F.Fab")
			(hide yes)
			(effects
				(font
					(size 1.016 1.016)
					(thickness 0.1524)
				)
			)
		)
		(duplicate_pad_numbers_are_jumpers no)
		(fp_poly
			(pts
				(arc
					(start 0.3556 0)
					(mid -0.3556 0)
					(end 0.3556 0)
				)
			)
			(stroke
				(width 0)
				(type default)
			)
			(fill no)
			(layer "F.CrtYd")
		)
		(fp_poly
			(pts
				(arc
					(start 0.6096 0)
					(mid -0.6096 0)
					(end 0.6096 0)
				)
			)
			(stroke
				(width 0)
				(type default)
			)
			(fill no)
			(layer "F.Fab")
		)
		(pad "1" smd circle
			(at 0 0)
			(size 0.7112 0.7112)
			(layers "F.Cu" "F.Mask" "F.Paste")
			(net "IOC_GPIO_39")
		)
	)
	(footprint ""
		(layer "F.Cu")
		(at 177.537872 -198.369936)
		(property "Reference" "R428"
			(at 0 0 0)
			(layer "F.SilkS")
			(hide yes)
			(effects
				(font
					(size 1.27 1.27)
				)
			)
		)
		(property "Value" "10KR2F-2-GP"
			(at 0.064008 -3.993896 0)
			(unlocked yes)
			(layer "F.Fab")
			(hide yes)
			(effects
				(font
					(size 1.016 1.016)
					(thickness 0.1524)
				)
			)
		)
		(property "Device Type" "R402H16"
			(at 0.064008 -5.517896 0)
			(unlocked yes)
			(layer "F.Fab")
			(hide yes)
			(effects
				(font
					(size 1.016 1.016)
					(thickness 0.1524)
				)
			)
		)
		(duplicate_pad_numbers_are_jumpers no)
		(fp_line
			(start -0.508 -0.9398)
			(end -0.508 0.9398)
			(stroke
				(width 0.1524)
				(type default)
			)
			(layer "F.SilkS")
		)
		(fp_line
			(start 0.508 -0.9398)
			(end -0.508 -0.9398)
			(stroke
				(width 0.1524)
				(type default)
			)
			(layer "F.SilkS")
		)
		(fp_rect
			(start -0.508 0.9398)
			(end 0.508 -0.9398)
			(stroke
				(width 0)
				(type default)
			)
			(fill no)
			(layer "F.CrtYd")
		)
		(fp_rect
			(start -0.508 0.9398)
			(end 0.508 -0.9398)
			(stroke
				(width 0)
				(type default)
			)
			(fill no)
			(layer "F.Fab")
		)
		(pad "1" smd custom
			(at 0 -0.4445)
			(size 0.1397 0.1397)
			(layers "F.Cu" "F.Mask" "F.Paste")
			(net "P3V3_STBY")
			(options
				(clearance outline)
				(anchor circle)
			)
			(primitives
				(gr_poly
					(pts
						(arc
							(start -0.1778 -0.2794)
							(mid -0.249642 -0.249642)
							(end -0.2794 -0.1778)
						)
						(arc
							(start -0.2794 0.1778)
							(mid -0.249642 0.249642)
							(end -0.1778 0.2794)
						)
						(arc
							(start 0.1778 0.2794)
							(mid 0.249642 0.249642)
							(end 0.2794 0.1778)
						)
						(arc
							(start 0.2794 -0.1778)
							(mid 0.249642 -0.249642)
							(end 0.1778 -0.2794)
						)
					)
					(width 0)
					(fill yes)
				)
			)
		)
		(pad "2" smd custom
			(at 0 0.4445)
			(size 0.1397 0.1397)
			(layers "F.Cu" "F.Mask" "F.Paste")
			(net "I2C_C_BUFF_EN")
			(options
				(clearance outline)
				(anchor circle)
			)
			(primitives
				(gr_poly
					(pts
						(arc
							(start -0.1778 -0.2794)
							(mid -0.249642 -0.249642)
							(end -0.2794 -0.1778)
						)
						(arc
							(start -0.2794 0.1778)
							(mid -0.249642 0.249642)
							(end -0.1778 0.2794)
						)
						(arc
							(start 0.1778 0.2794)
							(mid 0.249642 0.249642)
							(end 0.2794 0.1778)
						)
						(arc
							(start 0.2794 -0.1778)
							(mid 0.249642 -0.249642)
							(end 0.1778 -0.2794)
						)
					)
					(width 0)
					(fill yes)
				)
			)
		)
	)
	(footprint ""
		(layer "F.Cu")
		(at 279.2857 -213.03996)
		(property "Reference" "TP181"
			(at 0 0 0)
			(layer "F.SilkS")
			(hide yes)
			(effects
				(font
					(size 1.27 1.27)
				)
			)
		)
		(property "Value" "TPAD28"
			(at -0.0127 -1.6637 0)
			(unlocked yes)
			(layer "F.Fab")
			(hide yes)
			(effects
				(font
					(size 1.016 1.016)
					(thickness 0.1524)
				)
			)
		)
		(property "Device Type" "TPAD28"
			(at -0.0127 -3.1877 0)
			(unlocked yes)
			(layer "F.Fab")
			(hide yes)
			(effects
				(font
					(size 1.016 1.016)
					(thickness 0.1524)
				)
			)
		)
		(duplicate_pad_numbers_are_jumpers no)
		(fp_poly
			(pts
				(arc
					(start 0.3556 0)
					(mid -0.3556 0)
					(end 0.3556 0)
				)
			)
			(stroke
				(width 0)
				(type default)
			)
			(fill no)
			(layer "F.CrtYd")
		)
		(fp_poly
			(pts
				(arc
					(start 0.6096 0)
					(mid -0.6096 0)
					(end 0.6096 0)
				)
			)
			(stroke
				(width 0)
				(type default)
			)
			(fill no)
			(layer "F.Fab")
		)
		(pad "1" smd circle
			(at 0 0)
			(size 0.7112 0.7112)
			(layers "F.Cu" "F.Mask" "F.Paste")
			(net "FM_BMC_RESET_N")
		)
	)
	(footprint ""
		(layer "F.Cu")
		(at 304.918872 -205.177136 -90)
		(property "Reference" "C143"
			(at 0 0 270)
			(layer "F.SilkS")
			(hide yes)
			(effects
				(font
					(size 1.27 1.27)
				)
			)
		)
		(property "Value" "SCD01U50V2KX-1GP"
			(at 1.1811 -2.7051 270)
			(unlocked yes)
			(layer "F.Fab")
			(hide yes)
			(effects
				(font
					(size 1.016 1.016)
					(thickness 0.1524)
				)
			)
		)
		(property "Device Type" "C402H22"
			(at 1.1811 -4.2291 270)
			(unlocked yes)
			(layer "F.Fab")
			(hide yes)
			(effects
				(font
					(size 1.016 1.016)
					(thickness 0.1524)
				)
			)
		)
		(duplicate_pad_numbers_are_jumpers no)
		(fp_rect
			(start -0.4318 0.9525)
			(end 0.4318 -0.9525)
			(stroke
				(width 0)
				(type default)
			)
			(fill no)
			(layer "F.CrtYd")
		)
		(fp_rect
			(start -0.4318 0.9525)
			(end 0.4318 -0.9525)
			(stroke
				(width 0)
				(type default)
			)
			(fill no)
			(layer "F.Fab")
		)
		(pad "1" smd custom
			(at 0 -0.4445 270)
			(size 0.1524 0.1524)
			(layers "F.Cu" "F.Mask" "F.Paste")
			(net "P3V3_STBY")
			(options
				(clearance outline)
				(anchor circle)
			)
			(primitives
				(gr_poly
					(pts
						(arc
							(start 0.3048 -0.2032)
							(mid 0.275042 -0.275042)
							(end 0.2032 -0.3048)
						)
						(arc
							(start -0.2032 -0.3048)
							(mid -0.275042 -0.275042)
							(end -0.3048 -0.2032)
						)
						(arc
							(start -0.3048 0.2032)
							(mid -0.275042 0.275042)
							(end -0.2032 0.3048)
						)
						(arc
							(start 0.2032 0.3048)
							(mid 0.275042 0.275042)
							(end 0.3048 0.2032)
						)
					)
					(width 0)
					(fill yes)
				)
			)
		)
		(pad "2" smd custom
			(at 0 0.4445 270)
			(size 0.1524 0.1524)
			(layers "F.Cu" "F.Mask" "F.Paste")
			(net "GND")
			(options
				(clearance outline)
				(anchor circle)
			)
			(primitives
				(gr_poly
					(pts
						(arc
							(start 0.3048 -0.2032)
							(mid 0.275042 -0.275042)
							(end 0.2032 -0.3048)
						)
						(arc
							(start -0.2032 -0.3048)
							(mid -0.275042 -0.275042)
							(end -0.3048 -0.2032)
						)
						(arc
							(start -0.3048 0.2032)
							(mid -0.275042 0.275042)
							(end -0.2032 0.3048)
						)
						(arc
							(start 0.2032 0.3048)
							(mid 0.275042 0.275042)
							(end 0.3048 0.2032)
						)
					)
					(width 0)
					(fill yes)
				)
			)
		)
	)
	(footprint ""
		(layer "F.Cu")
		(at 173.473872 -194.051936 180)
		(property "Reference" "R427"
			(at 0 0 180)
			(layer "F.SilkS")
			(hide yes)
			(effects
				(font
					(size 1.27 1.27)
				)
			)
		)
		(property "Value" "2KR2F-3-GP"
			(at 0.064008 -3.993896 180)
			(unlocked yes)
			(layer "F.Fab")
			(hide yes)
			(effects
				(font
					(size 1.016 1.016)
					(thickness 0.1524)
				)
			)
		)
		(property "Device Type" "R402H16"
			(at 0.064008 -5.517896 180)
			(unlocked yes)
			(layer "F.Fab")
			(hide yes)
			(effects
				(font
					(size 1.016 1.016)
					(thickness 0.1524)
				)
			)
		)
		(duplicate_pad_numbers_are_jumpers no)
		(fp_line
			(start 0.508 -0.9398)
			(end -0.508 -0.9398)
			(stroke
				(width 0.1524)
				(type default)
			)
			(layer "F.SilkS")
		)
		(fp_line
			(start -0.508 -0.9398)
			(end -0.508 0.9398)
			(stroke
				(width 0.1524)
				(type default)
			)
			(layer "F.SilkS")
		)
		(fp_rect
			(start -0.508 0.9398)
			(end 0.508 -0.9398)
			(stroke
				(width 0)
				(type default)
			)
			(fill no)
			(layer "F.CrtYd")
		)
		(fp_rect
			(start -0.508 0.9398)
			(end 0.508 -0.9398)
			(stroke
				(width 0)
				(type default)
			)
			(fill no)
			(layer "F.Fab")
		)
		(pad "1" smd custom
			(at 0 -0.4445 180)
			(size 0.1397 0.1397)
			(layers "F.Cu" "F.Mask" "F.Paste")
			(net "P3V3_STBY")
			(options
				(clearance outline)
				(anchor circle)
			)
			(primitives
				(gr_poly
					(pts
						(arc
							(start -0.1778 -0.2794)
							(mid -0.249642 -0.249642)
							(end -0.2794 -0.1778)
						)
						(arc
							(start -0.2794 0.1778)
							(mid -0.249642 0.249642)
							(end -0.1778 0.2794)
						)
						(arc
							(start 0.1778 0.2794)
							(mid 0.249642 0.249642)
							(end 0.2794 0.1778)
						)
						(arc
							(start 0.2794 -0.1778)
							(mid 0.249642 -0.249642)
							(end 0.1778 -0.2794)
						)
					)
					(width 0)
					(fill yes)
				)
			)
		)
		(pad "2" smd custom
			(at 0 0.4445 180)
			(size 0.1397 0.1397)
			(layers "F.Cu" "F.Mask" "F.Paste")
			(net "SAS_I2C_C_BUF_SCL")
			(options
				(clearance outline)
				(anchor circle)
			)
			(primitives
				(gr_poly
					(pts
						(arc
							(start -0.1778 -0.2794)
							(mid -0.249642 -0.249642)
							(end -0.2794 -0.1778)
						)
						(arc
							(start -0.2794 0.1778)
							(mid -0.249642 0.249642)
							(end -0.1778 0.2794)
						)
						(arc
							(start 0.1778 0.2794)
							(mid 0.249642 0.249642)
							(end 0.2794 0.1778)
						)
						(arc
							(start 0.2794 -0.1778)
							(mid 0.249642 -0.249642)
							(end 0.1778 -0.2794)
						)
					)
					(width 0)
					(fill yes)
				)
			)
		)
	)
	(footprint ""
		(layer "F.Cu")
		(at 29.922216 -231.57688)
		(property "Reference" "SU13"
			(at 0 0 0)
			(layer "F.SilkS")
			(hide yes)
			(effects
				(font
					(size 1.27 1.27)
				)
			)
		)
		(property "Value" "PI3C3861-AQE-GP"
			(at 0 -13.1572 0)
			(unlocked yes)
			(layer "F.Fab")
			(hide yes)
			(effects
				(font
					(size 1.016 1.016)
					(thickness 0.1524)
				)
			)
		)
		(property "Device Type" "QSOIC24H69"
			(at 0 -15.1892 0)
			(unlocked yes)
			(layer "F.Fab")
			(hide yes)
			(effects
				(font
					(size 1.016 1.016)
					(thickness 0.1524)
				)
			)
		)
		(duplicate_pad_numbers_are_jumpers no)
		(fp_line
			(start -4.4958 -1.5748)
			(end 3.5814 -1.5748)
			(stroke
				(width 0.1524)
				(type default)
			)
			(layer "F.SilkS")
		)
		(fp_line
			(start -4.4958 -0.4318)
			(end -4.4958 -1.5748)
			(stroke
				(width 0.1524)
				(type default)
			)
			(layer "F.SilkS")
		)
		(fp_line
			(start -4.4958 -0.4318)
			(end -4.064 0)
			(stroke
				(width 0.1524)
				(type default)
			)
			(layer "F.SilkS")
		)
		(fp_line
			(start -4.4958 0.4318)
			(end -4.4958 -0.4318)
			(stroke
				(width 0.1524)
				(type default)
			)
			(layer "F.SilkS")
		)
		(fp_line
			(start -4.4958 0.4318)
			(end -4.4958 1.5748)
			(stroke
				(width 0.1524)
				(type default)
			)
			(layer "F.SilkS")
		)
		(fp_line
			(start -4.318 1.5748)
			(end -4.318 3.556)
			(stroke
				(width 0.508)
				(type default)
			)
			(layer "F.SilkS")
		)
		(fp_line
			(start -4.064 0)
			(end -4.4958 0.4318)
			(stroke
				(width 0.1524)
				(type default)
			)
			(layer "F.SilkS")
		)
		(fp_line
			(start 3.5814 -1.5748)
			(end 3.5814 1.5748)
			(stroke
				(width 0.1524)
				(type default)
			)
			(layer "F.SilkS")
		)
		(fp_line
			(start 3.5814 1.5748)
			(end -4.4958 1.5748)
			(stroke
				(width 0.1524)
				(type default)
			)
			(layer "F.SilkS")
		)
		(fp_line
			(start 3.5814 1.5748)
			(end 3.5814 -1.5748)
			(stroke
				(width 0.1524)
				(type default)
			)
			(layer "F.SilkS")
		)
		(fp_poly
			(pts
				(xy -3.683 -1.5748) (xy 3.5814 -1.5748) (xy 3.5814 1.5748) (xy -3.683 1.5748)
			)
			(stroke
				(width 0)
				(type default)
			)
			(fill yes)
			(layer "F.SilkS")
		)
		(fp_rect
			(start -4.572 3.81)
			(end 4.572 -3.81)
			(stroke
				(width 0)
				(type default)
			)
			(fill no)
			(layer "F.CrtYd")
		)
		(fp_poly
			(pts
				(xy -4.572 -3.81) (xy 4.572 -3.81) (xy 4.572 3.81) (xy -4.572 3.81)
			)
			(stroke
				(width 0)
				(type default)
			)
			(fill no)
			(layer "F.Fab")
		)
		(pad "1" smd rect
			(at -3.4925 2.6162)
			(size 0.3556 1.524)
			(layers "F.Cu" "F.Mask" "F.Paste")
			(net "Net_1512")
		)
		(pad "2" smd rect
			(at -2.8575 2.6162)
			(size 0.3556 1.524)
			(layers "F.Cu" "F.Mask" "F.Paste")
			(net "SAS_HDD_PWR0")
		)
		(pad "3" smd rect
			(at -2.2225 2.6162)
			(size 0.3556 1.524)
			(layers "F.Cu" "F.Mask" "F.Paste")
			(net "SAS_HDD_PWR1")
		)
		(pad "4" smd rect
			(at -1.5875 2.6162)
			(size 0.3556 1.524)
			(layers "F.Cu" "F.Mask" "F.Paste")
			(net "SAS_HDD_PWR2")
		)
		(pad "5" smd rect
			(at -0.9525 2.6162)
			(size 0.3556 1.524)
			(layers "F.Cu" "F.Mask" "F.Paste")
			(net "SAS_HDD_PWR3")
		)
		(pad "6" smd rect
			(at -0.3175 2.6162)
			(size 0.3556 1.524)
			(layers "F.Cu" "F.Mask" "F.Paste")
			(net "SAS_HDD_PWR4")
		)
		(pad "7" smd rect
			(at 0.3175 2.6162)
			(size 0.3556 1.524)
			(layers "F.Cu" "F.Mask" "F.Paste")
			(net "SAS_HDD_PWR5")
		)
		(pad "8" smd rect
			(at 0.9525 2.6162)
			(size 0.3556 1.524)
			(layers "F.Cu" "F.Mask" "F.Paste")
			(net "SAS_HDD_PWR6")
		)
		(pad "9" smd rect
			(at 1.5875 2.6162)
			(size 0.3556 1.524)
			(layers "F.Cu" "F.Mask" "F.Paste")
			(net "SAS_HDD_PWR7")
		)
		(pad "10" smd rect
			(at 2.2225 2.6162)
			(size 0.3556 1.524)
			(layers "F.Cu" "F.Mask" "F.Paste")
			(net "SAS_HDD_PWR8")
		)
		(pad "11" smd rect
			(at 2.8575 2.6162)
			(size 0.3556 1.524)
			(layers "F.Cu" "F.Mask" "F.Paste")
			(net "SAS_HDD_PWR9")
		)
		(pad "12" smd rect
			(at 3.4925 2.6162)
			(size 0.3556 1.524)
			(layers "F.Cu" "F.Mask" "F.Paste")
			(net "GND")
		)
		(pad "13" smd rect
			(at 3.4925 -2.6162)
			(size 0.3556 1.524)
			(layers "F.Cu" "F.Mask" "F.Paste")
			(net "SAS_HDD_PWR9_PCIE")
		)
		(pad "14" smd rect
			(at 2.8575 -2.6162)
			(size 0.3556 1.524)
			(layers "F.Cu" "F.Mask" "F.Paste")
			(net "SAS_HDD_PWR8_PCIE")
		)
		(pad "15" smd rect
			(at 2.2225 -2.6162)
			(size 0.3556 1.524)
			(layers "F.Cu" "F.Mask" "F.Paste")
			(net "SAS_HDD_PWR7_PCIE")
		)
		(pad "16" smd rect
			(at 1.5875 -2.6162)
			(size 0.3556 1.524)
			(layers "F.Cu" "F.Mask" "F.Paste")
			(net "SAS_HDD_PWR6_PCIE")
		)
		(pad "17" smd rect
			(at 0.9525 -2.6162)
			(size 0.3556 1.524)
			(layers "F.Cu" "F.Mask" "F.Paste")
			(net "SAS_HDD_PWR5_PCIE")
		)
		(pad "18" smd rect
			(at 0.3175 -2.6162)
			(size 0.3556 1.524)
			(layers "F.Cu" "F.Mask" "F.Paste")
			(net "SAS_HDD_PWR4_PCIE")
		)
		(pad "19" smd rect
			(at -0.3175 -2.6162)
			(size 0.3556 1.524)
			(layers "F.Cu" "F.Mask" "F.Paste")
			(net "SAS_HDD_PWR3_PCIE")
		)
		(pad "20" smd rect
			(at -0.9525 -2.6162)
			(size 0.3556 1.524)
			(layers "F.Cu" "F.Mask" "F.Paste")
			(net "SAS_HDD_PWR2_PCIE")
		)
		(pad "21" smd rect
			(at -1.5875 -2.6162)
			(size 0.3556 1.524)
			(layers "F.Cu" "F.Mask" "F.Paste")
			(net "SAS_HDD_PWR1_PCIE")
		)
		(pad "22" smd rect
			(at -2.2225 -2.6162)
			(size 0.3556 1.524)
			(layers "F.Cu" "F.Mask" "F.Paste")
			(net "SAS_HDD_PWR0_PCIE")
		)
		(pad "23" smd rect
			(at -2.8575 -2.6162)
			(size 0.3556 1.524)
			(layers "F.Cu" "F.Mask" "F.Paste")
			(net "PCIE_MATED#_AB")
		)
		(pad "24" smd rect
			(at -3.4925 -2.6162)
			(size 0.3556 1.524)
			(layers "F.Cu" "F.Mask" "F.Paste")
			(net "P3V3_STBY")
		)
	)
	(footprint ""
		(layer "F.Cu")
		(at 117.729 -35.941)
		(property "Reference" "STP133"
			(at 0 0 0)
			(layer "F.SilkS")
			(hide yes)
			(effects
				(font
					(size 1.27 1.27)
				)
			)
		)
		(property "Value" "TPAD28"
			(at 0.0127 -1.8034 0)
			(unlocked yes)
			(layer "F.Fab")
			(hide yes)
			(effects
				(font
					(size 1.016 1.016)
					(thickness 0.1524)
				)
			)
		)
		(property "Device Type" "TPAD28"
			(at 0.0127 -3.3274 0)
			(unlocked yes)
			(layer "F.Fab")
			(hide yes)
			(effects
				(font
					(size 1.016 1.016)
					(thickness 0.1524)
				)
			)
		)
		(duplicate_pad_numbers_are_jumpers no)
		(fp_poly
			(pts
				(arc
					(start 0.3556 0)
					(mid -0.3556 0)
					(end 0.3556 0)
				)
			)
			(stroke
				(width 0)
				(type default)
			)
			(fill no)
			(layer "F.CrtYd")
		)
		(fp_poly
			(pts
				(arc
					(start 0.6096 0)
					(mid -0.6096 0)
					(end 0.6096 0)
				)
			)
			(stroke
				(width 0)
				(type default)
			)
			(fill no)
			(layer "F.Fab")
		)
		(pad "1" smd circle
			(at 0 0)
			(size 0.7112 0.7112)
			(layers "F.Cu" "F.Mask" "F.Paste")
			(net "IOC_GPIO_8")
		)
	)
	(footprint ""
		(layer "F.Cu")
		(at 191.897 -22.479 -90)
		(property "Reference" "R646"
			(at 0 0 270)
			(layer "F.SilkS")
			(hide yes)
			(effects
				(font
					(size 1.27 1.27)
				)
			)
		)
		(property "Value" "0R2J-2-GP"
			(at 0.064008 -3.993896 270)
			(unlocked yes)
			(layer "F.Fab")
			(hide yes)
			(effects
				(font
					(size 1.016 1.016)
					(thickness 0.1524)
				)
			)
		)
		(property "Device Type" "R402H16"
			(at 0.064008 -5.517896 270)
			(unlocked yes)
			(layer "F.Fab")
			(hide yes)
			(effects
				(font
					(size 1.016 1.016)
					(thickness 0.1524)
				)
			)
		)
		(duplicate_pad_numbers_are_jumpers no)
		(fp_line
			(start -0.508 -0.9398)
			(end -0.508 0.9398)
			(stroke
				(width 0.1524)
				(type default)
			)
			(layer "F.SilkS")
		)
		(fp_line
			(start 0.508 -0.9398)
			(end -0.508 -0.9398)
			(stroke
				(width 0.1524)
				(type default)
			)
			(layer "F.SilkS")
		)
		(fp_rect
			(start -0.508 0.9398)
			(end 0.508 -0.9398)
			(stroke
				(width 0)
				(type default)
			)
			(fill no)
			(layer "F.CrtYd")
		)
		(fp_rect
			(start -0.508 0.9398)
			(end 0.508 -0.9398)
			(stroke
				(width 0)
				(type default)
			)
			(fill no)
			(layer "F.Fab")
		)
		(pad "1" smd custom
			(at 0 -0.4445 270)
			(size 0.1397 0.1397)
			(layers "F.Cu" "F.Mask" "F.Paste")
			(net "GND")
			(options
				(clearance outline)
				(anchor circle)
			)
			(primitives
				(gr_poly
					(pts
						(arc
							(start -0.1778 -0.2794)
							(mid -0.249642 -0.249642)
							(end -0.2794 -0.1778)
						)
						(arc
							(start -0.2794 0.1778)
							(mid -0.249642 0.249642)
							(end -0.1778 0.2794)
						)
						(arc
							(start 0.1778 0.2794)
							(mid 0.249642 0.249642)
							(end 0.2794 0.1778)
						)
						(arc
							(start 0.2794 -0.1778)
							(mid 0.249642 -0.249642)
							(end 0.1778 -0.2794)
						)
					)
					(width 0)
					(fill yes)
				)
			)
		)
		(pad "2" smd custom
			(at 0 0.4445 270)
			(size 0.1397 0.1397)
			(layers "F.Cu" "F.Mask" "F.Paste")
			(net "RMII_BMC_MDC")
			(options
				(clearance outline)
				(anchor circle)
			)
			(primitives
				(gr_poly
					(pts
						(arc
							(start -0.1778 -0.2794)
							(mid -0.249642 -0.249642)
							(end -0.2794 -0.1778)
						)
						(arc
							(start -0.2794 0.1778)
							(mid -0.249642 0.249642)
							(end -0.1778 0.2794)
						)
						(arc
							(start 0.1778 0.2794)
							(mid 0.249642 0.249642)
							(end 0.2794 0.1778)
						)
						(arc
							(start 0.2794 -0.1778)
							(mid 0.249642 -0.249642)
							(end 0.1778 -0.2794)
						)
					)
					(width 0)
					(fill yes)
				)
			)
		)
	)
	(footprint ""
		(layer "F.Cu")
		(at 144.907 -103.505 90)
		(property "Reference" "SC1188"
			(at 0 0 90)
			(layer "F.SilkS")
			(hide yes)
			(effects
				(font
					(size 1.27 1.27)
				)
			)
		)
		(property "Value" "SC100U6D3V0MX-2GP"
			(at -0.00254 -4.78536 90)
			(unlocked yes)
			(layer "F.Fab")
			(hide yes)
			(effects
				(font
					(size 1.016 1.016)
					(thickness 0.1524)
				)
			)
		)
		(property "Device Type" "C1210H107"
			(at -0.00254 -6.38048 90)
			(unlocked yes)
			(layer "F.Fab")
			(hide yes)
			(effects
				(font
					(size 1.016 1.016)
					(thickness 0.1524)
				)
			)
		)
		(duplicate_pad_numbers_are_jumpers no)
		(fp_line
			(start 1.5748 -2.3368)
			(end -1.5748 -2.3368)
			(stroke
				(width 0.1524)
				(type default)
			)
			(layer "F.SilkS")
		)
		(fp_line
			(start -1.5748 -2.3368)
			(end -1.5748 -0.762)
			(stroke
				(width 0.1524)
				(type default)
			)
			(layer "F.SilkS")
		)
		(fp_line
			(start 1.5748 -0.762)
			(end 1.5748 -2.3368)
			(stroke
				(width 0.1524)
				(type default)
			)
			(layer "F.SilkS")
		)
		(fp_line
			(start -1.5748 0.762)
			(end -1.5748 2.3368)
			(stroke
				(width 0.1524)
				(type default)
			)
			(layer "F.SilkS")
		)
		(fp_line
			(start 1.5748 2.3368)
			(end 1.5748 0.762)
			(stroke
				(width 0.1524)
				(type default)
			)
			(layer "F.SilkS")
		)
		(fp_line
			(start -1.5748 2.3368)
			(end 1.5748 2.3368)
			(stroke
				(width 0.1524)
				(type default)
			)
			(layer "F.SilkS")
		)
		(fp_rect
			(start -1.651 2.413)
			(end 1.651 -2.413)
			(stroke
				(width 0)
				(type default)
			)
			(fill no)
			(layer "F.CrtYd")
		)
		(fp_poly
			(pts
				(xy 1.651 2.413) (xy 1.651 -2.413) (xy -1.651 -2.413) (xy -1.651 2.413)
			)
			(stroke
				(width 0)
				(type default)
			)
			(fill no)
			(layer "F.Fab")
		)
		(pad "1" smd rect
			(at 0 -1.4732 90)
			(size 2.794 1.397)
			(layers "F.Cu" "F.Mask" "F.Paste")
			(net "GND")
		)
		(pad "2" smd rect
			(at 0 1.4732 90)
			(size 2.794 1.397)
			(layers "F.Cu" "F.Mask" "F.Paste")
			(net "GB_VDDA")
		)
	)
	(footprint ""
		(layer "F.Cu")
		(at 261.62 -16.383 180)
		(property "Reference" "TC10"
			(at 0 0 180)
			(layer "F.SilkS")
			(hide yes)
			(effects
				(font
					(size 1.27 1.27)
				)
			)
		)
		(property "Value" "SC47U16V0MX-GP"
			(at -0.00254 -4.78536 180)
			(unlocked yes)
			(layer "F.Fab")
			(hide yes)
			(effects
				(font
					(size 1.016 1.016)
					(thickness 0.1524)
				)
			)
		)
		(property "Device Type" "C1210H107"
			(at -0.00254 -6.38048 180)
			(unlocked yes)
			(layer "F.Fab")
			(hide yes)
			(effects
				(font
					(size 1.016 1.016)
					(thickness 0.1524)
				)
			)
		)
		(duplicate_pad_numbers_are_jumpers no)
		(fp_line
			(start 1.5748 2.3368)
			(end 1.5748 0.762)
			(stroke
				(width 0.1524)
				(type default)
			)
			(layer "F.SilkS")
		)
		(fp_line
			(start 1.5748 -0.762)
			(end 1.5748 -2.3368)
			(stroke
				(width 0.1524)
				(type default)
			)
			(layer "F.SilkS")
		)
		(fp_line
			(start 1.5748 -2.3368)
			(end -1.5748 -2.3368)
			(stroke
				(width 0.1524)
				(type default)
			)
			(layer "F.SilkS")
		)
		(fp_line
			(start -1.5748 2.3368)
			(end 1.5748 2.3368)
			(stroke
				(width 0.1524)
				(type default)
			)
			(layer "F.SilkS")
		)
		(fp_line
			(start -1.5748 0.762)
			(end -1.5748 2.3368)
			(stroke
				(width 0.1524)
				(type default)
			)
			(layer "F.SilkS")
		)
		(fp_line
			(start -1.5748 -2.3368)
			(end -1.5748 -0.762)
			(stroke
				(width 0.1524)
				(type default)
			)
			(layer "F.SilkS")
		)
		(fp_rect
			(start -1.651 2.413)
			(end 1.651 -2.413)
			(stroke
				(width 0)
				(type default)
			)
			(fill no)
			(layer "F.CrtYd")
		)
		(fp_poly
			(pts
				(xy 1.651 2.413) (xy 1.651 -2.413) (xy -1.651 -2.413) (xy -1.651 2.413)
			)
			(stroke
				(width 0)
				(type default)
			)
			(fill no)
			(layer "F.Fab")
		)
		(pad "1" smd rect
			(at 0 -1.4732 180)
			(size 2.794 1.397)
			(layers "F.Cu" "F.Mask" "F.Paste")
			(net "P5V_USB")
		)
		(pad "2" smd rect
			(at 0 1.4732 180)
			(size 2.794 1.397)
			(layers "F.Cu" "F.Mask" "F.Paste")
			(net "GND")
		)
	)
	(footprint ""
		(layer "F.Cu")
		(at 189.865 -25.273 90)
		(property "Reference" "R376"
			(at 0 0 90)
			(layer "F.SilkS")
			(hide yes)
			(effects
				(font
					(size 1.27 1.27)
				)
			)
		)
		(property "Value" "33R2J-2-GP"
			(at 0.064008 -3.993896 90)
			(unlocked yes)
			(layer "F.Fab")
			(hide yes)
			(effects
				(font
					(size 1.016 1.016)
					(thickness 0.1524)
				)
			)
		)
		(property "Device Type" "R402H16"
			(at 0.064008 -5.517896 90)
			(unlocked yes)
			(layer "F.Fab")
			(hide yes)
			(effects
				(font
					(size 1.016 1.016)
					(thickness 0.1524)
				)
			)
		)
		(duplicate_pad_numbers_are_jumpers no)
		(fp_line
			(start 0.508 -0.9398)
			(end -0.508 -0.9398)
			(stroke
				(width 0.1524)
				(type default)
			)
			(layer "F.SilkS")
		)
		(fp_line
			(start -0.508 -0.9398)
			(end -0.508 0.9398)
			(stroke
				(width 0.1524)
				(type default)
			)
			(layer "F.SilkS")
		)
		(fp_rect
			(start -0.508 0.9398)
			(end 0.508 -0.9398)
			(stroke
				(width 0)
				(type default)
			)
			(fill no)
			(layer "F.CrtYd")
		)
		(fp_rect
			(start -0.508 0.9398)
			(end 0.508 -0.9398)
			(stroke
				(width 0)
				(type default)
			)
			(fill no)
			(layer "F.Fab")
		)
		(pad "1" smd custom
			(at 0 -0.4445 90)
			(size 0.1397 0.1397)
			(layers "F.Cu" "F.Mask" "F.Paste")
			(net "RMII_PHY_BMC_RXD0_R")
			(options
				(clearance outline)
				(anchor circle)
			)
			(primitives
				(gr_poly
					(pts
						(arc
							(start -0.1778 -0.2794)
							(mid -0.249642 -0.249642)
							(end -0.2794 -0.1778)
						)
						(arc
							(start -0.2794 0.1778)
							(mid -0.249642 0.249642)
							(end -0.1778 0.2794)
						)
						(arc
							(start 0.1778 0.2794)
							(mid 0.249642 0.249642)
							(end 0.2794 0.1778)
						)
						(arc
							(start 0.2794 -0.1778)
							(mid 0.249642 -0.249642)
							(end 0.1778 -0.2794)
						)
					)
					(width 0)
					(fill yes)
				)
			)
		)
		(pad "2" smd custom
			(at 0 0.4445 90)
			(size 0.1397 0.1397)
			(layers "F.Cu" "F.Mask" "F.Paste")
			(net "RMII_PHY_BMC_RXD0")
			(options
				(clearance outline)
				(anchor circle)
			)
			(primitives
				(gr_poly
					(pts
						(arc
							(start -0.1778 -0.2794)
							(mid -0.249642 -0.249642)
							(end -0.2794 -0.1778)
						)
						(arc
							(start -0.2794 0.1778)
							(mid -0.249642 0.249642)
							(end -0.1778 0.2794)
						)
						(arc
							(start 0.1778 0.2794)
							(mid 0.249642 0.249642)
							(end 0.2794 0.1778)
						)
						(arc
							(start 0.2794 -0.1778)
							(mid 0.249642 -0.249642)
							(end 0.1778 -0.2794)
						)
					)
					(width 0)
					(fill yes)
				)
			)
		)
	)
	(footprint ""
		(layer "F.Cu")
		(at 66.172842 -133.142482 -90)
		(property "Reference" "SU73"
			(at 0 0 270)
			(layer "F.SilkS")
			(hide yes)
			(effects
				(font
					(size 1.27 1.27)
				)
			)
		)
		(property "Value" "S29GL128S10TFIV20-GP"
			(at -0.1778 -20.32 270)
			(unlocked yes)
			(layer "F.Fab")
			(hide yes)
			(effects
				(font
					(size 1.016 1.016)
					(thickness 0.1524)
				)
			)
		)
		(property "Device Type" "TSOP56-1H48"
			(at -0.1778 -22.225 270)
			(unlocked yes)
			(layer "F.Fab")
			(hide yes)
			(effects
				(font
					(size 1.016 1.016)
					(thickness 0.1524)
				)
			)
		)
		(duplicate_pad_numbers_are_jumpers no)
		(fp_line
			(start -7.5438 8.5598)
			(end 6.8326 8.5598)
			(stroke
				(width 0.1524)
				(type default)
			)
			(layer "F.SilkS")
		)
		(fp_line
			(start -7.366 8.5598)
			(end -7.366 10.795)
			(stroke
				(width 0.508)
				(type default)
			)
			(layer "F.SilkS")
		)
		(fp_line
			(start 6.8326 8.5598)
			(end 6.8326 -8.5598)
			(stroke
				(width 0.1524)
				(type default)
			)
			(layer "F.SilkS")
		)
		(fp_line
			(start -7.112 0)
			(end -7.5438 0.4318)
			(stroke
				(width 0.1524)
				(type default)
			)
			(layer "F.SilkS")
		)
		(fp_line
			(start -7.5438 -0.4318)
			(end -7.112 0)
			(stroke
				(width 0.1524)
				(type default)
			)
			(layer "F.SilkS")
		)
		(fp_line
			(start -7.5438 -8.5598)
			(end -7.5438 8.5598)
			(stroke
				(width 0.1524)
				(type default)
			)
			(layer "F.SilkS")
		)
		(fp_line
			(start 6.8326 -8.5598)
			(end -7.5438 -8.5598)
			(stroke
				(width 0.1524)
				(type default)
			)
			(layer "F.SilkS")
		)
		(fp_poly
			(pts
				(xy -7.62 11.049) (xy 7.62 11.049) (xy 7.62 -11.049) (xy -7.62 -11.049)
			)
			(stroke
				(width 0)
				(type default)
			)
			(fill no)
			(layer "F.CrtYd")
		)
		(fp_poly
			(pts
				(xy -7.62 -11.049) (xy 7.62 -11.049) (xy 7.62 11.049) (xy -7.62 11.049)
			)
			(stroke
				(width 0)
				(type default)
			)
			(fill no)
			(layer "F.Fab")
		)
		(pad "1" smd rect
			(at -6.75005 9.6139 270)
			(size 0.3048 1.524)
			(layers "F.Cu" "F.Mask" "F.Paste")
			(net "Net_174")
		)
		(pad "2" smd rect
			(at -6.24967 9.6139 270)
			(size 0.3048 1.524)
			(layers "F.Cu" "F.Mask" "F.Paste")
			(net "EXP_XM_ADDR_23")
		)
		(pad "3" smd rect
			(at -5.75056 9.6139 270)
			(size 0.3048 1.524)
			(layers "F.Cu" "F.Mask" "F.Paste")
			(net "EXP_XM_ADDR_16")
		)
		(pad "4" smd rect
			(at -5.25018 9.6139 270)
			(size 0.3048 1.524)
			(layers "F.Cu" "F.Mask" "F.Paste")
			(net "EXP_XM_ADDR_15")
		)
		(pad "5" smd rect
			(at -4.7498 9.6139 270)
			(size 0.3048 1.524)
			(layers "F.Cu" "F.Mask" "F.Paste")
			(net "EXP_XM_ADDR_14")
		)
		(pad "6" smd rect
			(at -4.24942 9.6139 270)
			(size 0.3048 1.524)
			(layers "F.Cu" "F.Mask" "F.Paste")
			(net "EXP_XM_ADDR_13")
		)
		(pad "7" smd rect
			(at -3.75031 9.6139 270)
			(size 0.3048 1.524)
			(layers "F.Cu" "F.Mask" "F.Paste")
			(net "EXP_XM_ADDR_12")
		)
		(pad "8" smd rect
			(at -3.24993 9.6139 270)
			(size 0.3048 1.524)
			(layers "F.Cu" "F.Mask" "F.Paste")
			(net "EXP_XM_ADDR_11")
		)
		(pad "9" smd rect
			(at -2.74955 9.6139 270)
			(size 0.3048 1.524)
			(layers "F.Cu" "F.Mask" "F.Paste")
			(net "EXP_XM_ADDR_10")
		)
		(pad "10" smd rect
			(at -2.25044 9.6139 270)
			(size 0.3048 1.524)
			(layers "F.Cu" "F.Mask" "F.Paste")
			(net "EXP_XM_ADDR_9")
		)
		(pad "11" smd rect
			(at -1.75006 9.6139 270)
			(size 0.3048 1.524)
			(layers "F.Cu" "F.Mask" "F.Paste")
			(net "EXP_XM_ADDR_20")
		)
		(pad "12" smd rect
			(at -1.24968 9.6139 270)
			(size 0.3048 1.524)
			(layers "F.Cu" "F.Mask" "F.Paste")
			(net "EXP_XM_ADDR_21")
		)
		(pad "13" smd rect
			(at -0.75057 9.6139 270)
			(size 0.3048 1.524)
			(layers "F.Cu" "F.Mask" "F.Paste")
			(net "EXP_XM_WE_N")
		)
		(pad "14" smd rect
			(at -0.25019 9.6139 270)
			(size 0.3048 1.524)
			(layers "F.Cu" "F.Mask" "F.Paste")
			(net "RESET_N")
		)
		(pad "15" smd rect
			(at 0.25019 9.6139 270)
			(size 0.3048 1.524)
			(layers "F.Cu" "F.Mask" "F.Paste")
			(net "EXP_XM_ADDR_22")
		)
		(pad "16" smd rect
			(at 0.75057 9.6139 270)
			(size 0.3048 1.524)
			(layers "F.Cu" "F.Mask" "F.Paste")
			(net "EXP_WP_N")
		)
		(pad "17" smd rect
			(at 1.24968 9.6139 270)
			(size 0.3048 1.524)
			(layers "F.Cu" "F.Mask" "F.Paste")
			(net "EXP_XM_BUSY_N")
		)
		(pad "18" smd rect
			(at 1.75006 9.6139 270)
			(size 0.3048 1.524)
			(layers "F.Cu" "F.Mask" "F.Paste")
			(net "EXP_XM_ADDR_19")
		)
		(pad "19" smd rect
			(at 2.25044 9.6139 270)
			(size 0.3048 1.524)
			(layers "F.Cu" "F.Mask" "F.Paste")
			(net "EXP_XM_ADDR_18")
		)
		(pad "20" smd rect
			(at 2.74955 9.6139 270)
			(size 0.3048 1.524)
			(layers "F.Cu" "F.Mask" "F.Paste")
			(net "EXP_XM_ADDR_8")
		)
		(pad "21" smd rect
			(at 3.24993 9.6139 270)
			(size 0.3048 1.524)
			(layers "F.Cu" "F.Mask" "F.Paste")
			(net "EXP_XM_ADDR_7")
		)
		(pad "22" smd rect
			(at 3.75031 9.6139 270)
			(size 0.3048 1.524)
			(layers "F.Cu" "F.Mask" "F.Paste")
			(net "EXP_XM_ADDR_6")
		)
		(pad "23" smd rect
			(at 4.24942 9.6139 270)
			(size 0.3048 1.524)
			(layers "F.Cu" "F.Mask" "F.Paste")
			(net "EXP_XM_ADDR_5")
		)
		(pad "24" smd rect
			(at 4.7498 9.6139 270)
			(size 0.3048 1.524)
			(layers "F.Cu" "F.Mask" "F.Paste")
			(net "EXP_XM_ADDR_4")
		)
		(pad "25" smd rect
			(at 5.25018 9.6139 270)
			(size 0.3048 1.524)
			(layers "F.Cu" "F.Mask" "F.Paste")
			(net "EXP_XM_ADDR_3")
		)
		(pad "26" smd rect
			(at 5.75056 9.6139 270)
			(size 0.3048 1.524)
			(layers "F.Cu" "F.Mask" "F.Paste")
			(net "EXP_XM_ADDR_2")
		)
		(pad "27" smd rect
			(at 6.24967 9.6139 270)
			(size 0.3048 1.524)
			(layers "F.Cu" "F.Mask" "F.Paste")
			(net "Net_1009")
		)
		(pad "28" smd rect
			(at 6.75005 9.6139 270)
			(size 0.3048 1.524)
			(layers "F.Cu" "F.Mask" "F.Paste")
			(net "Net_1010")
		)
		(pad "29" smd rect
			(at 6.75005 -9.6139 270)
			(size 0.3048 1.524)
			(layers "F.Cu" "F.Mask" "F.Paste")
			(net "P1V8_E")
		)
		(pad "30" smd rect
			(at 6.24967 -9.6139 270)
			(size 0.3048 1.524)
			(layers "F.Cu" "F.Mask" "F.Paste")
			(net "Net_1008")
		)
		(pad "31" smd rect
			(at 5.75056 -9.6139 270)
			(size 0.3048 1.524)
			(layers "F.Cu" "F.Mask" "F.Paste")
			(net "EXP_XM_ADDR_1")
		)
		(pad "32" smd rect
			(at 5.25018 -9.6139 270)
			(size 0.3048 1.524)
			(layers "F.Cu" "F.Mask" "F.Paste")
			(net "EXP_XM_NOR_CS_N")
		)
		(pad "33" smd rect
			(at 4.7498 -9.6139 270)
			(size 0.3048 1.524)
			(layers "F.Cu" "F.Mask" "F.Paste")
			(net "GND")
		)
		(pad "34" smd rect
			(at 4.24942 -9.6139 270)
			(size 0.3048 1.524)
			(layers "F.Cu" "F.Mask" "F.Paste")
			(net "EXP_XM_OE_N")
		)
		(pad "35" smd rect
			(at 3.75031 -9.6139 270)
			(size 0.3048 1.524)
			(layers "F.Cu" "F.Mask" "F.Paste")
			(net "XM_DATA0")
		)
		(pad "36" smd rect
			(at 3.24993 -9.6139 270)
			(size 0.3048 1.524)
			(layers "F.Cu" "F.Mask" "F.Paste")
			(net "XM_DATA8")
		)
		(pad "37" smd rect
			(at 2.74955 -9.6139 270)
			(size 0.3048 1.524)
			(layers "F.Cu" "F.Mask" "F.Paste")
			(net "XM_DATA1")
		)
		(pad "38" smd rect
			(at 2.25044 -9.6139 270)
			(size 0.3048 1.524)
			(layers "F.Cu" "F.Mask" "F.Paste")
			(net "XM_DATA9")
		)
		(pad "39" smd rect
			(at 1.75006 -9.6139 270)
			(size 0.3048 1.524)
			(layers "F.Cu" "F.Mask" "F.Paste")
			(net "XM_DATA2")
		)
		(pad "40" smd rect
			(at 1.24968 -9.6139 270)
			(size 0.3048 1.524)
			(layers "F.Cu" "F.Mask" "F.Paste")
			(net "XM_DATA10")
		)
		(pad "41" smd rect
			(at 0.75057 -9.6139 270)
			(size 0.3048 1.524)
			(layers "F.Cu" "F.Mask" "F.Paste")
			(net "XM_DATA3")
		)
		(pad "42" smd rect
			(at 0.25019 -9.6139 270)
			(size 0.3048 1.524)
			(layers "F.Cu" "F.Mask" "F.Paste")
			(net "XM_DATA11")
		)
		(pad "43" smd rect
			(at -0.25019 -9.6139 270)
			(size 0.3048 1.524)
			(layers "F.Cu" "F.Mask" "F.Paste")
			(net "P3V3_STBY")
		)
		(pad "44" smd rect
			(at -0.75057 -9.6139 270)
			(size 0.3048 1.524)
			(layers "F.Cu" "F.Mask" "F.Paste")
			(net "XM_DATA4")
		)
		(pad "45" smd rect
			(at -1.24968 -9.6139 270)
			(size 0.3048 1.524)
			(layers "F.Cu" "F.Mask" "F.Paste")
			(net "XM_DATA12")
		)
		(pad "46" smd rect
			(at -1.75006 -9.6139 270)
			(size 0.3048 1.524)
			(layers "F.Cu" "F.Mask" "F.Paste")
			(net "XM_DATA5")
		)
		(pad "47" smd rect
			(at -2.25044 -9.6139 270)
			(size 0.3048 1.524)
			(layers "F.Cu" "F.Mask" "F.Paste")
			(net "XM_DATA13")
		)
		(pad "48" smd rect
			(at -2.74955 -9.6139 270)
			(size 0.3048 1.524)
			(layers "F.Cu" "F.Mask" "F.Paste")
			(net "XM_DATA6")
		)
		(pad "49" smd rect
			(at -3.24993 -9.6139 270)
			(size 0.3048 1.524)
			(layers "F.Cu" "F.Mask" "F.Paste")
			(net "XM_DATA14")
		)
		(pad "50" smd rect
			(at -3.75031 -9.6139 270)
			(size 0.3048 1.524)
			(layers "F.Cu" "F.Mask" "F.Paste")
			(net "XM_DATA7")
		)
		(pad "51" smd rect
			(at -4.24942 -9.6139 270)
			(size 0.3048 1.524)
			(layers "F.Cu" "F.Mask" "F.Paste")
			(net "XM_DATA15")
		)
		(pad "52" smd rect
			(at -4.7498 -9.6139 270)
			(size 0.3048 1.524)
			(layers "F.Cu" "F.Mask" "F.Paste")
			(net "GND")
		)
		(pad "53" smd rect
			(at -5.25018 -9.6139 270)
			(size 0.3048 1.524)
			(layers "F.Cu" "F.Mask" "F.Paste")
			(net "Net_261")
		)
		(pad "54" smd rect
			(at -5.75056 -9.6139 270)
			(size 0.3048 1.524)
			(layers "F.Cu" "F.Mask" "F.Paste")
			(net "EXP_XM_ADDR_17")
		)
		(pad "55" smd rect
			(at -6.24967 -9.6139 270)
			(size 0.3048 1.524)
			(layers "F.Cu" "F.Mask" "F.Paste")
			(net "Net_1011")
		)
		(pad "56" smd rect
			(at -6.75005 -9.6139 270)
			(size 0.3048 1.524)
			(layers "F.Cu" "F.Mask" "F.Paste")
			(net "Net_173")
		)
	)
	(footprint ""
		(layer "F.Cu")
		(at 97.917 -10.5156 180)
		(property "Reference" "SL8"
			(at 0 0 180)
			(layer "F.SilkS")
			(hide yes)
			(effects
				(font
					(size 1.27 1.27)
				)
			)
		)
		(property "Value" "MPZ2012S300AT-GP"
			(at 0 -4.2418 180)
			(unlocked yes)
			(layer "F.Fab")
			(hide yes)
			(effects
				(font
					(size 1.016 1.016)
					(thickness 0.1524)
				)
			)
		)
		(property "Device Type" "L805H42"
			(at 0 -5.7912 180)
			(unlocked yes)
			(layer "F.Fab")
			(hide yes)
			(effects
				(font
					(size 1.016 1.016)
					(thickness 0.1524)
				)
			)
		)
		(duplicate_pad_numbers_are_jumpers no)
		(fp_line
			(start 0.889 1.7018)
			(end -0.889 1.7018)
			(stroke
				(width 0.1524)
				(type default)
			)
			(layer "F.SilkS")
		)
		(fp_line
			(start 0.889 -1.7018)
			(end 0.889 1.7018)
			(stroke
				(width 0.1524)
				(type default)
			)
			(layer "F.SilkS")
		)
		(fp_line
			(start -0.889 1.7018)
			(end -0.889 -1.7018)
			(stroke
				(width 0.1524)
				(type default)
			)
			(layer "F.SilkS")
		)
		(fp_line
			(start -0.889 -1.7018)
			(end 0.889 -1.7018)
			(stroke
				(width 0.1524)
				(type default)
			)
			(layer "F.SilkS")
		)
		(fp_rect
			(start -0.9652 1.778)
			(end 0.9652 -1.778)
			(stroke
				(width 0)
				(type default)
			)
			(fill no)
			(layer "F.CrtYd")
		)
		(fp_rect
			(start -0.9652 1.778)
			(end 0.9652 -1.778)
			(stroke
				(width 0)
				(type default)
			)
			(fill no)
			(layer "F.Fab")
		)
		(pad "1" smd rect
			(at 0 -0.9652 180)
			(size 1.397 1.143)
			(layers "F.Cu" "F.Mask" "F.Paste")
			(net "P0V955_C")
		)
		(pad "2" smd rect
			(at 0 0.9652 180)
			(size 1.397 1.143)
			(layers "F.Cu" "F.Mask" "F.Paste")
			(net "PCE_AVDD")
		)
	)
	(footprint ""
		(layer "F.Cu")
		(at 273.041872 -190.927736)
		(property "Reference" "R300"
			(at 0 0 0)
			(layer "F.SilkS")
			(hide yes)
			(effects
				(font
					(size 1.27 1.27)
				)
			)
		)
		(property "Value" "0R2J-2-GP"
			(at 0.064008 -3.993896 0)
			(unlocked yes)
			(layer "F.Fab")
			(hide yes)
			(effects
				(font
					(size 1.016 1.016)
					(thickness 0.1524)
				)
			)
		)
		(property "Device Type" "R402H16"
			(at 0.064008 -5.517896 0)
			(unlocked yes)
			(layer "F.Fab")
			(hide yes)
			(effects
				(font
					(size 1.016 1.016)
					(thickness 0.1524)
				)
			)
		)
		(duplicate_pad_numbers_are_jumpers no)
		(fp_line
			(start -0.508 -0.9398)
			(end -0.508 0.9398)
			(stroke
				(width 0.1524)
				(type default)
			)
			(layer "F.SilkS")
		)
		(fp_line
			(start 0.508 -0.9398)
			(end -0.508 -0.9398)
			(stroke
				(width 0.1524)
				(type default)
			)
			(layer "F.SilkS")
		)
		(fp_rect
			(start -0.508 0.9398)
			(end 0.508 -0.9398)
			(stroke
				(width 0)
				(type default)
			)
			(fill no)
			(layer "F.CrtYd")
		)
		(fp_rect
			(start -0.508 0.9398)
			(end 0.508 -0.9398)
			(stroke
				(width 0)
				(type default)
			)
			(fill no)
			(layer "F.Fab")
		)
		(pad "1" smd custom
			(at 0 -0.4445)
			(size 0.1397 0.1397)
			(layers "F.Cu" "F.Mask" "F.Paste")
			(net "P1V8_STBY_PG")
			(options
				(clearance outline)
				(anchor circle)
			)
			(primitives
				(gr_poly
					(pts
						(arc
							(start -0.1778 -0.2794)
							(mid -0.249642 -0.249642)
							(end -0.2794 -0.1778)
						)
						(arc
							(start -0.2794 0.1778)
							(mid -0.249642 0.249642)
							(end -0.1778 0.2794)
						)
						(arc
							(start 0.1778 0.2794)
							(mid 0.249642 0.249642)
							(end 0.2794 0.1778)
						)
						(arc
							(start 0.2794 -0.1778)
							(mid 0.249642 -0.249642)
							(end 0.1778 -0.2794)
						)
					)
					(width 0)
					(fill yes)
				)
			)
		)
		(pad "2" smd custom
			(at 0 0.4445)
			(size 0.1397 0.1397)
			(layers "F.Cu" "F.Mask" "F.Paste")
			(net "BMC0_SRST_N")
			(options
				(clearance outline)
				(anchor circle)
			)
			(primitives
				(gr_poly
					(pts
						(arc
							(start -0.1778 -0.2794)
							(mid -0.249642 -0.249642)
							(end -0.2794 -0.1778)
						)
						(arc
							(start -0.2794 0.1778)
							(mid -0.249642 0.249642)
							(end -0.1778 0.2794)
						)
						(arc
							(start 0.1778 0.2794)
							(mid 0.249642 0.249642)
							(end 0.2794 0.1778)
						)
						(arc
							(start 0.2794 -0.1778)
							(mid 0.249642 -0.249642)
							(end 0.1778 -0.2794)
						)
					)
					(width 0)
					(fill yes)
				)
			)
		)
	)
	(footprint ""
		(layer "F.Cu")
		(at 57.15 -225.806)
		(property "Reference" "R2119"
			(at 0 0 0)
			(layer "F.SilkS")
			(hide yes)
			(effects
				(font
					(size 1.27 1.27)
				)
			)
		)
		(property "Value" "10R2F-L-GP"
			(at 0.064008 -3.993896 0)
			(unlocked yes)
			(layer "F.Fab")
			(hide yes)
			(effects
				(font
					(size 1.016 1.016)
					(thickness 0.1524)
				)
			)
		)
		(property "Device Type" "R402H14"
			(at 0.064008 -5.517896 0)
			(unlocked yes)
			(layer "F.Fab")
			(hide yes)
			(effects
				(font
					(size 1.016 1.016)
					(thickness 0.1524)
				)
			)
		)
		(duplicate_pad_numbers_are_jumpers no)
		(fp_line
			(start -0.508 -0.9398)
			(end -0.508 0.9398)
			(stroke
				(width 0.1524)
				(type default)
			)
			(layer "F.SilkS")
		)
		(fp_line
			(start 0.508 -0.9398)
			(end -0.508 -0.9398)
			(stroke
				(width 0.1524)
				(type default)
			)
			(layer "F.SilkS")
		)
		(fp_rect
			(start -0.508 0.9398)
			(end 0.508 -0.9398)
			(stroke
				(width 0)
				(type default)
			)
			(fill no)
			(layer "F.CrtYd")
		)
		(fp_rect
			(start -0.508 0.9398)
			(end 0.508 -0.9398)
			(stroke
				(width 0)
				(type default)
			)
			(fill no)
			(layer "F.Fab")
		)
		(pad "1" smd custom
			(at 0 -0.4445)
			(size 0.1397 0.1397)
			(layers "F.Cu" "F.Mask" "F.Paste")
			(net "MB0_CM_SENSE_R1_P")
			(options
				(clearance outline)
				(anchor circle)
			)
			(primitives
				(gr_poly
					(pts
						(arc
							(start -0.1778 -0.2794)
							(mid -0.249642 -0.249642)
							(end -0.2794 -0.1778)
						)
						(arc
							(start -0.2794 0.1778)
							(mid -0.249642 0.249642)
							(end -0.1778 0.2794)
						)
						(arc
							(start 0.1778 0.2794)
							(mid 0.249642 0.249642)
							(end 0.2794 0.1778)
						)
						(arc
							(start 0.2794 -0.1778)
							(mid 0.249642 -0.249642)
							(end 0.1778 -0.2794)
						)
					)
					(width 0)
					(fill yes)
				)
			)
		)
		(pad "2" smd custom
			(at 0 0.4445)
			(size 0.1397 0.1397)
			(layers "F.Cu" "F.Mask" "F.Paste")
			(net "MB0_CM_SENSE_P")
			(options
				(clearance outline)
				(anchor circle)
			)
			(primitives
				(gr_poly
					(pts
						(arc
							(start -0.1778 -0.2794)
							(mid -0.249642 -0.249642)
							(end -0.2794 -0.1778)
						)
						(arc
							(start -0.2794 0.1778)
							(mid -0.249642 0.249642)
							(end -0.1778 0.2794)
						)
						(arc
							(start 0.1778 0.2794)
							(mid 0.249642 0.249642)
							(end 0.2794 0.1778)
						)
						(arc
							(start 0.2794 -0.1778)
							(mid 0.249642 -0.249642)
							(end 0.1778 -0.2794)
						)
					)
					(width 0)
					(fill yes)
				)
			)
		)
	)
	(footprint ""
		(layer "F.Cu")
		(at 266.065 -173.99 90)
		(property "Reference" "R542"
			(at 0 0 90)
			(layer "F.SilkS")
			(hide yes)
			(effects
				(font
					(size 1.27 1.27)
				)
			)
		)
		(property "Value" "10KR2F-2-GP"
			(at 0.064008 -3.993896 90)
			(unlocked yes)
			(layer "F.Fab")
			(hide yes)
			(effects
				(font
					(size 1.016 1.016)
					(thickness 0.1524)
				)
			)
		)
		(property "Device Type" "R402H16"
			(at 0.064008 -5.517896 90)
			(unlocked yes)
			(layer "F.Fab")
			(hide yes)
			(effects
				(font
					(size 1.016 1.016)
					(thickness 0.1524)
				)
			)
		)
		(duplicate_pad_numbers_are_jumpers no)
		(fp_line
			(start 0.508 -0.9398)
			(end -0.508 -0.9398)
			(stroke
				(width 0.1524)
				(type default)
			)
			(layer "F.SilkS")
		)
		(fp_line
			(start -0.508 -0.9398)
			(end -0.508 0.9398)
			(stroke
				(width 0.1524)
				(type default)
			)
			(layer "F.SilkS")
		)
		(fp_rect
			(start -0.508 0.9398)
			(end 0.508 -0.9398)
			(stroke
				(width 0)
				(type default)
			)
			(fill no)
			(layer "F.CrtYd")
		)
		(fp_rect
			(start -0.508 0.9398)
			(end 0.508 -0.9398)
			(stroke
				(width 0)
				(type default)
			)
			(fill no)
			(layer "F.Fab")
		)
		(pad "1" smd custom
			(at 0 -0.4445 90)
			(size 0.1397 0.1397)
			(layers "F.Cu" "F.Mask" "F.Paste")
			(net "P3V3_STBY")
			(options
				(clearance outline)
				(anchor circle)
			)
			(primitives
				(gr_poly
					(pts
						(arc
							(start -0.1778 -0.2794)
							(mid -0.249642 -0.249642)
							(end -0.2794 -0.1778)
						)
						(arc
							(start -0.2794 0.1778)
							(mid -0.249642 0.249642)
							(end -0.1778 0.2794)
						)
						(arc
							(start 0.1778 0.2794)
							(mid 0.249642 0.249642)
							(end 0.2794 0.1778)
						)
						(arc
							(start 0.2794 -0.1778)
							(mid 0.249642 -0.249642)
							(end 0.1778 -0.2794)
						)
					)
					(width 0)
					(fill yes)
				)
			)
		)
		(pad "2" smd custom
			(at 0 0.4445 90)
			(size 0.1397 0.1397)
			(layers "F.Cu" "F.Mask" "F.Paste")
			(net "NIC_SMBUS_ALERT_N")
			(options
				(clearance outline)
				(anchor circle)
			)
			(primitives
				(gr_poly
					(pts
						(arc
							(start -0.1778 -0.2794)
							(mid -0.249642 -0.249642)
							(end -0.2794 -0.1778)
						)
						(arc
							(start -0.2794 0.1778)
							(mid -0.249642 0.249642)
							(end -0.1778 0.2794)
						)
						(arc
							(start 0.1778 0.2794)
							(mid 0.249642 0.249642)
							(end 0.2794 0.1778)
						)
						(arc
							(start 0.2794 -0.1778)
							(mid 0.249642 -0.249642)
							(end 0.1778 -0.2794)
						)
					)
					(width 0)
					(fill yes)
				)
			)
		)
	)
	(footprint ""
		(layer "F.Cu")
		(at 173.072044 -29.200856 90)
		(property "Reference" "R397"
			(at 0 0 90)
			(layer "F.SilkS")
			(hide yes)
			(effects
				(font
					(size 1.27 1.27)
				)
			)
		)
		(property "Value" "49D9R5F-2-GP"
			(at 0 -8.9535 90)
			(unlocked yes)
			(layer "F.Fab")
			(hide yes)
			(effects
				(font
					(size 1.27 1.016)
					(thickness 0.1524)
				)
			)
		)
		(property "Device Type" "R805H24"
			(at 0 -10.6299 90)
			(unlocked yes)
			(layer "F.Fab")
			(hide yes)
			(effects
				(font
					(size 1.27 1.016)
					(thickness 0.1524)
				)
			)
		)
		(duplicate_pad_numbers_are_jumpers no)
		(fp_line
			(start 0.889 -1.7018)
			(end -0.889 -1.7018)
			(stroke
				(width 0.1524)
				(type default)
			)
			(layer "F.SilkS")
		)
		(fp_line
			(start 0.889 -1.7018)
			(end 0.889 -0.381)
			(stroke
				(width 0.1524)
				(type default)
			)
			(layer "F.SilkS")
		)
		(fp_line
			(start -0.889 -1.7018)
			(end -0.889 0.2794)
			(stroke
				(width 0.1524)
				(type default)
			)
			(layer "F.SilkS")
		)
		(fp_line
			(start -0.889 0.0762)
			(end -0.889 1.7018)
			(stroke
				(width 0.1524)
				(type default)
			)
			(layer "F.SilkS")
		)
		(fp_line
			(start 0.889 1.7018)
			(end 0.889 -0.508)
			(stroke
				(width 0.1524)
				(type default)
			)
			(layer "F.SilkS")
		)
		(fp_line
			(start -0.889 1.7018)
			(end 0.889 1.7018)
			(stroke
				(width 0.1524)
				(type default)
			)
			(layer "F.SilkS")
		)
		(fp_poly
			(pts
				(xy 0.9652 -1.778) (xy 0.9652 1.778) (xy -0.9652 1.778) (xy -0.9652 -1.778)
			)
			(stroke
				(width 0)
				(type default)
			)
			(fill no)
			(layer "F.CrtYd")
		)
		(fp_rect
			(start -0.9652 1.778)
			(end 0.9652 -1.778)
			(stroke
				(width 0)
				(type default)
			)
			(fill no)
			(layer "F.Fab")
		)
		(pad "1" smd rect
			(at 0 -0.9652 90)
			(size 1.397 1.143)
			(layers "F.Cu" "F.Mask" "F.Paste")
			(net "P3V3_STBY")
		)
		(pad "2" smd rect
			(at 0 0.9652 90)
			(size 1.397 1.143)
			(layers "F.Cu" "F.Mask" "F.Paste")
			(net "BCM5221_TX_C_DN")
		)
	)
	(footprint ""
		(layer "F.Cu")
		(at 198.755 -95.885 -90)
		(property "Reference" "PC237"
			(at 0 0 270)
			(layer "F.SilkS")
			(hide yes)
			(effects
				(font
					(size 1.27 1.27)
				)
			)
		)
		(property "Value" "SC47U6D3V5MX-1-GP"
			(at -0.0762 -6.1214 270)
			(unlocked yes)
			(layer "F.Fab")
			(hide yes)
			(effects
				(font
					(size 1.016 1.016)
					(thickness 0.1524)
				)
			)
		)
		(property "Device Type" "C805H54"
			(at -0.0762 -8.1534 270)
			(unlocked yes)
			(layer "F.Fab")
			(hide yes)
			(effects
				(font
					(size 1.016 1.016)
					(thickness 0.1524)
				)
			)
		)
		(duplicate_pad_numbers_are_jumpers no)
		(fp_line
			(start 0.635 0)
			(end -0.635 0)
			(stroke
				(width 0.508)
				(type default)
			)
			(layer "F.SilkS")
		)
		(fp_rect
			(start -0.9652 1.778)
			(end 0.9652 -1.778)
			(stroke
				(width 0)
				(type default)
			)
			(fill no)
			(layer "F.CrtYd")
		)
		(fp_poly
			(pts
				(xy -0.9652 -1.778) (xy 0.9652 -1.778) (xy 0.9652 1.778) (xy -0.9652 1.778)
			)
			(stroke
				(width 0)
				(type default)
			)
			(fill no)
			(layer "F.Fab")
		)
		(pad "1" smd rect
			(at 0 -0.9652 270)
			(size 1.397 1.143)
			(layers "F.Cu" "F.Mask" "F.Paste")
			(net "P1V5_E")
		)
		(pad "2" smd rect
			(at 0 0.9652 270)
			(size 1.397 1.143)
			(layers "F.Cu" "F.Mask" "F.Paste")
			(net "GND")
		)
	)
	(footprint ""
		(layer "F.Cu")
		(at 87.26297 -112.014 180)
		(property "Reference" "SC1236"
			(at 0 0 180)
			(layer "F.SilkS")
			(hide yes)
			(effects
				(font
					(size 1.27 1.27)
				)
			)
		)
		(property "Value" "SCD1U6D3V1KX-GP"
			(at -2.8321 -1.7399 180)
			(unlocked yes)
			(layer "F.Fab")
			(hide yes)
			(effects
				(font
					(size 1.016 1.016)
					(thickness 0.1524)
				)
			)
		)
		(property "Device Type" "C0201H13"
			(at -2.8321 -3.2639 180)
			(unlocked yes)
			(layer "F.Fab")
			(hide yes)
			(effects
				(font
					(size 1.016 1.016)
					(thickness 0.1524)
				)
			)
		)
		(duplicate_pad_numbers_are_jumpers no)
		(fp_rect
			(start -0.2794 0.6477)
			(end 0.2794 -0.6477)
			(stroke
				(width 0)
				(type default)
			)
			(fill no)
			(layer "F.CrtYd")
		)
		(fp_rect
			(start -0.2794 0.6477)
			(end 0.2794 -0.6477)
			(stroke
				(width 0)
				(type default)
			)
			(fill no)
			(layer "F.Fab")
		)
		(pad "1" smd custom
			(at 0 -0.2794 180)
			(size 0.0762 0.0762)
			(layers "F.Cu" "F.Mask" "F.Paste")
			(net "P1V8_E")
			(options
				(clearance outline)
				(anchor circle)
			)
			(primitives
				(gr_poly
					(pts
						(arc
							(start 0.1524 -0.127)
							(mid 0.137521 -0.162921)
							(end 0.1016 -0.1778)
						)
						(arc
							(start -0.1016 -0.1778)
							(mid -0.137521 -0.162921)
							(end -0.1524 -0.127)
						)
						(arc
							(start -0.1524 0.127)
							(mid -0.137521 0.162921)
							(end -0.1016 0.1778)
						)
						(arc
							(start 0.1016 0.1778)
							(mid 0.137521 0.162921)
							(end 0.1524 0.127)
						)
					)
					(width 0)
					(fill yes)
				)
			)
		)
		(pad "2" smd custom
			(at 0 0.2794 180)
			(size 0.0762 0.0762)
			(layers "F.Cu" "F.Mask" "F.Paste")
			(net "GND")
			(options
				(clearance outline)
				(anchor circle)
			)
			(primitives
				(gr_poly
					(pts
						(arc
							(start 0.1524 -0.127)
							(mid 0.137521 -0.162921)
							(end 0.1016 -0.1778)
						)
						(arc
							(start -0.1016 -0.1778)
							(mid -0.137521 -0.162921)
							(end -0.1524 -0.127)
						)
						(arc
							(start -0.1524 0.127)
							(mid -0.137521 0.162921)
							(end -0.1016 0.1778)
						)
						(arc
							(start 0.1016 0.1778)
							(mid 0.137521 0.162921)
							(end 0.1524 0.127)
						)
					)
					(width 0)
					(fill yes)
				)
			)
		)
	)
	(footprint ""
		(layer "F.Cu")
		(at 112.973612 -204.978)
		(property "Reference" "SR877"
			(at 0 0 0)
			(layer "F.SilkS")
			(hide yes)
			(effects
				(font
					(size 1.27 1.27)
				)
			)
		)
		(property "Value" "0R2J-2-GP"
			(at 0.064008 -3.993896 0)
			(unlocked yes)
			(layer "F.Fab")
			(hide yes)
			(effects
				(font
					(size 1.016 1.016)
					(thickness 0.1524)
				)
			)
		)
		(property "Device Type" "R402H16"
			(at 0.064008 -5.517896 0)
			(unlocked yes)
			(layer "F.Fab")
			(hide yes)
			(effects
				(font
					(size 1.016 1.016)
					(thickness 0.1524)
				)
			)
		)
		(duplicate_pad_numbers_are_jumpers no)
		(fp_line
			(start -0.508 -0.9398)
			(end -0.508 0.9398)
			(stroke
				(width 0.1524)
				(type default)
			)
			(layer "F.SilkS")
		)
		(fp_line
			(start 0.508 -0.9398)
			(end -0.508 -0.9398)
			(stroke
				(width 0.1524)
				(type default)
			)
			(layer "F.SilkS")
		)
		(fp_rect
			(start -0.508 0.9398)
			(end 0.508 -0.9398)
			(stroke
				(width 0)
				(type default)
			)
			(fill no)
			(layer "F.CrtYd")
		)
		(fp_rect
			(start -0.508 0.9398)
			(end 0.508 -0.9398)
			(stroke
				(width 0)
				(type default)
			)
			(fill no)
			(layer "F.Fab")
		)
		(pad "1" smd custom
			(at 0 -0.4445)
			(size 0.1397 0.1397)
			(layers "F.Cu" "F.Mask" "F.Paste")
			(net "SAS_HDD_REDV_TX8_P")
			(options
				(clearance outline)
				(anchor circle)
			)
			(primitives
				(gr_poly
					(pts
						(arc
							(start -0.1778 -0.2794)
							(mid -0.249642 -0.249642)
							(end -0.2794 -0.1778)
						)
						(arc
							(start -0.2794 0.1778)
							(mid -0.249642 0.249642)
							(end -0.1778 0.2794)
						)
						(arc
							(start 0.1778 0.2794)
							(mid 0.249642 0.249642)
							(end 0.2794 0.1778)
						)
						(arc
							(start 0.2794 -0.1778)
							(mid 0.249642 -0.249642)
							(end 0.1778 -0.2794)
						)
					)
					(width 0)
					(fill yes)
				)
			)
		)
		(pad "2" smd custom
			(at 0 0.4445)
			(size 0.1397 0.1397)
			(layers "F.Cu" "F.Mask" "F.Paste")
			(net "SAS_HDD_REDV_SER_TX8_P")
			(options
				(clearance outline)
				(anchor circle)
			)
			(primitives
				(gr_poly
					(pts
						(arc
							(start -0.1778 -0.2794)
							(mid -0.249642 -0.249642)
							(end -0.2794 -0.1778)
						)
						(arc
							(start -0.2794 0.1778)
							(mid -0.249642 0.249642)
							(end -0.1778 0.2794)
						)
						(arc
							(start 0.1778 0.2794)
							(mid 0.249642 0.249642)
							(end 0.2794 0.1778)
						)
						(arc
							(start 0.2794 -0.1778)
							(mid 0.249642 -0.249642)
							(end 0.1778 -0.2794)
						)
					)
					(width 0)
					(fill yes)
				)
			)
		)
	)
	(footprint ""
		(layer "F.Cu")
		(at 20.651216 -181.91988)
		(property "Reference" "R649"
			(at 0 0 0)
			(layer "F.SilkS")
			(hide yes)
			(effects
				(font
					(size 1.27 1.27)
				)
			)
		)
		(property "Value" "4K7R2F-GP"
			(at 0.064008 -3.993896 0)
			(unlocked yes)
			(layer "F.Fab")
			(hide yes)
			(effects
				(font
					(size 1.016 1.016)
					(thickness 0.1524)
				)
			)
		)
		(property "Device Type" "R402H16"
			(at 0.064008 -5.517896 0)
			(unlocked yes)
			(layer "F.Fab")
			(hide yes)
			(effects
				(font
					(size 1.016 1.016)
					(thickness 0.1524)
				)
			)
		)
		(duplicate_pad_numbers_are_jumpers no)
		(fp_line
			(start -0.508 -0.9398)
			(end -0.508 0.9398)
			(stroke
				(width 0.1524)
				(type default)
			)
			(layer "F.SilkS")
		)
		(fp_line
			(start 0.508 -0.9398)
			(end -0.508 -0.9398)
			(stroke
				(width 0.1524)
				(type default)
			)
			(layer "F.SilkS")
		)
		(fp_rect
			(start -0.508 0.9398)
			(end 0.508 -0.9398)
			(stroke
				(width 0)
				(type default)
			)
			(fill no)
			(layer "F.CrtYd")
		)
		(fp_rect
			(start -0.508 0.9398)
			(end 0.508 -0.9398)
			(stroke
				(width 0)
				(type default)
			)
			(fill no)
			(layer "F.Fab")
		)
		(pad "1" smd custom
			(at 0 -0.4445)
			(size 0.1397 0.1397)
			(layers "F.Cu" "F.Mask" "F.Paste")
			(net "IO_EXP_HDD_PRE_A3")
			(options
				(clearance outline)
				(anchor circle)
			)
			(primitives
				(gr_poly
					(pts
						(arc
							(start -0.1778 -0.2794)
							(mid -0.249642 -0.249642)
							(end -0.2794 -0.1778)
						)
						(arc
							(start -0.2794 0.1778)
							(mid -0.249642 0.249642)
							(end -0.1778 0.2794)
						)
						(arc
							(start 0.1778 0.2794)
							(mid 0.249642 0.249642)
							(end 0.2794 0.1778)
						)
						(arc
							(start 0.2794 -0.1778)
							(mid 0.249642 -0.249642)
							(end 0.1778 -0.2794)
						)
					)
					(width 0)
					(fill yes)
				)
			)
		)
		(pad "2" smd custom
			(at 0 0.4445)
			(size 0.1397 0.1397)
			(layers "F.Cu" "F.Mask" "F.Paste")
			(net "GND")
			(options
				(clearance outline)
				(anchor circle)
			)
			(primitives
				(gr_poly
					(pts
						(arc
							(start -0.1778 -0.2794)
							(mid -0.249642 -0.249642)
							(end -0.2794 -0.1778)
						)
						(arc
							(start -0.2794 0.1778)
							(mid -0.249642 0.249642)
							(end -0.1778 0.2794)
						)
						(arc
							(start 0.1778 0.2794)
							(mid 0.249642 0.249642)
							(end 0.2794 0.1778)
						)
						(arc
							(start 0.2794 -0.1778)
							(mid 0.249642 -0.249642)
							(end 0.1778 -0.2794)
						)
					)
					(width 0)
					(fill yes)
				)
			)
		)
	)
	(footprint ""
		(layer "F.Cu")
		(at 47.498 -218.694 -90)
		(property "Reference" "C7277"
			(at 0 0 270)
			(layer "F.SilkS")
			(hide yes)
			(effects
				(font
					(size 1.27 1.27)
				)
			)
		)
		(property "Value" "SC1U16V3KX-5GP"
			(at 0 -2.8194 270)
			(unlocked yes)
			(layer "F.Fab")
			(hide yes)
			(effects
				(font
					(size 1.016 1.016)
					(thickness 0.1524)
				)
			)
		)
		(property "Device Type" "C603H36"
			(at 0 -4.3434 270)
			(unlocked yes)
			(layer "F.Fab")
			(hide yes)
			(effects
				(font
					(size 1.016 1.016)
					(thickness 0.1524)
				)
			)
		)
		(duplicate_pad_numbers_are_jumpers no)
		(fp_line
			(start 0.508 0)
			(end -0.508 0)
			(stroke
				(width 0.2032)
				(type default)
			)
			(layer "F.SilkS")
		)
		(fp_rect
			(start -0.5842 1.3335)
			(end 0.5842 -1.3335)
			(stroke
				(width 0)
				(type default)
			)
			(fill no)
			(layer "F.CrtYd")
		)
		(fp_rect
			(start -0.5842 1.3335)
			(end 0.5842 -1.3335)
			(stroke
				(width 0)
				(type default)
			)
			(fill no)
			(layer "F.Fab")
		)
		(pad "1" smd custom
			(at 0 -0.762 270)
			(size 0.2159 0.2159)
			(layers "F.Cu" "F.Mask" "F.Paste")
			(net "MB0_VCAP_R")
			(options
				(clearance outline)
				(anchor circle)
			)
			(primitives
				(gr_poly
					(pts
						(arc
							(start -0.3302 -0.4318)
							(mid -0.402042 -0.402042)
							(end -0.4318 -0.3302)
						)
						(arc
							(start -0.4318 0.3302)
							(mid -0.402042 0.402042)
							(end -0.3302 0.4318)
						)
						(arc
							(start 0.3302 0.4318)
							(mid 0.402042 0.402042)
							(end 0.4318 0.3302)
						)
						(arc
							(start 0.4318 -0.3302)
							(mid 0.402042 -0.402042)
							(end 0.3302 -0.4318)
						)
					)
					(width 0)
					(fill yes)
				)
			)
		)
		(pad "2" smd custom
			(at 0 0.762 270)
			(size 0.2159 0.2159)
			(layers "F.Cu" "F.Mask" "F.Paste")
			(net "AGND_CURRENT_MON")
			(options
				(clearance outline)
				(anchor circle)
			)
			(primitives
				(gr_poly
					(pts
						(arc
							(start -0.3302 -0.4318)
							(mid -0.402042 -0.402042)
							(end -0.4318 -0.3302)
						)
						(arc
							(start -0.4318 0.3302)
							(mid -0.402042 0.402042)
							(end -0.3302 0.4318)
						)
						(arc
							(start 0.3302 0.4318)
							(mid 0.402042 0.402042)
							(end 0.4318 0.3302)
						)
						(arc
							(start 0.4318 -0.3302)
							(mid 0.402042 -0.402042)
							(end 0.3302 -0.4318)
						)
					)
					(width 0)
					(fill yes)
				)
			)
		)
	)
	(footprint ""
		(layer "F.Cu")
		(at 274.193 -165.608 90)
		(property "Reference" "R330"
			(at 0 0 90)
			(layer "F.SilkS")
			(hide yes)
			(effects
				(font
					(size 1.27 1.27)
				)
			)
		)
		(property "Value" "0R2J-2-GP"
			(at 0.064008 -3.993896 90)
			(unlocked yes)
			(layer "F.Fab")
			(hide yes)
			(effects
				(font
					(size 1.016 1.016)
					(thickness 0.1524)
				)
			)
		)
		(property "Device Type" "R402H16"
			(at 0.064008 -5.517896 90)
			(unlocked yes)
			(layer "F.Fab")
			(hide yes)
			(effects
				(font
					(size 1.016 1.016)
					(thickness 0.1524)
				)
			)
		)
		(duplicate_pad_numbers_are_jumpers no)
		(fp_line
			(start 0.508 -0.9398)
			(end -0.508 -0.9398)
			(stroke
				(width 0.1524)
				(type default)
			)
			(layer "F.SilkS")
		)
		(fp_line
			(start -0.508 -0.9398)
			(end -0.508 0.9398)
			(stroke
				(width 0.1524)
				(type default)
			)
			(layer "F.SilkS")
		)
		(fp_rect
			(start -0.508 0.9398)
			(end 0.508 -0.9398)
			(stroke
				(width 0)
				(type default)
			)
			(fill no)
			(layer "F.CrtYd")
		)
		(fp_rect
			(start -0.508 0.9398)
			(end 0.508 -0.9398)
			(stroke
				(width 0)
				(type default)
			)
			(fill no)
			(layer "F.Fab")
		)
		(pad "1" smd custom
			(at 0 -0.4445 90)
			(size 0.1397 0.1397)
			(layers "F.Cu" "F.Mask" "F.Paste")
			(net "BMC_RSTBTN_N")
			(options
				(clearance outline)
				(anchor circle)
			)
			(primitives
				(gr_poly
					(pts
						(arc
							(start -0.1778 -0.2794)
							(mid -0.249642 -0.249642)
							(end -0.2794 -0.1778)
						)
						(arc
							(start -0.2794 0.1778)
							(mid -0.249642 0.249642)
							(end -0.1778 0.2794)
						)
						(arc
							(start 0.1778 0.2794)
							(mid 0.249642 0.249642)
							(end 0.2794 0.1778)
						)
						(arc
							(start 0.2794 -0.1778)
							(mid 0.249642 -0.249642)
							(end 0.1778 -0.2794)
						)
					)
					(width 0)
					(fill yes)
				)
			)
		)
		(pad "2" smd custom
			(at 0 0.4445 90)
			(size 0.1397 0.1397)
			(layers "F.Cu" "F.Mask" "F.Paste")
			(net "BMC_RSTBTN_N_R")
			(options
				(clearance outline)
				(anchor circle)
			)
			(primitives
				(gr_poly
					(pts
						(arc
							(start -0.1778 -0.2794)
							(mid -0.249642 -0.249642)
							(end -0.2794 -0.1778)
						)
						(arc
							(start -0.2794 0.1778)
							(mid -0.249642 0.249642)
							(end -0.1778 0.2794)
						)
						(arc
							(start 0.1778 0.2794)
							(mid 0.249642 0.249642)
							(end 0.2794 0.1778)
						)
						(arc
							(start 0.2794 -0.1778)
							(mid 0.249642 -0.249642)
							(end 0.1778 -0.2794)
						)
					)
					(width 0)
					(fill yes)
				)
			)
		)
	)
	(footprint ""
		(layer "F.Cu")
		(at 268.351 -220.091 90)
		(property "Reference" "PC95"
			(at 0 0 90)
			(layer "F.SilkS")
			(hide yes)
			(effects
				(font
					(size 1.27 1.27)
				)
			)
		)
		(property "Value" "SC10U6D3V5KX-1GP"
			(at -0.0762 -6.1214 90)
			(unlocked yes)
			(layer "F.Fab")
			(hide yes)
			(effects
				(font
					(size 1.016 1.016)
					(thickness 0.1524)
				)
			)
		)
		(property "Device Type" "C805H54"
			(at -0.0762 -8.1534 90)
			(unlocked yes)
			(layer "F.Fab")
			(hide yes)
			(effects
				(font
					(size 1.016 1.016)
					(thickness 0.1524)
				)
			)
		)
		(duplicate_pad_numbers_are_jumpers no)
		(fp_line
			(start 0.635 0)
			(end -0.635 0)
			(stroke
				(width 0.508)
				(type default)
			)
			(layer "F.SilkS")
		)
		(fp_rect
			(start -0.9652 1.778)
			(end 0.9652 -1.778)
			(stroke
				(width 0)
				(type default)
			)
			(fill no)
			(layer "F.CrtYd")
		)
		(fp_poly
			(pts
				(xy -0.9652 -1.778) (xy 0.9652 -1.778) (xy 0.9652 1.778) (xy -0.9652 1.778)
			)
			(stroke
				(width 0)
				(type default)
			)
			(fill no)
			(layer "F.Fab")
		)
		(pad "1" smd rect
			(at 0 -0.9652 90)
			(size 1.397 1.143)
			(layers "F.Cu" "F.Mask" "F.Paste")
			(net "TPS74801_1V26_STBY_OUT")
		)
		(pad "2" smd rect
			(at 0 0.9652 90)
			(size 1.397 1.143)
			(layers "F.Cu" "F.Mask" "F.Paste")
			(net "GND")
		)
	)
	(footprint ""
		(layer "F.Cu")
		(at 49.403 -219.202)
		(property "Reference" "R2174"
			(at 0 0 0)
			(layer "F.SilkS")
			(hide yes)
			(effects
				(font
					(size 1.27 1.27)
				)
			)
		)
		(property "Value" "100KR2J-4-GP"
			(at -1.1811 -1.1303 0)
			(unlocked yes)
			(layer "F.Fab")
			(hide yes)
			(effects
				(font
					(size 1.016 1.016)
					(thickness 0.1524)
				)
			)
		)
		(property "Device Type" "R402H15"
			(at -1.1811 -2.6543 0)
			(unlocked yes)
			(layer "F.Fab")
			(hide yes)
			(effects
				(font
					(size 1.016 1.016)
					(thickness 0.1524)
				)
			)
		)
		(duplicate_pad_numbers_are_jumpers no)
		(fp_line
			(start -0.508 -0.9398)
			(end -0.508 0.9398)
			(stroke
				(width 0.1524)
				(type default)
			)
			(layer "F.SilkS")
		)
		(fp_line
			(start 0.508 -0.9398)
			(end -0.508 -0.9398)
			(stroke
				(width 0.1524)
				(type default)
			)
			(layer "F.SilkS")
		)
		(fp_rect
			(start -0.508 0.9398)
			(end 0.508 -0.9398)
			(stroke
				(width 0)
				(type default)
			)
			(fill no)
			(layer "F.CrtYd")
		)
		(fp_rect
			(start -0.508 0.9398)
			(end 0.508 -0.9398)
			(stroke
				(width 0)
				(type default)
			)
			(fill no)
			(layer "F.Fab")
		)
		(pad "1" smd custom
			(at 0 -0.4445)
			(size 0.1397 0.1397)
			(layers "F.Cu" "F.Mask" "F.Paste")
			(net "MB0_VCAP_R")
			(options
				(clearance outline)
				(anchor circle)
			)
			(primitives
				(gr_poly
					(pts
						(arc
							(start -0.1778 -0.2794)
							(mid -0.249642 -0.249642)
							(end -0.2794 -0.1778)
						)
						(arc
							(start -0.2794 0.1778)
							(mid -0.249642 0.249642)
							(end -0.1778 0.2794)
						)
						(arc
							(start 0.1778 0.2794)
							(mid 0.249642 0.249642)
							(end 0.2794 0.1778)
						)
						(arc
							(start 0.2794 -0.1778)
							(mid 0.249642 -0.249642)
							(end 0.1778 -0.2794)
						)
					)
					(width 0)
					(fill yes)
				)
			)
		)
		(pad "2" smd custom
			(at 0 0.4445)
			(size 0.1397 0.1397)
			(layers "F.Cu" "F.Mask" "F.Paste")
			(net "MB0_ISTART_R")
			(options
				(clearance outline)
				(anchor circle)
			)
			(primitives
				(gr_poly
					(pts
						(arc
							(start -0.1778 -0.2794)
							(mid -0.249642 -0.249642)
							(end -0.2794 -0.1778)
						)
						(arc
							(start -0.2794 0.1778)
							(mid -0.249642 0.249642)
							(end -0.1778 0.2794)
						)
						(arc
							(start 0.1778 0.2794)
							(mid 0.249642 0.249642)
							(end 0.2794 0.1778)
						)
						(arc
							(start 0.2794 -0.1778)
							(mid 0.249642 -0.249642)
							(end 0.1778 -0.2794)
						)
					)
					(width 0)
					(fill yes)
				)
			)
		)
	)
	(footprint ""
		(layer "F.Cu")
		(at 318.893952 -57.404 -90)
		(property "Reference" "R211"
			(at 0 0 270)
			(layer "F.SilkS")
			(hide yes)
			(effects
				(font
					(size 1.27 1.27)
				)
			)
		)
		(property "Value" "0R2J-2-GP"
			(at 0.064008 -3.993896 270)
			(unlocked yes)
			(layer "F.Fab")
			(hide yes)
			(effects
				(font
					(size 1.016 1.016)
					(thickness 0.1524)
				)
			)
		)
		(property "Device Type" "R402H16"
			(at 0.064008 -5.517896 270)
			(unlocked yes)
			(layer "F.Fab")
			(hide yes)
			(effects
				(font
					(size 1.016 1.016)
					(thickness 0.1524)
				)
			)
		)
		(duplicate_pad_numbers_are_jumpers no)
		(fp_line
			(start -0.508 -0.9398)
			(end -0.508 0.9398)
			(stroke
				(width 0.1524)
				(type default)
			)
			(layer "F.SilkS")
		)
		(fp_line
			(start 0.508 -0.9398)
			(end -0.508 -0.9398)
			(stroke
				(width 0.1524)
				(type default)
			)
			(layer "F.SilkS")
		)
		(fp_rect
			(start -0.508 0.9398)
			(end 0.508 -0.9398)
			(stroke
				(width 0)
				(type default)
			)
			(fill no)
			(layer "F.CrtYd")
		)
		(fp_rect
			(start -0.508 0.9398)
			(end 0.508 -0.9398)
			(stroke
				(width 0)
				(type default)
			)
			(fill no)
			(layer "F.Fab")
		)
		(pad "1" smd custom
			(at 0 -0.4445 270)
			(size 0.1397 0.1397)
			(layers "F.Cu" "F.Mask" "F.Paste")
			(net "NCSI_10G_RCLK")
			(options
				(clearance outline)
				(anchor circle)
			)
			(primitives
				(gr_poly
					(pts
						(arc
							(start -0.1778 -0.2794)
							(mid -0.249642 -0.249642)
							(end -0.2794 -0.1778)
						)
						(arc
							(start -0.2794 0.1778)
							(mid -0.249642 0.249642)
							(end -0.1778 0.2794)
						)
						(arc
							(start 0.1778 0.2794)
							(mid 0.249642 0.249642)
							(end 0.2794 0.1778)
						)
						(arc
							(start 0.2794 -0.1778)
							(mid 0.249642 -0.249642)
							(end 0.1778 -0.2794)
						)
					)
					(width 0)
					(fill yes)
				)
			)
		)
		(pad "2" smd custom
			(at 0 0.4445 270)
			(size 0.1397 0.1397)
			(layers "F.Cu" "F.Mask" "F.Paste")
			(net "NCSI_10G_RCLK_R")
			(options
				(clearance outline)
				(anchor circle)
			)
			(primitives
				(gr_poly
					(pts
						(arc
							(start -0.1778 -0.2794)
							(mid -0.249642 -0.249642)
							(end -0.2794 -0.1778)
						)
						(arc
							(start -0.2794 0.1778)
							(mid -0.249642 0.249642)
							(end -0.1778 0.2794)
						)
						(arc
							(start 0.1778 0.2794)
							(mid 0.249642 0.249642)
							(end 0.2794 0.1778)
						)
						(arc
							(start 0.2794 -0.1778)
							(mid 0.249642 -0.249642)
							(end 0.1778 -0.2794)
						)
					)
					(width 0)
					(fill yes)
				)
			)
		)
	)
	(footprint ""
		(layer "F.Cu")
		(at 121.990612 -222.885)
		(property "Reference" "SR869"
			(at 0 0 0)
			(layer "F.SilkS")
			(hide yes)
			(effects
				(font
					(size 1.27 1.27)
				)
			)
		)
		(property "Value" "0R2J-2-GP"
			(at 0.064008 -3.993896 0)
			(unlocked yes)
			(layer "F.Fab")
			(hide yes)
			(effects
				(font
					(size 1.016 1.016)
					(thickness 0.1524)
				)
			)
		)
		(property "Device Type" "R402H16"
			(at 0.064008 -5.517896 0)
			(unlocked yes)
			(layer "F.Fab")
			(hide yes)
			(effects
				(font
					(size 1.016 1.016)
					(thickness 0.1524)
				)
			)
		)
		(duplicate_pad_numbers_are_jumpers no)
		(fp_line
			(start -0.508 -0.9398)
			(end -0.508 0.9398)
			(stroke
				(width 0.1524)
				(type default)
			)
			(layer "F.SilkS")
		)
		(fp_line
			(start 0.508 -0.9398)
			(end -0.508 -0.9398)
			(stroke
				(width 0.1524)
				(type default)
			)
			(layer "F.SilkS")
		)
		(fp_rect
			(start -0.508 0.9398)
			(end 0.508 -0.9398)
			(stroke
				(width 0)
				(type default)
			)
			(fill no)
			(layer "F.CrtYd")
		)
		(fp_rect
			(start -0.508 0.9398)
			(end 0.508 -0.9398)
			(stroke
				(width 0)
				(type default)
			)
			(fill no)
			(layer "F.Fab")
		)
		(pad "1" smd custom
			(at 0 -0.4445)
			(size 0.1397 0.1397)
			(layers "F.Cu" "F.Mask" "F.Paste")
			(net "SAS_HDD_CONN_SER_TX7_P")
			(options
				(clearance outline)
				(anchor circle)
			)
			(primitives
				(gr_poly
					(pts
						(arc
							(start -0.1778 -0.2794)
							(mid -0.249642 -0.249642)
							(end -0.2794 -0.1778)
						)
						(arc
							(start -0.2794 0.1778)
							(mid -0.249642 0.249642)
							(end -0.1778 0.2794)
						)
						(arc
							(start 0.1778 0.2794)
							(mid 0.249642 0.249642)
							(end 0.2794 0.1778)
						)
						(arc
							(start 0.2794 -0.1778)
							(mid 0.249642 -0.249642)
							(end 0.1778 -0.2794)
						)
					)
					(width 0)
					(fill yes)
				)
			)
		)
		(pad "2" smd custom
			(at 0 0.4445)
			(size 0.1397 0.1397)
			(layers "F.Cu" "F.Mask" "F.Paste")
			(net "SAS_HDD_CONN_TX7_P")
			(options
				(clearance outline)
				(anchor circle)
			)
			(primitives
				(gr_poly
					(pts
						(arc
							(start -0.1778 -0.2794)
							(mid -0.249642 -0.249642)
							(end -0.2794 -0.1778)
						)
						(arc
							(start -0.2794 0.1778)
							(mid -0.249642 0.249642)
							(end -0.1778 0.2794)
						)
						(arc
							(start 0.1778 0.2794)
							(mid 0.249642 0.249642)
							(end 0.2794 0.1778)
						)
						(arc
							(start 0.2794 -0.1778)
							(mid 0.249642 -0.249642)
							(end 0.1778 -0.2794)
						)
					)
					(width 0)
					(fill yes)
				)
			)
		)
	)
	(footprint ""
		(layer "F.Cu")
		(at 178.997864 -38.172136)
		(property "Reference" "R378"
			(at 0 0 0)
			(layer "F.SilkS")
			(hide yes)
			(effects
				(font
					(size 1.27 1.27)
				)
			)
		)
		(property "Value" "150R2F-1-GP"
			(at 0.064008 -3.993896 0)
			(unlocked yes)
			(layer "F.Fab")
			(hide yes)
			(effects
				(font
					(size 1.016 1.016)
					(thickness 0.1524)
				)
			)
		)
		(property "Device Type" "R402H16"
			(at 0.064008 -5.517896 0)
			(unlocked yes)
			(layer "F.Fab")
			(hide yes)
			(effects
				(font
					(size 1.016 1.016)
					(thickness 0.1524)
				)
			)
		)
		(duplicate_pad_numbers_are_jumpers no)
		(fp_line
			(start -0.508 -0.9398)
			(end -0.508 0.9398)
			(stroke
				(width 0.1524)
				(type default)
			)
			(layer "F.SilkS")
		)
		(fp_line
			(start 0.508 -0.9398)
			(end -0.508 -0.9398)
			(stroke
				(width 0.1524)
				(type default)
			)
			(layer "F.SilkS")
		)
		(fp_rect
			(start -0.508 0.9398)
			(end 0.508 -0.9398)
			(stroke
				(width 0)
				(type default)
			)
			(fill no)
			(layer "F.CrtYd")
		)
		(fp_rect
			(start -0.508 0.9398)
			(end 0.508 -0.9398)
			(stroke
				(width 0)
				(type default)
			)
			(fill no)
			(layer "F.Fab")
		)
		(pad "1" smd custom
			(at 0 -0.4445)
			(size 0.1397 0.1397)
			(layers "F.Cu" "F.Mask" "F.Paste")
			(net "GND")
			(options
				(clearance outline)
				(anchor circle)
			)
			(primitives
				(gr_poly
					(pts
						(arc
							(start -0.1778 -0.2794)
							(mid -0.249642 -0.249642)
							(end -0.2794 -0.1778)
						)
						(arc
							(start -0.2794 0.1778)
							(mid -0.249642 0.249642)
							(end -0.1778 0.2794)
						)
						(arc
							(start 0.1778 0.2794)
							(mid 0.249642 0.249642)
							(end 0.2794 0.1778)
						)
						(arc
							(start 0.2794 -0.1778)
							(mid 0.249642 -0.249642)
							(end 0.1778 -0.2794)
						)
					)
					(width 0)
					(fill yes)
				)
			)
		)
		(pad "2" smd custom
			(at 0 0.4445)
			(size 0.1397 0.1397)
			(layers "F.Cu" "F.Mask" "F.Paste")
			(net "PHY_TEST_EN")
			(options
				(clearance outline)
				(anchor circle)
			)
			(primitives
				(gr_poly
					(pts
						(arc
							(start -0.1778 -0.2794)
							(mid -0.249642 -0.249642)
							(end -0.2794 -0.1778)
						)
						(arc
							(start -0.2794 0.1778)
							(mid -0.249642 0.249642)
							(end -0.1778 0.2794)
						)
						(arc
							(start 0.1778 0.2794)
							(mid 0.249642 0.249642)
							(end 0.2794 0.1778)
						)
						(arc
							(start 0.2794 -0.1778)
							(mid 0.249642 -0.249642)
							(end 0.1778 -0.2794)
						)
					)
					(width 0)
					(fill yes)
				)
			)
		)
	)
	(footprint ""
		(layer "F.Cu")
		(at 95.89897 -85.09 90)
		(property "Reference" "SR808"
			(at 0 0 90)
			(layer "F.SilkS")
			(hide yes)
			(effects
				(font
					(size 1.27 1.27)
				)
			)
		)
		(property "Value" "4K75R2F-1-GP"
			(at 0.064008 -3.993896 90)
			(unlocked yes)
			(layer "F.Fab")
			(hide yes)
			(effects
				(font
					(size 1.016 1.016)
					(thickness 0.1524)
				)
			)
		)
		(property "Device Type" "R402H16"
			(at 0.064008 -5.517896 90)
			(unlocked yes)
			(layer "F.Fab")
			(hide yes)
			(effects
				(font
					(size 1.016 1.016)
					(thickness 0.1524)
				)
			)
		)
		(duplicate_pad_numbers_are_jumpers no)
		(fp_line
			(start 0.508 -0.9398)
			(end -0.508 -0.9398)
			(stroke
				(width 0.1524)
				(type default)
			)
			(layer "F.SilkS")
		)
		(fp_line
			(start -0.508 -0.9398)
			(end -0.508 0.9398)
			(stroke
				(width 0.1524)
				(type default)
			)
			(layer "F.SilkS")
		)
		(fp_rect
			(start -0.508 0.9398)
			(end 0.508 -0.9398)
			(stroke
				(width 0)
				(type default)
			)
			(fill no)
			(layer "F.CrtYd")
		)
		(fp_rect
			(start -0.508 0.9398)
			(end 0.508 -0.9398)
			(stroke
				(width 0)
				(type default)
			)
			(fill no)
			(layer "F.Fab")
		)
		(pad "1" smd custom
			(at 0 -0.4445 90)
			(size 0.1397 0.1397)
			(layers "F.Cu" "F.Mask" "F.Paste")
			(net "P1V8_E")
			(options
				(clearance outline)
				(anchor circle)
			)
			(primitives
				(gr_poly
					(pts
						(arc
							(start -0.1778 -0.2794)
							(mid -0.249642 -0.249642)
							(end -0.2794 -0.1778)
						)
						(arc
							(start -0.2794 0.1778)
							(mid -0.249642 0.249642)
							(end -0.1778 0.2794)
						)
						(arc
							(start 0.1778 0.2794)
							(mid 0.249642 0.249642)
							(end 0.2794 0.1778)
						)
						(arc
							(start 0.2794 -0.1778)
							(mid 0.249642 -0.249642)
							(end 0.1778 -0.2794)
						)
					)
					(width 0)
					(fill yes)
				)
			)
		)
		(pad "2" smd custom
			(at 0 0.4445 90)
			(size 0.1397 0.1397)
			(layers "F.Cu" "F.Mask" "F.Paste")
			(net "LSI_T_N")
			(options
				(clearance outline)
				(anchor circle)
			)
			(primitives
				(gr_poly
					(pts
						(arc
							(start -0.1778 -0.2794)
							(mid -0.249642 -0.249642)
							(end -0.2794 -0.1778)
						)
						(arc
							(start -0.2794 0.1778)
							(mid -0.249642 0.249642)
							(end -0.1778 0.2794)
						)
						(arc
							(start 0.1778 0.2794)
							(mid 0.249642 0.249642)
							(end 0.2794 0.1778)
						)
						(arc
							(start 0.2794 -0.1778)
							(mid 0.249642 -0.249642)
							(end 0.1778 -0.2794)
						)
					)
					(width 0)
					(fill yes)
				)
			)
		)
	)
	(footprint ""
		(layer "F.Cu")
		(at 90.683842 -123.642882 90)
		(property "Reference" "SC1282"
			(at 0 0 90)
			(layer "F.SilkS")
			(hide yes)
			(effects
				(font
					(size 1.27 1.27)
				)
			)
		)
		(property "Value" "SCD1U16V2KX-3GP"
			(at 1.1811 -2.7051 90)
			(unlocked yes)
			(layer "F.Fab")
			(hide yes)
			(effects
				(font
					(size 1.016 1.016)
					(thickness 0.1524)
				)
			)
		)
		(property "Device Type" "C402H22"
			(at 1.1811 -4.2291 90)
			(unlocked yes)
			(layer "F.Fab")
			(hide yes)
			(effects
				(font
					(size 1.016 1.016)
					(thickness 0.1524)
				)
			)
		)
		(duplicate_pad_numbers_are_jumpers no)
		(fp_rect
			(start -0.4318 0.9525)
			(end 0.4318 -0.9525)
			(stroke
				(width 0)
				(type default)
			)
			(fill no)
			(layer "F.CrtYd")
		)
		(fp_rect
			(start -0.4318 0.9525)
			(end 0.4318 -0.9525)
			(stroke
				(width 0)
				(type default)
			)
			(fill no)
			(layer "F.Fab")
		)
		(pad "1" smd custom
			(at 0 -0.4445 90)
			(size 0.1524 0.1524)
			(layers "F.Cu" "F.Mask" "F.Paste")
			(net "EXP_I2C_VREF_0")
			(options
				(clearance outline)
				(anchor circle)
			)
			(primitives
				(gr_poly
					(pts
						(arc
							(start 0.3048 -0.2032)
							(mid 0.275042 -0.275042)
							(end 0.2032 -0.3048)
						)
						(arc
							(start -0.2032 -0.3048)
							(mid -0.275042 -0.275042)
							(end -0.3048 -0.2032)
						)
						(arc
							(start -0.3048 0.2032)
							(mid -0.275042 0.275042)
							(end -0.2032 0.3048)
						)
						(arc
							(start 0.2032 0.3048)
							(mid 0.275042 0.275042)
							(end 0.3048 0.2032)
						)
					)
					(width 0)
					(fill yes)
				)
			)
		)
		(pad "2" smd custom
			(at 0 0.4445 90)
			(size 0.1524 0.1524)
			(layers "F.Cu" "F.Mask" "F.Paste")
			(net "GND")
			(options
				(clearance outline)
				(anchor circle)
			)
			(primitives
				(gr_poly
					(pts
						(arc
							(start 0.3048 -0.2032)
							(mid 0.275042 -0.275042)
							(end 0.2032 -0.3048)
						)
						(arc
							(start -0.2032 -0.3048)
							(mid -0.275042 -0.275042)
							(end -0.3048 -0.2032)
						)
						(arc
							(start -0.3048 0.2032)
							(mid -0.275042 0.275042)
							(end -0.2032 0.3048)
						)
						(arc
							(start 0.2032 0.3048)
							(mid 0.275042 0.275042)
							(end 0.3048 0.2032)
						)
					)
					(width 0)
					(fill yes)
				)
			)
		)
	)
	(footprint ""
		(layer "F.Cu")
		(at 263.271 -65.532)
		(property "Reference" "C308"
			(at 0 0 0)
			(layer "F.SilkS")
			(hide yes)
			(effects
				(font
					(size 1.27 1.27)
				)
			)
		)
		(property "Value" "SC22U25V5MX-GP"
			(at -0.0762 -6.1214 0)
			(unlocked yes)
			(layer "F.Fab")
			(hide yes)
			(effects
				(font
					(size 1.016 1.016)
					(thickness 0.1524)
				)
			)
		)
		(property "Device Type" "C805H58"
			(at -0.0762 -8.1534 0)
			(unlocked yes)
			(layer "F.Fab")
			(hide yes)
			(effects
				(font
					(size 1.016 1.016)
					(thickness 0.1524)
				)
			)
		)
		(duplicate_pad_numbers_are_jumpers no)
		(fp_line
			(start 0.635 0)
			(end -0.635 0)
			(stroke
				(width 0.508)
				(type default)
			)
			(layer "F.SilkS")
		)
		(fp_rect
			(start -0.9652 1.778)
			(end 0.9652 -1.778)
			(stroke
				(width 0)
				(type default)
			)
			(fill no)
			(layer "F.CrtYd")
		)
		(fp_poly
			(pts
				(xy -0.9652 -1.778) (xy 0.9652 -1.778) (xy 0.9652 1.778) (xy -0.9652 1.778)
			)
			(stroke
				(width 0)
				(type default)
			)
			(fill no)
			(layer "F.Fab")
		)
		(pad "1" smd rect
			(at 0 -0.9652)
			(size 1.397 1.143)
			(layers "F.Cu" "F.Mask" "F.Paste")
			(net "P12V_MSB")
		)
		(pad "2" smd rect
			(at 0 0.9652)
			(size 1.397 1.143)
			(layers "F.Cu" "F.Mask" "F.Paste")
			(net "GND")
		)
	)
	(footprint ""
		(layer "F.Cu")
		(at 286.639 -210.693 180)
		(property "Reference" "C170"
			(at 0 0 180)
			(layer "F.SilkS")
			(hide yes)
			(effects
				(font
					(size 1.27 1.27)
				)
			)
		)
		(property "Value" "SC10U6D3V5KX-4GP"
			(at -0.0762 -6.1214 180)
			(unlocked yes)
			(layer "F.Fab")
			(hide yes)
			(effects
				(font
					(size 1.016 1.016)
					(thickness 0.1524)
				)
			)
		)
		(property "Device Type" "C805H58"
			(at -0.0762 -8.1534 180)
			(unlocked yes)
			(layer "F.Fab")
			(hide yes)
			(effects
				(font
					(size 1.016 1.016)
					(thickness 0.1524)
				)
			)
		)
		(duplicate_pad_numbers_are_jumpers no)
		(fp_line
			(start 0.635 0)
			(end -0.635 0)
			(stroke
				(width 0.508)
				(type default)
			)
			(layer "F.SilkS")
		)
		(fp_rect
			(start -0.9652 1.778)
			(end 0.9652 -1.778)
			(stroke
				(width 0)
				(type default)
			)
			(fill no)
			(layer "F.CrtYd")
		)
		(fp_poly
			(pts
				(xy -0.9652 -1.778) (xy 0.9652 -1.778) (xy 0.9652 1.778) (xy -0.9652 1.778)
			)
			(stroke
				(width 0)
				(type default)
			)
			(fill no)
			(layer "F.Fab")
		)
		(pad "1" smd rect
			(at 0 -0.9652 180)
			(size 1.397 1.143)
			(layers "F.Cu" "F.Mask" "F.Paste")
			(net "P1V53_STBY")
		)
		(pad "2" smd rect
			(at 0 0.9652 180)
			(size 1.397 1.143)
			(layers "F.Cu" "F.Mask" "F.Paste")
			(net "GND")
		)
	)
	(footprint ""
		(layer "F.Cu")
		(at 194.818 -118.237 180)
		(property "Reference" "R601"
			(at 0 0 180)
			(layer "F.SilkS")
			(hide yes)
			(effects
				(font
					(size 1.27 1.27)
				)
			)
		)
		(property "Value" "0R2J-2-GP"
			(at 0.064008 -3.993896 180)
			(unlocked yes)
			(layer "F.Fab")
			(hide yes)
			(effects
				(font
					(size 1.016 1.016)
					(thickness 0.1524)
				)
			)
		)
		(property "Device Type" "R402H16"
			(at 0.064008 -5.517896 180)
			(unlocked yes)
			(layer "F.Fab")
			(hide yes)
			(effects
				(font
					(size 1.016 1.016)
					(thickness 0.1524)
				)
			)
		)
		(duplicate_pad_numbers_are_jumpers no)
		(fp_line
			(start 0.508 -0.9398)
			(end -0.508 -0.9398)
			(stroke
				(width 0.1524)
				(type default)
			)
			(layer "F.SilkS")
		)
		(fp_line
			(start -0.508 -0.9398)
			(end -0.508 0.9398)
			(stroke
				(width 0.1524)
				(type default)
			)
			(layer "F.SilkS")
		)
		(fp_rect
			(start -0.508 0.9398)
			(end 0.508 -0.9398)
			(stroke
				(width 0)
				(type default)
			)
			(fill no)
			(layer "F.CrtYd")
		)
		(fp_rect
			(start -0.508 0.9398)
			(end 0.508 -0.9398)
			(stroke
				(width 0)
				(type default)
			)
			(fill no)
			(layer "F.Fab")
		)
		(pad "1" smd custom
			(at 0 -0.4445 180)
			(size 0.1397 0.1397)
			(layers "F.Cu" "F.Mask" "F.Paste")
			(net "P1V8_E_PG")
			(options
				(clearance outline)
				(anchor circle)
			)
			(primitives
				(gr_poly
					(pts
						(arc
							(start -0.1778 -0.2794)
							(mid -0.249642 -0.249642)
							(end -0.2794 -0.1778)
						)
						(arc
							(start -0.2794 0.1778)
							(mid -0.249642 0.249642)
							(end -0.1778 0.2794)
						)
						(arc
							(start 0.1778 0.2794)
							(mid 0.249642 0.249642)
							(end 0.2794 0.1778)
						)
						(arc
							(start 0.2794 -0.1778)
							(mid 0.249642 -0.249642)
							(end 0.1778 -0.2794)
						)
					)
					(width 0)
					(fill yes)
				)
			)
		)
		(pad "2" smd custom
			(at 0 0.4445 180)
			(size 0.1397 0.1397)
			(layers "F.Cu" "F.Mask" "F.Paste")
			(net "P1V8_PG_R_1")
			(options
				(clearance outline)
				(anchor circle)
			)
			(primitives
				(gr_poly
					(pts
						(arc
							(start -0.1778 -0.2794)
							(mid -0.249642 -0.249642)
							(end -0.2794 -0.1778)
						)
						(arc
							(start -0.2794 0.1778)
							(mid -0.249642 0.249642)
							(end -0.1778 0.2794)
						)
						(arc
							(start 0.1778 0.2794)
							(mid 0.249642 0.249642)
							(end 0.2794 0.1778)
						)
						(arc
							(start 0.2794 -0.1778)
							(mid 0.249642 -0.249642)
							(end 0.1778 -0.2794)
						)
					)
					(width 0)
					(fill yes)
				)
			)
		)
	)
	(footprint ""
		(layer "F.Cu")
		(at 131.069842 -84.399882 90)
		(property "Reference" "SC1097"
			(at 0 0 90)
			(layer "F.SilkS")
			(hide yes)
			(effects
				(font
					(size 1.27 1.27)
				)
			)
		)
		(property "Value" "SCD01U10V1KX-GP"
			(at -2.8321 -1.7399 90)
			(unlocked yes)
			(layer "F.Fab")
			(hide yes)
			(effects
				(font
					(size 1.016 1.016)
					(thickness 0.1524)
				)
			)
		)
		(property "Device Type" "C0201H13"
			(at -2.8321 -3.2639 90)
			(unlocked yes)
			(layer "F.Fab")
			(hide yes)
			(effects
				(font
					(size 1.016 1.016)
					(thickness 0.1524)
				)
			)
		)
		(duplicate_pad_numbers_are_jumpers no)
		(fp_rect
			(start -0.2794 0.6477)
			(end 0.2794 -0.6477)
			(stroke
				(width 0)
				(type default)
			)
			(fill no)
			(layer "F.CrtYd")
		)
		(fp_rect
			(start -0.2794 0.6477)
			(end 0.2794 -0.6477)
			(stroke
				(width 0)
				(type default)
			)
			(fill no)
			(layer "F.Fab")
		)
		(pad "1" smd custom
			(at 0 -0.2794 90)
			(size 0.0762 0.0762)
			(layers "F.Cu" "F.Mask" "F.Paste")
			(net "SAS_HDD_TX15_N")
			(options
				(clearance outline)
				(anchor circle)
			)
			(primitives
				(gr_poly
					(pts
						(arc
							(start 0.1524 -0.127)
							(mid 0.137521 -0.162921)
							(end 0.1016 -0.1778)
						)
						(arc
							(start -0.1016 -0.1778)
							(mid -0.137521 -0.162921)
							(end -0.1524 -0.127)
						)
						(arc
							(start -0.1524 0.127)
							(mid -0.137521 0.162921)
							(end -0.1016 0.1778)
						)
						(arc
							(start 0.1016 0.1778)
							(mid 0.137521 0.162921)
							(end 0.1524 0.127)
						)
					)
					(width 0)
					(fill yes)
				)
			)
		)
		(pad "2" smd custom
			(at 0 0.2794 90)
			(size 0.0762 0.0762)
			(layers "F.Cu" "F.Mask" "F.Paste")
			(net "3008_SAS_RX_N3")
			(options
				(clearance outline)
				(anchor circle)
			)
			(primitives
				(gr_poly
					(pts
						(arc
							(start 0.1524 -0.127)
							(mid 0.137521 -0.162921)
							(end 0.1016 -0.1778)
						)
						(arc
							(start -0.1016 -0.1778)
							(mid -0.137521 -0.162921)
							(end -0.1524 -0.127)
						)
						(arc
							(start -0.1524 0.127)
							(mid -0.137521 0.162921)
							(end -0.1016 0.1778)
						)
						(arc
							(start 0.1016 0.1778)
							(mid 0.137521 0.162921)
							(end 0.1524 0.127)
						)
					)
					(width 0)
					(fill yes)
				)
			)
		)
	)
	(footprint ""
		(layer "F.Cu")
		(at 301.498 -102.108 180)
		(property "Reference" "R165"
			(at 0 0 180)
			(layer "F.SilkS")
			(hide yes)
			(effects
				(font
					(size 1.27 1.27)
				)
			)
		)
		(property "Value" "4K7R2F-GP"
			(at 0.064008 -3.993896 180)
			(unlocked yes)
			(layer "F.Fab")
			(hide yes)
			(effects
				(font
					(size 1.016 1.016)
					(thickness 0.1524)
				)
			)
		)
		(property "Device Type" "R402H16"
			(at 0.064008 -5.517896 180)
			(unlocked yes)
			(layer "F.Fab")
			(hide yes)
			(effects
				(font
					(size 1.016 1.016)
					(thickness 0.1524)
				)
			)
		)
		(duplicate_pad_numbers_are_jumpers no)
		(fp_line
			(start 0.508 -0.9398)
			(end -0.508 -0.9398)
			(stroke
				(width 0.1524)
				(type default)
			)
			(layer "F.SilkS")
		)
		(fp_line
			(start -0.508 -0.9398)
			(end -0.508 0.9398)
			(stroke
				(width 0.1524)
				(type default)
			)
			(layer "F.SilkS")
		)
		(fp_rect
			(start -0.508 0.9398)
			(end 0.508 -0.9398)
			(stroke
				(width 0)
				(type default)
			)
			(fill no)
			(layer "F.CrtYd")
		)
		(fp_rect
			(start -0.508 0.9398)
			(end 0.508 -0.9398)
			(stroke
				(width 0)
				(type default)
			)
			(fill no)
			(layer "F.Fab")
		)
		(pad "1" smd custom
			(at 0 -0.4445 180)
			(size 0.1397 0.1397)
			(layers "F.Cu" "F.Mask" "F.Paste")
			(net "TEMP_2_A1")
			(options
				(clearance outline)
				(anchor circle)
			)
			(primitives
				(gr_poly
					(pts
						(arc
							(start -0.1778 -0.2794)
							(mid -0.249642 -0.249642)
							(end -0.2794 -0.1778)
						)
						(arc
							(start -0.2794 0.1778)
							(mid -0.249642 0.249642)
							(end -0.1778 0.2794)
						)
						(arc
							(start 0.1778 0.2794)
							(mid 0.249642 0.249642)
							(end 0.2794 0.1778)
						)
						(arc
							(start 0.2794 -0.1778)
							(mid 0.249642 -0.249642)
							(end 0.1778 -0.2794)
						)
					)
					(width 0)
					(fill yes)
				)
			)
		)
		(pad "2" smd custom
			(at 0 0.4445 180)
			(size 0.1397 0.1397)
			(layers "F.Cu" "F.Mask" "F.Paste")
			(net "GND")
			(options
				(clearance outline)
				(anchor circle)
			)
			(primitives
				(gr_poly
					(pts
						(arc
							(start -0.1778 -0.2794)
							(mid -0.249642 -0.249642)
							(end -0.2794 -0.1778)
						)
						(arc
							(start -0.2794 0.1778)
							(mid -0.249642 0.249642)
							(end -0.1778 0.2794)
						)
						(arc
							(start 0.1778 0.2794)
							(mid 0.249642 0.249642)
							(end 0.2794 0.1778)
						)
						(arc
							(start 0.2794 -0.1778)
							(mid 0.249642 -0.249642)
							(end 0.1778 -0.2794)
						)
					)
					(width 0)
					(fill yes)
				)
			)
		)
	)
	(footprint ""
		(layer "F.Cu")
		(at 51.689 -225.298 180)
		(property "Reference" "C7276"
			(at 0 0 180)
			(layer "F.SilkS")
			(hide yes)
			(effects
				(font
					(size 1.27 1.27)
				)
			)
		)
		(property "Value" "SC1U16V3KX-5GP"
			(at 0 -2.8194 180)
			(unlocked yes)
			(layer "F.Fab")
			(hide yes)
			(effects
				(font
					(size 1.016 1.016)
					(thickness 0.1524)
				)
			)
		)
		(property "Device Type" "C603H36"
			(at 0 -4.3434 180)
			(unlocked yes)
			(layer "F.Fab")
			(hide yes)
			(effects
				(font
					(size 1.016 1.016)
					(thickness 0.1524)
				)
			)
		)
		(duplicate_pad_numbers_are_jumpers no)
		(fp_line
			(start 0.508 0)
			(end -0.508 0)
			(stroke
				(width 0.2032)
				(type default)
			)
			(layer "F.SilkS")
		)
		(fp_rect
			(start -0.5842 1.3335)
			(end 0.5842 -1.3335)
			(stroke
				(width 0)
				(type default)
			)
			(fill no)
			(layer "F.CrtYd")
		)
		(fp_rect
			(start -0.5842 1.3335)
			(end 0.5842 -1.3335)
			(stroke
				(width 0)
				(type default)
			)
			(fill no)
			(layer "F.Fab")
		)
		(pad "1" smd custom
			(at 0 -0.762 180)
			(size 0.2159 0.2159)
			(layers "F.Cu" "F.Mask" "F.Paste")
			(net "MB0_CM_UV_R")
			(options
				(clearance outline)
				(anchor circle)
			)
			(primitives
				(gr_poly
					(pts
						(arc
							(start -0.3302 -0.4318)
							(mid -0.402042 -0.402042)
							(end -0.4318 -0.3302)
						)
						(arc
							(start -0.4318 0.3302)
							(mid -0.402042 0.402042)
							(end -0.3302 0.4318)
						)
						(arc
							(start 0.3302 0.4318)
							(mid 0.402042 0.402042)
							(end 0.4318 0.3302)
						)
						(arc
							(start 0.4318 -0.3302)
							(mid 0.402042 -0.402042)
							(end 0.3302 -0.4318)
						)
					)
					(width 0)
					(fill yes)
				)
			)
		)
		(pad "2" smd custom
			(at 0 0.762 180)
			(size 0.2159 0.2159)
			(layers "F.Cu" "F.Mask" "F.Paste")
			(net "AGND_CURRENT_MON")
			(options
				(clearance outline)
				(anchor circle)
			)
			(primitives
				(gr_poly
					(pts
						(arc
							(start -0.3302 -0.4318)
							(mid -0.402042 -0.402042)
							(end -0.4318 -0.3302)
						)
						(arc
							(start -0.4318 0.3302)
							(mid -0.402042 0.402042)
							(end -0.3302 0.4318)
						)
						(arc
							(start 0.3302 0.4318)
							(mid 0.402042 0.402042)
							(end 0.4318 0.3302)
						)
						(arc
							(start 0.4318 -0.3302)
							(mid 0.402042 -0.402042)
							(end 0.3302 -0.4318)
						)
					)
					(width 0)
					(fill yes)
				)
			)
		)
	)
	(footprint ""
		(layer "F.Cu")
		(at 171.619164 -24.014176 -90)
		(property "Reference" "R406"
			(at 0 0 270)
			(layer "F.SilkS")
			(hide yes)
			(effects
				(font
					(size 1.27 1.27)
				)
			)
		)
		(property "Value" "220R2J-L2-GP"
			(at 0.064008 -3.993896 270)
			(unlocked yes)
			(layer "F.Fab")
			(hide yes)
			(effects
				(font
					(size 1.016 1.016)
					(thickness 0.1524)
				)
			)
		)
		(property "Device Type" "R402H16"
			(at 0.064008 -5.517896 270)
			(unlocked yes)
			(layer "F.Fab")
			(hide yes)
			(effects
				(font
					(size 1.016 1.016)
					(thickness 0.1524)
				)
			)
		)
		(duplicate_pad_numbers_are_jumpers no)
		(fp_line
			(start -0.508 -0.9398)
			(end -0.508 0.9398)
			(stroke
				(width 0.1524)
				(type default)
			)
			(layer "F.SilkS")
		)
		(fp_line
			(start 0.508 -0.9398)
			(end -0.508 -0.9398)
			(stroke
				(width 0.1524)
				(type default)
			)
			(layer "F.SilkS")
		)
		(fp_rect
			(start -0.508 0.9398)
			(end 0.508 -0.9398)
			(stroke
				(width 0)
				(type default)
			)
			(fill no)
			(layer "F.CrtYd")
		)
		(fp_rect
			(start -0.508 0.9398)
			(end 0.508 -0.9398)
			(stroke
				(width 0)
				(type default)
			)
			(fill no)
			(layer "F.Fab")
		)
		(pad "1" smd custom
			(at 0 -0.4445 270)
			(size 0.1397 0.1397)
			(layers "F.Cu" "F.Mask" "F.Paste")
			(net "MOD_IMC_FAB_D_COP")
			(options
				(clearance outline)
				(anchor circle)
			)
			(primitives
				(gr_poly
					(pts
						(arc
							(start -0.1778 -0.2794)
							(mid -0.249642 -0.249642)
							(end -0.2794 -0.1778)
						)
						(arc
							(start -0.2794 0.1778)
							(mid -0.249642 0.249642)
							(end -0.1778 0.2794)
						)
						(arc
							(start 0.1778 0.2794)
							(mid 0.249642 0.249642)
							(end 0.2794 0.1778)
						)
						(arc
							(start 0.2794 -0.1778)
							(mid 0.249642 -0.249642)
							(end 0.1778 -0.2794)
						)
					)
					(width 0)
					(fill yes)
				)
			)
		)
		(pad "2" smd custom
			(at 0 0.4445 270)
			(size 0.1397 0.1397)
			(layers "F.Cu" "F.Mask" "F.Paste")
			(net "GND")
			(options
				(clearance outline)
				(anchor circle)
			)
			(primitives
				(gr_poly
					(pts
						(arc
							(start -0.1778 -0.2794)
							(mid -0.249642 -0.249642)
							(end -0.2794 -0.1778)
						)
						(arc
							(start -0.2794 0.1778)
							(mid -0.249642 0.249642)
							(end -0.1778 0.2794)
						)
						(arc
							(start 0.1778 0.2794)
							(mid 0.249642 0.249642)
							(end 0.2794 0.1778)
						)
						(arc
							(start 0.2794 -0.1778)
							(mid 0.249642 -0.249642)
							(end 0.1778 -0.2794)
						)
					)
					(width 0)
					(fill yes)
				)
			)
		)
	)
	(footprint ""
		(layer "F.Cu")
		(at 82.784188 -19.119596 90)
		(property "Reference" "PU13"
			(at 0 0 90)
			(layer "F.SilkS")
			(hide yes)
			(effects
				(font
					(size 1.27 1.27)
				)
			)
		)
		(property "Value" "VT235WFQX-ADJ-1-GP"
			(at -5.8166 -7.7216 90)
			(unlocked yes)
			(layer "F.Fab")
			(hide yes)
			(effects
				(font
					(size 1.016 1.016)
					(thickness 0.1524)
				)
			)
		)
		(property "Device Type" "QFN19-1H40"
			(at -5.8166 -9.2456 90)
			(unlocked yes)
			(layer "F.Fab")
			(hide yes)
			(effects
				(font
					(size 1.016 1.016)
					(thickness 0.1524)
				)
			)
		)
		(duplicate_pad_numbers_are_jumpers no)
		(fp_line
			(start -1.4859 -3.0734)
			(end -2.7559 -3.0734)
			(stroke
				(width 0.1524)
				(type default)
			)
			(layer "F.SilkS")
		)
		(fp_line
			(start -2.7559 -3.0734)
			(end -2.7559 -1.8034)
			(stroke
				(width 0.1524)
				(type default)
			)
			(layer "F.SilkS")
		)
		(fp_line
			(start -1.253236 -2.821432)
			(end -1.253236 -3.329432)
			(stroke
				(width 0.1524)
				(type default)
			)
			(layer "F.SilkS")
		)
		(fp_line
			(start 2.821432 0.23876)
			(end 3.329432 0.23876)
			(stroke
				(width 0.1524)
				(type default)
			)
			(layer "F.SilkS")
		)
		(fp_line
			(start -2.7559 1.8034)
			(end -2.7559 3.0734)
			(stroke
				(width 0.1524)
				(type default)
			)
			(layer "F.SilkS")
		)
		(fp_line
			(start 0.766064 2.796032)
			(end 0.766064 3.558032)
			(stroke
				(width 0.1524)
				(type default)
			)
			(layer "F.SilkS")
		)
		(fp_line
			(start 3.0861 3.0734)
			(end 3.0861 1.8034)
			(stroke
				(width 0.1524)
				(type default)
			)
			(layer "F.SilkS")
		)
		(fp_line
			(start 1.8161 3.0734)
			(end 3.0861 3.0734)
			(stroke
				(width 0.1524)
				(type default)
			)
			(layer "F.SilkS")
		)
		(fp_line
			(start -2.7559 3.0734)
			(end -1.4859 3.0734)
			(stroke
				(width 0.1524)
				(type default)
			)
			(layer "F.SilkS")
		)
		(fp_poly
			(pts
				(xy 3.0861 -3.0734) (xy 1.8161 -3.0734) (xy 3.0861 -1.8034)
			)
			(stroke
				(width 0)
				(type default)
			)
			(fill yes)
			(layer "F.SilkS")
		)
		(fp_rect
			(start -2.2479 2.2479)
			(end 2.2479 -2.2479)
			(stroke
				(width 0)
				(type default)
			)
			(fill no)
			(layer "F.CrtYd")
		)
		(fp_poly
			(pts
				(xy -2.7559 -3.0734) (xy -2.7559 3.0734) (xy 3.0861 3.0734) (xy 3.0861 2.0193) (xy 2.2479 2.0193)
				(xy 2.2479 2.2479) (xy -2.2479 2.2479) (xy -2.2479 -2.2479) (xy 2.2479 -2.2479) (xy 2.2479 2.0066)
				(xy 3.0861 2.0066) (xy 3.0861 -3.0734)
			)
			(stroke
				(width 0)
				(type default)
			)
			(fill no)
			(layer "F.CrtYd")
		)
		(fp_rect
			(start -2.7559 3.0734)
			(end 3.0861 -3.0734)
			(stroke
				(width 0)
				(type default)
			)
			(fill no)
			(layer "F.Fab")
		)
		(pad "1" smd rect
			(at 1.249934 -2.135632 90)
			(size 0.3556 0.8382)
			(layers "F.Cu" "F.Mask" "F.Paste")
			(net "AGND_P0V9_C")
		)
		(pad "2" smd rect
			(at 0.750062 -2.135632 90)
			(size 0.3556 0.8382)
			(layers "F.Cu" "F.Mask" "F.Paste")
			(net "Net_1133")
		)
		(pad "3" smd rect
			(at 0.249936 -2.135632 90)
			(size 0.3556 0.8382)
			(layers "F.Cu" "F.Mask" "F.Paste")
			(net "VT235_AVDD")
		)
		(pad "4" smd rect
			(at -0.249936 -0.687832 90)
			(size 0.3556 3.7338)
			(layers "F.Cu" "F.Mask" "F.Paste")
			(net "VT235_VDDH")
		)
		(pad "5" smd rect
			(at -1.249934 -1.335532 90)
			(size 0.3556 2.4384)
			(layers "F.Cu" "F.Mask" "F.Paste")
			(net "GND")
		)
		(pad "6" smd rect
			(at -1.75006 1.335532 90)
			(size 0.3556 2.4384)
			(layers "F.Cu" "F.Mask" "F.Paste")
			(net "VT235_VX")
		)
		(pad "7" smd rect
			(at -0.750062 1.335532 90)
			(size 0.3556 2.4384)
			(layers "F.Cu" "F.Mask" "F.Paste")
			(net "VT235_VX")
		)
		(pad "8" smd rect
			(at -0.249936 2.135632 90)
			(size 0.3556 0.8382)
			(layers "F.Cu" "F.Mask" "F.Paste")
			(net "VT235_BST")
		)
		(pad "9" smd rect
			(at 0.249936 2.135632 90)
			(size 0.3556 0.8382)
			(layers "F.Cu" "F.Mask" "F.Paste")
			(net "VT235_VDDL")
		)
		(pad "10" smd rect
			(at 0.750062 2.135632 90)
			(size 0.3556 0.8382)
			(layers "F.Cu" "F.Mask" "F.Paste")
			(net "VT235_AVDD")
		)
		(pad "11" smd rect
			(at 1.249934 2.135632 90)
			(size 0.3556 0.8382)
			(layers "F.Cu" "F.Mask" "F.Paste")
			(net "VT235_VFB")
		)
		(pad "12" smd rect
			(at 2.135632 1.75006 90)
			(size 0.8382 0.3556)
			(layers "F.Cu" "F.Mask" "F.Paste")
			(net "VT235_PGIN")
		)
		(pad "13" smd rect
			(at 2.135632 1.249934 90)
			(size 0.8382 0.3556)
			(layers "F.Cu" "F.Mask" "F.Paste")
			(net "VT235_VDES")
		)
		(pad "14" smd rect
			(at 2.135632 0.750062 90)
			(size 0.8382 0.3556)
			(layers "F.Cu" "F.Mask" "F.Paste")
			(net "VT235_VREF")
		)
		(pad "15" smd rect
			(at 2.135632 0.249936 90)
			(size 0.8382 0.3556)
			(layers "F.Cu" "F.Mask" "F.Paste")
			(net "VT235_BIAS")
		)
		(pad "16" smd rect
			(at 2.135632 -0.249936 90)
			(size 0.8382 0.3556)
			(layers "F.Cu" "F.Mask" "F.Paste")
			(net "VT235_IMAX")
		)
		(pad "17" smd rect
			(at 2.135632 -0.750062 90)
			(size 0.8382 0.3556)
			(layers "F.Cu" "F.Mask" "F.Paste")
			(net "PG_STAT_P0V955_C")
		)
		(pad "18" smd rect
			(at 2.135632 -1.249934 90)
			(size 0.8382 0.3556)
			(layers "F.Cu" "F.Mask" "F.Paste")
			(net "VT235_EN")
		)
		(pad "19" smd rect
			(at 2.135632 -1.75006 90)
			(size 0.8382 0.3556)
			(layers "F.Cu" "F.Mask" "F.Paste")
			(net "VT235_IRIP")
		)
	)
	(footprint ""
		(layer "F.Cu")
		(at 112.846612 -221.996 180)
		(property "Reference" "SR884"
			(at 0 0 180)
			(layer "F.SilkS")
			(hide yes)
			(effects
				(font
					(size 1.27 1.27)
				)
			)
		)
		(property "Value" "0R2J-2-GP"
			(at 0.064008 -3.993896 180)
			(unlocked yes)
			(layer "F.Fab")
			(hide yes)
			(effects
				(font
					(size 1.016 1.016)
					(thickness 0.1524)
				)
			)
		)
		(property "Device Type" "R402H16"
			(at 0.064008 -5.517896 180)
			(unlocked yes)
			(layer "F.Fab")
			(hide yes)
			(effects
				(font
					(size 1.016 1.016)
					(thickness 0.1524)
				)
			)
		)
		(duplicate_pad_numbers_are_jumpers no)
		(fp_line
			(start 0.508 -0.9398)
			(end -0.508 -0.9398)
			(stroke
				(width 0.1524)
				(type default)
			)
			(layer "F.SilkS")
		)
		(fp_line
			(start -0.508 -0.9398)
			(end -0.508 0.9398)
			(stroke
				(width 0.1524)
				(type default)
			)
			(layer "F.SilkS")
		)
		(fp_rect
			(start -0.508 0.9398)
			(end 0.508 -0.9398)
			(stroke
				(width 0)
				(type default)
			)
			(fill no)
			(layer "F.CrtYd")
		)
		(fp_rect
			(start -0.508 0.9398)
			(end 0.508 -0.9398)
			(stroke
				(width 0)
				(type default)
			)
			(fill no)
			(layer "F.Fab")
		)
		(pad "1" smd custom
			(at 0 -0.4445 180)
			(size 0.1397 0.1397)
			(layers "F.Cu" "F.Mask" "F.Paste")
			(net "REDV_TX8_N")
			(options
				(clearance outline)
				(anchor circle)
			)
			(primitives
				(gr_poly
					(pts
						(arc
							(start -0.1778 -0.2794)
							(mid -0.249642 -0.249642)
							(end -0.2794 -0.1778)
						)
						(arc
							(start -0.2794 0.1778)
							(mid -0.249642 0.249642)
							(end -0.1778 0.2794)
						)
						(arc
							(start 0.1778 0.2794)
							(mid 0.249642 0.249642)
							(end 0.2794 0.1778)
						)
						(arc
							(start 0.2794 -0.1778)
							(mid 0.249642 -0.249642)
							(end 0.1778 -0.2794)
						)
					)
					(width 0)
					(fill yes)
				)
			)
		)
		(pad "2" smd custom
			(at 0 0.4445 180)
			(size 0.1397 0.1397)
			(layers "F.Cu" "F.Mask" "F.Paste")
			(net "SAS_HDD_CONN_TX8_N")
			(options
				(clearance outline)
				(anchor circle)
			)
			(primitives
				(gr_poly
					(pts
						(arc
							(start -0.1778 -0.2794)
							(mid -0.249642 -0.249642)
							(end -0.2794 -0.1778)
						)
						(arc
							(start -0.2794 0.1778)
							(mid -0.249642 0.249642)
							(end -0.1778 0.2794)
						)
						(arc
							(start 0.1778 0.2794)
							(mid 0.249642 0.249642)
							(end 0.2794 0.1778)
						)
						(arc
							(start 0.2794 -0.1778)
							(mid 0.249642 -0.249642)
							(end 0.1778 -0.2794)
						)
					)
					(width 0)
					(fill yes)
				)
			)
		)
	)
	(footprint ""
		(layer "F.Cu")
		(at 277.495 -115.824)
		(property "Reference" "PR180"
			(at 0 0 0)
			(layer "F.SilkS")
			(hide yes)
			(effects
				(font
					(size 1.27 1.27)
				)
			)
		)
		(property "Value" "0R2J-2-GP"
			(at 0.064008 -3.993896 0)
			(unlocked yes)
			(layer "F.Fab")
			(hide yes)
			(effects
				(font
					(size 1.016 1.016)
					(thickness 0.1524)
				)
			)
		)
		(property "Device Type" "R402H16"
			(at 0.064008 -5.517896 0)
			(unlocked yes)
			(layer "F.Fab")
			(hide yes)
			(effects
				(font
					(size 1.016 1.016)
					(thickness 0.1524)
				)
			)
		)
		(duplicate_pad_numbers_are_jumpers no)
		(fp_line
			(start -0.508 -0.9398)
			(end -0.508 0.9398)
			(stroke
				(width 0.1524)
				(type default)
			)
			(layer "F.SilkS")
		)
		(fp_line
			(start 0.508 -0.9398)
			(end -0.508 -0.9398)
			(stroke
				(width 0.1524)
				(type default)
			)
			(layer "F.SilkS")
		)
		(fp_rect
			(start -0.508 0.9398)
			(end 0.508 -0.9398)
			(stroke
				(width 0)
				(type default)
			)
			(fill no)
			(layer "F.CrtYd")
		)
		(fp_rect
			(start -0.508 0.9398)
			(end 0.508 -0.9398)
			(stroke
				(width 0)
				(type default)
			)
			(fill no)
			(layer "F.Fab")
		)
		(pad "1" smd custom
			(at 0 -0.4445)
			(size 0.1397 0.1397)
			(layers "F.Cu" "F.Mask" "F.Paste")
			(net "BMC_1V8_C_EN")
			(options
				(clearance outline)
				(anchor circle)
			)
			(primitives
				(gr_poly
					(pts
						(arc
							(start -0.1778 -0.2794)
							(mid -0.249642 -0.249642)
							(end -0.2794 -0.1778)
						)
						(arc
							(start -0.2794 0.1778)
							(mid -0.249642 0.249642)
							(end -0.1778 0.2794)
						)
						(arc
							(start 0.1778 0.2794)
							(mid 0.249642 0.249642)
							(end 0.2794 0.1778)
						)
						(arc
							(start 0.2794 -0.1778)
							(mid 0.249642 -0.249642)
							(end 0.1778 -0.2794)
						)
					)
					(width 0)
					(fill yes)
				)
			)
		)
		(pad "2" smd custom
			(at 0 0.4445)
			(size 0.1397 0.1397)
			(layers "F.Cu" "F.Mask" "F.Paste")
			(net "P1V8_C_EN_B")
			(options
				(clearance outline)
				(anchor circle)
			)
			(primitives
				(gr_poly
					(pts
						(arc
							(start -0.1778 -0.2794)
							(mid -0.249642 -0.249642)
							(end -0.2794 -0.1778)
						)
						(arc
							(start -0.2794 0.1778)
							(mid -0.249642 0.249642)
							(end -0.1778 0.2794)
						)
						(arc
							(start 0.1778 0.2794)
							(mid 0.249642 0.249642)
							(end 0.2794 0.1778)
						)
						(arc
							(start 0.2794 -0.1778)
							(mid 0.249642 -0.249642)
							(end 0.1778 -0.2794)
						)
					)
					(width 0)
					(fill yes)
				)
			)
		)
	)
	(footprint ""
		(layer "F.Cu")
		(at 111.887 -61.976 -90)
		(property "Reference" "SR732"
			(at 0 0 270)
			(layer "F.SilkS")
			(hide yes)
			(effects
				(font
					(size 1.27 1.27)
				)
			)
		)
		(property "Value" "10KR2F-2-GP"
			(at 0.064008 -3.993896 270)
			(unlocked yes)
			(layer "F.Fab")
			(hide yes)
			(effects
				(font
					(size 1.016 1.016)
					(thickness 0.1524)
				)
			)
		)
		(property "Device Type" "R402H16"
			(at 0.064008 -5.517896 270)
			(unlocked yes)
			(layer "F.Fab")
			(hide yes)
			(effects
				(font
					(size 1.016 1.016)
					(thickness 0.1524)
				)
			)
		)
		(duplicate_pad_numbers_are_jumpers no)
		(fp_line
			(start -0.508 -0.9398)
			(end -0.508 0.9398)
			(stroke
				(width 0.1524)
				(type default)
			)
			(layer "F.SilkS")
		)
		(fp_line
			(start 0.508 -0.9398)
			(end -0.508 -0.9398)
			(stroke
				(width 0.1524)
				(type default)
			)
			(layer "F.SilkS")
		)
		(fp_rect
			(start -0.508 0.9398)
			(end 0.508 -0.9398)
			(stroke
				(width 0)
				(type default)
			)
			(fill no)
			(layer "F.CrtYd")
		)
		(fp_rect
			(start -0.508 0.9398)
			(end 0.508 -0.9398)
			(stroke
				(width 0)
				(type default)
			)
			(fill no)
			(layer "F.Fab")
		)
		(pad "1" smd custom
			(at 0 -0.4445 270)
			(size 0.1397 0.1397)
			(layers "F.Cu" "F.Mask" "F.Paste")
			(net "P1V8_C")
			(options
				(clearance outline)
				(anchor circle)
			)
			(primitives
				(gr_poly
					(pts
						(arc
							(start -0.1778 -0.2794)
							(mid -0.249642 -0.249642)
							(end -0.2794 -0.1778)
						)
						(arc
							(start -0.2794 0.1778)
							(mid -0.249642 0.249642)
							(end -0.1778 0.2794)
						)
						(arc
							(start 0.1778 0.2794)
							(mid 0.249642 0.249642)
							(end 0.2794 0.1778)
						)
						(arc
							(start 0.2794 -0.1778)
							(mid 0.249642 -0.249642)
							(end 0.1778 -0.2794)
						)
					)
					(width 0)
					(fill yes)
				)
			)
		)
		(pad "2" smd custom
			(at 0 0.4445 270)
			(size 0.1397 0.1397)
			(layers "F.Cu" "F.Mask" "F.Paste")
			(net "XM_CS0_N")
			(options
				(clearance outline)
				(anchor circle)
			)
			(primitives
				(gr_poly
					(pts
						(arc
							(start -0.1778 -0.2794)
							(mid -0.249642 -0.249642)
							(end -0.2794 -0.1778)
						)
						(arc
							(start -0.2794 0.1778)
							(mid -0.249642 0.249642)
							(end -0.1778 0.2794)
						)
						(arc
							(start 0.1778 0.2794)
							(mid 0.249642 0.249642)
							(end 0.2794 0.1778)
						)
						(arc
							(start 0.2794 -0.1778)
							(mid 0.249642 -0.249642)
							(end 0.1778 -0.2794)
						)
					)
					(width 0)
					(fill yes)
				)
			)
		)
	)
	(footprint ""
		(layer "F.Cu")
		(at 199.771 -103.759)
		(property "Reference" "PL12"
			(at 0 0 0)
			(layer "F.SilkS")
			(hide yes)
			(effects
				(font
					(size 1.27 1.27)
				)
			)
		)
		(property "Value" "COIL-3D3UH-26-GP"
			(at -4.699 -4.0132 0)
			(unlocked yes)
			(layer "F.Fab")
			(hide yes)
			(effects
				(font
					(size 1.016 1.016)
					(thickness 0.1524)
				)
			)
		)
		(property "Device Type" "L7066-1830-UH119"
			(at -4.699 -5.5372 0)
			(unlocked yes)
			(layer "F.Fab")
			(hide yes)
			(effects
				(font
					(size 1.016 1.016)
					(thickness 0.1524)
				)
			)
		)
		(duplicate_pad_numbers_are_jumpers no)
		(fp_line
			(start -3.556 -4.4958)
			(end 3.556 -4.4958)
			(stroke
				(width 0.1524)
				(type default)
			)
			(layer "F.SilkS")
		)
		(fp_line
			(start -3.556 4.4958)
			(end -3.556 -4.4958)
			(stroke
				(width 0.1524)
				(type default)
			)
			(layer "F.SilkS")
		)
		(fp_line
			(start 3.556 -4.4958)
			(end 3.556 4.4958)
			(stroke
				(width 0.1524)
				(type default)
			)
			(layer "F.SilkS")
		)
		(fp_line
			(start 3.556 4.4958)
			(end -3.556 4.4958)
			(stroke
				(width 0.1524)
				(type default)
			)
			(layer "F.SilkS")
		)
		(fp_rect
			(start -3.302 3.4798)
			(end 3.302 -3.4798)
			(stroke
				(width 0)
				(type default)
			)
			(fill no)
			(layer "F.CrtYd")
		)
		(fp_poly
			(pts
				(xy -3.81 4.572) (xy -3.81 -4.572) (xy 3.81 -4.572) (xy 3.81 -0.5588) (xy 3.302 -0.5588) (xy 3.302 -3.4798)
				(xy -3.302 -3.4798) (xy -3.302 3.4798) (xy 3.302 3.4798) (xy 3.302 -0.5461) (xy 3.81 -0.5461) (xy 3.81 4.572)
			)
			(stroke
				(width 0)
				(type default)
			)
			(fill no)
			(layer "F.CrtYd")
		)
		(fp_rect
			(start -3.81 4.572)
			(end 3.81 -4.572)
			(stroke
				(width 0)
				(type default)
			)
			(fill no)
			(layer "F.Fab")
		)
		(pad "1" smd rect
			(at 0 -2.779522)
			(size 3.5052 2.921)
			(layers "F.Cu" "F.Mask" "F.Paste")
			(net "P1V5_E_SW")
		)
		(pad "2" smd rect
			(at 0 2.779522)
			(size 3.5052 2.921)
			(layers "F.Cu" "F.Mask" "F.Paste")
			(net "P1V5_E")
		)
	)
	(footprint ""
		(layer "F.Cu")
		(at 90.683842 -122.626882 90)
		(property "Reference" "SR751"
			(at 0 0 90)
			(layer "F.SilkS")
			(hide yes)
			(effects
				(font
					(size 1.27 1.27)
				)
			)
		)
		(property "Value" "200KR2F-L-GP"
			(at 0.064008 -3.993896 90)
			(unlocked yes)
			(layer "F.Fab")
			(hide yes)
			(effects
				(font
					(size 1.016 1.016)
					(thickness 0.1524)
				)
			)
		)
		(property "Device Type" "R402H16"
			(at 0.064008 -5.517896 90)
			(unlocked yes)
			(layer "F.Fab")
			(hide yes)
			(effects
				(font
					(size 1.016 1.016)
					(thickness 0.1524)
				)
			)
		)
		(duplicate_pad_numbers_are_jumpers no)
		(fp_line
			(start 0.508 -0.9398)
			(end -0.508 -0.9398)
			(stroke
				(width 0.1524)
				(type default)
			)
			(layer "F.SilkS")
		)
		(fp_line
			(start -0.508 -0.9398)
			(end -0.508 0.9398)
			(stroke
				(width 0.1524)
				(type default)
			)
			(layer "F.SilkS")
		)
		(fp_rect
			(start -0.508 0.9398)
			(end 0.508 -0.9398)
			(stroke
				(width 0)
				(type default)
			)
			(fill no)
			(layer "F.CrtYd")
		)
		(fp_rect
			(start -0.508 0.9398)
			(end 0.508 -0.9398)
			(stroke
				(width 0)
				(type default)
			)
			(fill no)
			(layer "F.Fab")
		)
		(pad "1" smd custom
			(at 0 -0.4445 90)
			(size 0.1397 0.1397)
			(layers "F.Cu" "F.Mask" "F.Paste")
			(net "EXP_I2C_VREF_0")
			(options
				(clearance outline)
				(anchor circle)
			)
			(primitives
				(gr_poly
					(pts
						(arc
							(start -0.1778 -0.2794)
							(mid -0.249642 -0.249642)
							(end -0.2794 -0.1778)
						)
						(arc
							(start -0.2794 0.1778)
							(mid -0.249642 0.249642)
							(end -0.1778 0.2794)
						)
						(arc
							(start 0.1778 0.2794)
							(mid 0.249642 0.249642)
							(end 0.2794 0.1778)
						)
						(arc
							(start 0.2794 -0.1778)
							(mid 0.249642 -0.249642)
							(end 0.1778 -0.2794)
						)
					)
					(width 0)
					(fill yes)
				)
			)
		)
		(pad "2" smd custom
			(at 0 0.4445 90)
			(size 0.1397 0.1397)
			(layers "F.Cu" "F.Mask" "F.Paste")
			(net "P3V3_STBY")
			(options
				(clearance outline)
				(anchor circle)
			)
			(primitives
				(gr_poly
					(pts
						(arc
							(start -0.1778 -0.2794)
							(mid -0.249642 -0.249642)
							(end -0.2794 -0.1778)
						)
						(arc
							(start -0.2794 0.1778)
							(mid -0.249642 0.249642)
							(end -0.1778 0.2794)
						)
						(arc
							(start 0.1778 0.2794)
							(mid 0.249642 0.249642)
							(end 0.2794 0.1778)
						)
						(arc
							(start 0.2794 -0.1778)
							(mid 0.249642 -0.249642)
							(end 0.1778 -0.2794)
						)
					)
					(width 0)
					(fill yes)
				)
			)
		)
	)
	(footprint ""
		(layer "F.Cu")
		(at 327.383648 -110.416848 90)
		(property "Reference" "PC28"
			(at 0 0 90)
			(layer "F.SilkS")
			(hide yes)
			(effects
				(font
					(size 1.27 1.27)
				)
			)
		)
		(property "Value" "SC2K2P50V3KX-GP"
			(at 0 -2.8194 90)
			(unlocked yes)
			(layer "F.Fab")
			(hide yes)
			(effects
				(font
					(size 1.016 1.016)
					(thickness 0.1524)
				)
			)
		)
		(property "Device Type" "C603"
			(at 0 -4.3434 90)
			(unlocked yes)
			(layer "F.Fab")
			(hide yes)
			(effects
				(font
					(size 1.016 1.016)
					(thickness 0.1524)
				)
			)
		)
		(duplicate_pad_numbers_are_jumpers no)
		(fp_line
			(start 0.508 0)
			(end -0.508 0)
			(stroke
				(width 0.2032)
				(type default)
			)
			(layer "F.SilkS")
		)
		(fp_rect
			(start -0.5842 1.3335)
			(end 0.5842 -1.3335)
			(stroke
				(width 0)
				(type default)
			)
			(fill no)
			(layer "F.CrtYd")
		)
		(fp_rect
			(start -0.5842 1.3335)
			(end 0.5842 -1.3335)
			(stroke
				(width 0)
				(type default)
			)
			(fill no)
			(layer "F.Fab")
		)
		(pad "1" smd custom
			(at 0 -0.762 90)
			(size 0.2159 0.2159)
			(layers "F.Cu" "F.Mask" "F.Paste")
			(net "P3V3_STBY_LL")
			(options
				(clearance outline)
				(anchor circle)
			)
			(primitives
				(gr_poly
					(pts
						(arc
							(start -0.3302 -0.4318)
							(mid -0.402042 -0.402042)
							(end -0.4318 -0.3302)
						)
						(arc
							(start -0.4318 0.3302)
							(mid -0.402042 0.402042)
							(end -0.3302 0.4318)
						)
						(arc
							(start 0.3302 0.4318)
							(mid 0.402042 0.402042)
							(end 0.4318 0.3302)
						)
						(arc
							(start 0.4318 -0.3302)
							(mid 0.402042 -0.402042)
							(end 0.3302 -0.4318)
						)
					)
					(width 0)
					(fill yes)
				)
			)
		)
		(pad "2" smd custom
			(at 0 0.762 90)
			(size 0.2159 0.2159)
			(layers "F.Cu" "F.Mask" "F.Paste")
			(net "P3V3_STBY_SNB")
			(options
				(clearance outline)
				(anchor circle)
			)
			(primitives
				(gr_poly
					(pts
						(arc
							(start -0.3302 -0.4318)
							(mid -0.402042 -0.402042)
							(end -0.4318 -0.3302)
						)
						(arc
							(start -0.4318 0.3302)
							(mid -0.402042 0.402042)
							(end -0.3302 0.4318)
						)
						(arc
							(start 0.3302 0.4318)
							(mid 0.402042 0.402042)
							(end 0.4318 0.3302)
						)
						(arc
							(start 0.4318 -0.3302)
							(mid 0.402042 -0.402042)
							(end 0.3302 -0.4318)
						)
					)
					(width 0)
					(fill yes)
				)
			)
		)
	)
	(footprint ""
		(layer "F.Cu")
		(at 92.21597 -94.234 -90)
		(property "Reference" "SR781"
			(at 0 0 270)
			(layer "F.SilkS")
			(hide yes)
			(effects
				(font
					(size 1.27 1.27)
				)
			)
		)
		(property "Value" "4K7R2F-GP"
			(at 0.064008 -3.993896 270)
			(unlocked yes)
			(layer "F.Fab")
			(hide yes)
			(effects
				(font
					(size 1.016 1.016)
					(thickness 0.1524)
				)
			)
		)
		(property "Device Type" "R402H16"
			(at 0.064008 -5.517896 270)
			(unlocked yes)
			(layer "F.Fab")
			(hide yes)
			(effects
				(font
					(size 1.016 1.016)
					(thickness 0.1524)
				)
			)
		)
		(duplicate_pad_numbers_are_jumpers no)
		(fp_line
			(start -0.508 -0.9398)
			(end -0.508 0.9398)
			(stroke
				(width 0.1524)
				(type default)
			)
			(layer "F.SilkS")
		)
		(fp_line
			(start 0.508 -0.9398)
			(end -0.508 -0.9398)
			(stroke
				(width 0.1524)
				(type default)
			)
			(layer "F.SilkS")
		)
		(fp_rect
			(start -0.508 0.9398)
			(end 0.508 -0.9398)
			(stroke
				(width 0)
				(type default)
			)
			(fill no)
			(layer "F.CrtYd")
		)
		(fp_rect
			(start -0.508 0.9398)
			(end 0.508 -0.9398)
			(stroke
				(width 0)
				(type default)
			)
			(fill no)
			(layer "F.Fab")
		)
		(pad "1" smd custom
			(at 0 -0.4445 270)
			(size 0.1397 0.1397)
			(layers "F.Cu" "F.Mask" "F.Paste")
			(net "EXP_XM_ADDR_23")
			(options
				(clearance outline)
				(anchor circle)
			)
			(primitives
				(gr_poly
					(pts
						(arc
							(start -0.1778 -0.2794)
							(mid -0.249642 -0.249642)
							(end -0.2794 -0.1778)
						)
						(arc
							(start -0.2794 0.1778)
							(mid -0.249642 0.249642)
							(end -0.1778 0.2794)
						)
						(arc
							(start 0.1778 0.2794)
							(mid 0.249642 0.249642)
							(end 0.2794 0.1778)
						)
						(arc
							(start 0.2794 -0.1778)
							(mid 0.249642 -0.249642)
							(end 0.1778 -0.2794)
						)
					)
					(width 0)
					(fill yes)
				)
			)
		)
		(pad "2" smd custom
			(at 0 0.4445 270)
			(size 0.1397 0.1397)
			(layers "F.Cu" "F.Mask" "F.Paste")
			(net "GND")
			(options
				(clearance outline)
				(anchor circle)
			)
			(primitives
				(gr_poly
					(pts
						(arc
							(start -0.1778 -0.2794)
							(mid -0.249642 -0.249642)
							(end -0.2794 -0.1778)
						)
						(arc
							(start -0.2794 0.1778)
							(mid -0.249642 0.249642)
							(end -0.1778 0.2794)
						)
						(arc
							(start 0.1778 0.2794)
							(mid 0.249642 0.249642)
							(end 0.2794 0.1778)
						)
						(arc
							(start 0.2794 -0.1778)
							(mid 0.249642 -0.249642)
							(end 0.1778 -0.2794)
						)
					)
					(width 0)
					(fill yes)
				)
			)
		)
	)
	(footprint ""
		(layer "F.Cu")
		(at 318.516 -176.276)
		(property "Reference" "C189"
			(at 0 0 0)
			(layer "F.SilkS")
			(hide yes)
			(effects
				(font
					(size 1.27 1.27)
				)
			)
		)
		(property "Value" "SCD1U16V2KX-3GP"
			(at 1.1811 -2.7051 0)
			(unlocked yes)
			(layer "F.Fab")
			(hide yes)
			(effects
				(font
					(size 1.016 1.016)
					(thickness 0.1524)
				)
			)
		)
		(property "Device Type" "C402H22"
			(at 1.1811 -4.2291 0)
			(unlocked yes)
			(layer "F.Fab")
			(hide yes)
			(effects
				(font
					(size 1.016 1.016)
					(thickness 0.1524)
				)
			)
		)
		(duplicate_pad_numbers_are_jumpers no)
		(fp_rect
			(start -0.4318 0.9525)
			(end 0.4318 -0.9525)
			(stroke
				(width 0)
				(type default)
			)
			(fill no)
			(layer "F.CrtYd")
		)
		(fp_rect
			(start -0.4318 0.9525)
			(end 0.4318 -0.9525)
			(stroke
				(width 0)
				(type default)
			)
			(fill no)
			(layer "F.Fab")
		)
		(pad "1" smd custom
			(at 0 -0.4445)
			(size 0.1524 0.1524)
			(layers "F.Cu" "F.Mask" "F.Paste")
			(net "ADCAV33")
			(options
				(clearance outline)
				(anchor circle)
			)
			(primitives
				(gr_poly
					(pts
						(arc
							(start 0.3048 -0.2032)
							(mid 0.275042 -0.275042)
							(end 0.2032 -0.3048)
						)
						(arc
							(start -0.2032 -0.3048)
							(mid -0.275042 -0.275042)
							(end -0.3048 -0.2032)
						)
						(arc
							(start -0.3048 0.2032)
							(mid -0.275042 0.275042)
							(end -0.2032 0.3048)
						)
						(arc
							(start 0.2032 0.3048)
							(mid 0.275042 0.275042)
							(end 0.3048 0.2032)
						)
					)
					(width 0)
					(fill yes)
				)
			)
		)
		(pad "2" smd custom
			(at 0 0.4445)
			(size 0.1524 0.1524)
			(layers "F.Cu" "F.Mask" "F.Paste")
			(net "ADCVREFFP")
			(options
				(clearance outline)
				(anchor circle)
			)
			(primitives
				(gr_poly
					(pts
						(arc
							(start 0.3048 -0.2032)
							(mid 0.275042 -0.275042)
							(end 0.2032 -0.3048)
						)
						(arc
							(start -0.2032 -0.3048)
							(mid -0.275042 -0.275042)
							(end -0.3048 -0.2032)
						)
						(arc
							(start -0.3048 0.2032)
							(mid -0.275042 0.275042)
							(end -0.2032 0.3048)
						)
						(arc
							(start 0.2032 0.3048)
							(mid 0.275042 0.275042)
							(end 0.3048 0.2032)
						)
					)
					(width 0)
					(fill yes)
				)
			)
		)
	)
	(footprint ""
		(layer "F.Cu")
		(at 89.29497 -112.014 180)
		(property "Reference" "SC1238"
			(at 0 0 180)
			(layer "F.SilkS")
			(hide yes)
			(effects
				(font
					(size 1.27 1.27)
				)
			)
		)
		(property "Value" "SCD1U6D3V1KX-GP"
			(at -2.8321 -1.7399 180)
			(unlocked yes)
			(layer "F.Fab")
			(hide yes)
			(effects
				(font
					(size 1.016 1.016)
					(thickness 0.1524)
				)
			)
		)
		(property "Device Type" "C0201H13"
			(at -2.8321 -3.2639 180)
			(unlocked yes)
			(layer "F.Fab")
			(hide yes)
			(effects
				(font
					(size 1.016 1.016)
					(thickness 0.1524)
				)
			)
		)
		(duplicate_pad_numbers_are_jumpers no)
		(fp_rect
			(start -0.2794 0.6477)
			(end 0.2794 -0.6477)
			(stroke
				(width 0)
				(type default)
			)
			(fill no)
			(layer "F.CrtYd")
		)
		(fp_rect
			(start -0.2794 0.6477)
			(end 0.2794 -0.6477)
			(stroke
				(width 0)
				(type default)
			)
			(fill no)
			(layer "F.Fab")
		)
		(pad "1" smd custom
			(at 0 -0.2794 180)
			(size 0.0762 0.0762)
			(layers "F.Cu" "F.Mask" "F.Paste")
			(net "P1V8_E")
			(options
				(clearance outline)
				(anchor circle)
			)
			(primitives
				(gr_poly
					(pts
						(arc
							(start 0.1524 -0.127)
							(mid 0.137521 -0.162921)
							(end 0.1016 -0.1778)
						)
						(arc
							(start -0.1016 -0.1778)
							(mid -0.137521 -0.162921)
							(end -0.1524 -0.127)
						)
						(arc
							(start -0.1524 0.127)
							(mid -0.137521 0.162921)
							(end -0.1016 0.1778)
						)
						(arc
							(start 0.1016 0.1778)
							(mid 0.137521 0.162921)
							(end 0.1524 0.127)
						)
					)
					(width 0)
					(fill yes)
				)
			)
		)
		(pad "2" smd custom
			(at 0 0.2794 180)
			(size 0.0762 0.0762)
			(layers "F.Cu" "F.Mask" "F.Paste")
			(net "GND")
			(options
				(clearance outline)
				(anchor circle)
			)
			(primitives
				(gr_poly
					(pts
						(arc
							(start 0.1524 -0.127)
							(mid 0.137521 -0.162921)
							(end 0.1016 -0.1778)
						)
						(arc
							(start -0.1016 -0.1778)
							(mid -0.137521 -0.162921)
							(end -0.1524 -0.127)
						)
						(arc
							(start -0.1524 0.127)
							(mid -0.137521 0.162921)
							(end -0.1016 0.1778)
						)
						(arc
							(start 0.1016 0.1778)
							(mid 0.137521 0.162921)
							(end 0.1524 0.127)
						)
					)
					(width 0)
					(fill yes)
				)
			)
		)
	)
	(footprint ""
		(layer "F.Cu")
		(at 326.263 -80.391)
		(property "Reference" "R486"
			(at 0 0 0)
			(layer "F.SilkS")
			(hide yes)
			(effects
				(font
					(size 1.27 1.27)
				)
			)
		)
		(property "Value" "2K2R2J-2-GP"
			(at 0.064008 -3.993896 0)
			(unlocked yes)
			(layer "F.Fab")
			(hide yes)
			(effects
				(font
					(size 1.016 1.016)
					(thickness 0.1524)
				)
			)
		)
		(property "Device Type" "R402H16"
			(at 0.064008 -5.517896 0)
			(unlocked yes)
			(layer "F.Fab")
			(hide yes)
			(effects
				(font
					(size 1.016 1.016)
					(thickness 0.1524)
				)
			)
		)
		(duplicate_pad_numbers_are_jumpers no)
		(fp_line
			(start -0.508 -0.9398)
			(end -0.508 0.9398)
			(stroke
				(width 0.1524)
				(type default)
			)
			(layer "F.SilkS")
		)
		(fp_line
			(start 0.508 -0.9398)
			(end -0.508 -0.9398)
			(stroke
				(width 0.1524)
				(type default)
			)
			(layer "F.SilkS")
		)
		(fp_rect
			(start -0.508 0.9398)
			(end 0.508 -0.9398)
			(stroke
				(width 0)
				(type default)
			)
			(fill no)
			(layer "F.CrtYd")
		)
		(fp_rect
			(start -0.508 0.9398)
			(end 0.508 -0.9398)
			(stroke
				(width 0)
				(type default)
			)
			(fill no)
			(layer "F.Fab")
		)
		(pad "1" smd custom
			(at 0 -0.4445)
			(size 0.1397 0.1397)
			(layers "F.Cu" "F.Mask" "F.Paste")
			(net "P3V3_STBY")
			(options
				(clearance outline)
				(anchor circle)
			)
			(primitives
				(gr_poly
					(pts
						(arc
							(start -0.1778 -0.2794)
							(mid -0.249642 -0.249642)
							(end -0.2794 -0.1778)
						)
						(arc
							(start -0.2794 0.1778)
							(mid -0.249642 0.249642)
							(end -0.1778 0.2794)
						)
						(arc
							(start 0.1778 0.2794)
							(mid 0.249642 0.249642)
							(end 0.2794 0.1778)
						)
						(arc
							(start 0.2794 -0.1778)
							(mid 0.249642 -0.249642)
							(end 0.1778 -0.2794)
						)
					)
					(width 0)
					(fill yes)
				)
			)
		)
		(pad "2" smd custom
			(at 0 0.4445)
			(size 0.1397 0.1397)
			(layers "F.Cu" "F.Mask" "F.Paste")
			(net "FLA_CS_1")
			(options
				(clearance outline)
				(anchor circle)
			)
			(primitives
				(gr_poly
					(pts
						(arc
							(start -0.1778 -0.2794)
							(mid -0.249642 -0.249642)
							(end -0.2794 -0.1778)
						)
						(arc
							(start -0.2794 0.1778)
							(mid -0.249642 0.249642)
							(end -0.1778 0.2794)
						)
						(arc
							(start 0.1778 0.2794)
							(mid 0.249642 0.249642)
							(end 0.2794 0.1778)
						)
						(arc
							(start 0.2794 -0.1778)
							(mid 0.249642 -0.249642)
							(end 0.1778 -0.2794)
						)
					)
					(width 0)
					(fill yes)
				)
			)
		)
	)
	(footprint ""
		(layer "F.Cu")
		(at 96.882966 -60.325)
		(property "Reference" "STP30"
			(at 0 0 0)
			(layer "F.SilkS")
			(hide yes)
			(effects
				(font
					(size 1.27 1.27)
				)
			)
		)
		(property "Value" "TPAD28"
			(at 0.0127 -1.8034 0)
			(unlocked yes)
			(layer "F.Fab")
			(hide yes)
			(effects
				(font
					(size 1.016 1.016)
					(thickness 0.1524)
				)
			)
		)
		(property "Device Type" "TPAD28"
			(at 0.0127 -3.3274 0)
			(unlocked yes)
			(layer "F.Fab")
			(hide yes)
			(effects
				(font
					(size 1.016 1.016)
					(thickness 0.1524)
				)
			)
		)
		(duplicate_pad_numbers_are_jumpers no)
		(fp_poly
			(pts
				(arc
					(start 0.3556 0)
					(mid -0.3556 0)
					(end 0.3556 0)
				)
			)
			(stroke
				(width 0)
				(type default)
			)
			(fill no)
			(layer "F.CrtYd")
		)
		(fp_poly
			(pts
				(arc
					(start 0.6096 0)
					(mid -0.6096 0)
					(end 0.6096 0)
				)
			)
			(stroke
				(width 0)
				(type default)
			)
			(fill no)
			(layer "F.Fab")
		)
		(pad "1" smd circle
			(at 0 0)
			(size 0.7112 0.7112)
			(layers "F.Cu" "F.Mask" "F.Paste")
			(net "ICE0_TCK")
		)
	)
	(footprint ""
		(layer "F.Cu")
		(at 254.762 -122.555)
		(property "Reference" "R7908"
			(at 0 0 0)
			(layer "F.SilkS")
			(hide yes)
			(effects
				(font
					(size 1.27 1.27)
				)
			)
		)
		(property "Value" "0R2J-2-GP"
			(at 0.064008 -3.993896 0)
			(unlocked yes)
			(layer "F.Fab")
			(hide yes)
			(effects
				(font
					(size 1.016 1.016)
					(thickness 0.1524)
				)
			)
		)
		(property "Device Type" "R402H16"
			(at 0.064008 -5.517896 0)
			(unlocked yes)
			(layer "F.Fab")
			(hide yes)
			(effects
				(font
					(size 1.016 1.016)
					(thickness 0.1524)
				)
			)
		)
		(duplicate_pad_numbers_are_jumpers no)
		(fp_line
			(start -0.508 -0.9398)
			(end -0.508 0.9398)
			(stroke
				(width 0.1524)
				(type default)
			)
			(layer "F.SilkS")
		)
		(fp_line
			(start 0.508 -0.9398)
			(end -0.508 -0.9398)
			(stroke
				(width 0.1524)
				(type default)
			)
			(layer "F.SilkS")
		)
		(fp_rect
			(start -0.508 0.9398)
			(end 0.508 -0.9398)
			(stroke
				(width 0)
				(type default)
			)
			(fill no)
			(layer "F.CrtYd")
		)
		(fp_rect
			(start -0.508 0.9398)
			(end 0.508 -0.9398)
			(stroke
				(width 0)
				(type default)
			)
			(fill no)
			(layer "F.Fab")
		)
		(pad "1" smd custom
			(at 0 -0.4445)
			(size 0.1397 0.1397)
			(layers "F.Cu" "F.Mask" "F.Paste")
			(net "CPU_U192_PIN3_RX")
			(options
				(clearance outline)
				(anchor circle)
			)
			(primitives
				(gr_poly
					(pts
						(arc
							(start -0.1778 -0.2794)
							(mid -0.249642 -0.249642)
							(end -0.2794 -0.1778)
						)
						(arc
							(start -0.2794 0.1778)
							(mid -0.249642 0.249642)
							(end -0.1778 0.2794)
						)
						(arc
							(start 0.1778 0.2794)
							(mid 0.249642 0.249642)
							(end 0.2794 0.1778)
						)
						(arc
							(start 0.2794 -0.1778)
							(mid 0.249642 -0.249642)
							(end 0.1778 -0.2794)
						)
					)
					(width 0)
					(fill yes)
				)
			)
		)
		(pad "2" smd custom
			(at 0 0.4445)
			(size 0.1397 0.1397)
			(layers "F.Cu" "F.Mask" "F.Paste")
			(net "CPU_U192_PIN3_RX_R")
			(options
				(clearance outline)
				(anchor circle)
			)
			(primitives
				(gr_poly
					(pts
						(arc
							(start -0.1778 -0.2794)
							(mid -0.249642 -0.249642)
							(end -0.2794 -0.1778)
						)
						(arc
							(start -0.2794 0.1778)
							(mid -0.249642 0.249642)
							(end -0.1778 0.2794)
						)
						(arc
							(start 0.1778 0.2794)
							(mid 0.249642 0.249642)
							(end 0.2794 0.1778)
						)
						(arc
							(start 0.2794 -0.1778)
							(mid 0.249642 -0.249642)
							(end 0.1778 -0.2794)
						)
					)
					(width 0)
					(fill yes)
				)
			)
		)
	)
	(footprint ""
		(layer "F.Cu")
		(at 318.893952 -56.261 -90)
		(property "Reference" "R210"
			(at 0 0 270)
			(layer "F.SilkS")
			(hide yes)
			(effects
				(font
					(size 1.27 1.27)
				)
			)
		)
		(property "Value" "0R2J-2-GP"
			(at 0.064008 -3.993896 270)
			(unlocked yes)
			(layer "F.Fab")
			(hide yes)
			(effects
				(font
					(size 1.016 1.016)
					(thickness 0.1524)
				)
			)
		)
		(property "Device Type" "R402H16"
			(at 0.064008 -5.517896 270)
			(unlocked yes)
			(layer "F.Fab")
			(hide yes)
			(effects
				(font
					(size 1.016 1.016)
					(thickness 0.1524)
				)
			)
		)
		(duplicate_pad_numbers_are_jumpers no)
		(fp_line
			(start -0.508 -0.9398)
			(end -0.508 0.9398)
			(stroke
				(width 0.1524)
				(type default)
			)
			(layer "F.SilkS")
		)
		(fp_line
			(start 0.508 -0.9398)
			(end -0.508 -0.9398)
			(stroke
				(width 0.1524)
				(type default)
			)
			(layer "F.SilkS")
		)
		(fp_rect
			(start -0.508 0.9398)
			(end 0.508 -0.9398)
			(stroke
				(width 0)
				(type default)
			)
			(fill no)
			(layer "F.CrtYd")
		)
		(fp_rect
			(start -0.508 0.9398)
			(end 0.508 -0.9398)
			(stroke
				(width 0)
				(type default)
			)
			(fill no)
			(layer "F.Fab")
		)
		(pad "1" smd custom
			(at 0 -0.4445 270)
			(size 0.1397 0.1397)
			(layers "F.Cu" "F.Mask" "F.Paste")
			(net "NCSI_10G_RCSDV")
			(options
				(clearance outline)
				(anchor circle)
			)
			(primitives
				(gr_poly
					(pts
						(arc
							(start -0.1778 -0.2794)
							(mid -0.249642 -0.249642)
							(end -0.2794 -0.1778)
						)
						(arc
							(start -0.2794 0.1778)
							(mid -0.249642 0.249642)
							(end -0.1778 0.2794)
						)
						(arc
							(start 0.1778 0.2794)
							(mid 0.249642 0.249642)
							(end 0.2794 0.1778)
						)
						(arc
							(start 0.2794 -0.1778)
							(mid 0.249642 -0.249642)
							(end 0.1778 -0.2794)
						)
					)
					(width 0)
					(fill yes)
				)
			)
		)
		(pad "2" smd custom
			(at 0 0.4445 270)
			(size 0.1397 0.1397)
			(layers "F.Cu" "F.Mask" "F.Paste")
			(net "NCSI_10G_RCSDV_R")
			(options
				(clearance outline)
				(anchor circle)
			)
			(primitives
				(gr_poly
					(pts
						(arc
							(start -0.1778 -0.2794)
							(mid -0.249642 -0.249642)
							(end -0.2794 -0.1778)
						)
						(arc
							(start -0.2794 0.1778)
							(mid -0.249642 0.249642)
							(end -0.1778 0.2794)
						)
						(arc
							(start 0.1778 0.2794)
							(mid 0.249642 0.249642)
							(end 0.2794 0.1778)
						)
						(arc
							(start 0.2794 -0.1778)
							(mid 0.249642 -0.249642)
							(end 0.1778 -0.2794)
						)
					)
					(width 0)
					(fill yes)
				)
			)
		)
	)
	(footprint ""
		(layer "F.Cu")
		(at 180.721 -145.288 -90)
		(property "Reference" "SR919"
			(at 0 0 270)
			(layer "F.SilkS")
			(hide yes)
			(effects
				(font
					(size 1.27 1.27)
				)
			)
		)
		(property "Value" "200KR2F-L-GP"
			(at 0.064008 -3.993896 270)
			(unlocked yes)
			(layer "F.Fab")
			(hide yes)
			(effects
				(font
					(size 1.016 1.016)
					(thickness 0.1524)
				)
			)
		)
		(property "Device Type" "R402H16"
			(at 0.064008 -5.517896 270)
			(unlocked yes)
			(layer "F.Fab")
			(hide yes)
			(effects
				(font
					(size 1.016 1.016)
					(thickness 0.1524)
				)
			)
		)
		(duplicate_pad_numbers_are_jumpers no)
		(fp_line
			(start -0.508 -0.9398)
			(end -0.508 0.9398)
			(stroke
				(width 0.1524)
				(type default)
			)
			(layer "F.SilkS")
		)
		(fp_line
			(start 0.508 -0.9398)
			(end -0.508 -0.9398)
			(stroke
				(width 0.1524)
				(type default)
			)
			(layer "F.SilkS")
		)
		(fp_rect
			(start -0.508 0.9398)
			(end 0.508 -0.9398)
			(stroke
				(width 0)
				(type default)
			)
			(fill no)
			(layer "F.CrtYd")
		)
		(fp_rect
			(start -0.508 0.9398)
			(end 0.508 -0.9398)
			(stroke
				(width 0)
				(type default)
			)
			(fill no)
			(layer "F.Fab")
		)
		(pad "1" smd custom
			(at 0 -0.4445 270)
			(size 0.1397 0.1397)
			(layers "F.Cu" "F.Mask" "F.Paste")
			(net "EXP_I2C_VREF_3")
			(options
				(clearance outline)
				(anchor circle)
			)
			(primitives
				(gr_poly
					(pts
						(arc
							(start -0.1778 -0.2794)
							(mid -0.249642 -0.249642)
							(end -0.2794 -0.1778)
						)
						(arc
							(start -0.2794 0.1778)
							(mid -0.249642 0.249642)
							(end -0.1778 0.2794)
						)
						(arc
							(start 0.1778 0.2794)
							(mid 0.249642 0.249642)
							(end 0.2794 0.1778)
						)
						(arc
							(start 0.2794 -0.1778)
							(mid 0.249642 -0.249642)
							(end 0.1778 -0.2794)
						)
					)
					(width 0)
					(fill yes)
				)
			)
		)
		(pad "2" smd custom
			(at 0 0.4445 270)
			(size 0.1397 0.1397)
			(layers "F.Cu" "F.Mask" "F.Paste")
			(net "P3V3_STBY")
			(options
				(clearance outline)
				(anchor circle)
			)
			(primitives
				(gr_poly
					(pts
						(arc
							(start -0.1778 -0.2794)
							(mid -0.249642 -0.249642)
							(end -0.2794 -0.1778)
						)
						(arc
							(start -0.2794 0.1778)
							(mid -0.249642 0.249642)
							(end -0.1778 0.2794)
						)
						(arc
							(start 0.1778 0.2794)
							(mid 0.249642 0.249642)
							(end 0.2794 0.1778)
						)
						(arc
							(start 0.2794 -0.1778)
							(mid 0.249642 -0.249642)
							(end 0.1778 -0.2794)
						)
					)
					(width 0)
					(fill yes)
				)
			)
		)
	)
	(footprint ""
		(layer "F.Cu")
		(at 266.065 -181.102 -90)
		(property "Reference" "R523"
			(at 0 0 270)
			(layer "F.SilkS")
			(hide yes)
			(effects
				(font
					(size 1.27 1.27)
				)
			)
		)
		(property "Value" "0R2J-2-GP"
			(at 0.064008 -3.993896 270)
			(unlocked yes)
			(layer "F.Fab")
			(hide yes)
			(effects
				(font
					(size 1.016 1.016)
					(thickness 0.1524)
				)
			)
		)
		(property "Device Type" "R402H16"
			(at 0.064008 -5.517896 270)
			(unlocked yes)
			(layer "F.Fab")
			(hide yes)
			(effects
				(font
					(size 1.016 1.016)
					(thickness 0.1524)
				)
			)
		)
		(duplicate_pad_numbers_are_jumpers no)
		(fp_line
			(start -0.508 -0.9398)
			(end -0.508 0.9398)
			(stroke
				(width 0.1524)
				(type default)
			)
			(layer "F.SilkS")
		)
		(fp_line
			(start 0.508 -0.9398)
			(end -0.508 -0.9398)
			(stroke
				(width 0.1524)
				(type default)
			)
			(layer "F.SilkS")
		)
		(fp_rect
			(start -0.508 0.9398)
			(end 0.508 -0.9398)
			(stroke
				(width 0)
				(type default)
			)
			(fill no)
			(layer "F.CrtYd")
		)
		(fp_rect
			(start -0.508 0.9398)
			(end 0.508 -0.9398)
			(stroke
				(width 0)
				(type default)
			)
			(fill no)
			(layer "F.Fab")
		)
		(pad "1" smd custom
			(at 0 -0.4445 270)
			(size 0.1397 0.1397)
			(layers "F.Cu" "F.Mask" "F.Paste")
			(net "EXP_TRAY_ID_BMC")
			(options
				(clearance outline)
				(anchor circle)
			)
			(primitives
				(gr_poly
					(pts
						(arc
							(start -0.1778 -0.2794)
							(mid -0.249642 -0.249642)
							(end -0.2794 -0.1778)
						)
						(arc
							(start -0.2794 0.1778)
							(mid -0.249642 0.249642)
							(end -0.1778 0.2794)
						)
						(arc
							(start 0.1778 0.2794)
							(mid 0.249642 0.249642)
							(end 0.2794 0.1778)
						)
						(arc
							(start 0.2794 -0.1778)
							(mid 0.249642 -0.249642)
							(end 0.1778 -0.2794)
						)
					)
					(width 0)
					(fill yes)
				)
			)
		)
		(pad "2" smd custom
			(at 0 0.4445 270)
			(size 0.1397 0.1397)
			(layers "F.Cu" "F.Mask" "F.Paste")
			(net "EXP_TRAY_ID")
			(options
				(clearance outline)
				(anchor circle)
			)
			(primitives
				(gr_poly
					(pts
						(arc
							(start -0.1778 -0.2794)
							(mid -0.249642 -0.249642)
							(end -0.2794 -0.1778)
						)
						(arc
							(start -0.2794 0.1778)
							(mid -0.249642 0.249642)
							(end -0.1778 0.2794)
						)
						(arc
							(start 0.1778 0.2794)
							(mid 0.249642 0.249642)
							(end 0.2794 0.1778)
						)
						(arc
							(start 0.2794 -0.1778)
							(mid 0.249642 -0.249642)
							(end 0.1778 -0.2794)
						)
					)
					(width 0)
					(fill yes)
				)
			)
		)
	)
	(footprint ""
		(layer "F.Cu")
		(at 118.12397 -79.629)
		(property "Reference" "STP113"
			(at 0 0 0)
			(layer "F.SilkS")
			(hide yes)
			(effects
				(font
					(size 1.27 1.27)
				)
			)
		)
		(property "Value" "TPAD28"
			(at 0.0127 -1.8034 0)
			(unlocked yes)
			(layer "F.Fab")
			(hide yes)
			(effects
				(font
					(size 1.016 1.016)
					(thickness 0.1524)
				)
			)
		)
		(property "Device Type" "TPAD28"
			(at 0.0127 -3.3274 0)
			(unlocked yes)
			(layer "F.Fab")
			(hide yes)
			(effects
				(font
					(size 1.016 1.016)
					(thickness 0.1524)
				)
			)
		)
		(duplicate_pad_numbers_are_jumpers no)
		(fp_poly
			(pts
				(arc
					(start 0.3556 0)
					(mid -0.3556 0)
					(end 0.3556 0)
				)
			)
			(stroke
				(width 0)
				(type default)
			)
			(fill no)
			(layer "F.CrtYd")
		)
		(fp_poly
			(pts
				(arc
					(start 0.6096 0)
					(mid -0.6096 0)
					(end 0.6096 0)
				)
			)
			(stroke
				(width 0)
				(type default)
			)
			(fill no)
			(layer "F.Fab")
		)
		(pad "1" smd circle
			(at 0 0)
			(size 0.7112 0.7112)
			(layers "F.Cu" "F.Mask" "F.Paste")
			(net "TEST_MUX_46")
		)
	)
	(footprint ""
		(layer "F.Cu")
		(at 253.619 -132.08)
		(property "Reference" "U193"
			(at 0 0 0)
			(layer "F.SilkS")
			(hide yes)
			(effects
				(font
					(size 1.27 1.27)
				)
			)
		)
		(property "Value" "74HC2G125DP-GP"
			(at 0 -9.0932 0)
			(unlocked yes)
			(layer "F.Fab")
			(hide yes)
			(effects
				(font
					(size 1.016 1.016)
					(thickness 0.1524)
				)
			)
		)
		(property "Device Type" "SSOIC8H44"
			(at 0 -10.6172 0)
			(unlocked yes)
			(layer "F.Fab")
			(hide yes)
			(effects
				(font
					(size 1.016 1.016)
					(thickness 0.1524)
				)
			)
		)
		(duplicate_pad_numbers_are_jumpers no)
		(fp_line
			(start -1.7018 -0.5842)
			(end -1.7018 0.5842)
			(stroke
				(width 0.1524)
				(type default)
			)
			(layer "F.SilkS")
		)
		(fp_line
			(start -1.7018 -0.5842)
			(end 1.0668 -0.5842)
			(stroke
				(width 0.1524)
				(type default)
			)
			(layer "F.SilkS")
		)
		(fp_line
			(start -1.524 0.5842)
			(end -1.524 2.286)
			(stroke
				(width 0.508)
				(type default)
			)
			(layer "F.SilkS")
		)
		(fp_line
			(start -1.397 0)
			(end -1.7018 -0.3048)
			(stroke
				(width 0.1524)
				(type default)
			)
			(layer "F.SilkS")
		)
		(fp_line
			(start -1.397 0)
			(end -1.7018 0.3048)
			(stroke
				(width 0.1524)
				(type default)
			)
			(layer "F.SilkS")
		)
		(fp_line
			(start 1.0668 -0.5842)
			(end 1.0668 0.5842)
			(stroke
				(width 0.1524)
				(type default)
			)
			(layer "F.SilkS")
		)
		(fp_line
			(start 1.0668 0.5842)
			(end -1.7018 0.5842)
			(stroke
				(width 0.1524)
				(type default)
			)
			(layer "F.SilkS")
		)
		(fp_poly
			(pts
				(xy -1.1684 0.5842) (xy 1.0668 0.5842) (xy 1.0668 -0.5842) (xy -1.1684 -0.5842)
			)
			(stroke
				(width 0)
				(type default)
			)
			(fill yes)
			(layer "F.SilkS")
		)
		(fp_rect
			(start -1.778 2.54)
			(end 1.778 -2.54)
			(stroke
				(width 0)
				(type default)
			)
			(fill no)
			(layer "F.CrtYd")
		)
		(fp_poly
			(pts
				(xy -1.778 -2.54) (xy 1.778 -2.54) (xy 1.778 2.54) (xy -1.778 2.54)
			)
			(stroke
				(width 0)
				(type default)
			)
			(fill no)
			(layer "F.Fab")
		)
		(pad "1" smd rect
			(at -0.97536 1.6256)
			(size 0.3556 1.524)
			(layers "F.Cu" "F.Mask" "F.Paste")
			(net "DEBUG_OE_2_N")
		)
		(pad "2" smd rect
			(at -0.32512 1.6256)
			(size 0.3556 1.524)
			(layers "F.Cu" "F.Mask" "F.Paste")
			(net "CPU_U193_PIN2_TX")
		)
		(pad "3" smd rect
			(at 0.32512 1.6256)
			(size 0.3556 1.524)
			(layers "F.Cu" "F.Mask" "F.Paste")
			(net "CPU_U193_PIN3_RX")
		)
		(pad "4" smd rect
			(at 0.97536 1.6256)
			(size 0.3556 1.524)
			(layers "F.Cu" "F.Mask" "F.Paste")
			(net "GND")
		)
		(pad "5" smd rect
			(at 0.97536 -1.6256)
			(size 0.3556 1.524)
			(layers "F.Cu" "F.Mask" "F.Paste")
			(net "CPU_U193_PIN5_TX")
		)
		(pad "6" smd rect
			(at 0.32512 -1.6256)
			(size 0.3556 1.524)
			(layers "F.Cu" "F.Mask" "F.Paste")
			(net "CPU_U193_PIN6_RX")
		)
		(pad "7" smd rect
			(at -0.32512 -1.6256)
			(size 0.3556 1.524)
			(layers "F.Cu" "F.Mask" "F.Paste")
			(net "DEBUG_OE_2_N")
		)
		(pad "8" smd rect
			(at -0.97536 -1.6256)
			(size 0.3556 1.524)
			(layers "F.Cu" "F.Mask" "F.Paste")
			(net "P3V3_STBY")
		)
	)
	(footprint ""
		(layer "F.Cu")
		(at 274.828 -104.648 90)
		(property "Reference" "PC192"
			(at 0 0 90)
			(layer "F.SilkS")
			(hide yes)
			(effects
				(font
					(size 1.27 1.27)
				)
			)
		)
		(property "Value" "SCD47U25V3KX-3-GP"
			(at 0 -2.8194 90)
			(unlocked yes)
			(layer "F.Fab")
			(hide yes)
			(effects
				(font
					(size 1.016 1.016)
					(thickness 0.1524)
				)
			)
		)
		(property "Device Type" "C603H36"
			(at 0 -4.3434 90)
			(unlocked yes)
			(layer "F.Fab")
			(hide yes)
			(effects
				(font
					(size 1.016 1.016)
					(thickness 0.1524)
				)
			)
		)
		(duplicate_pad_numbers_are_jumpers no)
		(fp_line
			(start 0.508 0)
			(end -0.508 0)
			(stroke
				(width 0.2032)
				(type default)
			)
			(layer "F.SilkS")
		)
		(fp_rect
			(start -0.5842 1.3335)
			(end 0.5842 -1.3335)
			(stroke
				(width 0)
				(type default)
			)
			(fill no)
			(layer "F.CrtYd")
		)
		(fp_rect
			(start -0.5842 1.3335)
			(end 0.5842 -1.3335)
			(stroke
				(width 0)
				(type default)
			)
			(fill no)
			(layer "F.Fab")
		)
		(pad "1" smd custom
			(at 0 -0.762 90)
			(size 0.2159 0.2159)
			(layers "F.Cu" "F.Mask" "F.Paste")
			(net "P1V8_C_EN_LV")
			(options
				(clearance outline)
				(anchor circle)
			)
			(primitives
				(gr_poly
					(pts
						(arc
							(start -0.3302 -0.4318)
							(mid -0.402042 -0.402042)
							(end -0.4318 -0.3302)
						)
						(arc
							(start -0.4318 0.3302)
							(mid -0.402042 0.402042)
							(end -0.3302 0.4318)
						)
						(arc
							(start 0.3302 0.4318)
							(mid 0.402042 0.402042)
							(end 0.4318 0.3302)
						)
						(arc
							(start 0.4318 -0.3302)
							(mid 0.402042 -0.402042)
							(end 0.3302 -0.4318)
						)
					)
					(width 0)
					(fill yes)
				)
			)
		)
		(pad "2" smd custom
			(at 0 0.762 90)
			(size 0.2159 0.2159)
			(layers "F.Cu" "F.Mask" "F.Paste")
			(net "P1V8_C")
			(options
				(clearance outline)
				(anchor circle)
			)
			(primitives
				(gr_poly
					(pts
						(arc
							(start -0.3302 -0.4318)
							(mid -0.402042 -0.402042)
							(end -0.4318 -0.3302)
						)
						(arc
							(start -0.4318 0.3302)
							(mid -0.402042 0.402042)
							(end -0.3302 0.4318)
						)
						(arc
							(start 0.3302 0.4318)
							(mid 0.402042 0.402042)
							(end 0.4318 0.3302)
						)
						(arc
							(start 0.4318 -0.3302)
							(mid 0.402042 -0.402042)
							(end 0.3302 -0.4318)
						)
					)
					(width 0)
					(fill yes)
				)
			)
		)
	)
	(footprint ""
		(layer "F.Cu")
		(at 114.497612 -221.996 180)
		(property "Reference" "SR880"
			(at 0 0 180)
			(layer "F.SilkS")
			(hide yes)
			(effects
				(font
					(size 1.27 1.27)
				)
			)
		)
		(property "Value" "0R2J-2-GP"
			(at 0.064008 -3.993896 180)
			(unlocked yes)
			(layer "F.Fab")
			(hide yes)
			(effects
				(font
					(size 1.016 1.016)
					(thickness 0.1524)
				)
			)
		)
		(property "Device Type" "R402H16"
			(at 0.064008 -5.517896 180)
			(unlocked yes)
			(layer "F.Fab")
			(hide yes)
			(effects
				(font
					(size 1.016 1.016)
					(thickness 0.1524)
				)
			)
		)
		(duplicate_pad_numbers_are_jumpers no)
		(fp_line
			(start 0.508 -0.9398)
			(end -0.508 -0.9398)
			(stroke
				(width 0.1524)
				(type default)
			)
			(layer "F.SilkS")
		)
		(fp_line
			(start -0.508 -0.9398)
			(end -0.508 0.9398)
			(stroke
				(width 0.1524)
				(type default)
			)
			(layer "F.SilkS")
		)
		(fp_rect
			(start -0.508 0.9398)
			(end 0.508 -0.9398)
			(stroke
				(width 0)
				(type default)
			)
			(fill no)
			(layer "F.CrtYd")
		)
		(fp_rect
			(start -0.508 0.9398)
			(end 0.508 -0.9398)
			(stroke
				(width 0)
				(type default)
			)
			(fill no)
			(layer "F.Fab")
		)
		(pad "1" smd custom
			(at 0 -0.4445 180)
			(size 0.1397 0.1397)
			(layers "F.Cu" "F.Mask" "F.Paste")
			(net "REDV_TX8_P")
			(options
				(clearance outline)
				(anchor circle)
			)
			(primitives
				(gr_poly
					(pts
						(arc
							(start -0.1778 -0.2794)
							(mid -0.249642 -0.249642)
							(end -0.2794 -0.1778)
						)
						(arc
							(start -0.2794 0.1778)
							(mid -0.249642 0.249642)
							(end -0.1778 0.2794)
						)
						(arc
							(start 0.1778 0.2794)
							(mid 0.249642 0.249642)
							(end 0.2794 0.1778)
						)
						(arc
							(start 0.2794 -0.1778)
							(mid 0.249642 -0.249642)
							(end 0.1778 -0.2794)
						)
					)
					(width 0)
					(fill yes)
				)
			)
		)
		(pad "2" smd custom
			(at 0 0.4445 180)
			(size 0.1397 0.1397)
			(layers "F.Cu" "F.Mask" "F.Paste")
			(net "SAS_HDD_CONN_TX8_P")
			(options
				(clearance outline)
				(anchor circle)
			)
			(primitives
				(gr_poly
					(pts
						(arc
							(start -0.1778 -0.2794)
							(mid -0.249642 -0.249642)
							(end -0.2794 -0.1778)
						)
						(arc
							(start -0.2794 0.1778)
							(mid -0.249642 0.249642)
							(end -0.1778 0.2794)
						)
						(arc
							(start 0.1778 0.2794)
							(mid 0.249642 0.249642)
							(end 0.2794 0.1778)
						)
						(arc
							(start 0.2794 -0.1778)
							(mid 0.249642 -0.249642)
							(end 0.1778 -0.2794)
						)
					)
					(width 0)
					(fill yes)
				)
			)
		)
	)
	(footprint ""
		(layer "F.Cu")
		(at 200.533 -224.282 180)
		(property "Reference" "R2055"
			(at 0 0 180)
			(layer "F.SilkS")
			(hide yes)
			(effects
				(font
					(size 1.27 1.27)
				)
			)
		)
		(property "Value" "4K7R2F-GP"
			(at 0.064008 -3.993896 180)
			(unlocked yes)
			(layer "F.Fab")
			(hide yes)
			(effects
				(font
					(size 1.016 1.016)
					(thickness 0.1524)
				)
			)
		)
		(property "Device Type" "R402H16"
			(at 0.064008 -5.517896 180)
			(unlocked yes)
			(layer "F.Fab")
			(hide yes)
			(effects
				(font
					(size 1.016 1.016)
					(thickness 0.1524)
				)
			)
		)
		(duplicate_pad_numbers_are_jumpers no)
		(fp_line
			(start 0.508 -0.9398)
			(end -0.508 -0.9398)
			(stroke
				(width 0.1524)
				(type default)
			)
			(layer "F.SilkS")
		)
		(fp_line
			(start -0.508 -0.9398)
			(end -0.508 0.9398)
			(stroke
				(width 0.1524)
				(type default)
			)
			(layer "F.SilkS")
		)
		(fp_rect
			(start -0.508 0.9398)
			(end 0.508 -0.9398)
			(stroke
				(width 0)
				(type default)
			)
			(fill no)
			(layer "F.CrtYd")
		)
		(fp_rect
			(start -0.508 0.9398)
			(end 0.508 -0.9398)
			(stroke
				(width 0)
				(type default)
			)
			(fill no)
			(layer "F.Fab")
		)
		(pad "1" smd custom
			(at 0 -0.4445 180)
			(size 0.1397 0.1397)
			(layers "F.Cu" "F.Mask" "F.Paste")
			(net "FM_BMC_READY_N")
			(options
				(clearance outline)
				(anchor circle)
			)
			(primitives
				(gr_poly
					(pts
						(arc
							(start -0.1778 -0.2794)
							(mid -0.249642 -0.249642)
							(end -0.2794 -0.1778)
						)
						(arc
							(start -0.2794 0.1778)
							(mid -0.249642 0.249642)
							(end -0.1778 0.2794)
						)
						(arc
							(start 0.1778 0.2794)
							(mid 0.249642 0.249642)
							(end 0.2794 0.1778)
						)
						(arc
							(start 0.2794 -0.1778)
							(mid 0.249642 -0.249642)
							(end 0.1778 -0.2794)
						)
					)
					(width 0)
					(fill yes)
				)
			)
		)
		(pad "2" smd custom
			(at 0 0.4445 180)
			(size 0.1397 0.1397)
			(layers "F.Cu" "F.Mask" "F.Paste")
			(net "P3V3_STBY")
			(options
				(clearance outline)
				(anchor circle)
			)
			(primitives
				(gr_poly
					(pts
						(arc
							(start -0.1778 -0.2794)
							(mid -0.249642 -0.249642)
							(end -0.2794 -0.1778)
						)
						(arc
							(start -0.2794 0.1778)
							(mid -0.249642 0.249642)
							(end -0.1778 0.2794)
						)
						(arc
							(start 0.1778 0.2794)
							(mid 0.249642 0.249642)
							(end 0.2794 0.1778)
						)
						(arc
							(start 0.2794 -0.1778)
							(mid 0.249642 -0.249642)
							(end 0.1778 -0.2794)
						)
					)
					(width 0)
					(fill yes)
				)
			)
		)
	)
	(footprint ""
		(layer "F.Cu")
		(at 70.485 -227.965 180)
		(property "Reference" "R2114"
			(at 0 0 180)
			(layer "F.SilkS")
			(hide yes)
			(effects
				(font
					(size 1.27 1.27)
				)
			)
		)
		(property "Value" "0R2J-2-GP"
			(at 0.064008 -3.993896 180)
			(unlocked yes)
			(layer "F.Fab")
			(hide yes)
			(effects
				(font
					(size 1.016 1.016)
					(thickness 0.1524)
				)
			)
		)
		(property "Device Type" "R402H16"
			(at 0.064008 -5.517896 180)
			(unlocked yes)
			(layer "F.Fab")
			(hide yes)
			(effects
				(font
					(size 1.016 1.016)
					(thickness 0.1524)
				)
			)
		)
		(duplicate_pad_numbers_are_jumpers no)
		(fp_line
			(start 0.508 -0.9398)
			(end -0.508 -0.9398)
			(stroke
				(width 0.1524)
				(type default)
			)
			(layer "F.SilkS")
		)
		(fp_line
			(start -0.508 -0.9398)
			(end -0.508 0.9398)
			(stroke
				(width 0.1524)
				(type default)
			)
			(layer "F.SilkS")
		)
		(fp_rect
			(start -0.508 0.9398)
			(end 0.508 -0.9398)
			(stroke
				(width 0)
				(type default)
			)
			(fill no)
			(layer "F.CrtYd")
		)
		(fp_rect
			(start -0.508 0.9398)
			(end 0.508 -0.9398)
			(stroke
				(width 0)
				(type default)
			)
			(fill no)
			(layer "F.Fab")
		)
		(pad "1" smd custom
			(at 0 -0.4445 180)
			(size 0.1397 0.1397)
			(layers "F.Cu" "F.Mask" "F.Paste")
			(net "MB0_CM_GATE")
			(options
				(clearance outline)
				(anchor circle)
			)
			(primitives
				(gr_poly
					(pts
						(arc
							(start -0.1778 -0.2794)
							(mid -0.249642 -0.249642)
							(end -0.2794 -0.1778)
						)
						(arc
							(start -0.2794 0.1778)
							(mid -0.249642 0.249642)
							(end -0.1778 0.2794)
						)
						(arc
							(start 0.1778 0.2794)
							(mid 0.249642 0.249642)
							(end 0.2794 0.1778)
						)
						(arc
							(start 0.2794 -0.1778)
							(mid 0.249642 -0.249642)
							(end 0.1778 -0.2794)
						)
					)
					(width 0)
					(fill yes)
				)
			)
		)
		(pad "2" smd custom
			(at 0 0.4445 180)
			(size 0.1397 0.1397)
			(layers "F.Cu" "F.Mask" "F.Paste")
			(net "MB0_CM_GATE_R")
			(options
				(clearance outline)
				(anchor circle)
			)
			(primitives
				(gr_poly
					(pts
						(arc
							(start -0.1778 -0.2794)
							(mid -0.249642 -0.249642)
							(end -0.2794 -0.1778)
						)
						(arc
							(start -0.2794 0.1778)
							(mid -0.249642 0.249642)
							(end -0.1778 0.2794)
						)
						(arc
							(start 0.1778 0.2794)
							(mid 0.249642 0.249642)
							(end 0.2794 0.1778)
						)
						(arc
							(start 0.2794 -0.1778)
							(mid 0.249642 -0.249642)
							(end 0.1778 -0.2794)
						)
					)
					(width 0)
					(fill yes)
				)
			)
		)
	)
	(footprint ""
		(layer "F.Cu")
		(at 108.59897 -74.549 180)
		(property "Reference" "R591"
			(at 0 0 180)
			(layer "F.SilkS")
			(hide yes)
			(effects
				(font
					(size 1.27 1.27)
				)
			)
		)
		(property "Value" "4K7R2F-GP"
			(at 0.064008 -3.993896 180)
			(unlocked yes)
			(layer "F.Fab")
			(hide yes)
			(effects
				(font
					(size 1.016 1.016)
					(thickness 0.1524)
				)
			)
		)
		(property "Device Type" "R402H16"
			(at 0.064008 -5.517896 180)
			(unlocked yes)
			(layer "F.Fab")
			(hide yes)
			(effects
				(font
					(size 1.016 1.016)
					(thickness 0.1524)
				)
			)
		)
		(duplicate_pad_numbers_are_jumpers no)
		(fp_line
			(start 0.508 -0.9398)
			(end -0.508 -0.9398)
			(stroke
				(width 0.1524)
				(type default)
			)
			(layer "F.SilkS")
		)
		(fp_line
			(start -0.508 -0.9398)
			(end -0.508 0.9398)
			(stroke
				(width 0.1524)
				(type default)
			)
			(layer "F.SilkS")
		)
		(fp_rect
			(start -0.508 0.9398)
			(end 0.508 -0.9398)
			(stroke
				(width 0)
				(type default)
			)
			(fill no)
			(layer "F.CrtYd")
		)
		(fp_rect
			(start -0.508 0.9398)
			(end 0.508 -0.9398)
			(stroke
				(width 0)
				(type default)
			)
			(fill no)
			(layer "F.Fab")
		)
		(pad "1" smd custom
			(at 0 -0.4445 180)
			(size 0.1397 0.1397)
			(layers "F.Cu" "F.Mask" "F.Paste")
			(net "TEMP_4_A2")
			(options
				(clearance outline)
				(anchor circle)
			)
			(primitives
				(gr_poly
					(pts
						(arc
							(start -0.1778 -0.2794)
							(mid -0.249642 -0.249642)
							(end -0.2794 -0.1778)
						)
						(arc
							(start -0.2794 0.1778)
							(mid -0.249642 0.249642)
							(end -0.1778 0.2794)
						)
						(arc
							(start 0.1778 0.2794)
							(mid 0.249642 0.249642)
							(end 0.2794 0.1778)
						)
						(arc
							(start 0.2794 -0.1778)
							(mid 0.249642 -0.249642)
							(end 0.1778 -0.2794)
						)
					)
					(width 0)
					(fill yes)
				)
			)
		)
		(pad "2" smd custom
			(at 0 0.4445 180)
			(size 0.1397 0.1397)
			(layers "F.Cu" "F.Mask" "F.Paste")
			(net "GND")
			(options
				(clearance outline)
				(anchor circle)
			)
			(primitives
				(gr_poly
					(pts
						(arc
							(start -0.1778 -0.2794)
							(mid -0.249642 -0.249642)
							(end -0.2794 -0.1778)
						)
						(arc
							(start -0.2794 0.1778)
							(mid -0.249642 0.249642)
							(end -0.1778 0.2794)
						)
						(arc
							(start 0.1778 0.2794)
							(mid 0.249642 0.249642)
							(end 0.2794 0.1778)
						)
						(arc
							(start 0.2794 -0.1778)
							(mid 0.249642 -0.249642)
							(end 0.1778 -0.2794)
						)
					)
					(width 0)
					(fill yes)
				)
			)
		)
	)
	(footprint ""
		(layer "F.Cu")
		(at 103.105966 -61.4426 90)
		(property "Reference" "SC917"
			(at 0 0 90)
			(layer "F.SilkS")
			(hide yes)
			(effects
				(font
					(size 1.27 1.27)
				)
			)
		)
		(property "Value" "SC1U6D3V1MX-GP"
			(at 1.9177 2.0193 90)
			(unlocked yes)
			(layer "F.Fab")
			(hide yes)
			(effects
				(font
					(size 1.016 1.016)
					(thickness 0.1524)
				)
			)
		)
		(property "Device Type" "C0201H14"
			(at 1.9177 0.4953 90)
			(unlocked yes)
			(layer "F.Fab")
			(hide yes)
			(effects
				(font
					(size 1.016 1.016)
					(thickness 0.1524)
				)
			)
		)
		(duplicate_pad_numbers_are_jumpers no)
		(fp_rect
			(start -0.1524 0.3048)
			(end 0.1524 -0.3048)
			(stroke
				(width 0)
				(type default)
			)
			(fill no)
			(layer "F.CrtYd")
		)
		(fp_poly
			(pts
				(xy -0.2794 0.6477) (xy -0.2794 -0.6477) (xy 0.2794 -0.6477) (xy 0.2794 -0.1905) (xy 0.1524 -0.1905)
				(xy 0.1524 -0.3048) (xy -0.1524 -0.3048) (xy -0.1524 0.3048) (xy 0.1524 0.3048) (xy 0.1524 -0.1778)
				(xy 0.2794 -0.1778) (xy 0.2794 0.6477)
			)
			(stroke
				(width 0)
				(type default)
			)
			(fill no)
			(layer "F.CrtYd")
		)
		(fp_rect
			(start -0.2794 0.6477)
			(end 0.2794 -0.6477)
			(stroke
				(width 0)
				(type default)
			)
			(fill no)
			(layer "F.Fab")
		)
		(pad "1" smd custom
			(at 0 -0.2794 90)
			(size 0.0762 0.0762)
			(layers "F.Cu" "F.Mask" "F.Paste")
			(net "HM40ADC_VDDA")
			(options
				(clearance outline)
				(anchor circle)
			)
			(primitives
				(gr_poly
					(pts
						(arc
							(start 0.1524 -0.127)
							(mid 0.137521 -0.162921)
							(end 0.1016 -0.1778)
						)
						(arc
							(start -0.1016 -0.1778)
							(mid -0.137521 -0.162921)
							(end -0.1524 -0.127)
						)
						(arc
							(start -0.1524 0.127)
							(mid -0.137521 0.162921)
							(end -0.1016 0.1778)
						)
						(arc
							(start 0.1016 0.1778)
							(mid 0.137521 0.162921)
							(end 0.1524 0.127)
						)
					)
					(width 0)
					(fill yes)
				)
			)
		)
		(pad "2" smd custom
			(at 0 0.2794 90)
			(size 0.0762 0.0762)
			(layers "F.Cu" "F.Mask" "F.Paste")
			(net "GND")
			(options
				(clearance outline)
				(anchor circle)
			)
			(primitives
				(gr_poly
					(pts
						(arc
							(start 0.1524 -0.127)
							(mid 0.137521 -0.162921)
							(end 0.1016 -0.1778)
						)
						(arc
							(start -0.1016 -0.1778)
							(mid -0.137521 -0.162921)
							(end -0.1524 -0.127)
						)
						(arc
							(start -0.1524 0.127)
							(mid -0.137521 0.162921)
							(end -0.1016 0.1778)
						)
						(arc
							(start 0.1016 0.1778)
							(mid 0.137521 0.162921)
							(end 0.1524 0.127)
						)
					)
					(width 0)
					(fill yes)
				)
			)
		)
	)
	(footprint ""
		(layer "F.Cu")
		(at 77.343 -33.401)
		(property "Reference" "SC956"
			(at 0 0 0)
			(layer "F.SilkS")
			(hide yes)
			(effects
				(font
					(size 1.27 1.27)
				)
			)
		)
		(property "Value" "SC100U6D3V0MX-2GP"
			(at -0.00254 -4.78536 0)
			(unlocked yes)
			(layer "F.Fab")
			(hide yes)
			(effects
				(font
					(size 1.016 1.016)
					(thickness 0.1524)
				)
			)
		)
		(property "Device Type" "C1210H107"
			(at -0.00254 -6.38048 0)
			(unlocked yes)
			(layer "F.Fab")
			(hide yes)
			(effects
				(font
					(size 1.016 1.016)
					(thickness 0.1524)
				)
			)
		)
		(duplicate_pad_numbers_are_jumpers no)
		(fp_line
			(start -1.5748 -2.3368)
			(end -1.5748 -0.762)
			(stroke
				(width 0.1524)
				(type default)
			)
			(layer "F.SilkS")
		)
		(fp_line
			(start -1.5748 0.762)
			(end -1.5748 2.3368)
			(stroke
				(width 0.1524)
				(type default)
			)
			(layer "F.SilkS")
		)
		(fp_line
			(start -1.5748 2.3368)
			(end 1.5748 2.3368)
			(stroke
				(width 0.1524)
				(type default)
			)
			(layer "F.SilkS")
		)
		(fp_line
			(start 1.5748 -2.3368)
			(end -1.5748 -2.3368)
			(stroke
				(width 0.1524)
				(type default)
			)
			(layer "F.SilkS")
		)
		(fp_line
			(start 1.5748 -0.762)
			(end 1.5748 -2.3368)
			(stroke
				(width 0.1524)
				(type default)
			)
			(layer "F.SilkS")
		)
		(fp_line
			(start 1.5748 2.3368)
			(end 1.5748 0.762)
			(stroke
				(width 0.1524)
				(type default)
			)
			(layer "F.SilkS")
		)
		(fp_rect
			(start -1.651 2.413)
			(end 1.651 -2.413)
			(stroke
				(width 0)
				(type default)
			)
			(fill no)
			(layer "F.CrtYd")
		)
		(fp_poly
			(pts
				(xy 1.651 2.413) (xy 1.651 -2.413) (xy -1.651 -2.413) (xy -1.651 2.413)
			)
			(stroke
				(width 0)
				(type default)
			)
			(fill no)
			(layer "F.Fab")
		)
		(pad "1" smd rect
			(at 0 -1.4732)
			(size 2.794 1.397)
			(layers "F.Cu" "F.Mask" "F.Paste")
			(net "GND")
		)
		(pad "2" smd rect
			(at 0 1.4732)
			(size 2.794 1.397)
			(layers "F.Cu" "F.Mask" "F.Paste")
			(net "SAS0_AVDD")
		)
	)
	(footprint ""
		(layer "F.Cu")
		(at 202.692 -185.42 180)
		(property "Reference" "R478"
			(at 0 0 180)
			(layer "F.SilkS")
			(hide yes)
			(effects
				(font
					(size 1.27 1.27)
				)
			)
		)
		(property "Value" "2MR2F-GP"
			(at 0.064008 -3.993896 180)
			(unlocked yes)
			(layer "F.Fab")
			(hide yes)
			(effects
				(font
					(size 1.016 1.016)
					(thickness 0.1524)
				)
			)
		)
		(property "Device Type" "R402H16"
			(at 0.064008 -5.517896 180)
			(unlocked yes)
			(layer "F.Fab")
			(hide yes)
			(effects
				(font
					(size 1.016 1.016)
					(thickness 0.1524)
				)
			)
		)
		(duplicate_pad_numbers_are_jumpers no)
		(fp_line
			(start 0.508 -0.9398)
			(end -0.508 -0.9398)
			(stroke
				(width 0.1524)
				(type default)
			)
			(layer "F.SilkS")
		)
		(fp_line
			(start -0.508 -0.9398)
			(end -0.508 0.9398)
			(stroke
				(width 0.1524)
				(type default)
			)
			(layer "F.SilkS")
		)
		(fp_rect
			(start -0.508 0.9398)
			(end 0.508 -0.9398)
			(stroke
				(width 0)
				(type default)
			)
			(fill no)
			(layer "F.CrtYd")
		)
		(fp_rect
			(start -0.508 0.9398)
			(end 0.508 -0.9398)
			(stroke
				(width 0)
				(type default)
			)
			(fill no)
			(layer "F.Fab")
		)
		(pad "1" smd custom
			(at 0 -0.4445 180)
			(size 0.1397 0.1397)
			(layers "F.Cu" "F.Mask" "F.Paste")
			(net "HB_OUT_BMC")
			(options
				(clearance outline)
				(anchor circle)
			)
			(primitives
				(gr_poly
					(pts
						(arc
							(start -0.1778 -0.2794)
							(mid -0.249642 -0.249642)
							(end -0.2794 -0.1778)
						)
						(arc
							(start -0.2794 0.1778)
							(mid -0.249642 0.249642)
							(end -0.1778 0.2794)
						)
						(arc
							(start 0.1778 0.2794)
							(mid 0.249642 0.249642)
							(end 0.2794 0.1778)
						)
						(arc
							(start 0.2794 -0.1778)
							(mid 0.249642 -0.249642)
							(end 0.1778 -0.2794)
						)
					)
					(width 0)
					(fill yes)
				)
			)
		)
		(pad "2" smd custom
			(at 0 0.4445 180)
			(size 0.1397 0.1397)
			(layers "F.Cu" "F.Mask" "F.Paste")
			(net "HB_A_IN")
			(options
				(clearance outline)
				(anchor circle)
			)
			(primitives
				(gr_poly
					(pts
						(arc
							(start -0.1778 -0.2794)
							(mid -0.249642 -0.249642)
							(end -0.2794 -0.1778)
						)
						(arc
							(start -0.2794 0.1778)
							(mid -0.249642 0.249642)
							(end -0.1778 0.2794)
						)
						(arc
							(start 0.1778 0.2794)
							(mid 0.249642 0.249642)
							(end 0.2794 0.1778)
						)
						(arc
							(start 0.2794 -0.1778)
							(mid 0.249642 -0.249642)
							(end 0.1778 -0.2794)
						)
					)
					(width 0)
					(fill yes)
				)
			)
		)
	)
	(footprint ""
		(layer "F.Cu")
		(at 318.008 -179.705 -90)
		(property "Reference" "R319"
			(at 0 0 270)
			(layer "F.SilkS")
			(hide yes)
			(effects
				(font
					(size 1.27 1.27)
				)
			)
		)
		(property "Value" "0R2J-2-GP"
			(at 0.064008 -3.993896 270)
			(unlocked yes)
			(layer "F.Fab")
			(hide yes)
			(effects
				(font
					(size 1.016 1.016)
					(thickness 0.1524)
				)
			)
		)
		(property "Device Type" "R402H16"
			(at 0.064008 -5.517896 270)
			(unlocked yes)
			(layer "F.Fab")
			(hide yes)
			(effects
				(font
					(size 1.016 1.016)
					(thickness 0.1524)
				)
			)
		)
		(duplicate_pad_numbers_are_jumpers no)
		(fp_line
			(start -0.508 -0.9398)
			(end -0.508 0.9398)
			(stroke
				(width 0.1524)
				(type default)
			)
			(layer "F.SilkS")
		)
		(fp_line
			(start 0.508 -0.9398)
			(end -0.508 -0.9398)
			(stroke
				(width 0.1524)
				(type default)
			)
			(layer "F.SilkS")
		)
		(fp_rect
			(start -0.508 0.9398)
			(end 0.508 -0.9398)
			(stroke
				(width 0)
				(type default)
			)
			(fill no)
			(layer "F.CrtYd")
		)
		(fp_rect
			(start -0.508 0.9398)
			(end 0.508 -0.9398)
			(stroke
				(width 0)
				(type default)
			)
			(fill no)
			(layer "F.Fab")
		)
		(pad "1" smd custom
			(at 0 -0.4445 270)
			(size 0.1397 0.1397)
			(layers "F.Cu" "F.Mask" "F.Paste")
			(net "ADC_P1V8_STBY")
			(options
				(clearance outline)
				(anchor circle)
			)
			(primitives
				(gr_poly
					(pts
						(arc
							(start -0.1778 -0.2794)
							(mid -0.249642 -0.249642)
							(end -0.2794 -0.1778)
						)
						(arc
							(start -0.2794 0.1778)
							(mid -0.249642 0.249642)
							(end -0.1778 0.2794)
						)
						(arc
							(start 0.1778 0.2794)
							(mid 0.249642 0.249642)
							(end 0.2794 0.1778)
						)
						(arc
							(start 0.2794 -0.1778)
							(mid 0.249642 -0.249642)
							(end 0.1778 -0.2794)
						)
					)
					(width 0)
					(fill yes)
				)
			)
		)
		(pad "2" smd custom
			(at 0 0.4445 270)
			(size 0.1397 0.1397)
			(layers "F.Cu" "F.Mask" "F.Paste")
			(net "ADC_P1V8_STBY_BMC")
			(options
				(clearance outline)
				(anchor circle)
			)
			(primitives
				(gr_poly
					(pts
						(arc
							(start -0.1778 -0.2794)
							(mid -0.249642 -0.249642)
							(end -0.2794 -0.1778)
						)
						(arc
							(start -0.2794 0.1778)
							(mid -0.249642 0.249642)
							(end -0.1778 0.2794)
						)
						(arc
							(start 0.1778 0.2794)
							(mid 0.249642 0.249642)
							(end 0.2794 0.1778)
						)
						(arc
							(start 0.2794 -0.1778)
							(mid 0.249642 -0.249642)
							(end 0.1778 -0.2794)
						)
					)
					(width 0)
					(fill yes)
				)
			)
		)
	)
	(footprint ""
		(layer "F.Cu")
		(at 96.52 -233.807)
		(property "Reference" "R661"
			(at 0 0 0)
			(layer "F.SilkS")
			(hide yes)
			(effects
				(font
					(size 1.27 1.27)
				)
			)
		)
		(property "Value" "0R2J-2-GP"
			(at 0.064008 -3.993896 0)
			(unlocked yes)
			(layer "F.Fab")
			(hide yes)
			(effects
				(font
					(size 1.016 1.016)
					(thickness 0.1524)
				)
			)
		)
		(property "Device Type" "R402H16"
			(at 0.064008 -5.517896 0)
			(unlocked yes)
			(layer "F.Fab")
			(hide yes)
			(effects
				(font
					(size 1.016 1.016)
					(thickness 0.1524)
				)
			)
		)
		(duplicate_pad_numbers_are_jumpers no)
		(fp_line
			(start -0.508 -0.9398)
			(end -0.508 0.9398)
			(stroke
				(width 0.1524)
				(type default)
			)
			(layer "F.SilkS")
		)
		(fp_line
			(start 0.508 -0.9398)
			(end -0.508 -0.9398)
			(stroke
				(width 0.1524)
				(type default)
			)
			(layer "F.SilkS")
		)
		(fp_rect
			(start -0.508 0.9398)
			(end 0.508 -0.9398)
			(stroke
				(width 0)
				(type default)
			)
			(fill no)
			(layer "F.CrtYd")
		)
		(fp_rect
			(start -0.508 0.9398)
			(end 0.508 -0.9398)
			(stroke
				(width 0)
				(type default)
			)
			(fill no)
			(layer "F.Fab")
		)
		(pad "1" smd custom
			(at 0 -0.4445)
			(size 0.1397 0.1397)
			(layers "F.Cu" "F.Mask" "F.Paste")
			(net "SAS_FAULT_LED9")
			(options
				(clearance outline)
				(anchor circle)
			)
			(primitives
				(gr_poly
					(pts
						(arc
							(start -0.1778 -0.2794)
							(mid -0.249642 -0.249642)
							(end -0.2794 -0.1778)
						)
						(arc
							(start -0.2794 0.1778)
							(mid -0.249642 0.249642)
							(end -0.1778 0.2794)
						)
						(arc
							(start 0.1778 0.2794)
							(mid 0.249642 0.249642)
							(end 0.2794 0.1778)
						)
						(arc
							(start 0.2794 -0.1778)
							(mid 0.249642 -0.249642)
							(end 0.1778 -0.2794)
						)
					)
					(width 0)
					(fill yes)
				)
			)
		)
		(pad "2" smd custom
			(at 0 0.4445)
			(size 0.1397 0.1397)
			(layers "F.Cu" "F.Mask" "F.Paste")
			(net "SAS_HDD_LED_9")
			(options
				(clearance outline)
				(anchor circle)
			)
			(primitives
				(gr_poly
					(pts
						(arc
							(start -0.1778 -0.2794)
							(mid -0.249642 -0.249642)
							(end -0.2794 -0.1778)
						)
						(arc
							(start -0.2794 0.1778)
							(mid -0.249642 0.249642)
							(end -0.1778 0.2794)
						)
						(arc
							(start 0.1778 0.2794)
							(mid 0.249642 0.249642)
							(end 0.2794 0.1778)
						)
						(arc
							(start 0.2794 -0.1778)
							(mid 0.249642 -0.249642)
							(end 0.1778 -0.2794)
						)
					)
					(width 0)
					(fill yes)
				)
			)
		)
	)
	(footprint ""
		(layer "F.Cu")
		(at 38.989 -170.815 180)
		(property "Reference" "SR1274"
			(at 0 0 180)
			(layer "F.SilkS")
			(hide yes)
			(effects
				(font
					(size 1.27 1.27)
				)
			)
		)
		(property "Value" "4K7R2F-GP"
			(at 0.064008 -3.993896 180)
			(unlocked yes)
			(layer "F.Fab")
			(hide yes)
			(effects
				(font
					(size 1.016 1.016)
					(thickness 0.1524)
				)
			)
		)
		(property "Device Type" "R402H16"
			(at 0.064008 -5.517896 180)
			(unlocked yes)
			(layer "F.Fab")
			(hide yes)
			(effects
				(font
					(size 1.016 1.016)
					(thickness 0.1524)
				)
			)
		)
		(duplicate_pad_numbers_are_jumpers no)
		(fp_line
			(start 0.508 -0.9398)
			(end -0.508 -0.9398)
			(stroke
				(width 0.1524)
				(type default)
			)
			(layer "F.SilkS")
		)
		(fp_line
			(start -0.508 -0.9398)
			(end -0.508 0.9398)
			(stroke
				(width 0.1524)
				(type default)
			)
			(layer "F.SilkS")
		)
		(fp_rect
			(start -0.508 0.9398)
			(end 0.508 -0.9398)
			(stroke
				(width 0)
				(type default)
			)
			(fill no)
			(layer "F.CrtYd")
		)
		(fp_rect
			(start -0.508 0.9398)
			(end 0.508 -0.9398)
			(stroke
				(width 0)
				(type default)
			)
			(fill no)
			(layer "F.Fab")
		)
		(pad "1" smd custom
			(at 0 -0.4445 180)
			(size 0.1397 0.1397)
			(layers "F.Cu" "F.Mask" "F.Paste")
			(net "P3V3_STBY")
			(options
				(clearance outline)
				(anchor circle)
			)
			(primitives
				(gr_poly
					(pts
						(arc
							(start -0.1778 -0.2794)
							(mid -0.249642 -0.249642)
							(end -0.2794 -0.1778)
						)
						(arc
							(start -0.2794 0.1778)
							(mid -0.249642 0.249642)
							(end -0.1778 0.2794)
						)
						(arc
							(start 0.1778 0.2794)
							(mid 0.249642 0.249642)
							(end 0.2794 0.1778)
						)
						(arc
							(start 0.2794 -0.1778)
							(mid 0.249642 -0.249642)
							(end 0.1778 -0.2794)
						)
					)
					(width 0)
					(fill yes)
				)
			)
		)
		(pad "2" smd custom
			(at 0 0.4445 180)
			(size 0.1397 0.1397)
			(layers "F.Cu" "F.Mask" "F.Paste")
			(net "P3V3_STBY_R7")
			(options
				(clearance outline)
				(anchor circle)
			)
			(primitives
				(gr_poly
					(pts
						(arc
							(start -0.1778 -0.2794)
							(mid -0.249642 -0.249642)
							(end -0.2794 -0.1778)
						)
						(arc
							(start -0.2794 0.1778)
							(mid -0.249642 0.249642)
							(end -0.1778 0.2794)
						)
						(arc
							(start 0.1778 0.2794)
							(mid 0.249642 0.249642)
							(end 0.2794 0.1778)
						)
						(arc
							(start 0.2794 -0.1778)
							(mid 0.249642 -0.249642)
							(end 0.1778 -0.2794)
						)
					)
					(width 0)
					(fill yes)
				)
			)
		)
	)
	(footprint ""
		(layer "F.Cu")
		(at 242.1763 -111.6838 180)
		(property "Reference" "SR933"
			(at 0 0 180)
			(layer "F.SilkS")
			(hide yes)
			(effects
				(font
					(size 1.27 1.27)
				)
			)
		)
		(property "Value" "0R2J-2-GP"
			(at 0.064008 -3.993896 180)
			(unlocked yes)
			(layer "F.Fab")
			(hide yes)
			(effects
				(font
					(size 1.016 1.016)
					(thickness 0.1524)
				)
			)
		)
		(property "Device Type" "R402H16"
			(at 0.064008 -5.517896 180)
			(unlocked yes)
			(layer "F.Fab")
			(hide yes)
			(effects
				(font
					(size 1.016 1.016)
					(thickness 0.1524)
				)
			)
		)
		(duplicate_pad_numbers_are_jumpers no)
		(fp_line
			(start 0.508 -0.9398)
			(end -0.508 -0.9398)
			(stroke
				(width 0.1524)
				(type default)
			)
			(layer "F.SilkS")
		)
		(fp_line
			(start -0.508 -0.9398)
			(end -0.508 0.9398)
			(stroke
				(width 0.1524)
				(type default)
			)
			(layer "F.SilkS")
		)
		(fp_rect
			(start -0.508 0.9398)
			(end 0.508 -0.9398)
			(stroke
				(width 0)
				(type default)
			)
			(fill no)
			(layer "F.CrtYd")
		)
		(fp_rect
			(start -0.508 0.9398)
			(end 0.508 -0.9398)
			(stroke
				(width 0)
				(type default)
			)
			(fill no)
			(layer "F.Fab")
		)
		(pad "1" smd custom
			(at 0 -0.4445 180)
			(size 0.1397 0.1397)
			(layers "F.Cu" "F.Mask" "F.Paste")
			(net "EXP_SMART_TX")
			(options
				(clearance outline)
				(anchor circle)
			)
			(primitives
				(gr_poly
					(pts
						(arc
							(start -0.1778 -0.2794)
							(mid -0.249642 -0.249642)
							(end -0.2794 -0.1778)
						)
						(arc
							(start -0.2794 0.1778)
							(mid -0.249642 0.249642)
							(end -0.1778 0.2794)
						)
						(arc
							(start 0.1778 0.2794)
							(mid 0.249642 0.249642)
							(end 0.2794 0.1778)
						)
						(arc
							(start 0.2794 -0.1778)
							(mid 0.249642 -0.249642)
							(end 0.1778 -0.2794)
						)
					)
					(width 0)
					(fill yes)
				)
			)
		)
		(pad "2" smd custom
			(at 0 0.4445 180)
			(size 0.1397 0.1397)
			(layers "F.Cu" "F.Mask" "F.Paste")
			(net "EXP_SMART_TX_R")
			(options
				(clearance outline)
				(anchor circle)
			)
			(primitives
				(gr_poly
					(pts
						(arc
							(start -0.1778 -0.2794)
							(mid -0.249642 -0.249642)
							(end -0.2794 -0.1778)
						)
						(arc
							(start -0.2794 0.1778)
							(mid -0.249642 0.249642)
							(end -0.1778 0.2794)
						)
						(arc
							(start 0.1778 0.2794)
							(mid 0.249642 0.249642)
							(end 0.2794 0.1778)
						)
						(arc
							(start 0.2794 -0.1778)
							(mid 0.249642 -0.249642)
							(end 0.1778 -0.2794)
						)
					)
					(width 0)
					(fill yes)
				)
			)
		)
	)
	(footprint ""
		(layer "F.Cu")
		(at 265.049 -16.383 180)
		(property "Reference" "TC12"
			(at 0 0 180)
			(layer "F.SilkS")
			(hide yes)
			(effects
				(font
					(size 1.27 1.27)
				)
			)
		)
		(property "Value" "SC47U16V0MX-GP"
			(at -0.00254 -4.78536 180)
			(unlocked yes)
			(layer "F.Fab")
			(hide yes)
			(effects
				(font
					(size 1.016 1.016)
					(thickness 0.1524)
				)
			)
		)
		(property "Device Type" "C1210H107"
			(at -0.00254 -6.38048 180)
			(unlocked yes)
			(layer "F.Fab")
			(hide yes)
			(effects
				(font
					(size 1.016 1.016)
					(thickness 0.1524)
				)
			)
		)
		(duplicate_pad_numbers_are_jumpers no)
		(fp_line
			(start 1.5748 2.3368)
			(end 1.5748 0.762)
			(stroke
				(width 0.1524)
				(type default)
			)
			(layer "F.SilkS")
		)
		(fp_line
			(start 1.5748 -0.762)
			(end 1.5748 -2.3368)
			(stroke
				(width 0.1524)
				(type default)
			)
			(layer "F.SilkS")
		)
		(fp_line
			(start 1.5748 -2.3368)
			(end -1.5748 -2.3368)
			(stroke
				(width 0.1524)
				(type default)
			)
			(layer "F.SilkS")
		)
		(fp_line
			(start -1.5748 2.3368)
			(end 1.5748 2.3368)
			(stroke
				(width 0.1524)
				(type default)
			)
			(layer "F.SilkS")
		)
		(fp_line
			(start -1.5748 0.762)
			(end -1.5748 2.3368)
			(stroke
				(width 0.1524)
				(type default)
			)
			(layer "F.SilkS")
		)
		(fp_line
			(start -1.5748 -2.3368)
			(end -1.5748 -0.762)
			(stroke
				(width 0.1524)
				(type default)
			)
			(layer "F.SilkS")
		)
		(fp_rect
			(start -1.651 2.413)
			(end 1.651 -2.413)
			(stroke
				(width 0)
				(type default)
			)
			(fill no)
			(layer "F.CrtYd")
		)
		(fp_poly
			(pts
				(xy 1.651 2.413) (xy 1.651 -2.413) (xy -1.651 -2.413) (xy -1.651 2.413)
			)
			(stroke
				(width 0)
				(type default)
			)
			(fill no)
			(layer "F.Fab")
		)
		(pad "1" smd rect
			(at 0 -1.4732 180)
			(size 2.794 1.397)
			(layers "F.Cu" "F.Mask" "F.Paste")
			(net "P5V_USB")
		)
		(pad "2" smd rect
			(at 0 1.4732 180)
			(size 2.794 1.397)
			(layers "F.Cu" "F.Mask" "F.Paste")
			(net "GND")
		)
	)
	(footprint ""
		(layer "F.Cu")
		(at 189.665864 -31.695136 180)
		(property "Reference" "C225"
			(at 0 0 180)
			(layer "F.SilkS")
			(hide yes)
			(effects
				(font
					(size 1.27 1.27)
				)
			)
		)
		(property "Value" "SCD1U16V2KX-3GP"
			(at 1.1811 -2.7051 180)
			(unlocked yes)
			(layer "F.Fab")
			(hide yes)
			(effects
				(font
					(size 1.016 1.016)
					(thickness 0.1524)
				)
			)
		)
		(property "Device Type" "C402H22"
			(at 1.1811 -4.2291 180)
			(unlocked yes)
			(layer "F.Fab")
			(hide yes)
			(effects
				(font
					(size 1.016 1.016)
					(thickness 0.1524)
				)
			)
		)
		(duplicate_pad_numbers_are_jumpers no)
		(fp_rect
			(start -0.4318 0.9525)
			(end 0.4318 -0.9525)
			(stroke
				(width 0)
				(type default)
			)
			(fill no)
			(layer "F.CrtYd")
		)
		(fp_rect
			(start -0.4318 0.9525)
			(end 0.4318 -0.9525)
			(stroke
				(width 0)
				(type default)
			)
			(fill no)
			(layer "F.Fab")
		)
		(pad "1" smd custom
			(at 0 -0.4445 180)
			(size 0.1524 0.1524)
			(layers "F.Cu" "F.Mask" "F.Paste")
			(net "PHY_DVDD")
			(options
				(clearance outline)
				(anchor circle)
			)
			(primitives
				(gr_poly
					(pts
						(arc
							(start 0.3048 -0.2032)
							(mid 0.275042 -0.275042)
							(end 0.2032 -0.3048)
						)
						(arc
							(start -0.2032 -0.3048)
							(mid -0.275042 -0.275042)
							(end -0.3048 -0.2032)
						)
						(arc
							(start -0.3048 0.2032)
							(mid -0.275042 0.275042)
							(end -0.2032 0.3048)
						)
						(arc
							(start 0.2032 0.3048)
							(mid 0.275042 0.275042)
							(end 0.3048 0.2032)
						)
					)
					(width 0)
					(fill yes)
				)
			)
		)
		(pad "2" smd custom
			(at 0 0.4445 180)
			(size 0.1524 0.1524)
			(layers "F.Cu" "F.Mask" "F.Paste")
			(net "GND")
			(options
				(clearance outline)
				(anchor circle)
			)
			(primitives
				(gr_poly
					(pts
						(arc
							(start 0.3048 -0.2032)
							(mid 0.275042 -0.275042)
							(end 0.2032 -0.3048)
						)
						(arc
							(start -0.2032 -0.3048)
							(mid -0.275042 -0.275042)
							(end -0.3048 -0.2032)
						)
						(arc
							(start -0.3048 0.2032)
							(mid -0.275042 0.275042)
							(end -0.2032 0.3048)
						)
						(arc
							(start 0.2032 0.3048)
							(mid 0.275042 0.275042)
							(end 0.3048 0.2032)
						)
					)
					(width 0)
					(fill yes)
				)
			)
		)
	)
	(footprint ""
		(layer "F.Cu")
		(at 348.390718 -150.853648 90)
		(property "Reference" "C167"
			(at 0 0 90)
			(layer "F.SilkS")
			(hide yes)
			(effects
				(font
					(size 1.27 1.27)
				)
			)
		)
		(property "Value" "SC1U10V2KX-4-GP"
			(at 1.1811 -2.7051 90)
			(unlocked yes)
			(layer "F.Fab")
			(hide yes)
			(effects
				(font
					(size 1.016 1.016)
					(thickness 0.1524)
				)
			)
		)
		(property "Device Type" "C402H22"
			(at 1.1811 -4.2291 90)
			(unlocked yes)
			(layer "F.Fab")
			(hide yes)
			(effects
				(font
					(size 1.016 1.016)
					(thickness 0.1524)
				)
			)
		)
		(duplicate_pad_numbers_are_jumpers no)
		(fp_rect
			(start -0.4318 0.9525)
			(end 0.4318 -0.9525)
			(stroke
				(width 0)
				(type default)
			)
			(fill no)
			(layer "F.CrtYd")
		)
		(fp_rect
			(start -0.4318 0.9525)
			(end 0.4318 -0.9525)
			(stroke
				(width 0)
				(type default)
			)
			(fill no)
			(layer "F.Fab")
		)
		(pad "1" smd custom
			(at 0 -0.4445 90)
			(size 0.1524 0.1524)
			(layers "F.Cu" "F.Mask" "F.Paste")
			(net "P3V3_STBY")
			(options
				(clearance outline)
				(anchor circle)
			)
			(primitives
				(gr_poly
					(pts
						(arc
							(start 0.3048 -0.2032)
							(mid 0.275042 -0.275042)
							(end 0.2032 -0.3048)
						)
						(arc
							(start -0.2032 -0.3048)
							(mid -0.275042 -0.275042)
							(end -0.3048 -0.2032)
						)
						(arc
							(start -0.3048 0.2032)
							(mid -0.275042 0.275042)
							(end -0.2032 0.3048)
						)
						(arc
							(start 0.2032 0.3048)
							(mid 0.275042 0.275042)
							(end 0.3048 0.2032)
						)
					)
					(width 0)
					(fill yes)
				)
			)
		)
		(pad "2" smd custom
			(at 0 0.4445 90)
			(size 0.1524 0.1524)
			(layers "F.Cu" "F.Mask" "F.Paste")
			(net "GND")
			(options
				(clearance outline)
				(anchor circle)
			)
			(primitives
				(gr_poly
					(pts
						(arc
							(start 0.3048 -0.2032)
							(mid 0.275042 -0.275042)
							(end 0.2032 -0.3048)
						)
						(arc
							(start -0.2032 -0.3048)
							(mid -0.275042 -0.275042)
							(end -0.3048 -0.2032)
						)
						(arc
							(start -0.3048 0.2032)
							(mid -0.275042 0.275042)
							(end -0.2032 0.3048)
						)
						(arc
							(start 0.2032 0.3048)
							(mid 0.275042 0.275042)
							(end 0.3048 0.2032)
						)
					)
					(width 0)
					(fill yes)
				)
			)
		)
	)
	(footprint ""
		(layer "F.Cu")
		(at 78.613 -22.86)
		(property "Reference" "PC220"
			(at 0 0 0)
			(layer "F.SilkS")
			(hide yes)
			(effects
				(font
					(size 1.27 1.27)
				)
			)
		)
		(property "Value" "SC1U10V2KX-1GP"
			(at 1.1811 -2.7051 0)
			(unlocked yes)
			(layer "F.Fab")
			(hide yes)
			(effects
				(font
					(size 1.016 1.016)
					(thickness 0.1524)
				)
			)
		)
		(property "Device Type" "C402H22"
			(at 1.1811 -4.2291 0)
			(unlocked yes)
			(layer "F.Fab")
			(hide yes)
			(effects
				(font
					(size 1.016 1.016)
					(thickness 0.1524)
				)
			)
		)
		(duplicate_pad_numbers_are_jumpers no)
		(fp_rect
			(start -0.4318 0.9525)
			(end 0.4318 -0.9525)
			(stroke
				(width 0)
				(type default)
			)
			(fill no)
			(layer "F.CrtYd")
		)
		(fp_rect
			(start -0.4318 0.9525)
			(end 0.4318 -0.9525)
			(stroke
				(width 0)
				(type default)
			)
			(fill no)
			(layer "F.Fab")
		)
		(pad "1" smd custom
			(at 0 -0.4445)
			(size 0.1524 0.1524)
			(layers "F.Cu" "F.Mask" "F.Paste")
			(net "GND")
			(options
				(clearance outline)
				(anchor circle)
			)
			(primitives
				(gr_poly
					(pts
						(arc
							(start 0.3048 -0.2032)
							(mid 0.275042 -0.275042)
							(end 0.2032 -0.3048)
						)
						(arc
							(start -0.2032 -0.3048)
							(mid -0.275042 -0.275042)
							(end -0.3048 -0.2032)
						)
						(arc
							(start -0.3048 0.2032)
							(mid -0.275042 0.275042)
							(end -0.2032 0.3048)
						)
						(arc
							(start 0.2032 0.3048)
							(mid 0.275042 0.275042)
							(end 0.3048 0.2032)
						)
					)
					(width 0)
					(fill yes)
				)
			)
		)
		(pad "2" smd custom
			(at 0 0.4445)
			(size 0.1524 0.1524)
			(layers "F.Cu" "F.Mask" "F.Paste")
			(net "VT235_EN")
			(options
				(clearance outline)
				(anchor circle)
			)
			(primitives
				(gr_poly
					(pts
						(arc
							(start 0.3048 -0.2032)
							(mid 0.275042 -0.275042)
							(end 0.2032 -0.3048)
						)
						(arc
							(start -0.2032 -0.3048)
							(mid -0.275042 -0.275042)
							(end -0.3048 -0.2032)
						)
						(arc
							(start -0.3048 0.2032)
							(mid -0.275042 0.275042)
							(end -0.2032 0.3048)
						)
						(arc
							(start 0.2032 0.3048)
							(mid 0.275042 0.275042)
							(end 0.3048 0.2032)
						)
					)
					(width 0)
					(fill yes)
				)
			)
		)
	)
	(footprint ""
		(layer "F.Cu")
		(at 343.916 -29.464 180)
		(property "Reference" "Q19"
			(at 0 0 180)
			(layer "F.SilkS")
			(hide yes)
			(effects
				(font
					(size 1.27 1.27)
				)
			)
		)
		(property "Value" "2N7002A-7-GP"
			(at 0.127 -8.9662 180)
			(unlocked yes)
			(layer "F.Fab")
			(hide yes)
			(effects
				(font
					(size 1.016 1.016)
					(thickness 0.1524)
				)
			)
		)
		(property "Device Type" "SOT23DGS2D4H48"
			(at 0.127 -10.4902 180)
			(unlocked yes)
			(layer "F.Fab")
			(hide yes)
			(effects
				(font
					(size 1.016 1.016)
					(thickness 0.1524)
				)
			)
		)
		(duplicate_pad_numbers_are_jumpers no)
		(fp_line
			(start 1.651 1.778)
			(end 1.651 -1.778)
			(stroke
				(width 0.1524)
				(type default)
			)
			(layer "F.SilkS")
		)
		(fp_line
			(start 1.651 -1.778)
			(end -1.651 -1.778)
			(stroke
				(width 0.1524)
				(type default)
			)
			(layer "F.SilkS")
		)
		(fp_line
			(start -1.651 1.778)
			(end 1.651 1.778)
			(stroke
				(width 0.1524)
				(type default)
			)
			(layer "F.SilkS")
		)
		(fp_line
			(start -1.651 -1.778)
			(end -1.651 1.778)
			(stroke
				(width 0.1524)
				(type default)
			)
			(layer "F.SilkS")
		)
		(fp_poly
			(pts
				(xy -1.778 1.8796) (xy -1.778 -1.8796) (xy 1.778 -1.8796) (xy 1.778 1.8796)
			)
			(stroke
				(width 0)
				(type default)
			)
			(fill no)
			(layer "F.CrtYd")
		)
		(fp_poly
			(pts
				(xy -1.778 1.8796) (xy -1.778 -1.8796) (xy 1.778 -1.8796) (xy 1.778 1.8796)
			)
			(stroke
				(width 0)
				(type default)
			)
			(fill no)
			(layer "F.Fab")
		)
		(pad "D" smd custom
			(at 0 -0.9525 180)
			(size 0.1905 0.1905)
			(layers "F.Cu" "F.Mask" "F.Paste")
			(net "DEBUG CONSOLE_LED_0")
			(options
				(clearance outline)
				(anchor circle)
			)
			(primitives
				(gr_poly
					(pts
						(arc
							(start -0.1778 0.5715)
							(mid -0.321484 0.511984)
							(end -0.381 0.3683)
						)
						(arc
							(start -0.381 -0.3683)
							(mid -0.321484 -0.511984)
							(end -0.1778 -0.5715)
						)
						(arc
							(start 0.1778 -0.5715)
							(mid 0.321484 -0.511984)
							(end 0.381 -0.3683)
						)
						(arc
							(start 0.381 0.3683)
							(mid 0.321484 0.511984)
							(end 0.1778 0.5715)
						)
					)
					(width 0)
					(fill yes)
				)
			)
		)
		(pad "G" smd custom
			(at -0.98425 0.9525 180)
			(size 0.1905 0.1905)
			(layers "F.Cu" "F.Mask" "F.Paste")
			(net "BMC_CONSOLE_LED0_R")
			(options
				(clearance outline)
				(anchor circle)
			)
			(primitives
				(gr_poly
					(pts
						(arc
							(start -0.1778 0.5715)
							(mid -0.321484 0.511984)
							(end -0.381 0.3683)
						)
						(arc
							(start -0.381 -0.3683)
							(mid -0.321484 -0.511984)
							(end -0.1778 -0.5715)
						)
						(arc
							(start 0.1778 -0.5715)
							(mid 0.321484 -0.511984)
							(end 0.381 -0.3683)
						)
						(arc
							(start 0.381 0.3683)
							(mid 0.321484 0.511984)
							(end 0.1778 0.5715)
						)
					)
					(width 0)
					(fill yes)
				)
			)
		)
		(pad "S" smd custom
			(at 0.98425 0.9525 180)
			(size 0.1905 0.1905)
			(layers "F.Cu" "F.Mask" "F.Paste")
			(net "GND")
			(options
				(clearance outline)
				(anchor circle)
			)
			(primitives
				(gr_poly
					(pts
						(arc
							(start -0.1778 0.5715)
							(mid -0.321484 0.511984)
							(end -0.381 0.3683)
						)
						(arc
							(start -0.381 -0.3683)
							(mid -0.321484 -0.511984)
							(end -0.1778 -0.5715)
						)
						(arc
							(start 0.1778 -0.5715)
							(mid 0.321484 -0.511984)
							(end 0.381 -0.3683)
						)
						(arc
							(start 0.381 0.3683)
							(mid 0.321484 0.511984)
							(end 0.1778 0.5715)
						)
					)
					(width 0)
					(fill yes)
				)
			)
		)
	)
	(footprint ""
		(layer "F.Cu")
		(at 131.897882 -81.147158)
		(property "Reference" "SC1092"
			(at 0 0 0)
			(layer "F.SilkS")
			(hide yes)
			(effects
				(font
					(size 1.27 1.27)
				)
			)
		)
		(property "Value" "SCD01U10V1KX-GP"
			(at -2.8321 -1.7399 0)
			(unlocked yes)
			(layer "F.Fab")
			(hide yes)
			(effects
				(font
					(size 1.016 1.016)
					(thickness 0.1524)
				)
			)
		)
		(property "Device Type" "C0201H13"
			(at -2.8321 -3.2639 0)
			(unlocked yes)
			(layer "F.Fab")
			(hide yes)
			(effects
				(font
					(size 1.016 1.016)
					(thickness 0.1524)
				)
			)
		)
		(duplicate_pad_numbers_are_jumpers no)
		(fp_rect
			(start -0.2794 0.6477)
			(end 0.2794 -0.6477)
			(stroke
				(width 0)
				(type default)
			)
			(fill no)
			(layer "F.CrtYd")
		)
		(fp_rect
			(start -0.2794 0.6477)
			(end 0.2794 -0.6477)
			(stroke
				(width 0)
				(type default)
			)
			(fill no)
			(layer "F.Fab")
		)
		(pad "1" smd custom
			(at 0 -0.2794)
			(size 0.0762 0.0762)
			(layers "F.Cu" "F.Mask" "F.Paste")
			(net "SAS_HDD_TX12_P")
			(options
				(clearance outline)
				(anchor circle)
			)
			(primitives
				(gr_poly
					(pts
						(arc
							(start 0.1524 -0.127)
							(mid 0.137521 -0.162921)
							(end 0.1016 -0.1778)
						)
						(arc
							(start -0.1016 -0.1778)
							(mid -0.137521 -0.162921)
							(end -0.1524 -0.127)
						)
						(arc
							(start -0.1524 0.127)
							(mid -0.137521 0.162921)
							(end -0.1016 0.1778)
						)
						(arc
							(start 0.1016 0.1778)
							(mid 0.137521 0.162921)
							(end 0.1524 0.127)
						)
					)
					(width 0)
					(fill yes)
				)
			)
		)
		(pad "2" smd custom
			(at 0 0.2794)
			(size 0.0762 0.0762)
			(layers "F.Cu" "F.Mask" "F.Paste")
			(net "3008_SAS_RX_P0")
			(options
				(clearance outline)
				(anchor circle)
			)
			(primitives
				(gr_poly
					(pts
						(arc
							(start 0.1524 -0.127)
							(mid 0.137521 -0.162921)
							(end 0.1016 -0.1778)
						)
						(arc
							(start -0.1016 -0.1778)
							(mid -0.137521 -0.162921)
							(end -0.1524 -0.127)
						)
						(arc
							(start -0.1524 0.127)
							(mid -0.137521 0.162921)
							(end -0.1016 0.1778)
						)
						(arc
							(start 0.1016 0.1778)
							(mid 0.137521 0.162921)
							(end 0.1524 0.127)
						)
					)
					(width 0)
					(fill yes)
				)
			)
		)
	)
	(footprint ""
		(layer "F.Cu")
		(at 90.91549 -118.9863 90)
		(property "Reference" "SR742"
			(at 0 0 90)
			(layer "F.SilkS")
			(hide yes)
			(effects
				(font
					(size 1.27 1.27)
				)
			)
		)
		(property "Value" "2K2R2F-GP"
			(at 0.064008 -3.993896 90)
			(unlocked yes)
			(layer "F.Fab")
			(hide yes)
			(effects
				(font
					(size 1.016 1.016)
					(thickness 0.1524)
				)
			)
		)
		(property "Device Type" "R402H16"
			(at 0.064008 -5.517896 90)
			(unlocked yes)
			(layer "F.Fab")
			(hide yes)
			(effects
				(font
					(size 1.016 1.016)
					(thickness 0.1524)
				)
			)
		)
		(duplicate_pad_numbers_are_jumpers no)
		(fp_line
			(start 0.508 -0.9398)
			(end -0.508 -0.9398)
			(stroke
				(width 0.1524)
				(type default)
			)
			(layer "F.SilkS")
		)
		(fp_line
			(start -0.508 -0.9398)
			(end -0.508 0.9398)
			(stroke
				(width 0.1524)
				(type default)
			)
			(layer "F.SilkS")
		)
		(fp_rect
			(start -0.508 0.9398)
			(end 0.508 -0.9398)
			(stroke
				(width 0)
				(type default)
			)
			(fill no)
			(layer "F.CrtYd")
		)
		(fp_rect
			(start -0.508 0.9398)
			(end 0.508 -0.9398)
			(stroke
				(width 0)
				(type default)
			)
			(fill no)
			(layer "F.Fab")
		)
		(pad "1" smd custom
			(at 0 -0.4445 90)
			(size 0.1397 0.1397)
			(layers "F.Cu" "F.Mask" "F.Paste")
			(net "EXP_I2C_SCL_1")
			(options
				(clearance outline)
				(anchor circle)
			)
			(primitives
				(gr_poly
					(pts
						(arc
							(start -0.1778 -0.2794)
							(mid -0.249642 -0.249642)
							(end -0.2794 -0.1778)
						)
						(arc
							(start -0.2794 0.1778)
							(mid -0.249642 0.249642)
							(end -0.1778 0.2794)
						)
						(arc
							(start 0.1778 0.2794)
							(mid 0.249642 0.249642)
							(end 0.2794 0.1778)
						)
						(arc
							(start 0.2794 -0.1778)
							(mid 0.249642 -0.249642)
							(end 0.1778 -0.2794)
						)
					)
					(width 0)
					(fill yes)
				)
			)
		)
		(pad "2" smd custom
			(at 0 0.4445 90)
			(size 0.1397 0.1397)
			(layers "F.Cu" "F.Mask" "F.Paste")
			(net "P1V8_E")
			(options
				(clearance outline)
				(anchor circle)
			)
			(primitives
				(gr_poly
					(pts
						(arc
							(start -0.1778 -0.2794)
							(mid -0.249642 -0.249642)
							(end -0.2794 -0.1778)
						)
						(arc
							(start -0.2794 0.1778)
							(mid -0.249642 0.249642)
							(end -0.1778 0.2794)
						)
						(arc
							(start 0.1778 0.2794)
							(mid 0.249642 0.249642)
							(end 0.2794 0.1778)
						)
						(arc
							(start 0.2794 -0.1778)
							(mid 0.249642 -0.249642)
							(end 0.1778 -0.2794)
						)
					)
					(width 0)
					(fill yes)
				)
			)
		)
	)
	(footprint ""
		(layer "F.Cu")
		(at 286.385 -70.612 -90)
		(property "Reference" "R488"
			(at 0 0 270)
			(layer "F.SilkS")
			(hide yes)
			(effects
				(font
					(size 1.27 1.27)
				)
			)
		)
		(property "Value" "4K7R2F-GP"
			(at 0.064008 -3.993896 270)
			(unlocked yes)
			(layer "F.Fab")
			(hide yes)
			(effects
				(font
					(size 1.016 1.016)
					(thickness 0.1524)
				)
			)
		)
		(property "Device Type" "R402H16"
			(at 0.064008 -5.517896 270)
			(unlocked yes)
			(layer "F.Fab")
			(hide yes)
			(effects
				(font
					(size 1.016 1.016)
					(thickness 0.1524)
				)
			)
		)
		(duplicate_pad_numbers_are_jumpers no)
		(fp_line
			(start -0.508 -0.9398)
			(end -0.508 0.9398)
			(stroke
				(width 0.1524)
				(type default)
			)
			(layer "F.SilkS")
		)
		(fp_line
			(start 0.508 -0.9398)
			(end -0.508 -0.9398)
			(stroke
				(width 0.1524)
				(type default)
			)
			(layer "F.SilkS")
		)
		(fp_rect
			(start -0.508 0.9398)
			(end 0.508 -0.9398)
			(stroke
				(width 0)
				(type default)
			)
			(fill no)
			(layer "F.CrtYd")
		)
		(fp_rect
			(start -0.508 0.9398)
			(end 0.508 -0.9398)
			(stroke
				(width 0)
				(type default)
			)
			(fill no)
			(layer "F.Fab")
		)
		(pad "1" smd custom
			(at 0 -0.4445 270)
			(size 0.1397 0.1397)
			(layers "F.Cu" "F.Mask" "F.Paste")
			(net "P3V3_STBY")
			(options
				(clearance outline)
				(anchor circle)
			)
			(primitives
				(gr_poly
					(pts
						(arc
							(start -0.1778 -0.2794)
							(mid -0.249642 -0.249642)
							(end -0.2794 -0.1778)
						)
						(arc
							(start -0.2794 0.1778)
							(mid -0.249642 0.249642)
							(end -0.1778 0.2794)
						)
						(arc
							(start 0.1778 0.2794)
							(mid 0.249642 0.249642)
							(end 0.2794 0.1778)
						)
						(arc
							(start 0.2794 -0.1778)
							(mid 0.249642 -0.249642)
							(end 0.1778 -0.2794)
						)
					)
					(width 0)
					(fill yes)
				)
			)
		)
		(pad "2" smd custom
			(at 0 0.4445 270)
			(size 0.1397 0.1397)
			(layers "F.Cu" "F.Mask" "F.Paste")
			(net "HSC_MSB_ALERT_N")
			(options
				(clearance outline)
				(anchor circle)
			)
			(primitives
				(gr_poly
					(pts
						(arc
							(start -0.1778 -0.2794)
							(mid -0.249642 -0.249642)
							(end -0.2794 -0.1778)
						)
						(arc
							(start -0.2794 0.1778)
							(mid -0.249642 0.249642)
							(end -0.1778 0.2794)
						)
						(arc
							(start 0.1778 0.2794)
							(mid 0.249642 0.249642)
							(end 0.2794 0.1778)
						)
						(arc
							(start 0.2794 -0.1778)
							(mid 0.249642 -0.249642)
							(end 0.1778 -0.2794)
						)
					)
					(width 0)
					(fill yes)
				)
			)
		)
	)
	(footprint ""
		(layer "F.Cu")
		(at 132.08 -37.846)
		(property "Reference" "SLED25"
			(at 0 0 0)
			(layer "F.SilkS")
			(hide yes)
			(effects
				(font
					(size 1.27 1.27)
				)
			)
		)
		(property "Value" "LED-YG-51-GP"
			(at -2.6924 -1.4224 0)
			(unlocked yes)
			(layer "F.Fab")
			(hide yes)
			(effects
				(font
					(size 1.016 1.016)
					(thickness 0.1524)
				)
			)
		)
		(property "Device Type" "LED1608AKH40"
			(at -2.6924 -2.9464 0)
			(unlocked yes)
			(layer "F.Fab")
			(hide yes)
			(effects
				(font
					(size 1.016 1.016)
					(thickness 0.1524)
				)
			)
		)
		(duplicate_pad_numbers_are_jumpers no)
		(fp_line
			(start -0.7493 1.651)
			(end -0.7493 1.1811)
			(stroke
				(width 0.3302)
				(type default)
			)
			(layer "F.SilkS")
		)
		(fp_line
			(start -0.6604 -1.3716)
			(end 0.6604 -1.3716)
			(stroke
				(width 0.1524)
				(type default)
			)
			(layer "F.SilkS")
		)
		(fp_line
			(start -0.6604 1.3716)
			(end -0.6604 -1.3716)
			(stroke
				(width 0.1524)
				(type default)
			)
			(layer "F.SilkS")
		)
		(fp_line
			(start -0.5969 1.5494)
			(end 0.5842 1.5494)
			(stroke
				(width 0.508)
				(type default)
			)
			(layer "F.SilkS")
		)
		(fp_line
			(start 0.6604 -1.3716)
			(end 0.6604 1.3716)
			(stroke
				(width 0.1524)
				(type default)
			)
			(layer "F.SilkS")
		)
		(fp_line
			(start 0.6604 1.3716)
			(end -0.6604 1.3716)
			(stroke
				(width 0.1524)
				(type default)
			)
			(layer "F.SilkS")
		)
		(fp_line
			(start 0.7493 1.651)
			(end 0.7493 1.1811)
			(stroke
				(width 0.3302)
				(type default)
			)
			(layer "F.SilkS")
		)
		(fp_rect
			(start -0.6223 1.3335)
			(end 0.6223 -1.3335)
			(stroke
				(width 0)
				(type default)
			)
			(fill no)
			(layer "F.CrtYd")
		)
		(fp_rect
			(start -0.6223 1.3335)
			(end 0.6223 -1.3335)
			(stroke
				(width 0)
				(type default)
			)
			(fill no)
			(layer "F.Fab")
		)
		(pad "A" smd custom
			(at 0 -0.762)
			(size 0.2159 0.2159)
			(layers "F.Cu" "F.Mask" "F.Paste")
			(net "SYS_HB_LED_R")
			(options
				(clearance outline)
				(anchor circle)
			)
			(primitives
				(gr_poly
					(pts
						(arc
							(start -0.3302 -0.4318)
							(mid -0.402042 -0.402042)
							(end -0.4318 -0.3302)
						)
						(arc
							(start -0.4318 0.3302)
							(mid -0.402042 0.402042)
							(end -0.3302 0.4318)
						)
						(arc
							(start 0.3302 0.4318)
							(mid 0.402042 0.402042)
							(end 0.4318 0.3302)
						)
						(arc
							(start 0.4318 -0.3302)
							(mid 0.402042 -0.402042)
							(end 0.3302 -0.4318)
						)
					)
					(width 0)
					(fill yes)
				)
			)
		)
		(pad "K" smd custom
			(at 0 0.762)
			(size 0.2159 0.2159)
			(layers "F.Cu" "F.Mask" "F.Paste")
			(net "SYS_HB_LED_D")
			(options
				(clearance outline)
				(anchor circle)
			)
			(primitives
				(gr_poly
					(pts
						(arc
							(start -0.3302 -0.4318)
							(mid -0.402042 -0.402042)
							(end -0.4318 -0.3302)
						)
						(arc
							(start -0.4318 0.3302)
							(mid -0.402042 0.402042)
							(end -0.3302 0.4318)
						)
						(arc
							(start 0.3302 0.4318)
							(mid 0.402042 0.402042)
							(end 0.4318 0.3302)
						)
						(arc
							(start 0.4318 -0.3302)
							(mid 0.402042 -0.402042)
							(end 0.3302 -0.4318)
						)
					)
					(width 0)
					(fill yes)
				)
			)
		)
	)
	(footprint ""
		(layer "F.Cu")
		(at 82.555842 -139.771882 180)
		(property "Reference" "SC1121"
			(at 0 0 180)
			(layer "F.SilkS")
			(hide yes)
			(effects
				(font
					(size 1.27 1.27)
				)
			)
		)
		(property "Value" "SCD1U16V2KX-3GP"
			(at 1.1811 -2.7051 180)
			(unlocked yes)
			(layer "F.Fab")
			(hide yes)
			(effects
				(font
					(size 1.016 1.016)
					(thickness 0.1524)
				)
			)
		)
		(property "Device Type" "C402H22"
			(at 1.1811 -4.2291 180)
			(unlocked yes)
			(layer "F.Fab")
			(hide yes)
			(effects
				(font
					(size 1.016 1.016)
					(thickness 0.1524)
				)
			)
		)
		(duplicate_pad_numbers_are_jumpers no)
		(fp_rect
			(start -0.4318 0.9525)
			(end 0.4318 -0.9525)
			(stroke
				(width 0)
				(type default)
			)
			(fill no)
			(layer "F.CrtYd")
		)
		(fp_rect
			(start -0.4318 0.9525)
			(end 0.4318 -0.9525)
			(stroke
				(width 0)
				(type default)
			)
			(fill no)
			(layer "F.Fab")
		)
		(pad "1" smd custom
			(at 0 -0.4445 180)
			(size 0.1524 0.1524)
			(layers "F.Cu" "F.Mask" "F.Paste")
			(net "P3V3_STBY")
			(options
				(clearance outline)
				(anchor circle)
			)
			(primitives
				(gr_poly
					(pts
						(arc
							(start 0.3048 -0.2032)
							(mid 0.275042 -0.275042)
							(end 0.2032 -0.3048)
						)
						(arc
							(start -0.2032 -0.3048)
							(mid -0.275042 -0.275042)
							(end -0.3048 -0.2032)
						)
						(arc
							(start -0.3048 0.2032)
							(mid -0.275042 0.275042)
							(end -0.2032 0.3048)
						)
						(arc
							(start 0.2032 0.3048)
							(mid 0.275042 0.275042)
							(end 0.3048 0.2032)
						)
					)
					(width 0)
					(fill yes)
				)
			)
		)
		(pad "2" smd custom
			(at 0 0.4445 180)
			(size 0.1524 0.1524)
			(layers "F.Cu" "F.Mask" "F.Paste")
			(net "GND")
			(options
				(clearance outline)
				(anchor circle)
			)
			(primitives
				(gr_poly
					(pts
						(arc
							(start 0.3048 -0.2032)
							(mid 0.275042 -0.275042)
							(end 0.2032 -0.3048)
						)
						(arc
							(start -0.2032 -0.3048)
							(mid -0.275042 -0.275042)
							(end -0.3048 -0.2032)
						)
						(arc
							(start -0.3048 0.2032)
							(mid -0.275042 0.275042)
							(end -0.2032 0.3048)
						)
						(arc
							(start 0.2032 0.3048)
							(mid 0.275042 0.275042)
							(end 0.3048 0.2032)
						)
					)
					(width 0)
					(fill yes)
				)
			)
		)
	)
	(footprint ""
		(layer "F.Cu")
		(at 261.366 -39.37 90)
		(property "Reference" "PG4"
			(at 0 0 90)
			(layer "F.SilkS")
			(hide yes)
			(effects
				(font
					(size 1.27 1.27)
				)
			)
		)
		(property "Value" "COPPER-CLOSE-GP-U"
			(at 0.0762 -2.8702 90)
			(unlocked yes)
			(layer "F.Fab")
			(hide yes)
			(effects
				(font
					(size 1.016 1.016)
					(thickness 0.1524)
				)
			)
		)
		(property "Device Type" "CON2C-U"
			(at 0.0762 -4.3942 90)
			(unlocked yes)
			(layer "F.Fab")
			(hide yes)
			(effects
				(font
					(size 1.016 1.016)
					(thickness 0.1524)
				)
			)
		)
		(duplicate_pad_numbers_are_jumpers no)
		(fp_rect
			(start -0.9398 0.9652)
			(end 0.9398 -0.9652)
			(stroke
				(width 0)
				(type default)
			)
			(fill no)
			(layer "F.CrtYd")
		)
		(fp_rect
			(start -0.9398 0.9652)
			(end 0.9398 -0.9652)
			(stroke
				(width 0)
				(type default)
			)
			(fill no)
			(layer "F.Fab")
		)
		(pad "1" smd custom
			(at 0 -0.5334 90)
			(size 0.17145 0.17145)
			(layers "F.Cu" "F.Mask" "F.Paste")
			(net "AGND_P1V8_STBY")
			(options
				(clearance outline)
				(anchor circle)
			)
			(primitives
				(gr_poly
					(pts
						(xy -0.127 0.3429) (xy -0.127 0.1651) (xy -0.635 -0.3429) (xy 0.635 -0.3429) (xy 0.127 0.1651)
						(xy 0.127 0.3429)
					)
					(width 0)
					(fill yes)
				)
			)
		)
		(pad "2" smd custom
			(at 0 0.5334 90)
			(size 0.17145 0.17145)
			(layers "F.Cu" "F.Mask" "F.Paste")
			(net "GND")
			(options
				(clearance outline)
				(anchor circle)
			)
			(primitives
				(gr_poly
					(pts
						(xy -0.635 0.3429) (xy -0.127 -0.1651) (xy -0.127 -0.3429) (xy 0.127 -0.3429) (xy 0.127 -0.1651)
						(xy 0.635 0.3429)
					)
					(width 0)
					(fill yes)
				)
			)
		)
	)
	(footprint ""
		(layer "F.Cu")
		(at 178.816 -225.171)
		(property "Reference" "R325"
			(at 0 0 0)
			(layer "F.SilkS")
			(hide yes)
			(effects
				(font
					(size 1.27 1.27)
				)
			)
		)
		(property "Value" "4K7R2F-GP"
			(at 0.064008 -3.993896 0)
			(unlocked yes)
			(layer "F.Fab")
			(hide yes)
			(effects
				(font
					(size 1.016 1.016)
					(thickness 0.1524)
				)
			)
		)
		(property "Device Type" "R402H16"
			(at 0.064008 -5.517896 0)
			(unlocked yes)
			(layer "F.Fab")
			(hide yes)
			(effects
				(font
					(size 1.016 1.016)
					(thickness 0.1524)
				)
			)
		)
		(duplicate_pad_numbers_are_jumpers no)
		(fp_line
			(start -0.508 -0.9398)
			(end -0.508 0.9398)
			(stroke
				(width 0.1524)
				(type default)
			)
			(layer "F.SilkS")
		)
		(fp_line
			(start 0.508 -0.9398)
			(end -0.508 -0.9398)
			(stroke
				(width 0.1524)
				(type default)
			)
			(layer "F.SilkS")
		)
		(fp_rect
			(start -0.508 0.9398)
			(end 0.508 -0.9398)
			(stroke
				(width 0)
				(type default)
			)
			(fill no)
			(layer "F.CrtYd")
		)
		(fp_rect
			(start -0.508 0.9398)
			(end 0.508 -0.9398)
			(stroke
				(width 0)
				(type default)
			)
			(fill no)
			(layer "F.Fab")
		)
		(pad "1" smd custom
			(at 0 -0.4445)
			(size 0.1397 0.1397)
			(layers "F.Cu" "F.Mask" "F.Paste")
			(net "P3V3_STBY")
			(options
				(clearance outline)
				(anchor circle)
			)
			(primitives
				(gr_poly
					(pts
						(arc
							(start -0.1778 -0.2794)
							(mid -0.249642 -0.249642)
							(end -0.2794 -0.1778)
						)
						(arc
							(start -0.2794 0.1778)
							(mid -0.249642 0.249642)
							(end -0.1778 0.2794)
						)
						(arc
							(start 0.1778 0.2794)
							(mid 0.249642 0.249642)
							(end 0.2794 0.1778)
						)
						(arc
							(start 0.2794 -0.1778)
							(mid 0.249642 -0.249642)
							(end 0.1778 -0.2794)
						)
					)
					(width 0)
					(fill yes)
				)
			)
		)
		(pad "2" smd custom
			(at 0 0.4445)
			(size 0.1397 0.1397)
			(layers "F.Cu" "F.Mask" "F.Paste")
			(net "BMC_PWRBTN_N")
			(options
				(clearance outline)
				(anchor circle)
			)
			(primitives
				(gr_poly
					(pts
						(arc
							(start -0.1778 -0.2794)
							(mid -0.249642 -0.249642)
							(end -0.2794 -0.1778)
						)
						(arc
							(start -0.2794 0.1778)
							(mid -0.249642 0.249642)
							(end -0.1778 0.2794)
						)
						(arc
							(start 0.1778 0.2794)
							(mid 0.249642 0.249642)
							(end 0.2794 0.1778)
						)
						(arc
							(start 0.2794 -0.1778)
							(mid 0.249642 -0.249642)
							(end 0.1778 -0.2794)
						)
					)
					(width 0)
					(fill yes)
				)
			)
		)
	)
	(footprint ""
		(layer "F.Cu")
		(at 193.167 -13.081 -90)
		(property "Reference" "R191"
			(at 0 0 270)
			(layer "F.SilkS")
			(hide yes)
			(effects
				(font
					(size 1.27 1.27)
				)
			)
		)
		(property "Value" "0R2J-2-GP"
			(at 0.064008 -3.993896 270)
			(unlocked yes)
			(layer "F.Fab")
			(hide yes)
			(effects
				(font
					(size 1.016 1.016)
					(thickness 0.1524)
				)
			)
		)
		(property "Device Type" "R402H16"
			(at 0.064008 -5.517896 270)
			(unlocked yes)
			(layer "F.Fab")
			(hide yes)
			(effects
				(font
					(size 1.016 1.016)
					(thickness 0.1524)
				)
			)
		)
		(duplicate_pad_numbers_are_jumpers no)
		(fp_line
			(start -0.508 -0.9398)
			(end -0.508 0.9398)
			(stroke
				(width 0.1524)
				(type default)
			)
			(layer "F.SilkS")
		)
		(fp_line
			(start 0.508 -0.9398)
			(end -0.508 -0.9398)
			(stroke
				(width 0.1524)
				(type default)
			)
			(layer "F.SilkS")
		)
		(fp_rect
			(start -0.508 0.9398)
			(end 0.508 -0.9398)
			(stroke
				(width 0)
				(type default)
			)
			(fill no)
			(layer "F.CrtYd")
		)
		(fp_rect
			(start -0.508 0.9398)
			(end 0.508 -0.9398)
			(stroke
				(width 0)
				(type default)
			)
			(fill no)
			(layer "F.Fab")
		)
		(pad "1" smd custom
			(at 0 -0.4445 270)
			(size 0.1397 0.1397)
			(layers "F.Cu" "F.Mask" "F.Paste")
			(net "BMC_I2C_D_SDA")
			(options
				(clearance outline)
				(anchor circle)
			)
			(primitives
				(gr_poly
					(pts
						(arc
							(start -0.1778 -0.2794)
							(mid -0.249642 -0.249642)
							(end -0.2794 -0.1778)
						)
						(arc
							(start -0.2794 0.1778)
							(mid -0.249642 0.249642)
							(end -0.1778 0.2794)
						)
						(arc
							(start 0.1778 0.2794)
							(mid 0.249642 0.249642)
							(end 0.2794 0.1778)
						)
						(arc
							(start 0.2794 -0.1778)
							(mid 0.249642 -0.249642)
							(end 0.1778 -0.2794)
						)
					)
					(width 0)
					(fill yes)
				)
			)
		)
		(pad "2" smd custom
			(at 0 0.4445 270)
			(size 0.1397 0.1397)
			(layers "F.Cu" "F.Mask" "F.Paste")
			(net "TEMP_1_SDA")
			(options
				(clearance outline)
				(anchor circle)
			)
			(primitives
				(gr_poly
					(pts
						(arc
							(start -0.1778 -0.2794)
							(mid -0.249642 -0.249642)
							(end -0.2794 -0.1778)
						)
						(arc
							(start -0.2794 0.1778)
							(mid -0.249642 0.249642)
							(end -0.1778 0.2794)
						)
						(arc
							(start 0.1778 0.2794)
							(mid 0.249642 0.249642)
							(end 0.2794 0.1778)
						)
						(arc
							(start 0.2794 -0.1778)
							(mid 0.249642 -0.249642)
							(end 0.1778 -0.2794)
						)
					)
					(width 0)
					(fill yes)
				)
			)
		)
	)
	(footprint ""
		(layer "F.Cu")
		(at 279.264872 -225.116136 180)
		(property "Reference" "PC78"
			(at 0 0 180)
			(layer "F.SilkS")
			(hide yes)
			(effects
				(font
					(size 1.27 1.27)
				)
			)
		)
		(property "Value" "SCD1U16V2KX-3GP"
			(at 1.1811 -2.7051 180)
			(unlocked yes)
			(layer "F.Fab")
			(hide yes)
			(effects
				(font
					(size 1.016 1.016)
					(thickness 0.1524)
				)
			)
		)
		(property "Device Type" "C402H22"
			(at 1.1811 -4.2291 180)
			(unlocked yes)
			(layer "F.Fab")
			(hide yes)
			(effects
				(font
					(size 1.016 1.016)
					(thickness 0.1524)
				)
			)
		)
		(duplicate_pad_numbers_are_jumpers no)
		(fp_rect
			(start -0.4318 0.9525)
			(end 0.4318 -0.9525)
			(stroke
				(width 0)
				(type default)
			)
			(fill no)
			(layer "F.CrtYd")
		)
		(fp_rect
			(start -0.4318 0.9525)
			(end 0.4318 -0.9525)
			(stroke
				(width 0)
				(type default)
			)
			(fill no)
			(layer "F.Fab")
		)
		(pad "1" smd custom
			(at 0 -0.4445 180)
			(size 0.1524 0.1524)
			(layers "F.Cu" "F.Mask" "F.Paste")
			(net "TPS74801_P1V53_STBY_IN")
			(options
				(clearance outline)
				(anchor circle)
			)
			(primitives
				(gr_poly
					(pts
						(arc
							(start 0.3048 -0.2032)
							(mid 0.275042 -0.275042)
							(end 0.2032 -0.3048)
						)
						(arc
							(start -0.2032 -0.3048)
							(mid -0.275042 -0.275042)
							(end -0.3048 -0.2032)
						)
						(arc
							(start -0.3048 0.2032)
							(mid -0.275042 0.275042)
							(end -0.2032 0.3048)
						)
						(arc
							(start 0.2032 0.3048)
							(mid 0.275042 0.275042)
							(end 0.3048 0.2032)
						)
					)
					(width 0)
					(fill yes)
				)
			)
		)
		(pad "2" smd custom
			(at 0 0.4445 180)
			(size 0.1524 0.1524)
			(layers "F.Cu" "F.Mask" "F.Paste")
			(net "GND")
			(options
				(clearance outline)
				(anchor circle)
			)
			(primitives
				(gr_poly
					(pts
						(arc
							(start 0.3048 -0.2032)
							(mid 0.275042 -0.275042)
							(end 0.2032 -0.3048)
						)
						(arc
							(start -0.2032 -0.3048)
							(mid -0.275042 -0.275042)
							(end -0.3048 -0.2032)
						)
						(arc
							(start -0.3048 0.2032)
							(mid -0.275042 0.275042)
							(end -0.2032 0.3048)
						)
						(arc
							(start 0.2032 0.3048)
							(mid 0.275042 0.275042)
							(end 0.3048 0.2032)
						)
					)
					(width 0)
					(fill yes)
				)
			)
		)
	)
	(footprint ""
		(layer "F.Cu")
		(at 315.214 -196.977 180)
		(property "Reference" "U181"
			(at 0 0 180)
			(layer "F.SilkS")
			(hide yes)
			(effects
				(font
					(size 1.27 1.27)
				)
			)
		)
		(property "Value" "SN74AVC4T774RGYR-GP"
			(at -3.774948 -0.185674 180)
			(unlocked yes)
			(layer "F.Fab")
			(hide yes)
			(effects
				(font
					(size 1.016 1.016)
					(thickness 0.1524)
				)
			)
		)
		(property "Device Type" "QFN16G3540-G215265H40"
			(at -3.774948 -1.709674 180)
			(unlocked yes)
			(layer "F.Fab")
			(hide yes)
			(effects
				(font
					(size 1.016 1.016)
					(thickness 0.1524)
				)
			)
		)
		(duplicate_pad_numbers_are_jumpers no)
		(fp_line
			(start 3.0099 2.7686)
			(end 1.7399 2.7686)
			(stroke
				(width 0.1524)
				(type default)
			)
			(layer "F.SilkS")
		)
		(fp_line
			(start 3.0099 1.4986)
			(end 3.0099 2.7686)
			(stroke
				(width 0.1524)
				(type default)
			)
			(layer "F.SilkS")
		)
		(fp_line
			(start 1.249934 2.54)
			(end 1.249934 3.048)
			(stroke
				(width 0.1524)
				(type default)
			)
			(layer "F.SilkS")
		)
		(fp_line
			(start -0.249936 -2.54)
			(end -0.249936 -3.048)
			(stroke
				(width 0.1524)
				(type default)
			)
			(layer "F.SilkS")
		)
		(fp_line
			(start -1.249934 2.54)
			(end -1.249934 3.302)
			(stroke
				(width 0.1524)
				(type default)
			)
			(layer "F.SilkS")
		)
		(fp_line
			(start -3.0099 2.7686)
			(end -1.7399 2.7686)
			(stroke
				(width 0.1524)
				(type default)
			)
			(layer "F.SilkS")
		)
		(fp_line
			(start -3.0099 1.4986)
			(end -3.0099 2.7686)
			(stroke
				(width 0.1524)
				(type default)
			)
			(layer "F.SilkS")
		)
		(fp_line
			(start -3.0099 -1.4986)
			(end -3.0099 -2.7686)
			(stroke
				(width 0.1524)
				(type default)
			)
			(layer "F.SilkS")
		)
		(fp_line
			(start -3.0099 -2.7686)
			(end -1.7399 -2.7686)
			(stroke
				(width 0.1524)
				(type default)
			)
			(layer "F.SilkS")
		)
		(fp_poly
			(pts
				(xy 1.7399 -2.7686) (xy 3.0099 -1.4986) (xy 3.0099 -2.7686)
			)
			(stroke
				(width 0)
				(type default)
			)
			(fill yes)
			(layer "F.SilkS")
		)
		(fp_rect
			(start -1.9939 1.7526)
			(end 1.9939 -1.7526)
			(stroke
				(width 0)
				(type default)
			)
			(fill no)
			(layer "F.CrtYd")
		)
		(fp_poly
			(pts
				(xy -3.0099 2.7686) (xy -3.0099 -2.7686) (xy 3.0099 -2.7686) (xy 3.0099 -0.2286) (xy 1.9939 -0.2286)
				(xy 1.9939 -1.7526) (xy -1.9939 -1.7526) (xy -1.9939 1.7526) (xy 1.9939 1.7526) (xy 1.9939 -0.22352)
				(xy 3.0099 -0.22352) (xy 3.0099 2.7686)
			)
			(stroke
				(width 0)
				(type default)
			)
			(fill no)
			(layer "F.CrtYd")
		)
		(fp_rect
			(start -3.0099 2.7686)
			(end 3.0099 -2.7686)
			(stroke
				(width 0)
				(type default)
			)
			(fill no)
			(layer "F.Fab")
		)
		(pad "1" smd rect
			(at 2.0193 -0.750062 180)
			(size 0.9652 0.3048)
			(layers "F.Cu" "F.Mask" "F.Paste")
			(net "P3V3_STBY")
		)
		(pad "2" smd rect
			(at 1.249934 -1.778 180)
			(size 0.3048 0.9652)
			(layers "F.Cu" "F.Mask" "F.Paste")
			(net "P3V3_STBY")
		)
		(pad "3" smd rect
			(at 0.750062 -1.778 180)
			(size 0.3048 0.9652)
			(layers "F.Cu" "F.Mask" "F.Paste")
			(net "JTAG_BMC_TRST_N")
		)
		(pad "4" smd rect
			(at 0.249936 -1.778 180)
			(size 0.3048 0.9652)
			(layers "F.Cu" "F.Mask" "F.Paste")
			(net "JTAG_BMC_TMS")
		)
		(pad "5" smd rect
			(at -0.249936 -1.778 180)
			(size 0.3048 0.9652)
			(layers "F.Cu" "F.Mask" "F.Paste")
			(net "JTAG_BMC_TCK")
		)
		(pad "6" smd rect
			(at -0.750062 -1.778 180)
			(size 0.3048 0.9652)
			(layers "F.Cu" "F.Mask" "F.Paste")
			(net "JTAG_BMC_TDO")
		)
		(pad "7" smd rect
			(at -1.249934 -1.778 180)
			(size 0.3048 0.9652)
			(layers "F.Cu" "F.Mask" "F.Paste")
			(net "P3V3_STBY")
		)
		(pad "8" smd rect
			(at -2.0193 -0.750062 180)
			(size 0.9652 0.3048)
			(layers "F.Cu" "F.Mask" "F.Paste")
			(net "P3V3_STBY")
		)
		(pad "9" smd rect
			(at -2.0193 0.75311 180)
			(size 0.9652 0.3048)
			(layers "F.Cu" "F.Mask" "F.Paste")
			(net "BMC_JTAG_L_EN")
		)
		(pad "10" smd rect
			(at -1.249934 1.778 180)
			(size 0.3048 0.9652)
			(layers "F.Cu" "F.Mask" "F.Paste")
			(net "GND")
		)
		(pad "11" smd rect
			(at -0.750062 1.778 180)
			(size 0.3048 0.9652)
			(layers "F.Cu" "F.Mask" "F.Paste")
			(net "JTAG_BMC_L_TDO")
		)
		(pad "12" smd rect
			(at -0.249936 1.778 180)
			(size 0.3048 0.9652)
			(layers "F.Cu" "F.Mask" "F.Paste")
			(net "JTAG_EXP_IOC_TCK")
		)
		(pad "13" smd rect
			(at 0.249936 1.778 180)
			(size 0.3048 0.9652)
			(layers "F.Cu" "F.Mask" "F.Paste")
			(net "JTAG_EXP_IOC_TMS")
		)
		(pad "14" smd rect
			(at 0.750062 1.778 180)
			(size 0.3048 0.9652)
			(layers "F.Cu" "F.Mask" "F.Paste")
			(net "JTAG_EXP_IOC_RST")
		)
		(pad "15" smd rect
			(at 1.249934 1.778 180)
			(size 0.3048 0.9652)
			(layers "F.Cu" "F.Mask" "F.Paste")
			(net "P1V8_STBY")
		)
		(pad "16" smd rect
			(at 2.0193 0.750062 180)
			(size 0.9652 0.3048)
			(layers "F.Cu" "F.Mask" "F.Paste")
			(net "P3V3_STBY")
		)
		(pad "17" smd rect
			(at 0 0 180)
			(size 2.6416 2.159)
			(layers "F.Cu" "F.Mask" "F.Paste")
			(net "GND")
		)
	)
	(footprint ""
		(layer "F.Cu")
		(at 270.891 -44.958 180)
		(property "Reference" "PC43"
			(at 0 0 180)
			(layer "F.SilkS")
			(hide yes)
			(effects
				(font
					(size 1.27 1.27)
				)
			)
		)
		(property "Value" "SC22U25V5MX-GP"
			(at -0.0762 -6.1214 180)
			(unlocked yes)
			(layer "F.Fab")
			(hide yes)
			(effects
				(font
					(size 1.016 1.016)
					(thickness 0.1524)
				)
			)
		)
		(property "Device Type" "C805H58"
			(at -0.0762 -8.1534 180)
			(unlocked yes)
			(layer "F.Fab")
			(hide yes)
			(effects
				(font
					(size 1.016 1.016)
					(thickness 0.1524)
				)
			)
		)
		(duplicate_pad_numbers_are_jumpers no)
		(fp_line
			(start 0.635 0)
			(end -0.635 0)
			(stroke
				(width 0.508)
				(type default)
			)
			(layer "F.SilkS")
		)
		(fp_rect
			(start -0.9652 1.778)
			(end 0.9652 -1.778)
			(stroke
				(width 0)
				(type default)
			)
			(fill no)
			(layer "F.CrtYd")
		)
		(fp_poly
			(pts
				(xy -0.9652 -1.778) (xy 0.9652 -1.778) (xy 0.9652 1.778) (xy -0.9652 1.778)
			)
			(stroke
				(width 0)
				(type default)
			)
			(fill no)
			(layer "F.Fab")
		)
		(pad "1" smd rect
			(at 0 -0.9652 180)
			(size 1.397 1.143)
			(layers "F.Cu" "F.Mask" "F.Paste")
			(net "P1V8_STBY_VIN")
		)
		(pad "2" smd rect
			(at 0 0.9652 180)
			(size 1.397 1.143)
			(layers "F.Cu" "F.Mask" "F.Paste")
			(net "GND")
		)
	)
	(footprint ""
		(layer "F.Cu")
		(at 226.568 -17.907 -90)
		(property "Reference" "R543"
			(at 0 0 270)
			(layer "F.SilkS")
			(hide yes)
			(effects
				(font
					(size 1.27 1.27)
				)
			)
		)
		(property "Value" "330R1210J-GP"
			(at 0.0889 -6.9977 270)
			(unlocked yes)
			(layer "F.Fab")
			(hide yes)
			(effects
				(font
					(size 1.016 1.016)
					(thickness 0.1524)
				)
			)
		)
		(property "Device Type" "R1210H24"
			(at 0.0635 -8.636 270)
			(unlocked yes)
			(layer "F.Fab")
			(hide yes)
			(effects
				(font
					(size 1.016 1.016)
					(thickness 0.1524)
				)
			)
		)
		(duplicate_pad_numbers_are_jumpers no)
		(fp_line
			(start -1.651 2.413)
			(end -1.651 -2.413)
			(stroke
				(width 0.1524)
				(type default)
			)
			(layer "F.SilkS")
		)
		(fp_line
			(start 1.651 2.413)
			(end -1.651 2.413)
			(stroke
				(width 0.1524)
				(type default)
			)
			(layer "F.SilkS")
		)
		(fp_line
			(start -1.651 -2.413)
			(end 1.651 -2.413)
			(stroke
				(width 0.1524)
				(type default)
			)
			(layer "F.SilkS")
		)
		(fp_line
			(start 1.651 -2.413)
			(end 1.651 2.413)
			(stroke
				(width 0.1524)
				(type default)
			)
			(layer "F.SilkS")
		)
		(fp_poly
			(pts
				(xy -1.651 -2.413) (xy 1.651 -2.413) (xy 1.651 2.413) (xy -1.651 2.413)
			)
			(stroke
				(width 0)
				(type default)
			)
			(fill no)
			(layer "F.CrtYd")
		)
		(fp_poly
			(pts
				(xy -1.651 -2.413) (xy 1.651 -2.413) (xy 1.651 2.413) (xy -1.651 2.413)
			)
			(stroke
				(width 0)
				(type default)
			)
			(fill no)
			(layer "F.Fab")
		)
		(pad "1" smd rect
			(at 0 -1.4732 270)
			(size 2.794 1.397)
			(layers "F.Cu" "F.Mask" "F.Paste")
			(net "P5V_STBY")
		)
		(pad "2" smd rect
			(at 0 1.4732 270)
			(size 2.794 1.397)
			(layers "F.Cu" "F.Mask" "F.Paste")
			(net "ENCLO_LED_RED_R")
		)
	)
	(footprint ""
		(layer "F.Cu")
		(at 319.913 -165.354 -90)
		(property "Reference" "R492"
			(at 0 0 270)
			(layer "F.SilkS")
			(hide yes)
			(effects
				(font
					(size 1.27 1.27)
				)
			)
		)
		(property "Value" "10KR2F-2-GP"
			(at 0.064008 -3.993896 270)
			(unlocked yes)
			(layer "F.Fab")
			(hide yes)
			(effects
				(font
					(size 1.016 1.016)
					(thickness 0.1524)
				)
			)
		)
		(property "Device Type" "R402H16"
			(at 0.064008 -5.517896 270)
			(unlocked yes)
			(layer "F.Fab")
			(hide yes)
			(effects
				(font
					(size 1.016 1.016)
					(thickness 0.1524)
				)
			)
		)
		(duplicate_pad_numbers_are_jumpers no)
		(fp_line
			(start -0.508 -0.9398)
			(end -0.508 0.9398)
			(stroke
				(width 0.1524)
				(type default)
			)
			(layer "F.SilkS")
		)
		(fp_line
			(start 0.508 -0.9398)
			(end -0.508 -0.9398)
			(stroke
				(width 0.1524)
				(type default)
			)
			(layer "F.SilkS")
		)
		(fp_rect
			(start -0.508 0.9398)
			(end 0.508 -0.9398)
			(stroke
				(width 0)
				(type default)
			)
			(fill no)
			(layer "F.CrtYd")
		)
		(fp_rect
			(start -0.508 0.9398)
			(end 0.508 -0.9398)
			(stroke
				(width 0)
				(type default)
			)
			(fill no)
			(layer "F.Fab")
		)
		(pad "1" smd custom
			(at 0 -0.4445 270)
			(size 0.1397 0.1397)
			(layers "F.Cu" "F.Mask" "F.Paste")
			(net "P3V3_STBY")
			(options
				(clearance outline)
				(anchor circle)
			)
			(primitives
				(gr_poly
					(pts
						(arc
							(start -0.1778 -0.2794)
							(mid -0.249642 -0.249642)
							(end -0.2794 -0.1778)
						)
						(arc
							(start -0.2794 0.1778)
							(mid -0.249642 0.249642)
							(end -0.1778 0.2794)
						)
						(arc
							(start 0.1778 0.2794)
							(mid 0.249642 0.249642)
							(end 0.2794 0.1778)
						)
						(arc
							(start 0.2794 -0.1778)
							(mid 0.249642 -0.249642)
							(end 0.1778 -0.2794)
						)
					)
					(width 0)
					(fill yes)
				)
			)
		)
		(pad "2" smd custom
			(at 0 0.4445 270)
			(size 0.1397 0.1397)
			(layers "F.Cu" "F.Mask" "F.Paste")
			(net "BMC_I2C_C_SCL")
			(options
				(clearance outline)
				(anchor circle)
			)
			(primitives
				(gr_poly
					(pts
						(arc
							(start -0.1778 -0.2794)
							(mid -0.249642 -0.249642)
							(end -0.2794 -0.1778)
						)
						(arc
							(start -0.2794 0.1778)
							(mid -0.249642 0.249642)
							(end -0.1778 0.2794)
						)
						(arc
							(start 0.1778 0.2794)
							(mid 0.249642 0.249642)
							(end 0.2794 0.1778)
						)
						(arc
							(start 0.2794 -0.1778)
							(mid 0.249642 -0.249642)
							(end 0.1778 -0.2794)
						)
					)
					(width 0)
					(fill yes)
				)
			)
		)
	)
	(footprint ""
		(layer "F.Cu")
		(at 117.837966 -48.133 -90)
		(property "Reference" "SR649"
			(at 0 0 270)
			(layer "F.SilkS")
			(hide yes)
			(effects
				(font
					(size 1.27 1.27)
				)
			)
		)
		(property "Value" "10KR2F-2-GP"
			(at 0.064008 -3.993896 270)
			(unlocked yes)
			(layer "F.Fab")
			(hide yes)
			(effects
				(font
					(size 1.016 1.016)
					(thickness 0.1524)
				)
			)
		)
		(property "Device Type" "R402H16"
			(at 0.064008 -5.517896 270)
			(unlocked yes)
			(layer "F.Fab")
			(hide yes)
			(effects
				(font
					(size 1.016 1.016)
					(thickness 0.1524)
				)
			)
		)
		(duplicate_pad_numbers_are_jumpers no)
		(fp_line
			(start -0.508 -0.9398)
			(end -0.508 0.9398)
			(stroke
				(width 0.1524)
				(type default)
			)
			(layer "F.SilkS")
		)
		(fp_line
			(start 0.508 -0.9398)
			(end -0.508 -0.9398)
			(stroke
				(width 0.1524)
				(type default)
			)
			(layer "F.SilkS")
		)
		(fp_rect
			(start -0.508 0.9398)
			(end 0.508 -0.9398)
			(stroke
				(width 0)
				(type default)
			)
			(fill no)
			(layer "F.CrtYd")
		)
		(fp_rect
			(start -0.508 0.9398)
			(end 0.508 -0.9398)
			(stroke
				(width 0)
				(type default)
			)
			(fill no)
			(layer "F.Fab")
		)
		(pad "1" smd custom
			(at 0 -0.4445 270)
			(size 0.1397 0.1397)
			(layers "F.Cu" "F.Mask" "F.Paste")
			(net "GND")
			(options
				(clearance outline)
				(anchor circle)
			)
			(primitives
				(gr_poly
					(pts
						(arc
							(start -0.1778 -0.2794)
							(mid -0.249642 -0.249642)
							(end -0.2794 -0.1778)
						)
						(arc
							(start -0.2794 0.1778)
							(mid -0.249642 0.249642)
							(end -0.1778 0.2794)
						)
						(arc
							(start 0.1778 0.2794)
							(mid 0.249642 0.249642)
							(end 0.2794 0.1778)
						)
						(arc
							(start 0.2794 -0.1778)
							(mid 0.249642 -0.249642)
							(end 0.1778 -0.2794)
						)
					)
					(width 0)
					(fill yes)
				)
			)
		)
		(pad "2" smd custom
			(at 0 0.4445 270)
			(size 0.1397 0.1397)
			(layers "F.Cu" "F.Mask" "F.Paste")
			(net "MEM_CLK_SEL")
			(options
				(clearance outline)
				(anchor circle)
			)
			(primitives
				(gr_poly
					(pts
						(arc
							(start -0.1778 -0.2794)
							(mid -0.249642 -0.249642)
							(end -0.2794 -0.1778)
						)
						(arc
							(start -0.2794 0.1778)
							(mid -0.249642 0.249642)
							(end -0.1778 0.2794)
						)
						(arc
							(start 0.1778 0.2794)
							(mid 0.249642 0.249642)
							(end 0.2794 0.1778)
						)
						(arc
							(start 0.2794 -0.1778)
							(mid 0.249642 -0.249642)
							(end 0.1778 -0.2794)
						)
					)
					(width 0)
					(fill yes)
				)
			)
		)
	)
	(footprint ""
		(layer "F.Cu")
		(at 201.699876 -147.184872 90)
		(property "Reference" "SR761"
			(at 0 0 90)
			(layer "F.SilkS")
			(hide yes)
			(effects
				(font
					(size 1.27 1.27)
				)
			)
		)
		(property "Value" "200KR2F-L-GP"
			(at 0.064008 -3.993896 90)
			(unlocked yes)
			(layer "F.Fab")
			(hide yes)
			(effects
				(font
					(size 1.016 1.016)
					(thickness 0.1524)
				)
			)
		)
		(property "Device Type" "R402H16"
			(at 0.064008 -5.517896 90)
			(unlocked yes)
			(layer "F.Fab")
			(hide yes)
			(effects
				(font
					(size 1.016 1.016)
					(thickness 0.1524)
				)
			)
		)
		(duplicate_pad_numbers_are_jumpers no)
		(fp_line
			(start 0.508 -0.9398)
			(end -0.508 -0.9398)
			(stroke
				(width 0.1524)
				(type default)
			)
			(layer "F.SilkS")
		)
		(fp_line
			(start -0.508 -0.9398)
			(end -0.508 0.9398)
			(stroke
				(width 0.1524)
				(type default)
			)
			(layer "F.SilkS")
		)
		(fp_rect
			(start -0.508 0.9398)
			(end 0.508 -0.9398)
			(stroke
				(width 0)
				(type default)
			)
			(fill no)
			(layer "F.CrtYd")
		)
		(fp_rect
			(start -0.508 0.9398)
			(end 0.508 -0.9398)
			(stroke
				(width 0)
				(type default)
			)
			(fill no)
			(layer "F.Fab")
		)
		(pad "1" smd custom
			(at 0 -0.4445 90)
			(size 0.1397 0.1397)
			(layers "F.Cu" "F.Mask" "F.Paste")
			(net "EXP_I2C_VREF_2")
			(options
				(clearance outline)
				(anchor circle)
			)
			(primitives
				(gr_poly
					(pts
						(arc
							(start -0.1778 -0.2794)
							(mid -0.249642 -0.249642)
							(end -0.2794 -0.1778)
						)
						(arc
							(start -0.2794 0.1778)
							(mid -0.249642 0.249642)
							(end -0.1778 0.2794)
						)
						(arc
							(start 0.1778 0.2794)
							(mid 0.249642 0.249642)
							(end 0.2794 0.1778)
						)
						(arc
							(start 0.2794 -0.1778)
							(mid 0.249642 -0.249642)
							(end 0.1778 -0.2794)
						)
					)
					(width 0)
					(fill yes)
				)
			)
		)
		(pad "2" smd custom
			(at 0 0.4445 90)
			(size 0.1397 0.1397)
			(layers "F.Cu" "F.Mask" "F.Paste")
			(net "P3V3_STBY")
			(options
				(clearance outline)
				(anchor circle)
			)
			(primitives
				(gr_poly
					(pts
						(arc
							(start -0.1778 -0.2794)
							(mid -0.249642 -0.249642)
							(end -0.2794 -0.1778)
						)
						(arc
							(start -0.2794 0.1778)
							(mid -0.249642 0.249642)
							(end -0.1778 0.2794)
						)
						(arc
							(start 0.1778 0.2794)
							(mid 0.249642 0.249642)
							(end 0.2794 0.1778)
						)
						(arc
							(start 0.2794 -0.1778)
							(mid 0.249642 -0.249642)
							(end 0.1778 -0.2794)
						)
					)
					(width 0)
					(fill yes)
				)
			)
		)
	)
	(footprint ""
		(layer "F.Cu")
		(at 121.93397 -114.3 180)
		(property "Reference" "SC1068"
			(at 0 0 180)
			(layer "F.SilkS")
			(hide yes)
			(effects
				(font
					(size 1.27 1.27)
				)
			)
		)
		(property "Value" "SCD01U10V1KX-GP"
			(at -2.8321 -1.7399 180)
			(unlocked yes)
			(layer "F.Fab")
			(hide yes)
			(effects
				(font
					(size 1.016 1.016)
					(thickness 0.1524)
				)
			)
		)
		(property "Device Type" "C0201H13"
			(at -2.8321 -3.2639 180)
			(unlocked yes)
			(layer "F.Fab")
			(hide yes)
			(effects
				(font
					(size 1.016 1.016)
					(thickness 0.1524)
				)
			)
		)
		(duplicate_pad_numbers_are_jumpers no)
		(fp_rect
			(start -0.2794 0.6477)
			(end 0.2794 -0.6477)
			(stroke
				(width 0)
				(type default)
			)
			(fill no)
			(layer "F.CrtYd")
		)
		(fp_rect
			(start -0.2794 0.6477)
			(end 0.2794 -0.6477)
			(stroke
				(width 0)
				(type default)
			)
			(fill no)
			(layer "F.Fab")
		)
		(pad "1" smd custom
			(at 0 -0.2794 180)
			(size 0.0762 0.0762)
			(layers "F.Cu" "F.Mask" "F.Paste")
			(net "SAS_HDD_TX0_P")
			(options
				(clearance outline)
				(anchor circle)
			)
			(primitives
				(gr_poly
					(pts
						(arc
							(start 0.1524 -0.127)
							(mid 0.137521 -0.162921)
							(end 0.1016 -0.1778)
						)
						(arc
							(start -0.1016 -0.1778)
							(mid -0.137521 -0.162921)
							(end -0.1524 -0.127)
						)
						(arc
							(start -0.1524 0.127)
							(mid -0.137521 0.162921)
							(end -0.1016 0.1778)
						)
						(arc
							(start 0.1016 0.1778)
							(mid 0.137521 0.162921)
							(end 0.1524 0.127)
						)
					)
					(width 0)
					(fill yes)
				)
			)
		)
		(pad "2" smd custom
			(at 0 0.2794 180)
			(size 0.0762 0.0762)
			(layers "F.Cu" "F.Mask" "F.Paste")
			(net "SAS_EXP_GF_TX_DP4")
			(options
				(clearance outline)
				(anchor circle)
			)
			(primitives
				(gr_poly
					(pts
						(arc
							(start 0.1524 -0.127)
							(mid 0.137521 -0.162921)
							(end 0.1016 -0.1778)
						)
						(arc
							(start -0.1016 -0.1778)
							(mid -0.137521 -0.162921)
							(end -0.1524 -0.127)
						)
						(arc
							(start -0.1524 0.127)
							(mid -0.137521 0.162921)
							(end -0.1016 0.1778)
						)
						(arc
							(start 0.1016 0.1778)
							(mid 0.137521 0.162921)
							(end 0.1524 0.127)
						)
					)
					(width 0)
					(fill yes)
				)
			)
		)
	)
	(footprint ""
		(layer "F.Cu")
		(at 280.289 -198.247 -90)
		(property "Reference" "C194"
			(at 0 0 270)
			(layer "F.SilkS")
			(hide yes)
			(effects
				(font
					(size 1.27 1.27)
				)
			)
		)
		(property "Value" "SC1U6D3V3KX-2GP"
			(at 0 -2.8194 270)
			(unlocked yes)
			(layer "F.Fab")
			(hide yes)
			(effects
				(font
					(size 1.016 1.016)
					(thickness 0.1524)
				)
			)
		)
		(property "Device Type" "C603H36"
			(at 0 -4.3434 270)
			(unlocked yes)
			(layer "F.Fab")
			(hide yes)
			(effects
				(font
					(size 1.016 1.016)
					(thickness 0.1524)
				)
			)
		)
		(duplicate_pad_numbers_are_jumpers no)
		(fp_line
			(start 0.508 0)
			(end -0.508 0)
			(stroke
				(width 0.2032)
				(type default)
			)
			(layer "F.SilkS")
		)
		(fp_rect
			(start -0.5842 1.3335)
			(end 0.5842 -1.3335)
			(stroke
				(width 0)
				(type default)
			)
			(fill no)
			(layer "F.CrtYd")
		)
		(fp_rect
			(start -0.5842 1.3335)
			(end 0.5842 -1.3335)
			(stroke
				(width 0)
				(type default)
			)
			(fill no)
			(layer "F.Fab")
		)
		(pad "1" smd custom
			(at 0 -0.762 270)
			(size 0.2159 0.2159)
			(layers "F.Cu" "F.Mask" "F.Paste")
			(net "MPLLAV33")
			(options
				(clearance outline)
				(anchor circle)
			)
			(primitives
				(gr_poly
					(pts
						(arc
							(start -0.3302 -0.4318)
							(mid -0.402042 -0.402042)
							(end -0.4318 -0.3302)
						)
						(arc
							(start -0.4318 0.3302)
							(mid -0.402042 0.402042)
							(end -0.3302 0.4318)
						)
						(arc
							(start 0.3302 0.4318)
							(mid 0.402042 0.402042)
							(end 0.4318 0.3302)
						)
						(arc
							(start 0.4318 -0.3302)
							(mid 0.402042 -0.402042)
							(end 0.3302 -0.4318)
						)
					)
					(width 0)
					(fill yes)
				)
			)
		)
		(pad "2" smd custom
			(at 0 0.762 270)
			(size 0.2159 0.2159)
			(layers "F.Cu" "F.Mask" "F.Paste")
			(net "GND")
			(options
				(clearance outline)
				(anchor circle)
			)
			(primitives
				(gr_poly
					(pts
						(arc
							(start -0.3302 -0.4318)
							(mid -0.402042 -0.402042)
							(end -0.4318 -0.3302)
						)
						(arc
							(start -0.4318 0.3302)
							(mid -0.402042 0.402042)
							(end -0.3302 0.4318)
						)
						(arc
							(start 0.3302 0.4318)
							(mid 0.402042 0.402042)
							(end 0.4318 0.3302)
						)
						(arc
							(start 0.4318 -0.3302)
							(mid 0.402042 -0.402042)
							(end 0.3302 -0.4318)
						)
					)
					(width 0)
					(fill yes)
				)
			)
		)
	)
	(footprint ""
		(layer "F.Cu")
		(at 194.183 -34.036 -90)
		(property "Reference" "R463"
			(at 0 0 270)
			(layer "F.SilkS")
			(hide yes)
			(effects
				(font
					(size 1.27 1.27)
				)
			)
		)
		(property "Value" "0R2J-2-GP"
			(at 0.064008 -3.993896 270)
			(unlocked yes)
			(layer "F.Fab")
			(hide yes)
			(effects
				(font
					(size 1.016 1.016)
					(thickness 0.1524)
				)
			)
		)
		(property "Device Type" "R402H16"
			(at 0.064008 -5.517896 270)
			(unlocked yes)
			(layer "F.Fab")
			(hide yes)
			(effects
				(font
					(size 1.016 1.016)
					(thickness 0.1524)
				)
			)
		)
		(duplicate_pad_numbers_are_jumpers no)
		(fp_line
			(start -0.508 -0.9398)
			(end -0.508 0.9398)
			(stroke
				(width 0.1524)
				(type default)
			)
			(layer "F.SilkS")
		)
		(fp_line
			(start 0.508 -0.9398)
			(end -0.508 -0.9398)
			(stroke
				(width 0.1524)
				(type default)
			)
			(layer "F.SilkS")
		)
		(fp_rect
			(start -0.508 0.9398)
			(end 0.508 -0.9398)
			(stroke
				(width 0)
				(type default)
			)
			(fill no)
			(layer "F.CrtYd")
		)
		(fp_rect
			(start -0.508 0.9398)
			(end 0.508 -0.9398)
			(stroke
				(width 0)
				(type default)
			)
			(fill no)
			(layer "F.Fab")
		)
		(pad "1" smd custom
			(at 0 -0.4445 270)
			(size 0.1397 0.1397)
			(layers "F.Cu" "F.Mask" "F.Paste")
			(net "GND")
			(options
				(clearance outline)
				(anchor circle)
			)
			(primitives
				(gr_poly
					(pts
						(arc
							(start -0.1778 -0.2794)
							(mid -0.249642 -0.249642)
							(end -0.2794 -0.1778)
						)
						(arc
							(start -0.2794 0.1778)
							(mid -0.249642 0.249642)
							(end -0.1778 0.2794)
						)
						(arc
							(start 0.1778 0.2794)
							(mid 0.249642 0.249642)
							(end 0.2794 0.1778)
						)
						(arc
							(start 0.2794 -0.1778)
							(mid 0.249642 -0.249642)
							(end 0.1778 -0.2794)
						)
					)
					(width 0)
					(fill yes)
				)
			)
		)
		(pad "2" smd custom
			(at 0 0.4445 270)
			(size 0.1397 0.1397)
			(layers "F.Cu" "F.Mask" "F.Paste")
			(net "RMII_BMC_TX_EN")
			(options
				(clearance outline)
				(anchor circle)
			)
			(primitives
				(gr_poly
					(pts
						(arc
							(start -0.1778 -0.2794)
							(mid -0.249642 -0.249642)
							(end -0.2794 -0.1778)
						)
						(arc
							(start -0.2794 0.1778)
							(mid -0.249642 0.249642)
							(end -0.1778 0.2794)
						)
						(arc
							(start 0.1778 0.2794)
							(mid 0.249642 0.249642)
							(end 0.2794 0.1778)
						)
						(arc
							(start 0.2794 -0.1778)
							(mid 0.249642 -0.249642)
							(end 0.1778 -0.2794)
						)
					)
					(width 0)
					(fill yes)
				)
			)
		)
	)
	(footprint ""
		(layer "F.Cu")
		(at 48.768 -214.376 -90)
		(property "Reference" "R2103"
			(at 0 0 270)
			(layer "F.SilkS")
			(hide yes)
			(effects
				(font
					(size 1.27 1.27)
				)
			)
		)
		(property "Value" "150KR2J-GP"
			(at 0.064008 -3.993896 270)
			(unlocked yes)
			(layer "F.Fab")
			(hide yes)
			(effects
				(font
					(size 1.016 1.016)
					(thickness 0.1524)
				)
			)
		)
		(property "Device Type" "R402H16"
			(at 0.064008 -5.517896 270)
			(unlocked yes)
			(layer "F.Fab")
			(hide yes)
			(effects
				(font
					(size 1.016 1.016)
					(thickness 0.1524)
				)
			)
		)
		(duplicate_pad_numbers_are_jumpers no)
		(fp_line
			(start -0.508 -0.9398)
			(end -0.508 0.9398)
			(stroke
				(width 0.1524)
				(type default)
			)
			(layer "F.SilkS")
		)
		(fp_line
			(start 0.508 -0.9398)
			(end -0.508 -0.9398)
			(stroke
				(width 0.1524)
				(type default)
			)
			(layer "F.SilkS")
		)
		(fp_rect
			(start -0.508 0.9398)
			(end 0.508 -0.9398)
			(stroke
				(width 0)
				(type default)
			)
			(fill no)
			(layer "F.CrtYd")
		)
		(fp_rect
			(start -0.508 0.9398)
			(end 0.508 -0.9398)
			(stroke
				(width 0)
				(type default)
			)
			(fill no)
			(layer "F.Fab")
		)
		(pad "1" smd custom
			(at 0 -0.4445 270)
			(size 0.1397 0.1397)
			(layers "F.Cu" "F.Mask" "F.Paste")
			(net "MB0_CM_ADR1_R")
			(options
				(clearance outline)
				(anchor circle)
			)
			(primitives
				(gr_poly
					(pts
						(arc
							(start -0.1778 -0.2794)
							(mid -0.249642 -0.249642)
							(end -0.2794 -0.1778)
						)
						(arc
							(start -0.2794 0.1778)
							(mid -0.249642 0.249642)
							(end -0.1778 0.2794)
						)
						(arc
							(start 0.1778 0.2794)
							(mid 0.249642 0.249642)
							(end 0.2794 0.1778)
						)
						(arc
							(start 0.2794 -0.1778)
							(mid 0.249642 -0.249642)
							(end 0.1778 -0.2794)
						)
					)
					(width 0)
					(fill yes)
				)
			)
		)
		(pad "2" smd custom
			(at 0 0.4445 270)
			(size 0.1397 0.1397)
			(layers "F.Cu" "F.Mask" "F.Paste")
			(net "AGND_CURRENT_MON")
			(options
				(clearance outline)
				(anchor circle)
			)
			(primitives
				(gr_poly
					(pts
						(arc
							(start -0.1778 -0.2794)
							(mid -0.249642 -0.249642)
							(end -0.2794 -0.1778)
						)
						(arc
							(start -0.2794 0.1778)
							(mid -0.249642 0.249642)
							(end -0.1778 0.2794)
						)
						(arc
							(start 0.1778 0.2794)
							(mid 0.249642 0.249642)
							(end 0.2794 0.1778)
						)
						(arc
							(start 0.2794 -0.1778)
							(mid 0.249642 -0.249642)
							(end 0.1778 -0.2794)
						)
					)
					(width 0)
					(fill yes)
				)
			)
		)
	)
	(footprint ""
		(layer "F.Cu")
		(at 258.318 -16.383 180)
		(property "Reference" "F1"
			(at 0 0 180)
			(layer "F.SilkS")
			(hide yes)
			(effects
				(font
					(size 1.27 1.27)
				)
			)
		)
		(property "Value" "POLYSW-1D5A8V-4-GP"
			(at -2.401824 -0.181102 180)
			(unlocked yes)
			(layer "F.Fab")
			(hide yes)
			(effects
				(font
					(size 1.016 1.016)
					(thickness 0.1524)
				)
			)
		)
		(property "Device Type" "POLYSW-3217-UH40"
			(at -2.401824 -1.705102 180)
			(unlocked yes)
			(layer "F.Fab")
			(hide yes)
			(effects
				(font
					(size 1.016 1.016)
					(thickness 0.1524)
				)
			)
		)
		(duplicate_pad_numbers_are_jumpers no)
		(fp_line
			(start 1.2065 2.2479)
			(end 1.2065 -2.2479)
			(stroke
				(width 0.1524)
				(type default)
			)
			(layer "F.SilkS")
		)
		(fp_line
			(start 1.2065 -2.2479)
			(end -1.2065 -2.2479)
			(stroke
				(width 0.1524)
				(type default)
			)
			(layer "F.SilkS")
		)
		(fp_line
			(start -1.2065 2.2479)
			(end 1.2065 2.2479)
			(stroke
				(width 0.1524)
				(type default)
			)
			(layer "F.SilkS")
		)
		(fp_line
			(start -1.2065 -2.2479)
			(end -1.2065 2.2479)
			(stroke
				(width 0.1524)
				(type default)
			)
			(layer "F.SilkS")
		)
		(fp_rect
			(start -0.8255 1.6002)
			(end 0.8255 -1.6002)
			(stroke
				(width 0)
				(type default)
			)
			(fill no)
			(layer "F.CrtYd")
		)
		(fp_poly
			(pts
				(xy -1.4605 2.3241) (xy -1.4605 -2.3241) (xy 1.4605 -2.3241) (xy 1.4605 1.59512) (xy 0.8255 1.59512)
				(xy 0.8255 -1.6002) (xy -0.8255 -1.6002) (xy -0.8255 1.6002) (xy 1.4605 1.6002) (xy 1.4605 2.3241)
			)
			(stroke
				(width 0)
				(type default)
			)
			(fill no)
			(layer "F.CrtYd")
		)
		(fp_rect
			(start -1.4605 2.3241)
			(end 1.4605 -2.3241)
			(stroke
				(width 0)
				(type default)
			)
			(fill no)
			(layer "F.Fab")
		)
		(pad "1" smd rect
			(at 0 -1.417574 180)
			(size 1.905 1.143)
			(layers "F.Cu" "F.Mask" "F.Paste")
			(net "P5V_USB")
		)
		(pad "2" smd rect
			(at 0 1.417574 180)
			(size 1.905 1.143)
			(layers "F.Cu" "F.Mask" "F.Paste")
			(net "P5V_USB_BP1_F")
		)
	)
	(footprint ""
		(layer "F.Cu")
		(at 181.36997 -67.183)
		(property "Reference" "C290"
			(at 0 0 0)
			(layer "F.SilkS")
			(hide yes)
			(effects
				(font
					(size 1.27 1.27)
				)
			)
		)
		(property "Value" "SCD1U25V2KX-2-GP"
			(at 1.1811 -2.7051 0)
			(unlocked yes)
			(layer "F.Fab")
			(hide yes)
			(effects
				(font
					(size 1.016 1.016)
					(thickness 0.1524)
				)
			)
		)
		(property "Device Type" "C402H22"
			(at 1.1811 -4.2291 0)
			(unlocked yes)
			(layer "F.Fab")
			(hide yes)
			(effects
				(font
					(size 1.016 1.016)
					(thickness 0.1524)
				)
			)
		)
		(duplicate_pad_numbers_are_jumpers no)
		(fp_rect
			(start -0.4318 0.9525)
			(end 0.4318 -0.9525)
			(stroke
				(width 0)
				(type default)
			)
			(fill no)
			(layer "F.CrtYd")
		)
		(fp_rect
			(start -0.4318 0.9525)
			(end 0.4318 -0.9525)
			(stroke
				(width 0)
				(type default)
			)
			(fill no)
			(layer "F.Fab")
		)
		(pad "1" smd custom
			(at 0 -0.4445)
			(size 0.1524 0.1524)
			(layers "F.Cu" "F.Mask" "F.Paste")
			(net "TP_MSB_A33_CPU_SATA_RX_P")
			(options
				(clearance outline)
				(anchor circle)
			)
			(primitives
				(gr_poly
					(pts
						(arc
							(start 0.3048 -0.2032)
							(mid 0.275042 -0.275042)
							(end 0.2032 -0.3048)
						)
						(arc
							(start -0.2032 -0.3048)
							(mid -0.275042 -0.275042)
							(end -0.3048 -0.2032)
						)
						(arc
							(start -0.3048 0.2032)
							(mid -0.275042 0.275042)
							(end -0.2032 0.3048)
						)
						(arc
							(start 0.2032 0.3048)
							(mid 0.275042 0.275042)
							(end 0.3048 0.2032)
						)
					)
					(width 0)
					(fill yes)
				)
			)
		)
		(pad "2" smd custom
			(at 0 0.4445)
			(size 0.1524 0.1524)
			(layers "F.Cu" "F.Mask" "F.Paste")
			(net "GND")
			(options
				(clearance outline)
				(anchor circle)
			)
			(primitives
				(gr_poly
					(pts
						(arc
							(start 0.3048 -0.2032)
							(mid 0.275042 -0.275042)
							(end 0.2032 -0.3048)
						)
						(arc
							(start -0.2032 -0.3048)
							(mid -0.275042 -0.275042)
							(end -0.3048 -0.2032)
						)
						(arc
							(start -0.3048 0.2032)
							(mid -0.275042 0.275042)
							(end -0.2032 0.3048)
						)
						(arc
							(start 0.2032 0.3048)
							(mid 0.275042 0.275042)
							(end 0.3048 0.2032)
						)
					)
					(width 0)
					(fill yes)
				)
			)
		)
	)
	(footprint ""
		(layer "F.Cu")
		(at 81.285842 -120.721882 -90)
		(property "Reference" "SR741"
			(at 0 0 270)
			(layer "F.SilkS")
			(hide yes)
			(effects
				(font
					(size 1.27 1.27)
				)
			)
		)
		(property "Value" "2K2R2F-GP"
			(at 0.064008 -3.993896 270)
			(unlocked yes)
			(layer "F.Fab")
			(hide yes)
			(effects
				(font
					(size 1.016 1.016)
					(thickness 0.1524)
				)
			)
		)
		(property "Device Type" "R402H16"
			(at 0.064008 -5.517896 270)
			(unlocked yes)
			(layer "F.Fab")
			(hide yes)
			(effects
				(font
					(size 1.016 1.016)
					(thickness 0.1524)
				)
			)
		)
		(duplicate_pad_numbers_are_jumpers no)
		(fp_line
			(start -0.508 -0.9398)
			(end -0.508 0.9398)
			(stroke
				(width 0.1524)
				(type default)
			)
			(layer "F.SilkS")
		)
		(fp_line
			(start 0.508 -0.9398)
			(end -0.508 -0.9398)
			(stroke
				(width 0.1524)
				(type default)
			)
			(layer "F.SilkS")
		)
		(fp_rect
			(start -0.508 0.9398)
			(end 0.508 -0.9398)
			(stroke
				(width 0)
				(type default)
			)
			(fill no)
			(layer "F.CrtYd")
		)
		(fp_rect
			(start -0.508 0.9398)
			(end 0.508 -0.9398)
			(stroke
				(width 0)
				(type default)
			)
			(fill no)
			(layer "F.Fab")
		)
		(pad "1" smd custom
			(at 0 -0.4445 270)
			(size 0.1397 0.1397)
			(layers "F.Cu" "F.Mask" "F.Paste")
			(net "EXP_SDA_0")
			(options
				(clearance outline)
				(anchor circle)
			)
			(primitives
				(gr_poly
					(pts
						(arc
							(start -0.1778 -0.2794)
							(mid -0.249642 -0.249642)
							(end -0.2794 -0.1778)
						)
						(arc
							(start -0.2794 0.1778)
							(mid -0.249642 0.249642)
							(end -0.1778 0.2794)
						)
						(arc
							(start 0.1778 0.2794)
							(mid 0.249642 0.249642)
							(end 0.2794 0.1778)
						)
						(arc
							(start 0.2794 -0.1778)
							(mid 0.249642 -0.249642)
							(end 0.1778 -0.2794)
						)
					)
					(width 0)
					(fill yes)
				)
			)
		)
		(pad "2" smd custom
			(at 0 0.4445 270)
			(size 0.1397 0.1397)
			(layers "F.Cu" "F.Mask" "F.Paste")
			(net "P1V8_E")
			(options
				(clearance outline)
				(anchor circle)
			)
			(primitives
				(gr_poly
					(pts
						(arc
							(start -0.1778 -0.2794)
							(mid -0.249642 -0.249642)
							(end -0.2794 -0.1778)
						)
						(arc
							(start -0.2794 0.1778)
							(mid -0.249642 0.249642)
							(end -0.1778 0.2794)
						)
						(arc
							(start 0.1778 0.2794)
							(mid 0.249642 0.249642)
							(end 0.2794 0.1778)
						)
						(arc
							(start 0.2794 -0.1778)
							(mid 0.249642 -0.249642)
							(end 0.1778 -0.2794)
						)
					)
					(width 0)
					(fill yes)
				)
			)
		)
	)
	(footprint ""
		(layer "F.Cu")
		(at 108.85297 -114.3 180)
		(property "Reference" "SC1082"
			(at 0 0 180)
			(layer "F.SilkS")
			(hide yes)
			(effects
				(font
					(size 1.27 1.27)
				)
			)
		)
		(property "Value" "SCD01U10V1KX-GP"
			(at -2.8321 -1.7399 180)
			(unlocked yes)
			(layer "F.Fab")
			(hide yes)
			(effects
				(font
					(size 1.016 1.016)
					(thickness 0.1524)
				)
			)
		)
		(property "Device Type" "C0201H13"
			(at -2.8321 -3.2639 180)
			(unlocked yes)
			(layer "F.Fab")
			(hide yes)
			(effects
				(font
					(size 1.016 1.016)
					(thickness 0.1524)
				)
			)
		)
		(duplicate_pad_numbers_are_jumpers no)
		(fp_rect
			(start -0.2794 0.6477)
			(end 0.2794 -0.6477)
			(stroke
				(width 0)
				(type default)
			)
			(fill no)
			(layer "F.CrtYd")
		)
		(fp_rect
			(start -0.2794 0.6477)
			(end 0.2794 -0.6477)
			(stroke
				(width 0)
				(type default)
			)
			(fill no)
			(layer "F.Fab")
		)
		(pad "1" smd custom
			(at 0 -0.2794 180)
			(size 0.0762 0.0762)
			(layers "F.Cu" "F.Mask" "F.Paste")
			(net "SAS_HDD_TX7_N")
			(options
				(clearance outline)
				(anchor circle)
			)
			(primitives
				(gr_poly
					(pts
						(arc
							(start 0.1524 -0.127)
							(mid 0.137521 -0.162921)
							(end 0.1016 -0.1778)
						)
						(arc
							(start -0.1016 -0.1778)
							(mid -0.137521 -0.162921)
							(end -0.1524 -0.127)
						)
						(arc
							(start -0.1524 0.127)
							(mid -0.137521 0.162921)
							(end -0.1016 0.1778)
						)
						(arc
							(start 0.1016 0.1778)
							(mid 0.137521 0.162921)
							(end 0.1524 0.127)
						)
					)
					(width 0)
					(fill yes)
				)
			)
		)
		(pad "2" smd custom
			(at 0 0.2794 180)
			(size 0.0762 0.0762)
			(layers "F.Cu" "F.Mask" "F.Paste")
			(net "SAS_EXP_GF_TX_DN11")
			(options
				(clearance outline)
				(anchor circle)
			)
			(primitives
				(gr_poly
					(pts
						(arc
							(start 0.1524 -0.127)
							(mid 0.137521 -0.162921)
							(end 0.1016 -0.1778)
						)
						(arc
							(start -0.1016 -0.1778)
							(mid -0.137521 -0.162921)
							(end -0.1524 -0.127)
						)
						(arc
							(start -0.1524 0.127)
							(mid -0.137521 0.162921)
							(end -0.1016 0.1778)
						)
						(arc
							(start 0.1016 0.1778)
							(mid 0.137521 0.162921)
							(end 0.1524 0.127)
						)
					)
					(width 0)
					(fill yes)
				)
			)
		)
	)
	(footprint ""
		(layer "F.Cu")
		(at 50.546 -109.601 -90)
		(property "Reference" "SC1307"
			(at 0 0 270)
			(layer "F.SilkS")
			(hide yes)
			(effects
				(font
					(size 1.27 1.27)
				)
			)
		)
		(property "Value" "SCD1U16V2KX-3GP"
			(at 1.1811 -2.7051 270)
			(unlocked yes)
			(layer "F.Fab")
			(hide yes)
			(effects
				(font
					(size 1.016 1.016)
					(thickness 0.1524)
				)
			)
		)
		(property "Device Type" "C402H22"
			(at 1.1811 -4.2291 270)
			(unlocked yes)
			(layer "F.Fab")
			(hide yes)
			(effects
				(font
					(size 1.016 1.016)
					(thickness 0.1524)
				)
			)
		)
		(duplicate_pad_numbers_are_jumpers no)
		(fp_rect
			(start -0.4318 0.9525)
			(end 0.4318 -0.9525)
			(stroke
				(width 0)
				(type default)
			)
			(fill no)
			(layer "F.CrtYd")
		)
		(fp_rect
			(start -0.4318 0.9525)
			(end 0.4318 -0.9525)
			(stroke
				(width 0)
				(type default)
			)
			(fill no)
			(layer "F.Fab")
		)
		(pad "1" smd custom
			(at 0 -0.4445 270)
			(size 0.1524 0.1524)
			(layers "F.Cu" "F.Mask" "F.Paste")
			(net "P5V_STBY")
			(options
				(clearance outline)
				(anchor circle)
			)
			(primitives
				(gr_poly
					(pts
						(arc
							(start 0.3048 -0.2032)
							(mid 0.275042 -0.275042)
							(end 0.2032 -0.3048)
						)
						(arc
							(start -0.2032 -0.3048)
							(mid -0.275042 -0.275042)
							(end -0.3048 -0.2032)
						)
						(arc
							(start -0.3048 0.2032)
							(mid -0.275042 0.275042)
							(end -0.2032 0.3048)
						)
						(arc
							(start 0.2032 0.3048)
							(mid 0.275042 0.275042)
							(end 0.3048 0.2032)
						)
					)
					(width 0)
					(fill yes)
				)
			)
		)
		(pad "2" smd custom
			(at 0 0.4445 270)
			(size 0.1524 0.1524)
			(layers "F.Cu" "F.Mask" "F.Paste")
			(net "GND")
			(options
				(clearance outline)
				(anchor circle)
			)
			(primitives
				(gr_poly
					(pts
						(arc
							(start 0.3048 -0.2032)
							(mid 0.275042 -0.275042)
							(end 0.2032 -0.3048)
						)
						(arc
							(start -0.2032 -0.3048)
							(mid -0.275042 -0.275042)
							(end -0.3048 -0.2032)
						)
						(arc
							(start -0.3048 0.2032)
							(mid -0.275042 0.275042)
							(end -0.2032 0.3048)
						)
						(arc
							(start 0.2032 0.3048)
							(mid 0.275042 0.275042)
							(end 0.3048 0.2032)
						)
					)
					(width 0)
					(fill yes)
				)
			)
		)
	)
	(footprint ""
		(layer "F.Cu")
		(at 30.011116 -80.379062 -90)
		(property "Reference" "R678"
			(at 0 0 270)
			(layer "F.SilkS")
			(hide yes)
			(effects
				(font
					(size 1.27 1.27)
				)
			)
		)
		(property "Value" "1KR2F-3-GP"
			(at 0.064008 -3.993896 270)
			(unlocked yes)
			(layer "F.Fab")
			(hide yes)
			(effects
				(font
					(size 1.016 1.016)
					(thickness 0.1524)
				)
			)
		)
		(property "Device Type" "R402H16"
			(at 0.064008 -5.517896 270)
			(unlocked yes)
			(layer "F.Fab")
			(hide yes)
			(effects
				(font
					(size 1.016 1.016)
					(thickness 0.1524)
				)
			)
		)
		(duplicate_pad_numbers_are_jumpers no)
		(fp_line
			(start -0.508 -0.9398)
			(end -0.508 0.9398)
			(stroke
				(width 0.1524)
				(type default)
			)
			(layer "F.SilkS")
		)
		(fp_line
			(start 0.508 -0.9398)
			(end -0.508 -0.9398)
			(stroke
				(width 0.1524)
				(type default)
			)
			(layer "F.SilkS")
		)
		(fp_rect
			(start -0.508 0.9398)
			(end 0.508 -0.9398)
			(stroke
				(width 0)
				(type default)
			)
			(fill no)
			(layer "F.CrtYd")
		)
		(fp_rect
			(start -0.508 0.9398)
			(end 0.508 -0.9398)
			(stroke
				(width 0)
				(type default)
			)
			(fill no)
			(layer "F.Fab")
		)
		(pad "1" smd custom
			(at 0 -0.4445 270)
			(size 0.1397 0.1397)
			(layers "F.Cu" "F.Mask" "F.Paste")
			(net "INTA_LED_RED_B")
			(options
				(clearance outline)
				(anchor circle)
			)
			(primitives
				(gr_poly
					(pts
						(arc
							(start -0.1778 -0.2794)
							(mid -0.249642 -0.249642)
							(end -0.2794 -0.1778)
						)
						(arc
							(start -0.2794 0.1778)
							(mid -0.249642 0.249642)
							(end -0.1778 0.2794)
						)
						(arc
							(start 0.1778 0.2794)
							(mid 0.249642 0.249642)
							(end 0.2794 0.1778)
						)
						(arc
							(start 0.2794 -0.1778)
							(mid 0.249642 -0.249642)
							(end 0.1778 -0.2794)
						)
					)
					(width 0)
					(fill yes)
				)
			)
		)
		(pad "2" smd custom
			(at 0 0.4445 270)
			(size 0.1397 0.1397)
			(layers "F.Cu" "F.Mask" "F.Paste")
			(net "GND")
			(options
				(clearance outline)
				(anchor circle)
			)
			(primitives
				(gr_poly
					(pts
						(arc
							(start -0.1778 -0.2794)
							(mid -0.249642 -0.249642)
							(end -0.2794 -0.1778)
						)
						(arc
							(start -0.2794 0.1778)
							(mid -0.249642 0.249642)
							(end -0.1778 0.2794)
						)
						(arc
							(start 0.1778 0.2794)
							(mid 0.249642 0.249642)
							(end 0.2794 0.1778)
						)
						(arc
							(start 0.2794 -0.1778)
							(mid 0.249642 -0.249642)
							(end 0.1778 -0.2794)
						)
					)
					(width 0)
					(fill yes)
				)
			)
		)
	)
	(footprint ""
		(layer "F.Cu")
		(at 198.755 -93.853 -90)
		(property "Reference" "PC236"
			(at 0 0 270)
			(layer "F.SilkS")
			(hide yes)
			(effects
				(font
					(size 1.27 1.27)
				)
			)
		)
		(property "Value" "SC22U6D3V5MX-2GP"
			(at -0.0762 -6.1214 270)
			(unlocked yes)
			(layer "F.Fab")
			(hide yes)
			(effects
				(font
					(size 1.016 1.016)
					(thickness 0.1524)
				)
			)
		)
		(property "Device Type" "C805H58"
			(at -0.0762 -8.1534 270)
			(unlocked yes)
			(layer "F.Fab")
			(hide yes)
			(effects
				(font
					(size 1.016 1.016)
					(thickness 0.1524)
				)
			)
		)
		(duplicate_pad_numbers_are_jumpers no)
		(fp_line
			(start 0.635 0)
			(end -0.635 0)
			(stroke
				(width 0.508)
				(type default)
			)
			(layer "F.SilkS")
		)
		(fp_rect
			(start -0.9652 1.778)
			(end 0.9652 -1.778)
			(stroke
				(width 0)
				(type default)
			)
			(fill no)
			(layer "F.CrtYd")
		)
		(fp_poly
			(pts
				(xy -0.9652 -1.778) (xy 0.9652 -1.778) (xy 0.9652 1.778) (xy -0.9652 1.778)
			)
			(stroke
				(width 0)
				(type default)
			)
			(fill no)
			(layer "F.Fab")
		)
		(pad "1" smd rect
			(at 0 -0.9652 270)
			(size 1.397 1.143)
			(layers "F.Cu" "F.Mask" "F.Paste")
			(net "P1V5_E")
		)
		(pad "2" smd rect
			(at 0 0.9652 270)
			(size 1.397 1.143)
			(layers "F.Cu" "F.Mask" "F.Paste")
			(net "GND")
		)
	)
	(footprint ""
		(layer "F.Cu")
		(at 18.238216 -202.11288)
		(property "Reference" "SC867"
			(at 0 0 0)
			(layer "F.SilkS")
			(hide yes)
			(effects
				(font
					(size 1.27 1.27)
				)
			)
		)
		(property "Value" "SCD1U16V2KX-3GP"
			(at 1.1811 -2.7051 0)
			(unlocked yes)
			(layer "F.Fab")
			(hide yes)
			(effects
				(font
					(size 1.016 1.016)
					(thickness 0.1524)
				)
			)
		)
		(property "Device Type" "C402H22"
			(at 1.1811 -4.2291 0)
			(unlocked yes)
			(layer "F.Fab")
			(hide yes)
			(effects
				(font
					(size 1.016 1.016)
					(thickness 0.1524)
				)
			)
		)
		(duplicate_pad_numbers_are_jumpers no)
		(fp_rect
			(start -0.4318 0.9525)
			(end 0.4318 -0.9525)
			(stroke
				(width 0)
				(type default)
			)
			(fill no)
			(layer "F.CrtYd")
		)
		(fp_rect
			(start -0.4318 0.9525)
			(end 0.4318 -0.9525)
			(stroke
				(width 0)
				(type default)
			)
			(fill no)
			(layer "F.Fab")
		)
		(pad "1" smd custom
			(at 0 -0.4445)
			(size 0.1524 0.1524)
			(layers "F.Cu" "F.Mask" "F.Paste")
			(net "BMC_I2C10_EN")
			(options
				(clearance outline)
				(anchor circle)
			)
			(primitives
				(gr_poly
					(pts
						(arc
							(start 0.3048 -0.2032)
							(mid 0.275042 -0.275042)
							(end 0.2032 -0.3048)
						)
						(arc
							(start -0.2032 -0.3048)
							(mid -0.275042 -0.275042)
							(end -0.3048 -0.2032)
						)
						(arc
							(start -0.3048 0.2032)
							(mid -0.275042 0.275042)
							(end -0.2032 0.3048)
						)
						(arc
							(start 0.2032 0.3048)
							(mid 0.275042 0.275042)
							(end 0.3048 0.2032)
						)
					)
					(width 0)
					(fill yes)
				)
			)
		)
		(pad "2" smd custom
			(at 0 0.4445)
			(size 0.1524 0.1524)
			(layers "F.Cu" "F.Mask" "F.Paste")
			(net "GND")
			(options
				(clearance outline)
				(anchor circle)
			)
			(primitives
				(gr_poly
					(pts
						(arc
							(start 0.3048 -0.2032)
							(mid 0.275042 -0.275042)
							(end 0.2032 -0.3048)
						)
						(arc
							(start -0.2032 -0.3048)
							(mid -0.275042 -0.275042)
							(end -0.3048 -0.2032)
						)
						(arc
							(start -0.3048 0.2032)
							(mid -0.275042 0.275042)
							(end -0.2032 0.3048)
						)
						(arc
							(start 0.2032 0.3048)
							(mid 0.275042 0.275042)
							(end 0.3048 0.2032)
						)
					)
					(width 0)
					(fill yes)
				)
			)
		)
	)
	(footprint ""
		(layer "F.Cu")
		(at 142.621 -64.135 90)
		(property "Reference" "SC1099"
			(at 0 0 90)
			(layer "F.SilkS")
			(hide yes)
			(effects
				(font
					(size 1.27 1.27)
				)
			)
		)
		(property "Value" "SCD1U16V2KX-3GP"
			(at 1.1811 -2.7051 90)
			(unlocked yes)
			(layer "F.Fab")
			(hide yes)
			(effects
				(font
					(size 1.016 1.016)
					(thickness 0.1524)
				)
			)
		)
		(property "Device Type" "C402H22"
			(at 1.1811 -4.2291 90)
			(unlocked yes)
			(layer "F.Fab")
			(hide yes)
			(effects
				(font
					(size 1.016 1.016)
					(thickness 0.1524)
				)
			)
		)
		(duplicate_pad_numbers_are_jumpers no)
		(fp_rect
			(start -0.4318 0.9525)
			(end 0.4318 -0.9525)
			(stroke
				(width 0)
				(type default)
			)
			(fill no)
			(layer "F.CrtYd")
		)
		(fp_rect
			(start -0.4318 0.9525)
			(end 0.4318 -0.9525)
			(stroke
				(width 0)
				(type default)
			)
			(fill no)
			(layer "F.Fab")
		)
		(pad "1" smd custom
			(at 0 -0.4445 90)
			(size 0.1524 0.1524)
			(layers "F.Cu" "F.Mask" "F.Paste")
			(net "P3V3")
			(options
				(clearance outline)
				(anchor circle)
			)
			(primitives
				(gr_poly
					(pts
						(arc
							(start 0.3048 -0.2032)
							(mid 0.275042 -0.275042)
							(end 0.2032 -0.3048)
						)
						(arc
							(start -0.2032 -0.3048)
							(mid -0.275042 -0.275042)
							(end -0.3048 -0.2032)
						)
						(arc
							(start -0.3048 0.2032)
							(mid -0.275042 0.275042)
							(end -0.2032 0.3048)
						)
						(arc
							(start 0.2032 0.3048)
							(mid 0.275042 0.275042)
							(end 0.3048 0.2032)
						)
					)
					(width 0)
					(fill yes)
				)
			)
		)
		(pad "2" smd custom
			(at 0 0.4445 90)
			(size 0.1524 0.1524)
			(layers "F.Cu" "F.Mask" "F.Paste")
			(net "GND")
			(options
				(clearance outline)
				(anchor circle)
			)
			(primitives
				(gr_poly
					(pts
						(arc
							(start 0.3048 -0.2032)
							(mid 0.275042 -0.275042)
							(end 0.2032 -0.3048)
						)
						(arc
							(start -0.2032 -0.3048)
							(mid -0.275042 -0.275042)
							(end -0.3048 -0.2032)
						)
						(arc
							(start -0.3048 0.2032)
							(mid -0.275042 0.275042)
							(end -0.2032 0.3048)
						)
						(arc
							(start 0.2032 0.3048)
							(mid 0.275042 0.275042)
							(end 0.3048 0.2032)
						)
					)
					(width 0)
					(fill yes)
				)
			)
		)
	)
	(footprint ""
		(layer "F.Cu")
		(at 90.786966 -60.325)
		(property "Reference" "STP39"
			(at 0 0 0)
			(layer "F.SilkS")
			(hide yes)
			(effects
				(font
					(size 1.27 1.27)
				)
			)
		)
		(property "Value" "TPAD28"
			(at 0.0127 -1.8034 0)
			(unlocked yes)
			(layer "F.Fab")
			(hide yes)
			(effects
				(font
					(size 1.016 1.016)
					(thickness 0.1524)
				)
			)
		)
		(property "Device Type" "TPAD28"
			(at 0.0127 -3.3274 0)
			(unlocked yes)
			(layer "F.Fab")
			(hide yes)
			(effects
				(font
					(size 1.016 1.016)
					(thickness 0.1524)
				)
			)
		)
		(duplicate_pad_numbers_are_jumpers no)
		(fp_poly
			(pts
				(arc
					(start 0.3556 0)
					(mid -0.3556 0)
					(end 0.3556 0)
				)
			)
			(stroke
				(width 0)
				(type default)
			)
			(fill no)
			(layer "F.CrtYd")
		)
		(fp_poly
			(pts
				(arc
					(start 0.6096 0)
					(mid -0.6096 0)
					(end 0.6096 0)
				)
			)
			(stroke
				(width 0)
				(type default)
			)
			(fill no)
			(layer "F.Fab")
		)
		(pad "1" smd circle
			(at 0 0)
			(size 0.7112 0.7112)
			(layers "F.Cu" "F.Mask" "F.Paste")
			(net "ICE1_TRST#")
		)
	)
	(footprint ""
		(layer "F.Cu")
		(at 47.4472 -119.0752)
		(property "Reference" "SC1300"
			(at 0 0 0)
			(layer "F.SilkS")
			(hide yes)
			(effects
				(font
					(size 1.27 1.27)
				)
			)
		)
		(property "Value" "SCD1U16V2KX-3GP"
			(at 1.1811 -2.7051 0)
			(unlocked yes)
			(layer "F.Fab")
			(hide yes)
			(effects
				(font
					(size 1.016 1.016)
					(thickness 0.1524)
				)
			)
		)
		(property "Device Type" "C402H22"
			(at 1.1811 -4.2291 0)
			(unlocked yes)
			(layer "F.Fab")
			(hide yes)
			(effects
				(font
					(size 1.016 1.016)
					(thickness 0.1524)
				)
			)
		)
		(duplicate_pad_numbers_are_jumpers no)
		(fp_rect
			(start -0.4318 0.9525)
			(end 0.4318 -0.9525)
			(stroke
				(width 0)
				(type default)
			)
			(fill no)
			(layer "F.CrtYd")
		)
		(fp_rect
			(start -0.4318 0.9525)
			(end 0.4318 -0.9525)
			(stroke
				(width 0)
				(type default)
			)
			(fill no)
			(layer "F.Fab")
		)
		(pad "1" smd custom
			(at 0 -0.4445)
			(size 0.1524 0.1524)
			(layers "F.Cu" "F.Mask" "F.Paste")
			(net "P1V8_E")
			(options
				(clearance outline)
				(anchor circle)
			)
			(primitives
				(gr_poly
					(pts
						(arc
							(start 0.3048 -0.2032)
							(mid 0.275042 -0.275042)
							(end 0.2032 -0.3048)
						)
						(arc
							(start -0.2032 -0.3048)
							(mid -0.275042 -0.275042)
							(end -0.3048 -0.2032)
						)
						(arc
							(start -0.3048 0.2032)
							(mid -0.275042 0.275042)
							(end -0.2032 0.3048)
						)
						(arc
							(start 0.2032 0.3048)
							(mid 0.275042 0.275042)
							(end 0.3048 0.2032)
						)
					)
					(width 0)
					(fill yes)
				)
			)
		)
		(pad "2" smd custom
			(at 0 0.4445)
			(size 0.1524 0.1524)
			(layers "F.Cu" "F.Mask" "F.Paste")
			(net "GND")
			(options
				(clearance outline)
				(anchor circle)
			)
			(primitives
				(gr_poly
					(pts
						(arc
							(start 0.3048 -0.2032)
							(mid 0.275042 -0.275042)
							(end 0.2032 -0.3048)
						)
						(arc
							(start -0.2032 -0.3048)
							(mid -0.275042 -0.275042)
							(end -0.3048 -0.2032)
						)
						(arc
							(start -0.3048 0.2032)
							(mid -0.275042 0.275042)
							(end -0.2032 0.3048)
						)
						(arc
							(start 0.2032 0.3048)
							(mid 0.275042 0.275042)
							(end 0.3048 0.2032)
						)
					)
					(width 0)
					(fill yes)
				)
			)
		)
	)
	(footprint ""
		(layer "F.Cu")
		(at 110.63097 -114.3 180)
		(property "Reference" "SC1080"
			(at 0 0 180)
			(layer "F.SilkS")
			(hide yes)
			(effects
				(font
					(size 1.27 1.27)
				)
			)
		)
		(property "Value" "SCD01U10V1KX-GP"
			(at -2.8321 -1.7399 180)
			(unlocked yes)
			(layer "F.Fab")
			(hide yes)
			(effects
				(font
					(size 1.016 1.016)
					(thickness 0.1524)
				)
			)
		)
		(property "Device Type" "C0201H13"
			(at -2.8321 -3.2639 180)
			(unlocked yes)
			(layer "F.Fab")
			(hide yes)
			(effects
				(font
					(size 1.016 1.016)
					(thickness 0.1524)
				)
			)
		)
		(duplicate_pad_numbers_are_jumpers no)
		(fp_rect
			(start -0.2794 0.6477)
			(end 0.2794 -0.6477)
			(stroke
				(width 0)
				(type default)
			)
			(fill no)
			(layer "F.CrtYd")
		)
		(fp_rect
			(start -0.2794 0.6477)
			(end 0.2794 -0.6477)
			(stroke
				(width 0)
				(type default)
			)
			(fill no)
			(layer "F.Fab")
		)
		(pad "1" smd custom
			(at 0 -0.2794 180)
			(size 0.0762 0.0762)
			(layers "F.Cu" "F.Mask" "F.Paste")
			(net "SAS_HDD_TX6_N")
			(options
				(clearance outline)
				(anchor circle)
			)
			(primitives
				(gr_poly
					(pts
						(arc
							(start 0.1524 -0.127)
							(mid 0.137521 -0.162921)
							(end 0.1016 -0.1778)
						)
						(arc
							(start -0.1016 -0.1778)
							(mid -0.137521 -0.162921)
							(end -0.1524 -0.127)
						)
						(arc
							(start -0.1524 0.127)
							(mid -0.137521 0.162921)
							(end -0.1016 0.1778)
						)
						(arc
							(start 0.1016 0.1778)
							(mid 0.137521 0.162921)
							(end 0.1524 0.127)
						)
					)
					(width 0)
					(fill yes)
				)
			)
		)
		(pad "2" smd custom
			(at 0 0.2794 180)
			(size 0.0762 0.0762)
			(layers "F.Cu" "F.Mask" "F.Paste")
			(net "SAS_EXP_GF_TX_DN10")
			(options
				(clearance outline)
				(anchor circle)
			)
			(primitives
				(gr_poly
					(pts
						(arc
							(start 0.1524 -0.127)
							(mid 0.137521 -0.162921)
							(end 0.1016 -0.1778)
						)
						(arc
							(start -0.1016 -0.1778)
							(mid -0.137521 -0.162921)
							(end -0.1524 -0.127)
						)
						(arc
							(start -0.1524 0.127)
							(mid -0.137521 0.162921)
							(end -0.1016 0.1778)
						)
						(arc
							(start 0.1016 0.1778)
							(mid 0.137521 0.162921)
							(end 0.1524 0.127)
						)
					)
					(width 0)
					(fill yes)
				)
			)
		)
	)
	(footprint ""
		(layer "F.Cu")
		(at 204.089 -217.424 90)
		(property "Reference" "C42"
			(at 0 0 90)
			(layer "F.SilkS")
			(hide yes)
			(effects
				(font
					(size 1.27 1.27)
				)
			)
		)
		(property "Value" "SCD1U16V2KX-3GP"
			(at 1.1811 -2.7051 90)
			(unlocked yes)
			(layer "F.Fab")
			(hide yes)
			(effects
				(font
					(size 1.016 1.016)
					(thickness 0.1524)
				)
			)
		)
		(property "Device Type" "C402H22"
			(at 1.1811 -4.2291 90)
			(unlocked yes)
			(layer "F.Fab")
			(hide yes)
			(effects
				(font
					(size 1.016 1.016)
					(thickness 0.1524)
				)
			)
		)
		(duplicate_pad_numbers_are_jumpers no)
		(fp_rect
			(start -0.4318 0.9525)
			(end 0.4318 -0.9525)
			(stroke
				(width 0)
				(type default)
			)
			(fill no)
			(layer "F.CrtYd")
		)
		(fp_rect
			(start -0.4318 0.9525)
			(end 0.4318 -0.9525)
			(stroke
				(width 0)
				(type default)
			)
			(fill no)
			(layer "F.Fab")
		)
		(pad "1" smd custom
			(at 0 -0.4445 90)
			(size 0.1524 0.1524)
			(layers "F.Cu" "F.Mask" "F.Paste")
			(net "P3V3_STBY")
			(options
				(clearance outline)
				(anchor circle)
			)
			(primitives
				(gr_poly
					(pts
						(arc
							(start 0.3048 -0.2032)
							(mid 0.275042 -0.275042)
							(end 0.2032 -0.3048)
						)
						(arc
							(start -0.2032 -0.3048)
							(mid -0.275042 -0.275042)
							(end -0.3048 -0.2032)
						)
						(arc
							(start -0.3048 0.2032)
							(mid -0.275042 0.275042)
							(end -0.2032 0.3048)
						)
						(arc
							(start 0.2032 0.3048)
							(mid 0.275042 0.275042)
							(end 0.3048 0.2032)
						)
					)
					(width 0)
					(fill yes)
				)
			)
		)
		(pad "2" smd custom
			(at 0 0.4445 90)
			(size 0.1524 0.1524)
			(layers "F.Cu" "F.Mask" "F.Paste")
			(net "GND")
			(options
				(clearance outline)
				(anchor circle)
			)
			(primitives
				(gr_poly
					(pts
						(arc
							(start 0.3048 -0.2032)
							(mid 0.275042 -0.275042)
							(end 0.2032 -0.3048)
						)
						(arc
							(start -0.2032 -0.3048)
							(mid -0.275042 -0.275042)
							(end -0.3048 -0.2032)
						)
						(arc
							(start -0.3048 0.2032)
							(mid -0.275042 0.275042)
							(end -0.2032 0.3048)
						)
						(arc
							(start 0.2032 0.3048)
							(mid 0.275042 0.275042)
							(end 0.3048 0.2032)
						)
					)
					(width 0)
					(fill yes)
				)
			)
		)
	)
	(footprint ""
		(layer "F.Cu")
		(at 144.126966 -40.513)
		(property "Reference" "STP119"
			(at 0 0 0)
			(layer "F.SilkS")
			(hide yes)
			(effects
				(font
					(size 1.27 1.27)
				)
			)
		)
		(property "Value" "TPAD28"
			(at 0.0127 -1.8034 0)
			(unlocked yes)
			(layer "F.Fab")
			(hide yes)
			(effects
				(font
					(size 1.016 1.016)
					(thickness 0.1524)
				)
			)
		)
		(property "Device Type" "TPAD28"
			(at 0.0127 -3.3274 0)
			(unlocked yes)
			(layer "F.Fab")
			(hide yes)
			(effects
				(font
					(size 1.016 1.016)
					(thickness 0.1524)
				)
			)
		)
		(duplicate_pad_numbers_are_jumpers no)
		(fp_poly
			(pts
				(arc
					(start 0.3556 0)
					(mid -0.3556 0)
					(end 0.3556 0)
				)
			)
			(stroke
				(width 0)
				(type default)
			)
			(fill no)
			(layer "F.CrtYd")
		)
		(fp_poly
			(pts
				(arc
					(start 0.6096 0)
					(mid -0.6096 0)
					(end 0.6096 0)
				)
			)
			(stroke
				(width 0)
				(type default)
			)
			(fill no)
			(layer "F.Fab")
		)
		(pad "1" smd circle
			(at 0 0)
			(size 0.7112 0.7112)
			(layers "F.Cu" "F.Mask" "F.Paste")
			(net "XM_ADDR_19")
		)
	)
	(footprint ""
		(layer "F.Cu")
		(at 187.006992 -38.227)
		(property "Reference" "R372"
			(at 0 0 0)
			(layer "F.SilkS")
			(hide yes)
			(effects
				(font
					(size 1.27 1.27)
				)
			)
		)
		(property "Value" "0R2J-2-GP"
			(at 0.064008 -3.993896 0)
			(unlocked yes)
			(layer "F.Fab")
			(hide yes)
			(effects
				(font
					(size 1.016 1.016)
					(thickness 0.1524)
				)
			)
		)
		(property "Device Type" "R402H16"
			(at 0.064008 -5.517896 0)
			(unlocked yes)
			(layer "F.Fab")
			(hide yes)
			(effects
				(font
					(size 1.016 1.016)
					(thickness 0.1524)
				)
			)
		)
		(duplicate_pad_numbers_are_jumpers no)
		(fp_line
			(start -0.508 -0.9398)
			(end -0.508 0.9398)
			(stroke
				(width 0.1524)
				(type default)
			)
			(layer "F.SilkS")
		)
		(fp_line
			(start 0.508 -0.9398)
			(end -0.508 -0.9398)
			(stroke
				(width 0.1524)
				(type default)
			)
			(layer "F.SilkS")
		)
		(fp_rect
			(start -0.508 0.9398)
			(end 0.508 -0.9398)
			(stroke
				(width 0)
				(type default)
			)
			(fill no)
			(layer "F.CrtYd")
		)
		(fp_rect
			(start -0.508 0.9398)
			(end 0.508 -0.9398)
			(stroke
				(width 0)
				(type default)
			)
			(fill no)
			(layer "F.Fab")
		)
		(pad "1" smd custom
			(at 0 -0.4445)
			(size 0.1397 0.1397)
			(layers "F.Cu" "F.Mask" "F.Paste")
			(net "FM_BMC_RESET_N")
			(options
				(clearance outline)
				(anchor circle)
			)
			(primitives
				(gr_poly
					(pts
						(arc
							(start -0.1778 -0.2794)
							(mid -0.249642 -0.249642)
							(end -0.2794 -0.1778)
						)
						(arc
							(start -0.2794 0.1778)
							(mid -0.249642 0.249642)
							(end -0.1778 0.2794)
						)
						(arc
							(start 0.1778 0.2794)
							(mid 0.249642 0.249642)
							(end 0.2794 0.1778)
						)
						(arc
							(start 0.2794 -0.1778)
							(mid 0.249642 -0.249642)
							(end 0.1778 -0.2794)
						)
					)
					(width 0)
					(fill yes)
				)
			)
		)
		(pad "2" smd custom
			(at 0 0.4445)
			(size 0.1397 0.1397)
			(layers "F.Cu" "F.Mask" "F.Paste")
			(net "PHY_RESET#")
			(options
				(clearance outline)
				(anchor circle)
			)
			(primitives
				(gr_poly
					(pts
						(arc
							(start -0.1778 -0.2794)
							(mid -0.249642 -0.249642)
							(end -0.2794 -0.1778)
						)
						(arc
							(start -0.2794 0.1778)
							(mid -0.249642 0.249642)
							(end -0.1778 0.2794)
						)
						(arc
							(start 0.1778 0.2794)
							(mid 0.249642 0.249642)
							(end 0.2794 0.1778)
						)
						(arc
							(start 0.2794 -0.1778)
							(mid 0.249642 -0.249642)
							(end 0.1778 -0.2794)
						)
					)
					(width 0)
					(fill yes)
				)
			)
		)
	)
	(footprint ""
		(layer "F.Cu")
		(at 57.785 -231.267 -90)
		(property "Reference" "R9020"
			(at 0 0 270)
			(layer "F.SilkS")
			(hide yes)
			(effects
				(font
					(size 1.27 1.27)
				)
			)
		)
		(property "Value" "D002RL3115F-L-GP"
			(at 3.2258 1.2954 270)
			(unlocked yes)
			(layer "F.Fab")
			(hide yes)
			(effects
				(font
					(size 1.016 1.016)
					(thickness 0.1524)
				)
			)
		)
		(property "Device Type" "RL3115-4PH45"
			(at 3.2258 -0.2286 270)
			(unlocked yes)
			(layer "F.Fab")
			(hide yes)
			(effects
				(font
					(size 1.016 1.016)
					(thickness 0.1524)
				)
			)
		)
		(duplicate_pad_numbers_are_jumpers no)
		(fp_line
			(start -1.9685 1.651)
			(end -1.9685 -1.651)
			(stroke
				(width 0.1524)
				(type default)
			)
			(layer "F.SilkS")
		)
		(fp_line
			(start 1.9685 1.651)
			(end -1.9685 1.651)
			(stroke
				(width 0.1524)
				(type default)
			)
			(layer "F.SilkS")
		)
		(fp_line
			(start -1.9685 -1.651)
			(end 1.9685 -1.651)
			(stroke
				(width 0.1524)
				(type default)
			)
			(layer "F.SilkS")
		)
		(fp_line
			(start 1.9685 -1.651)
			(end 1.9685 1.651)
			(stroke
				(width 0.1524)
				(type default)
			)
			(layer "F.SilkS")
		)
		(fp_line
			(start -2.0574 -1.7653)
			(end -2.0574 -0.4064)
			(stroke
				(width 0.3302)
				(type default)
			)
			(layer "F.SilkS")
		)
		(fp_line
			(start -0.5334 -1.7653)
			(end -2.0574 -1.7653)
			(stroke
				(width 0.3302)
				(type default)
			)
			(layer "F.SilkS")
		)
		(fp_poly
			(pts
				(xy -0.561594 -1.726946) (xy -0.053594 -2.234946) (xy -1.069594 -2.234946)
			)
			(stroke
				(width 0)
				(type default)
			)
			(fill yes)
			(layer "F.SilkS")
		)
		(fp_rect
			(start -1.524 0.7493)
			(end 1.524 -0.7493)
			(stroke
				(width 0)
				(type default)
			)
			(fill no)
			(layer "F.CrtYd")
		)
		(fp_poly
			(pts
				(xy -2.2225 1.905) (xy -2.2225 -1.905) (xy 2.2225 -1.905) (xy 2.2225 -0.7493) (xy -1.524 -0.7493)
				(xy -1.524 0.7493) (xy 1.524 0.7493) (xy 1.524 -0.7366) (xy 2.2225 -0.7366) (xy 2.2225 1.905)
			)
			(stroke
				(width 0)
				(type default)
			)
			(fill no)
			(layer "F.CrtYd")
		)
		(fp_rect
			(start -2.2225 1.905)
			(end 2.2225 -1.905)
			(stroke
				(width 0)
				(type default)
			)
			(fill no)
			(layer "F.Fab")
		)
		(pad "1" smd rect
			(at -0.5715 -0.813562 270)
			(size 2.286 1.143)
			(layers "F.Cu" "F.Mask" "F.Paste")
			(net "MB0_P12V_MAIN_R")
		)
		(pad "2" smd rect
			(at -0.5715 0.813562 270)
			(size 2.286 1.143)
			(layers "F.Cu" "F.Mask" "F.Paste")
			(net "P12V_PCIE")
		)
		(pad "3" smd rect
			(at 1.334008 -0.813562 270)
			(size 0.762 1.143)
			(layers "F.Cu" "F.Mask" "F.Paste")
			(net "MB0_CM_SENSE_R1_N")
		)
		(pad "4" smd rect
			(at 1.334008 0.813562 270)
			(size 0.762 1.143)
			(layers "F.Cu" "F.Mask" "F.Paste")
			(net "MB0_CM_SENSE_R1_P")
		)
		(zone
			(layer "F.Cu")
			(hatch none 0.5)
			(connect_pads
				(clearance 0)
			)
			(min_thickness 0.25)
			(keepout
				(tracks allowed)
				(vias not_allowed)
				(pads allowed)
				(copperpour not_allowed)
				(footprints allowed)
			)
			(placement
				(enabled no)
				(sheetname "")
			)
			(fill
				(thermal_gap 0.5)
				(thermal_bridge_width 0.5)
				(island_removal_mode 0)
			)
			(polygon
				(pts
					(xy 57.0357 -230.6955) (xy 57.0357 -230.313992) (xy 57.542938 -230.313992) (xy 57.542938 -230.6955)
				)
			)
		)
		(zone
			(layer "F.Cu")
			(hatch none 0.5)
			(connect_pads
				(clearance 0)
			)
			(min_thickness 0.25)
			(keepout
				(tracks not_allowed)
				(vias allowed)
				(pads allowed)
				(copperpour not_allowed)
				(footprints allowed)
			)
			(placement
				(enabled no)
				(sheetname "")
			)
			(fill
				(thermal_gap 0.5)
				(thermal_bridge_width 0.5)
				(island_removal_mode 0)
			)
			(polygon
				(pts
					(xy 57.0357 -230.6955) (xy 57.0357 -230.313992) (xy 57.542938 -230.313992) (xy 57.542938 -230.6955)
				)
			)
		)
		(zone
			(layer "F.Cu")
			(hatch none 0.5)
			(connect_pads
				(clearance 0)
			)
			(min_thickness 0.25)
			(keepout
				(tracks not_allowed)
				(vias allowed)
				(pads allowed)
				(copperpour not_allowed)
				(footprints allowed)
			)
			(placement
				(enabled no)
				(sheetname "")
			)
			(fill
				(thermal_gap 0.5)
				(thermal_bridge_width 0.5)
				(island_removal_mode 0)
			)
			(polygon
				(pts
					(xy 58.027062 -230.6955) (xy 58.027062 -230.313992) (xy 58.5343 -230.313992) (xy 58.5343 -230.6955)
				)
			)
		)
		(zone
			(layer "F.Cu")
			(hatch none 0.5)
			(connect_pads
				(clearance 0)
			)
			(min_thickness 0.25)
			(keepout
				(tracks allowed)
				(vias not_allowed)
				(pads allowed)
				(copperpour not_allowed)
				(footprints allowed)
			)
			(placement
				(enabled no)
				(sheetname "")
			)
			(fill
				(thermal_gap 0.5)
				(thermal_bridge_width 0.5)
				(island_removal_mode 0)
			)
			(polygon
				(pts
					(xy 58.027062 -230.6955) (xy 58.027062 -230.313992) (xy 58.5343 -230.313992) (xy 58.5343 -230.6955)
				)
			)
		)
	)
	(footprint ""
		(layer "F.Cu")
		(at 42.3672 -116.2812 90)
		(property "Reference" "SR938"
			(at 0 0 90)
			(layer "F.SilkS")
			(hide yes)
			(effects
				(font
					(size 1.27 1.27)
				)
			)
		)
		(property "Value" "0R2J-2-GP"
			(at 0.064008 -3.993896 90)
			(unlocked yes)
			(layer "F.Fab")
			(hide yes)
			(effects
				(font
					(size 1.016 1.016)
					(thickness 0.1524)
				)
			)
		)
		(property "Device Type" "R402H16"
			(at 0.064008 -5.517896 90)
			(unlocked yes)
			(layer "F.Fab")
			(hide yes)
			(effects
				(font
					(size 1.016 1.016)
					(thickness 0.1524)
				)
			)
		)
		(duplicate_pad_numbers_are_jumpers no)
		(fp_line
			(start 0.508 -0.9398)
			(end -0.508 -0.9398)
			(stroke
				(width 0.1524)
				(type default)
			)
			(layer "F.SilkS")
		)
		(fp_line
			(start -0.508 -0.9398)
			(end -0.508 0.9398)
			(stroke
				(width 0.1524)
				(type default)
			)
			(layer "F.SilkS")
		)
		(fp_rect
			(start -0.508 0.9398)
			(end 0.508 -0.9398)
			(stroke
				(width 0)
				(type default)
			)
			(fill no)
			(layer "F.CrtYd")
		)
		(fp_rect
			(start -0.508 0.9398)
			(end 0.508 -0.9398)
			(stroke
				(width 0)
				(type default)
			)
			(fill no)
			(layer "F.Fab")
		)
		(pad "1" smd custom
			(at 0 -0.4445 90)
			(size 0.1397 0.1397)
			(layers "F.Cu" "F.Mask" "F.Paste")
			(net "SAS_SDBTX")
			(options
				(clearance outline)
				(anchor circle)
			)
			(primitives
				(gr_poly
					(pts
						(arc
							(start -0.1778 -0.2794)
							(mid -0.249642 -0.249642)
							(end -0.2794 -0.1778)
						)
						(arc
							(start -0.2794 0.1778)
							(mid -0.249642 0.249642)
							(end -0.1778 0.2794)
						)
						(arc
							(start 0.1778 0.2794)
							(mid 0.249642 0.249642)
							(end 0.2794 0.1778)
						)
						(arc
							(start 0.2794 -0.1778)
							(mid 0.249642 -0.249642)
							(end 0.1778 -0.2794)
						)
					)
					(width 0)
					(fill yes)
				)
			)
		)
		(pad "2" smd custom
			(at 0 0.4445 90)
			(size 0.1397 0.1397)
			(layers "F.Cu" "F.Mask" "F.Paste")
			(net "SAS_R_SDBTX")
			(options
				(clearance outline)
				(anchor circle)
			)
			(primitives
				(gr_poly
					(pts
						(arc
							(start -0.1778 -0.2794)
							(mid -0.249642 -0.249642)
							(end -0.2794 -0.1778)
						)
						(arc
							(start -0.2794 0.1778)
							(mid -0.249642 0.249642)
							(end -0.1778 0.2794)
						)
						(arc
							(start 0.1778 0.2794)
							(mid 0.249642 0.249642)
							(end 0.2794 0.1778)
						)
						(arc
							(start 0.2794 -0.1778)
							(mid 0.249642 -0.249642)
							(end 0.1778 -0.2794)
						)
					)
					(width 0)
					(fill yes)
				)
			)
		)
	)
	(footprint ""
		(layer "F.Cu")
		(at 320.9798 -119.4308 180)
		(property "Reference" "PR19"
			(at 0 0 180)
			(layer "F.SilkS")
			(hide yes)
			(effects
				(font
					(size 1.27 1.27)
				)
			)
		)
		(property "Value" "2D2R3J-2-GP"
			(at -0.0254 -2.5146 180)
			(unlocked yes)
			(layer "F.Fab")
			(hide yes)
			(effects
				(font
					(size 1.016 1.016)
					(thickness 0.1524)
				)
			)
		)
		(property "Device Type" "R603H22"
			(at -0.0254 -4.0386 180)
			(unlocked yes)
			(layer "F.Fab")
			(hide yes)
			(effects
				(font
					(size 1.016 1.016)
					(thickness 0.1524)
				)
			)
		)
		(duplicate_pad_numbers_are_jumpers no)
		(fp_line
			(start 0.2032 0)
			(end 0.4826 0)
			(stroke
				(width 0.2032)
				(type default)
			)
			(layer "F.SilkS")
		)
		(fp_line
			(start -0.4826 0)
			(end -0.2032 0)
			(stroke
				(width 0.2032)
				(type default)
			)
			(layer "F.SilkS")
		)
		(fp_rect
			(start -0.5842 1.3335)
			(end 0.5842 -1.3335)
			(stroke
				(width 0)
				(type default)
			)
			(fill no)
			(layer "F.CrtYd")
		)
		(fp_rect
			(start -0.5842 1.3335)
			(end 0.5842 -1.3335)
			(stroke
				(width 0)
				(type default)
			)
			(fill no)
			(layer "F.Fab")
		)
		(pad "1" smd custom
			(at 0 -0.762 180)
			(size 0.2159 0.2159)
			(layers "F.Cu" "F.Mask" "F.Paste")
			(net "P3V3_STBY_VDD")
			(options
				(clearance outline)
				(anchor circle)
			)
			(primitives
				(gr_poly
					(pts
						(arc
							(start -0.3302 -0.4318)
							(mid -0.402042 -0.402042)
							(end -0.4318 -0.3302)
						)
						(arc
							(start -0.4318 0.3302)
							(mid -0.402042 0.402042)
							(end -0.3302 0.4318)
						)
						(arc
							(start 0.3302 0.4318)
							(mid 0.402042 0.402042)
							(end 0.4318 0.3302)
						)
						(arc
							(start 0.4318 -0.3302)
							(mid 0.402042 -0.402042)
							(end 0.3302 -0.4318)
						)
					)
					(width 0)
					(fill yes)
				)
			)
		)
		(pad "2" smd custom
			(at 0 0.762 180)
			(size 0.2159 0.2159)
			(layers "F.Cu" "F.Mask" "F.Paste")
			(net "P12V")
			(options
				(clearance outline)
				(anchor circle)
			)
			(primitives
				(gr_poly
					(pts
						(arc
							(start -0.3302 -0.4318)
							(mid -0.402042 -0.402042)
							(end -0.4318 -0.3302)
						)
						(arc
							(start -0.4318 0.3302)
							(mid -0.402042 0.402042)
							(end -0.3302 0.4318)
						)
						(arc
							(start 0.3302 0.4318)
							(mid 0.402042 0.402042)
							(end 0.4318 0.3302)
						)
						(arc
							(start 0.4318 -0.3302)
							(mid 0.402042 -0.402042)
							(end 0.3302 -0.4318)
						)
					)
					(width 0)
					(fill yes)
				)
			)
		)
	)
	(footprint ""
		(layer "F.Cu")
		(at 347.374718 -143.233648)
		(property "Reference" "C254"
			(at 0 0 0)
			(layer "F.SilkS")
			(hide yes)
			(effects
				(font
					(size 1.27 1.27)
				)
			)
		)
		(property "Value" "SC1U10V2KX-4-GP"
			(at 1.1811 -2.7051 0)
			(unlocked yes)
			(layer "F.Fab")
			(hide yes)
			(effects
				(font
					(size 1.016 1.016)
					(thickness 0.1524)
				)
			)
		)
		(property "Device Type" "C402H22"
			(at 1.1811 -4.2291 0)
			(unlocked yes)
			(layer "F.Fab")
			(hide yes)
			(effects
				(font
					(size 1.016 1.016)
					(thickness 0.1524)
				)
			)
		)
		(duplicate_pad_numbers_are_jumpers no)
		(fp_rect
			(start -0.4318 0.9525)
			(end 0.4318 -0.9525)
			(stroke
				(width 0)
				(type default)
			)
			(fill no)
			(layer "F.CrtYd")
		)
		(fp_rect
			(start -0.4318 0.9525)
			(end 0.4318 -0.9525)
			(stroke
				(width 0)
				(type default)
			)
			(fill no)
			(layer "F.Fab")
		)
		(pad "1" smd custom
			(at 0 -0.4445)
			(size 0.1524 0.1524)
			(layers "F.Cu" "F.Mask" "F.Paste")
			(net "P3V3_STBY")
			(options
				(clearance outline)
				(anchor circle)
			)
			(primitives
				(gr_poly
					(pts
						(arc
							(start 0.3048 -0.2032)
							(mid 0.275042 -0.275042)
							(end 0.2032 -0.3048)
						)
						(arc
							(start -0.2032 -0.3048)
							(mid -0.275042 -0.275042)
							(end -0.3048 -0.2032)
						)
						(arc
							(start -0.3048 0.2032)
							(mid -0.275042 0.275042)
							(end -0.2032 0.3048)
						)
						(arc
							(start 0.2032 0.3048)
							(mid 0.275042 0.275042)
							(end 0.3048 0.2032)
						)
					)
					(width 0)
					(fill yes)
				)
			)
		)
		(pad "2" smd custom
			(at 0 0.4445)
			(size 0.1524 0.1524)
			(layers "F.Cu" "F.Mask" "F.Paste")
			(net "GND")
			(options
				(clearance outline)
				(anchor circle)
			)
			(primitives
				(gr_poly
					(pts
						(arc
							(start 0.3048 -0.2032)
							(mid 0.275042 -0.275042)
							(end 0.2032 -0.3048)
						)
						(arc
							(start -0.2032 -0.3048)
							(mid -0.275042 -0.275042)
							(end -0.3048 -0.2032)
						)
						(arc
							(start -0.3048 0.2032)
							(mid -0.275042 0.275042)
							(end -0.2032 0.3048)
						)
						(arc
							(start 0.2032 0.3048)
							(mid 0.275042 0.275042)
							(end 0.3048 0.2032)
						)
					)
					(width 0)
					(fill yes)
				)
			)
		)
	)
	(footprint ""
		(layer "F.Cu")
		(at 332.431136 -200.033128)
		(property "Reference" "R198"
			(at 0 0 0)
			(layer "F.SilkS")
			(hide yes)
			(effects
				(font
					(size 1.27 1.27)
				)
			)
		)
		(property "Value" "8K2R2J-3-GP"
			(at 0.064008 -3.993896 0)
			(unlocked yes)
			(layer "F.Fab")
			(hide yes)
			(effects
				(font
					(size 1.016 1.016)
					(thickness 0.1524)
				)
			)
		)
		(property "Device Type" "R402H16"
			(at 0.064008 -5.517896 0)
			(unlocked yes)
			(layer "F.Fab")
			(hide yes)
			(effects
				(font
					(size 1.016 1.016)
					(thickness 0.1524)
				)
			)
		)
		(duplicate_pad_numbers_are_jumpers no)
		(fp_line
			(start -0.508 -0.9398)
			(end -0.508 0.9398)
			(stroke
				(width 0.1524)
				(type default)
			)
			(layer "F.SilkS")
		)
		(fp_line
			(start 0.508 -0.9398)
			(end -0.508 -0.9398)
			(stroke
				(width 0.1524)
				(type default)
			)
			(layer "F.SilkS")
		)
		(fp_rect
			(start -0.508 0.9398)
			(end 0.508 -0.9398)
			(stroke
				(width 0)
				(type default)
			)
			(fill no)
			(layer "F.CrtYd")
		)
		(fp_rect
			(start -0.508 0.9398)
			(end 0.508 -0.9398)
			(stroke
				(width 0)
				(type default)
			)
			(fill no)
			(layer "F.Fab")
		)
		(pad "1" smd custom
			(at 0 -0.4445)
			(size 0.1397 0.1397)
			(layers "F.Cu" "F.Mask" "F.Paste")
			(net "EEPROM_A1_R")
			(options
				(clearance outline)
				(anchor circle)
			)
			(primitives
				(gr_poly
					(pts
						(arc
							(start -0.1778 -0.2794)
							(mid -0.249642 -0.249642)
							(end -0.2794 -0.1778)
						)
						(arc
							(start -0.2794 0.1778)
							(mid -0.249642 0.249642)
							(end -0.1778 0.2794)
						)
						(arc
							(start 0.1778 0.2794)
							(mid 0.249642 0.249642)
							(end 0.2794 0.1778)
						)
						(arc
							(start 0.2794 -0.1778)
							(mid 0.249642 -0.249642)
							(end 0.1778 -0.2794)
						)
					)
					(width 0)
					(fill yes)
				)
			)
		)
		(pad "2" smd custom
			(at 0 0.4445)
			(size 0.1397 0.1397)
			(layers "F.Cu" "F.Mask" "F.Paste")
			(net "GND")
			(options
				(clearance outline)
				(anchor circle)
			)
			(primitives
				(gr_poly
					(pts
						(arc
							(start -0.1778 -0.2794)
							(mid -0.249642 -0.249642)
							(end -0.2794 -0.1778)
						)
						(arc
							(start -0.2794 0.1778)
							(mid -0.249642 0.249642)
							(end -0.1778 0.2794)
						)
						(arc
							(start 0.1778 0.2794)
							(mid 0.249642 0.249642)
							(end 0.2794 0.1778)
						)
						(arc
							(start 0.2794 -0.1778)
							(mid 0.249642 -0.249642)
							(end 0.1778 -0.2794)
						)
					)
					(width 0)
					(fill yes)
				)
			)
		)
	)
	(footprint ""
		(layer "F.Cu")
		(at 282.194 -188.976)
		(property "Reference" "R298"
			(at 0 0 0)
			(layer "F.SilkS")
			(hide yes)
			(effects
				(font
					(size 1.27 1.27)
				)
			)
		)
		(property "Value" "10R2F-L-GP"
			(at 0.064008 -3.993896 0)
			(unlocked yes)
			(layer "F.Fab")
			(hide yes)
			(effects
				(font
					(size 1.016 1.016)
					(thickness 0.1524)
				)
			)
		)
		(property "Device Type" "R402H14"
			(at 0.064008 -5.517896 0)
			(unlocked yes)
			(layer "F.Fab")
			(hide yes)
			(effects
				(font
					(size 1.016 1.016)
					(thickness 0.1524)
				)
			)
		)
		(duplicate_pad_numbers_are_jumpers no)
		(fp_line
			(start -0.508 -0.9398)
			(end -0.508 0.9398)
			(stroke
				(width 0.1524)
				(type default)
			)
			(layer "F.SilkS")
		)
		(fp_line
			(start 0.508 -0.9398)
			(end -0.508 -0.9398)
			(stroke
				(width 0.1524)
				(type default)
			)
			(layer "F.SilkS")
		)
		(fp_rect
			(start -0.508 0.9398)
			(end 0.508 -0.9398)
			(stroke
				(width 0)
				(type default)
			)
			(fill no)
			(layer "F.CrtYd")
		)
		(fp_rect
			(start -0.508 0.9398)
			(end 0.508 -0.9398)
			(stroke
				(width 0)
				(type default)
			)
			(fill no)
			(layer "F.Fab")
		)
		(pad "1" smd custom
			(at 0 -0.4445)
			(size 0.1397 0.1397)
			(layers "F.Cu" "F.Mask" "F.Paste")
			(net "OSC2_OUT")
			(options
				(clearance outline)
				(anchor circle)
			)
			(primitives
				(gr_poly
					(pts
						(arc
							(start -0.1778 -0.2794)
							(mid -0.249642 -0.249642)
							(end -0.2794 -0.1778)
						)
						(arc
							(start -0.2794 0.1778)
							(mid -0.249642 0.249642)
							(end -0.1778 0.2794)
						)
						(arc
							(start 0.1778 0.2794)
							(mid 0.249642 0.249642)
							(end 0.2794 0.1778)
						)
						(arc
							(start 0.2794 -0.1778)
							(mid 0.249642 -0.249642)
							(end 0.1778 -0.2794)
						)
					)
					(width 0)
					(fill yes)
				)
			)
		)
		(pad "2" smd custom
			(at 0 0.4445)
			(size 0.1397 0.1397)
			(layers "F.Cu" "F.Mask" "F.Paste")
			(net "OSC0_AS_CLKIN")
			(options
				(clearance outline)
				(anchor circle)
			)
			(primitives
				(gr_poly
					(pts
						(arc
							(start -0.1778 -0.2794)
							(mid -0.249642 -0.249642)
							(end -0.2794 -0.1778)
						)
						(arc
							(start -0.2794 0.1778)
							(mid -0.249642 0.249642)
							(end -0.1778 0.2794)
						)
						(arc
							(start 0.1778 0.2794)
							(mid 0.249642 0.249642)
							(end 0.2794 0.1778)
						)
						(arc
							(start 0.2794 -0.1778)
							(mid 0.249642 -0.249642)
							(end 0.1778 -0.2794)
						)
					)
					(width 0)
					(fill yes)
				)
			)
		)
	)
	(footprint ""
		(layer "F.Cu")
		(at 76.5556 -18.3896 180)
		(property "Reference" "PC208"
			(at 0 0 180)
			(layer "F.SilkS")
			(hide yes)
			(effects
				(font
					(size 1.27 1.27)
				)
			)
		)
		(property "Value" "SC1U25V3KX-GP"
			(at 0 -2.8194 180)
			(unlocked yes)
			(layer "F.Fab")
			(hide yes)
			(effects
				(font
					(size 1.016 1.016)
					(thickness 0.1524)
				)
			)
		)
		(property "Device Type" "C603H36"
			(at 0 -4.3434 180)
			(unlocked yes)
			(layer "F.Fab")
			(hide yes)
			(effects
				(font
					(size 1.016 1.016)
					(thickness 0.1524)
				)
			)
		)
		(duplicate_pad_numbers_are_jumpers no)
		(fp_line
			(start 0.508 0)
			(end -0.508 0)
			(stroke
				(width 0.2032)
				(type default)
			)
			(layer "F.SilkS")
		)
		(fp_rect
			(start -0.5842 1.3335)
			(end 0.5842 -1.3335)
			(stroke
				(width 0)
				(type default)
			)
			(fill no)
			(layer "F.CrtYd")
		)
		(fp_rect
			(start -0.5842 1.3335)
			(end 0.5842 -1.3335)
			(stroke
				(width 0)
				(type default)
			)
			(fill no)
			(layer "F.Fab")
		)
		(pad "1" smd custom
			(at 0 -0.762 180)
			(size 0.2159 0.2159)
			(layers "F.Cu" "F.Mask" "F.Paste")
			(net "VT235_VDDH")
			(options
				(clearance outline)
				(anchor circle)
			)
			(primitives
				(gr_poly
					(pts
						(arc
							(start -0.3302 -0.4318)
							(mid -0.402042 -0.402042)
							(end -0.4318 -0.3302)
						)
						(arc
							(start -0.4318 0.3302)
							(mid -0.402042 0.402042)
							(end -0.3302 0.4318)
						)
						(arc
							(start 0.3302 0.4318)
							(mid 0.402042 0.402042)
							(end 0.4318 0.3302)
						)
						(arc
							(start 0.4318 -0.3302)
							(mid 0.402042 -0.402042)
							(end 0.3302 -0.4318)
						)
					)
					(width 0)
					(fill yes)
				)
			)
		)
		(pad "2" smd custom
			(at 0 0.762 180)
			(size 0.2159 0.2159)
			(layers "F.Cu" "F.Mask" "F.Paste")
			(net "GND")
			(options
				(clearance outline)
				(anchor circle)
			)
			(primitives
				(gr_poly
					(pts
						(arc
							(start -0.3302 -0.4318)
							(mid -0.402042 -0.402042)
							(end -0.4318 -0.3302)
						)
						(arc
							(start -0.4318 0.3302)
							(mid -0.402042 0.402042)
							(end -0.3302 0.4318)
						)
						(arc
							(start 0.3302 0.4318)
							(mid 0.402042 0.402042)
							(end 0.4318 0.3302)
						)
						(arc
							(start 0.4318 -0.3302)
							(mid 0.402042 -0.402042)
							(end 0.3302 -0.4318)
						)
					)
					(width 0)
					(fill yes)
				)
			)
		)
	)
	(footprint ""
		(layer "F.Cu")
		(at 322.961 -138.938)
		(property "Reference" "R5202"
			(at 0 0 0)
			(layer "F.SilkS")
			(hide yes)
			(effects
				(font
					(size 1.27 1.27)
				)
			)
		)
		(property "Value" "1KR2J-1-GP"
			(at 0.064008 -3.993896 0)
			(unlocked yes)
			(layer "F.Fab")
			(hide yes)
			(effects
				(font
					(size 1.016 1.016)
					(thickness 0.1524)
				)
			)
		)
		(property "Device Type" "R402H16"
			(at 0.064008 -5.517896 0)
			(unlocked yes)
			(layer "F.Fab")
			(hide yes)
			(effects
				(font
					(size 1.016 1.016)
					(thickness 0.1524)
				)
			)
		)
		(duplicate_pad_numbers_are_jumpers no)
		(fp_line
			(start -0.508 -0.9398)
			(end -0.508 0.9398)
			(stroke
				(width 0.1524)
				(type default)
			)
			(layer "F.SilkS")
		)
		(fp_line
			(start 0.508 -0.9398)
			(end -0.508 -0.9398)
			(stroke
				(width 0.1524)
				(type default)
			)
			(layer "F.SilkS")
		)
		(fp_rect
			(start -0.508 0.9398)
			(end 0.508 -0.9398)
			(stroke
				(width 0)
				(type default)
			)
			(fill no)
			(layer "F.CrtYd")
		)
		(fp_rect
			(start -0.508 0.9398)
			(end 0.508 -0.9398)
			(stroke
				(width 0)
				(type default)
			)
			(fill no)
			(layer "F.Fab")
		)
		(pad "1" smd custom
			(at 0 -0.4445)
			(size 0.1397 0.1397)
			(layers "F.Cu" "F.Mask" "F.Paste")
			(net "P3V0_BAT_R")
			(options
				(clearance outline)
				(anchor circle)
			)
			(primitives
				(gr_poly
					(pts
						(arc
							(start -0.1778 -0.2794)
							(mid -0.249642 -0.249642)
							(end -0.2794 -0.1778)
						)
						(arc
							(start -0.2794 0.1778)
							(mid -0.249642 0.249642)
							(end -0.1778 0.2794)
						)
						(arc
							(start 0.1778 0.2794)
							(mid 0.249642 0.249642)
							(end 0.2794 0.1778)
						)
						(arc
							(start 0.2794 -0.1778)
							(mid 0.249642 -0.249642)
							(end 0.1778 -0.2794)
						)
					)
					(width 0)
					(fill yes)
				)
			)
		)
		(pad "2" smd custom
			(at 0 0.4445)
			(size 0.1397 0.1397)
			(layers "F.Cu" "F.Mask" "F.Paste")
			(net "P3V0_BAT")
			(options
				(clearance outline)
				(anchor circle)
			)
			(primitives
				(gr_poly
					(pts
						(arc
							(start -0.1778 -0.2794)
							(mid -0.249642 -0.249642)
							(end -0.2794 -0.1778)
						)
						(arc
							(start -0.2794 0.1778)
							(mid -0.249642 0.249642)
							(end -0.1778 0.2794)
						)
						(arc
							(start 0.1778 0.2794)
							(mid 0.249642 0.249642)
							(end 0.2794 0.1778)
						)
						(arc
							(start 0.2794 -0.1778)
							(mid 0.249642 -0.249642)
							(end 0.1778 -0.2794)
						)
					)
					(width 0)
					(fill yes)
				)
			)
		)
	)
	(footprint ""
		(layer "F.Cu")
		(at 6.427216 -226.62388 180)
		(property "Reference" "R158"
			(at 0 0 180)
			(layer "F.SilkS")
			(hide yes)
			(effects
				(font
					(size 1.27 1.27)
				)
			)
		)
		(property "Value" "0R2J-2-GP"
			(at 0.064008 -3.993896 180)
			(unlocked yes)
			(layer "F.Fab")
			(hide yes)
			(effects
				(font
					(size 1.016 1.016)
					(thickness 0.1524)
				)
			)
		)
		(property "Device Type" "R402H16"
			(at 0.064008 -5.517896 180)
			(unlocked yes)
			(layer "F.Fab")
			(hide yes)
			(effects
				(font
					(size 1.016 1.016)
					(thickness 0.1524)
				)
			)
		)
		(duplicate_pad_numbers_are_jumpers no)
		(fp_line
			(start 0.508 -0.9398)
			(end -0.508 -0.9398)
			(stroke
				(width 0.1524)
				(type default)
			)
			(layer "F.SilkS")
		)
		(fp_line
			(start -0.508 -0.9398)
			(end -0.508 0.9398)
			(stroke
				(width 0.1524)
				(type default)
			)
			(layer "F.SilkS")
		)
		(fp_rect
			(start -0.508 0.9398)
			(end 0.508 -0.9398)
			(stroke
				(width 0)
				(type default)
			)
			(fill no)
			(layer "F.CrtYd")
		)
		(fp_rect
			(start -0.508 0.9398)
			(end 0.508 -0.9398)
			(stroke
				(width 0)
				(type default)
			)
			(fill no)
			(layer "F.Fab")
		)
		(pad "1" smd custom
			(at 0 -0.4445 180)
			(size 0.1397 0.1397)
			(layers "F.Cu" "F.Mask" "F.Paste")
			(net "SAS_SEB_PEER_PRSNT_BMC")
			(options
				(clearance outline)
				(anchor circle)
			)
			(primitives
				(gr_poly
					(pts
						(arc
							(start -0.1778 -0.2794)
							(mid -0.249642 -0.249642)
							(end -0.2794 -0.1778)
						)
						(arc
							(start -0.2794 0.1778)
							(mid -0.249642 0.249642)
							(end -0.1778 0.2794)
						)
						(arc
							(start 0.1778 0.2794)
							(mid 0.249642 0.249642)
							(end 0.2794 0.1778)
						)
						(arc
							(start 0.2794 -0.1778)
							(mid 0.249642 -0.249642)
							(end 0.1778 -0.2794)
						)
					)
					(width 0)
					(fill yes)
				)
			)
		)
		(pad "2" smd custom
			(at 0 0.4445 180)
			(size 0.1397 0.1397)
			(layers "F.Cu" "F.Mask" "F.Paste")
			(net "SAS_SEB_PEER_PRSNT")
			(options
				(clearance outline)
				(anchor circle)
			)
			(primitives
				(gr_poly
					(pts
						(arc
							(start -0.1778 -0.2794)
							(mid -0.249642 -0.249642)
							(end -0.2794 -0.1778)
						)
						(arc
							(start -0.2794 0.1778)
							(mid -0.249642 0.249642)
							(end -0.1778 0.2794)
						)
						(arc
							(start 0.1778 0.2794)
							(mid 0.249642 0.249642)
							(end 0.2794 0.1778)
						)
						(arc
							(start 0.2794 -0.1778)
							(mid 0.249642 -0.249642)
							(end 0.1778 -0.2794)
						)
					)
					(width 0)
					(fill yes)
				)
			)
		)
	)
	(footprint ""
		(layer "F.Cu")
		(at 231.267 -17.907 -90)
		(property "Reference" "R529"
			(at 0 0 270)
			(layer "F.SilkS")
			(hide yes)
			(effects
				(font
					(size 1.27 1.27)
				)
			)
		)
		(property "Value" "1KR2F-3-GP"
			(at 0.064008 -3.993896 270)
			(unlocked yes)
			(layer "F.Fab")
			(hide yes)
			(effects
				(font
					(size 1.016 1.016)
					(thickness 0.1524)
				)
			)
		)
		(property "Device Type" "R402H16"
			(at 0.064008 -5.517896 270)
			(unlocked yes)
			(layer "F.Fab")
			(hide yes)
			(effects
				(font
					(size 1.016 1.016)
					(thickness 0.1524)
				)
			)
		)
		(duplicate_pad_numbers_are_jumpers no)
		(fp_line
			(start -0.508 -0.9398)
			(end -0.508 0.9398)
			(stroke
				(width 0.1524)
				(type default)
			)
			(layer "F.SilkS")
		)
		(fp_line
			(start 0.508 -0.9398)
			(end -0.508 -0.9398)
			(stroke
				(width 0.1524)
				(type default)
			)
			(layer "F.SilkS")
		)
		(fp_rect
			(start -0.508 0.9398)
			(end 0.508 -0.9398)
			(stroke
				(width 0)
				(type default)
			)
			(fill no)
			(layer "F.CrtYd")
		)
		(fp_rect
			(start -0.508 0.9398)
			(end 0.508 -0.9398)
			(stroke
				(width 0)
				(type default)
			)
			(fill no)
			(layer "F.Fab")
		)
		(pad "1" smd custom
			(at 0 -0.4445 270)
			(size 0.1397 0.1397)
			(layers "F.Cu" "F.Mask" "F.Paste")
			(net "ENCLO_LED_RED_G")
			(options
				(clearance outline)
				(anchor circle)
			)
			(primitives
				(gr_poly
					(pts
						(arc
							(start -0.1778 -0.2794)
							(mid -0.249642 -0.249642)
							(end -0.2794 -0.1778)
						)
						(arc
							(start -0.2794 0.1778)
							(mid -0.249642 0.249642)
							(end -0.1778 0.2794)
						)
						(arc
							(start 0.1778 0.2794)
							(mid 0.249642 0.249642)
							(end 0.2794 0.1778)
						)
						(arc
							(start 0.2794 -0.1778)
							(mid 0.249642 -0.249642)
							(end 0.1778 -0.2794)
						)
					)
					(width 0)
					(fill yes)
				)
			)
		)
		(pad "2" smd custom
			(at 0 0.4445 270)
			(size 0.1397 0.1397)
			(layers "F.Cu" "F.Mask" "F.Paste")
			(net "GND")
			(options
				(clearance outline)
				(anchor circle)
			)
			(primitives
				(gr_poly
					(pts
						(arc
							(start -0.1778 -0.2794)
							(mid -0.249642 -0.249642)
							(end -0.2794 -0.1778)
						)
						(arc
							(start -0.2794 0.1778)
							(mid -0.249642 0.249642)
							(end -0.1778 0.2794)
						)
						(arc
							(start 0.1778 0.2794)
							(mid 0.249642 0.249642)
							(end 0.2794 0.1778)
						)
						(arc
							(start 0.2794 -0.1778)
							(mid 0.249642 -0.249642)
							(end 0.1778 -0.2794)
						)
					)
					(width 0)
					(fill yes)
				)
			)
		)
	)
	(footprint ""
		(layer "F.Cu")
		(at 152.247092 -108.233464 -90)
		(property "Reference" "SR831"
			(at 0 0 270)
			(layer "F.SilkS")
			(hide yes)
			(effects
				(font
					(size 1.27 1.27)
				)
			)
		)
		(property "Value" "D51R3F-2-GP"
			(at -0.0254 -2.5146 270)
			(unlocked yes)
			(layer "F.Fab")
			(hide yes)
			(effects
				(font
					(size 1.016 1.016)
					(thickness 0.1524)
				)
			)
		)
		(property "Device Type" "R603H22"
			(at -0.0254 -4.0386 270)
			(unlocked yes)
			(layer "F.Fab")
			(hide yes)
			(effects
				(font
					(size 1.016 1.016)
					(thickness 0.1524)
				)
			)
		)
		(duplicate_pad_numbers_are_jumpers no)
		(fp_line
			(start -0.4826 0)
			(end -0.2032 0)
			(stroke
				(width 0.2032)
				(type default)
			)
			(layer "F.SilkS")
		)
		(fp_line
			(start 0.2032 0)
			(end 0.4826 0)
			(stroke
				(width 0.2032)
				(type default)
			)
			(layer "F.SilkS")
		)
		(fp_rect
			(start -0.5842 1.3335)
			(end 0.5842 -1.3335)
			(stroke
				(width 0)
				(type default)
			)
			(fill no)
			(layer "F.CrtYd")
		)
		(fp_rect
			(start -0.5842 1.3335)
			(end 0.5842 -1.3335)
			(stroke
				(width 0)
				(type default)
			)
			(fill no)
			(layer "F.Fab")
		)
		(pad "1" smd custom
			(at 0 -0.762 270)
			(size 0.2159 0.2159)
			(layers "F.Cu" "F.Mask" "F.Paste")
			(net "P0V9_E")
			(options
				(clearance outline)
				(anchor circle)
			)
			(primitives
				(gr_poly
					(pts
						(arc
							(start -0.3302 -0.4318)
							(mid -0.402042 -0.402042)
							(end -0.4318 -0.3302)
						)
						(arc
							(start -0.4318 0.3302)
							(mid -0.402042 0.402042)
							(end -0.3302 0.4318)
						)
						(arc
							(start 0.3302 0.4318)
							(mid 0.402042 0.402042)
							(end 0.4318 0.3302)
						)
						(arc
							(start 0.4318 -0.3302)
							(mid 0.402042 -0.402042)
							(end 0.3302 -0.4318)
						)
					)
					(width 0)
					(fill yes)
				)
			)
		)
		(pad "2" smd custom
			(at 0 0.762 270)
			(size 0.2159 0.2159)
			(layers "F.Cu" "F.Mask" "F.Paste")
			(net "GB_VDDA")
			(options
				(clearance outline)
				(anchor circle)
			)
			(primitives
				(gr_poly
					(pts
						(arc
							(start -0.3302 -0.4318)
							(mid -0.402042 -0.402042)
							(end -0.4318 -0.3302)
						)
						(arc
							(start -0.4318 0.3302)
							(mid -0.402042 0.402042)
							(end -0.3302 0.4318)
						)
						(arc
							(start 0.3302 0.4318)
							(mid 0.402042 0.402042)
							(end 0.4318 0.3302)
						)
						(arc
							(start 0.4318 -0.3302)
							(mid 0.402042 -0.402042)
							(end 0.3302 -0.4318)
						)
					)
					(width 0)
					(fill yes)
				)
			)
		)
	)
	(footprint ""
		(layer "F.Cu")
		(at 287.401 -156.972 -90)
		(property "Reference" "R616"
			(at 0 0 270)
			(layer "F.SilkS")
			(hide yes)
			(effects
				(font
					(size 1.27 1.27)
				)
			)
		)
		(property "Value" "2K2R2J-2-GP"
			(at 0.064008 -3.993896 270)
			(unlocked yes)
			(layer "F.Fab")
			(hide yes)
			(effects
				(font
					(size 1.016 1.016)
					(thickness 0.1524)
				)
			)
		)
		(property "Device Type" "R402H16"
			(at 0.064008 -5.517896 270)
			(unlocked yes)
			(layer "F.Fab")
			(hide yes)
			(effects
				(font
					(size 1.016 1.016)
					(thickness 0.1524)
				)
			)
		)
		(duplicate_pad_numbers_are_jumpers no)
		(fp_line
			(start -0.508 -0.9398)
			(end -0.508 0.9398)
			(stroke
				(width 0.1524)
				(type default)
			)
			(layer "F.SilkS")
		)
		(fp_line
			(start 0.508 -0.9398)
			(end -0.508 -0.9398)
			(stroke
				(width 0.1524)
				(type default)
			)
			(layer "F.SilkS")
		)
		(fp_rect
			(start -0.508 0.9398)
			(end 0.508 -0.9398)
			(stroke
				(width 0)
				(type default)
			)
			(fill no)
			(layer "F.CrtYd")
		)
		(fp_rect
			(start -0.508 0.9398)
			(end 0.508 -0.9398)
			(stroke
				(width 0)
				(type default)
			)
			(fill no)
			(layer "F.Fab")
		)
		(pad "1" smd custom
			(at 0 -0.4445 270)
			(size 0.1397 0.1397)
			(layers "F.Cu" "F.Mask" "F.Paste")
			(net "CPU_BMC_UART_TX")
			(options
				(clearance outline)
				(anchor circle)
			)
			(primitives
				(gr_poly
					(pts
						(arc
							(start -0.1778 -0.2794)
							(mid -0.249642 -0.249642)
							(end -0.2794 -0.1778)
						)
						(arc
							(start -0.2794 0.1778)
							(mid -0.249642 0.249642)
							(end -0.1778 0.2794)
						)
						(arc
							(start 0.1778 0.2794)
							(mid 0.249642 0.249642)
							(end 0.2794 0.1778)
						)
						(arc
							(start 0.2794 -0.1778)
							(mid 0.249642 -0.249642)
							(end 0.1778 -0.2794)
						)
					)
					(width 0)
					(fill yes)
				)
			)
		)
		(pad "2" smd custom
			(at 0 0.4445 270)
			(size 0.1397 0.1397)
			(layers "F.Cu" "F.Mask" "F.Paste")
			(net "GND")
			(options
				(clearance outline)
				(anchor circle)
			)
			(primitives
				(gr_poly
					(pts
						(arc
							(start -0.1778 -0.2794)
							(mid -0.249642 -0.249642)
							(end -0.2794 -0.1778)
						)
						(arc
							(start -0.2794 0.1778)
							(mid -0.249642 0.249642)
							(end -0.1778 0.2794)
						)
						(arc
							(start 0.1778 0.2794)
							(mid 0.249642 0.249642)
							(end 0.2794 0.1778)
						)
						(arc
							(start 0.2794 -0.1778)
							(mid 0.249642 -0.249642)
							(end 0.1778 -0.2794)
						)
					)
					(width 0)
					(fill yes)
				)
			)
		)
	)
	(footprint ""
		(layer "F.Cu")
		(at 110.236 -62.103)
		(property "Reference" "STP60"
			(at 0 0 0)
			(layer "F.SilkS")
			(hide yes)
			(effects
				(font
					(size 1.27 1.27)
				)
			)
		)
		(property "Value" "TPAD28"
			(at 0.0127 -1.8034 0)
			(unlocked yes)
			(layer "F.Fab")
			(hide yes)
			(effects
				(font
					(size 1.016 1.016)
					(thickness 0.1524)
				)
			)
		)
		(property "Device Type" "TPAD28"
			(at 0.0127 -3.3274 0)
			(unlocked yes)
			(layer "F.Fab")
			(hide yes)
			(effects
				(font
					(size 1.016 1.016)
					(thickness 0.1524)
				)
			)
		)
		(duplicate_pad_numbers_are_jumpers no)
		(fp_poly
			(pts
				(arc
					(start 0.3556 0)
					(mid -0.3556 0)
					(end 0.3556 0)
				)
			)
			(stroke
				(width 0)
				(type default)
			)
			(fill no)
			(layer "F.CrtYd")
		)
		(fp_poly
			(pts
				(arc
					(start 0.6096 0)
					(mid -0.6096 0)
					(end 0.6096 0)
				)
			)
			(stroke
				(width 0)
				(type default)
			)
			(fill no)
			(layer "F.Fab")
		)
		(pad "1" smd circle
			(at 0 0)
			(size 0.7112 0.7112)
			(layers "F.Cu" "F.Mask" "F.Paste")
			(net "JTAG_IOC_TMS")
		)
	)
	(footprint ""
		(layer "F.Cu")
		(at 171.46397 -67.183 180)
		(property "Reference" "C295"
			(at 0 0 180)
			(layer "F.SilkS")
			(hide yes)
			(effects
				(font
					(size 1.27 1.27)
				)
			)
		)
		(property "Value" "SCD1U25V2KX-2-GP"
			(at 1.1811 -2.7051 180)
			(unlocked yes)
			(layer "F.Fab")
			(hide yes)
			(effects
				(font
					(size 1.016 1.016)
					(thickness 0.1524)
				)
			)
		)
		(property "Device Type" "C402H22"
			(at 1.1811 -4.2291 180)
			(unlocked yes)
			(layer "F.Fab")
			(hide yes)
			(effects
				(font
					(size 1.016 1.016)
					(thickness 0.1524)
				)
			)
		)
		(duplicate_pad_numbers_are_jumpers no)
		(fp_rect
			(start -0.4318 0.9525)
			(end 0.4318 -0.9525)
			(stroke
				(width 0)
				(type default)
			)
			(fill no)
			(layer "F.CrtYd")
		)
		(fp_rect
			(start -0.4318 0.9525)
			(end 0.4318 -0.9525)
			(stroke
				(width 0)
				(type default)
			)
			(fill no)
			(layer "F.Fab")
		)
		(pad "1" smd custom
			(at 0 -0.4445 180)
			(size 0.1524 0.1524)
			(layers "F.Cu" "F.Mask" "F.Paste")
			(net "GND")
			(options
				(clearance outline)
				(anchor circle)
			)
			(primitives
				(gr_poly
					(pts
						(arc
							(start 0.3048 -0.2032)
							(mid 0.275042 -0.275042)
							(end 0.2032 -0.3048)
						)
						(arc
							(start -0.2032 -0.3048)
							(mid -0.275042 -0.275042)
							(end -0.3048 -0.2032)
						)
						(arc
							(start -0.3048 0.2032)
							(mid -0.275042 0.275042)
							(end -0.2032 0.3048)
						)
						(arc
							(start 0.2032 0.3048)
							(mid 0.275042 0.275042)
							(end 0.3048 0.2032)
						)
					)
					(width 0)
					(fill yes)
				)
			)
		)
		(pad "2" smd custom
			(at 0 0.4445 180)
			(size 0.1524 0.1524)
			(layers "F.Cu" "F.Mask" "F.Paste")
			(net "TP_MSB_B47_CPU_GBE_TX_N")
			(options
				(clearance outline)
				(anchor circle)
			)
			(primitives
				(gr_poly
					(pts
						(arc
							(start 0.3048 -0.2032)
							(mid 0.275042 -0.275042)
							(end 0.2032 -0.3048)
						)
						(arc
							(start -0.2032 -0.3048)
							(mid -0.275042 -0.275042)
							(end -0.3048 -0.2032)
						)
						(arc
							(start -0.3048 0.2032)
							(mid -0.275042 0.275042)
							(end -0.2032 0.3048)
						)
						(arc
							(start 0.2032 0.3048)
							(mid 0.275042 0.275042)
							(end 0.3048 0.2032)
						)
					)
					(width 0)
					(fill yes)
				)
			)
		)
	)
	(footprint ""
		(layer "F.Cu")
		(at 62.357 -216.281 90)
		(property "Reference" "C7272"
			(at 0 0 90)
			(layer "F.SilkS")
			(hide yes)
			(effects
				(font
					(size 1.27 1.27)
				)
			)
		)
		(property "Value" "SCD1U16V2KX-3GP"
			(at 1.1811 -2.7051 90)
			(unlocked yes)
			(layer "F.Fab")
			(hide yes)
			(effects
				(font
					(size 1.016 1.016)
					(thickness 0.1524)
				)
			)
		)
		(property "Device Type" "C402H22"
			(at 1.1811 -4.2291 90)
			(unlocked yes)
			(layer "F.Fab")
			(hide yes)
			(effects
				(font
					(size 1.016 1.016)
					(thickness 0.1524)
				)
			)
		)
		(duplicate_pad_numbers_are_jumpers no)
		(fp_rect
			(start -0.4318 0.9525)
			(end 0.4318 -0.9525)
			(stroke
				(width 0)
				(type default)
			)
			(fill no)
			(layer "F.CrtYd")
		)
		(fp_rect
			(start -0.4318 0.9525)
			(end 0.4318 -0.9525)
			(stroke
				(width 0)
				(type default)
			)
			(fill no)
			(layer "F.Fab")
		)
		(pad "1" smd custom
			(at 0 -0.4445 90)
			(size 0.1524 0.1524)
			(layers "F.Cu" "F.Mask" "F.Paste")
			(net "MB0_CM_VOUT_R")
			(options
				(clearance outline)
				(anchor circle)
			)
			(primitives
				(gr_poly
					(pts
						(arc
							(start 0.3048 -0.2032)
							(mid 0.275042 -0.275042)
							(end 0.2032 -0.3048)
						)
						(arc
							(start -0.2032 -0.3048)
							(mid -0.275042 -0.275042)
							(end -0.3048 -0.2032)
						)
						(arc
							(start -0.3048 0.2032)
							(mid -0.275042 0.275042)
							(end -0.2032 0.3048)
						)
						(arc
							(start 0.2032 0.3048)
							(mid 0.275042 0.275042)
							(end 0.3048 0.2032)
						)
					)
					(width 0)
					(fill yes)
				)
			)
		)
		(pad "2" smd custom
			(at 0 0.4445 90)
			(size 0.1524 0.1524)
			(layers "F.Cu" "F.Mask" "F.Paste")
			(net "AGND_CURRENT_MON")
			(options
				(clearance outline)
				(anchor circle)
			)
			(primitives
				(gr_poly
					(pts
						(arc
							(start 0.3048 -0.2032)
							(mid 0.275042 -0.275042)
							(end 0.2032 -0.3048)
						)
						(arc
							(start -0.2032 -0.3048)
							(mid -0.275042 -0.275042)
							(end -0.3048 -0.2032)
						)
						(arc
							(start -0.3048 0.2032)
							(mid -0.275042 0.275042)
							(end -0.2032 0.3048)
						)
						(arc
							(start 0.2032 0.3048)
							(mid 0.275042 0.275042)
							(end 0.3048 0.2032)
						)
					)
					(width 0)
					(fill yes)
				)
			)
		)
	)
	(footprint ""
		(layer "F.Cu")
		(at 83.420966 -80.391)
		(property "Reference" "SC1194"
			(at 0 0 0)
			(layer "F.SilkS")
			(hide yes)
			(effects
				(font
					(size 1.27 1.27)
				)
			)
		)
		(property "Value" "SC22U6D3V5MX-2GP"
			(at -0.0762 -6.1214 0)
			(unlocked yes)
			(layer "F.Fab")
			(hide yes)
			(effects
				(font
					(size 1.016 1.016)
					(thickness 0.1524)
				)
			)
		)
		(property "Device Type" "C805H58"
			(at -0.0762 -8.1534 0)
			(unlocked yes)
			(layer "F.Fab")
			(hide yes)
			(effects
				(font
					(size 1.016 1.016)
					(thickness 0.1524)
				)
			)
		)
		(duplicate_pad_numbers_are_jumpers no)
		(fp_line
			(start 0.635 0)
			(end -0.635 0)
			(stroke
				(width 0.508)
				(type default)
			)
			(layer "F.SilkS")
		)
		(fp_rect
			(start -0.9652 1.778)
			(end 0.9652 -1.778)
			(stroke
				(width 0)
				(type default)
			)
			(fill no)
			(layer "F.CrtYd")
		)
		(fp_poly
			(pts
				(xy -0.9652 -1.778) (xy 0.9652 -1.778) (xy 0.9652 1.778) (xy -0.9652 1.778)
			)
			(stroke
				(width 0)
				(type default)
			)
			(fill no)
			(layer "F.Fab")
		)
		(pad "1" smd rect
			(at 0 -0.9652)
			(size 1.397 1.143)
			(layers "F.Cu" "F.Mask" "F.Paste")
			(net "XTAL_VDDA09")
		)
		(pad "2" smd rect
			(at 0 0.9652)
			(size 1.397 1.143)
			(layers "F.Cu" "F.Mask" "F.Paste")
			(net "GND")
		)
	)
	(footprint ""
		(layer "F.Cu")
		(at 110.217966 -65.8876)
		(property "Reference" "SR661"
			(at 0 0 0)
			(layer "F.SilkS")
			(hide yes)
			(effects
				(font
					(size 1.27 1.27)
				)
			)
		)
		(property "Value" "10KR2F-2-GP"
			(at 0.064008 -3.993896 0)
			(unlocked yes)
			(layer "F.Fab")
			(hide yes)
			(effects
				(font
					(size 1.016 1.016)
					(thickness 0.1524)
				)
			)
		)
		(property "Device Type" "R402H16"
			(at 0.064008 -5.517896 0)
			(unlocked yes)
			(layer "F.Fab")
			(hide yes)
			(effects
				(font
					(size 1.016 1.016)
					(thickness 0.1524)
				)
			)
		)
		(duplicate_pad_numbers_are_jumpers no)
		(fp_line
			(start -0.508 -0.9398)
			(end -0.508 0.9398)
			(stroke
				(width 0.1524)
				(type default)
			)
			(layer "F.SilkS")
		)
		(fp_line
			(start 0.508 -0.9398)
			(end -0.508 -0.9398)
			(stroke
				(width 0.1524)
				(type default)
			)
			(layer "F.SilkS")
		)
		(fp_rect
			(start -0.508 0.9398)
			(end 0.508 -0.9398)
			(stroke
				(width 0)
				(type default)
			)
			(fill no)
			(layer "F.CrtYd")
		)
		(fp_rect
			(start -0.508 0.9398)
			(end 0.508 -0.9398)
			(stroke
				(width 0)
				(type default)
			)
			(fill no)
			(layer "F.Fab")
		)
		(pad "1" smd custom
			(at 0 -0.4445)
			(size 0.1397 0.1397)
			(layers "F.Cu" "F.Mask" "F.Paste")
			(net "P1V8_C")
			(options
				(clearance outline)
				(anchor circle)
			)
			(primitives
				(gr_poly
					(pts
						(arc
							(start -0.1778 -0.2794)
							(mid -0.249642 -0.249642)
							(end -0.2794 -0.1778)
						)
						(arc
							(start -0.2794 0.1778)
							(mid -0.249642 0.249642)
							(end -0.1778 0.2794)
						)
						(arc
							(start 0.1778 0.2794)
							(mid 0.249642 0.249642)
							(end 0.2794 0.1778)
						)
						(arc
							(start 0.2794 -0.1778)
							(mid 0.249642 -0.249642)
							(end 0.1778 -0.2794)
						)
					)
					(width 0)
					(fill yes)
				)
			)
		)
		(pad "2" smd custom
			(at 0 0.4445)
			(size 0.1397 0.1397)
			(layers "F.Cu" "F.Mask" "F.Paste")
			(net "LSI_JTAG_EN_N")
			(options
				(clearance outline)
				(anchor circle)
			)
			(primitives
				(gr_poly
					(pts
						(arc
							(start -0.1778 -0.2794)
							(mid -0.249642 -0.249642)
							(end -0.2794 -0.1778)
						)
						(arc
							(start -0.2794 0.1778)
							(mid -0.249642 0.249642)
							(end -0.1778 0.2794)
						)
						(arc
							(start 0.1778 0.2794)
							(mid 0.249642 0.249642)
							(end 0.2794 0.1778)
						)
						(arc
							(start 0.2794 -0.1778)
							(mid 0.249642 -0.249642)
							(end 0.1778 -0.2794)
						)
					)
					(width 0)
					(fill yes)
				)
			)
		)
	)
	(footprint ""
		(layer "F.Cu")
		(at 335.915 -83.947 180)
		(property "Reference" "R296"
			(at 0 0 180)
			(layer "F.SilkS")
			(hide yes)
			(effects
				(font
					(size 1.27 1.27)
				)
			)
		)
		(property "Value" "0R0402-PAD-1-GP"
			(at 0.064008 -3.993896 180)
			(unlocked yes)
			(layer "F.Fab")
			(hide yes)
			(effects
				(font
					(size 1.016 1.016)
					(thickness 0.1524)
				)
			)
		)
		(property "Device Type" "0R0402-PAD"
			(at 0.064008 -5.517896 180)
			(unlocked yes)
			(layer "F.Fab")
			(hide yes)
			(effects
				(font
					(size 1.016 1.016)
					(thickness 0.1524)
				)
			)
		)
		(duplicate_pad_numbers_are_jumpers no)
		(fp_line
			(start 0.508 -0.9398)
			(end -0.508 -0.9398)
			(stroke
				(width 0.1524)
				(type default)
			)
			(layer "F.SilkS")
		)
		(fp_line
			(start -0.508 -0.9398)
			(end -0.508 0.9398)
			(stroke
				(width 0.1524)
				(type default)
			)
			(layer "F.SilkS")
		)
		(fp_rect
			(start -0.508 0.9398)
			(end 0.508 -0.9398)
			(stroke
				(width 0)
				(type default)
			)
			(fill no)
			(layer "F.CrtYd")
		)
		(fp_rect
			(start -0.508 0.9398)
			(end 0.508 -0.9398)
			(stroke
				(width 0)
				(type default)
			)
			(fill no)
			(layer "F.Fab")
		)
		(pad "1" smd custom
			(at 0 -0.4445 180)
			(size 0.1397 0.1397)
			(layers "F.Cu" "F.Mask" "F.Paste")
			(net "FLA_CS_R")
			(options
				(clearance outline)
				(anchor circle)
			)
			(primitives
				(gr_poly
					(pts
						(xy -0.2794 0.3683)
						(arc
							(start -0.2794 -0.2667)
							(mid -0.249642 -0.338542)
							(end -0.1778 -0.3683)
						)
						(arc
							(start 0.1778 -0.3683)
							(mid 0.249642 -0.338542)
							(end 0.2794 -0.2667)
						)
						(xy 0.2794 0.3683)
					)
					(width 0)
					(fill yes)
				)
			)
		)
		(pad "2" smd custom
			(at 0 0.4445 180)
			(size 0.1397 0.1397)
			(layers "F.Cu" "F.Mask" "F.Paste")
			(net "FLA_CS")
			(options
				(clearance outline)
				(anchor circle)
			)
			(primitives
				(gr_poly
					(pts
						(arc
							(start -0.1778 0.3683)
							(mid -0.249642 0.338542)
							(end -0.2794 0.2667)
						)
						(xy -0.2794 -0.3683) (xy 0.2794 -0.3683)
						(arc
							(start 0.2794 0.2667)
							(mid 0.249642 0.338542)
							(end 0.1778 0.3683)
						)
					)
					(width 0)
					(fill yes)
				)
			)
		)
	)
	(footprint ""
		(layer "F.Cu")
		(at 35.383216 -206.43088 90)
		(property "Reference" "R572"
			(at 0 0 90)
			(layer "F.SilkS")
			(hide yes)
			(effects
				(font
					(size 1.27 1.27)
				)
			)
		)
		(property "Value" "0R2J-2-GP"
			(at 0.064008 -3.993896 90)
			(unlocked yes)
			(layer "F.Fab")
			(hide yes)
			(effects
				(font
					(size 1.016 1.016)
					(thickness 0.1524)
				)
			)
		)
		(property "Device Type" "R402H16"
			(at 0.064008 -5.517896 90)
			(unlocked yes)
			(layer "F.Fab")
			(hide yes)
			(effects
				(font
					(size 1.016 1.016)
					(thickness 0.1524)
				)
			)
		)
		(duplicate_pad_numbers_are_jumpers no)
		(fp_line
			(start 0.508 -0.9398)
			(end -0.508 -0.9398)
			(stroke
				(width 0.1524)
				(type default)
			)
			(layer "F.SilkS")
		)
		(fp_line
			(start -0.508 -0.9398)
			(end -0.508 0.9398)
			(stroke
				(width 0.1524)
				(type default)
			)
			(layer "F.SilkS")
		)
		(fp_rect
			(start -0.508 0.9398)
			(end 0.508 -0.9398)
			(stroke
				(width 0)
				(type default)
			)
			(fill no)
			(layer "F.CrtYd")
		)
		(fp_rect
			(start -0.508 0.9398)
			(end 0.508 -0.9398)
			(stroke
				(width 0)
				(type default)
			)
			(fill no)
			(layer "F.Fab")
		)
		(pad "1" smd custom
			(at 0 -0.4445 90)
			(size 0.1397 0.1397)
			(layers "F.Cu" "F.Mask" "F.Paste")
			(net "VOL_SEN_SCL_U17")
			(options
				(clearance outline)
				(anchor circle)
			)
			(primitives
				(gr_poly
					(pts
						(arc
							(start -0.1778 -0.2794)
							(mid -0.249642 -0.249642)
							(end -0.2794 -0.1778)
						)
						(arc
							(start -0.2794 0.1778)
							(mid -0.249642 0.249642)
							(end -0.1778 0.2794)
						)
						(arc
							(start 0.1778 0.2794)
							(mid 0.249642 0.249642)
							(end 0.2794 0.1778)
						)
						(arc
							(start 0.2794 -0.1778)
							(mid 0.249642 -0.249642)
							(end 0.1778 -0.2794)
						)
					)
					(width 0)
					(fill yes)
				)
			)
		)
		(pad "2" smd custom
			(at 0 0.4445 90)
			(size 0.1397 0.1397)
			(layers "F.Cu" "F.Mask" "F.Paste")
			(net "BMC_I2C_A_SCL")
			(options
				(clearance outline)
				(anchor circle)
			)
			(primitives
				(gr_poly
					(pts
						(arc
							(start -0.1778 -0.2794)
							(mid -0.249642 -0.249642)
							(end -0.2794 -0.1778)
						)
						(arc
							(start -0.2794 0.1778)
							(mid -0.249642 0.249642)
							(end -0.1778 0.2794)
						)
						(arc
							(start 0.1778 0.2794)
							(mid 0.249642 0.249642)
							(end 0.2794 0.1778)
						)
						(arc
							(start 0.2794 -0.1778)
							(mid 0.249642 -0.249642)
							(end 0.1778 -0.2794)
						)
					)
					(width 0)
					(fill yes)
				)
			)
		)
	)
	(footprint ""
		(layer "F.Cu")
		(at 312.547 -193.548 90)
		(property "Reference" "R801"
			(at 0 0 90)
			(layer "F.SilkS")
			(hide yes)
			(effects
				(font
					(size 1.27 1.27)
				)
			)
		)
		(property "Value" "4K7R2F-GP"
			(at 0.064008 -3.993896 90)
			(unlocked yes)
			(layer "F.Fab")
			(hide yes)
			(effects
				(font
					(size 1.016 1.016)
					(thickness 0.1524)
				)
			)
		)
		(property "Device Type" "R402H16"
			(at 0.064008 -5.517896 90)
			(unlocked yes)
			(layer "F.Fab")
			(hide yes)
			(effects
				(font
					(size 1.016 1.016)
					(thickness 0.1524)
				)
			)
		)
		(duplicate_pad_numbers_are_jumpers no)
		(fp_line
			(start 0.508 -0.9398)
			(end -0.508 -0.9398)
			(stroke
				(width 0.1524)
				(type default)
			)
			(layer "F.SilkS")
		)
		(fp_line
			(start -0.508 -0.9398)
			(end -0.508 0.9398)
			(stroke
				(width 0.1524)
				(type default)
			)
			(layer "F.SilkS")
		)
		(fp_rect
			(start -0.508 0.9398)
			(end 0.508 -0.9398)
			(stroke
				(width 0)
				(type default)
			)
			(fill no)
			(layer "F.CrtYd")
		)
		(fp_rect
			(start -0.508 0.9398)
			(end 0.508 -0.9398)
			(stroke
				(width 0)
				(type default)
			)
			(fill no)
			(layer "F.Fab")
		)
		(pad "1" smd custom
			(at 0 -0.4445 90)
			(size 0.1397 0.1397)
			(layers "F.Cu" "F.Mask" "F.Paste")
			(net "P3V3_STBY")
			(options
				(clearance outline)
				(anchor circle)
			)
			(primitives
				(gr_poly
					(pts
						(arc
							(start -0.1778 -0.2794)
							(mid -0.249642 -0.249642)
							(end -0.2794 -0.1778)
						)
						(arc
							(start -0.2794 0.1778)
							(mid -0.249642 0.249642)
							(end -0.1778 0.2794)
						)
						(arc
							(start 0.1778 0.2794)
							(mid 0.249642 0.249642)
							(end 0.2794 0.1778)
						)
						(arc
							(start 0.2794 -0.1778)
							(mid 0.249642 -0.249642)
							(end 0.1778 -0.2794)
						)
					)
					(width 0)
					(fill yes)
				)
			)
		)
		(pad "2" smd custom
			(at 0 0.4445 90)
			(size 0.1397 0.1397)
			(layers "F.Cu" "F.Mask" "F.Paste")
			(net "JTAG_BMC_TRST_N")
			(options
				(clearance outline)
				(anchor circle)
			)
			(primitives
				(gr_poly
					(pts
						(arc
							(start -0.1778 -0.2794)
							(mid -0.249642 -0.249642)
							(end -0.2794 -0.1778)
						)
						(arc
							(start -0.2794 0.1778)
							(mid -0.249642 0.249642)
							(end -0.1778 0.2794)
						)
						(arc
							(start 0.1778 0.2794)
							(mid 0.249642 0.249642)
							(end 0.2794 0.1778)
						)
						(arc
							(start 0.2794 -0.1778)
							(mid 0.249642 -0.249642)
							(end 0.1778 -0.2794)
						)
					)
					(width 0)
					(fill yes)
				)
			)
		)
	)
	(footprint ""
		(layer "F.Cu")
		(at 344.424 -115.824 -90)
		(property "Reference" "PR10"
			(at 0 0 270)
			(layer "F.SilkS")
			(hide yes)
			(effects
				(font
					(size 1.27 1.27)
				)
			)
		)
		(property "Value" "54K9R2F-L-GP"
			(at 0.064008 -3.993896 270)
			(unlocked yes)
			(layer "F.Fab")
			(hide yes)
			(effects
				(font
					(size 1.016 1.016)
					(thickness 0.1524)
				)
			)
		)
		(property "Device Type" "R402H16"
			(at 0.064008 -5.517896 270)
			(unlocked yes)
			(layer "F.Fab")
			(hide yes)
			(effects
				(font
					(size 1.016 1.016)
					(thickness 0.1524)
				)
			)
		)
		(duplicate_pad_numbers_are_jumpers no)
		(fp_line
			(start -0.508 -0.9398)
			(end -0.508 0.9398)
			(stroke
				(width 0.1524)
				(type default)
			)
			(layer "F.SilkS")
		)
		(fp_line
			(start 0.508 -0.9398)
			(end -0.508 -0.9398)
			(stroke
				(width 0.1524)
				(type default)
			)
			(layer "F.SilkS")
		)
		(fp_rect
			(start -0.508 0.9398)
			(end 0.508 -0.9398)
			(stroke
				(width 0)
				(type default)
			)
			(fill no)
			(layer "F.CrtYd")
		)
		(fp_rect
			(start -0.508 0.9398)
			(end 0.508 -0.9398)
			(stroke
				(width 0)
				(type default)
			)
			(fill no)
			(layer "F.Fab")
		)
		(pad "1" smd custom
			(at 0 -0.4445 270)
			(size 0.1397 0.1397)
			(layers "F.Cu" "F.Mask" "F.Paste")
			(net "P5V_STBY_CC_R")
			(options
				(clearance outline)
				(anchor circle)
			)
			(primitives
				(gr_poly
					(pts
						(arc
							(start -0.1778 -0.2794)
							(mid -0.249642 -0.249642)
							(end -0.2794 -0.1778)
						)
						(arc
							(start -0.2794 0.1778)
							(mid -0.249642 0.249642)
							(end -0.1778 0.2794)
						)
						(arc
							(start 0.1778 0.2794)
							(mid 0.249642 0.249642)
							(end 0.2794 0.1778)
						)
						(arc
							(start 0.2794 -0.1778)
							(mid 0.249642 -0.249642)
							(end 0.1778 -0.2794)
						)
					)
					(width 0)
					(fill yes)
				)
			)
		)
		(pad "2" smd custom
			(at 0 0.4445 270)
			(size 0.1397 0.1397)
			(layers "F.Cu" "F.Mask" "F.Paste")
			(net "P5V_STBY_VFB")
			(options
				(clearance outline)
				(anchor circle)
			)
			(primitives
				(gr_poly
					(pts
						(arc
							(start -0.1778 -0.2794)
							(mid -0.249642 -0.249642)
							(end -0.2794 -0.1778)
						)
						(arc
							(start -0.2794 0.1778)
							(mid -0.249642 0.249642)
							(end -0.1778 0.2794)
						)
						(arc
							(start 0.1778 0.2794)
							(mid 0.249642 0.249642)
							(end 0.2794 0.1778)
						)
						(arc
							(start 0.2794 -0.1778)
							(mid 0.249642 -0.249642)
							(end 0.1778 -0.2794)
						)
					)
					(width 0)
					(fill yes)
				)
			)
		)
	)
	(footprint ""
		(layer "F.Cu")
		(at 238.1123 -114.9858 90)
		(property "Reference" "SR840"
			(at 0 0 90)
			(layer "F.SilkS")
			(hide yes)
			(effects
				(font
					(size 1.27 1.27)
				)
			)
		)
		(property "Value" "10KR2F-2-GP"
			(at 0.064008 -3.993896 90)
			(unlocked yes)
			(layer "F.Fab")
			(hide yes)
			(effects
				(font
					(size 1.016 1.016)
					(thickness 0.1524)
				)
			)
		)
		(property "Device Type" "R402H16"
			(at 0.064008 -5.517896 90)
			(unlocked yes)
			(layer "F.Fab")
			(hide yes)
			(effects
				(font
					(size 1.016 1.016)
					(thickness 0.1524)
				)
			)
		)
		(duplicate_pad_numbers_are_jumpers no)
		(fp_line
			(start 0.508 -0.9398)
			(end -0.508 -0.9398)
			(stroke
				(width 0.1524)
				(type default)
			)
			(layer "F.SilkS")
		)
		(fp_line
			(start -0.508 -0.9398)
			(end -0.508 0.9398)
			(stroke
				(width 0.1524)
				(type default)
			)
			(layer "F.SilkS")
		)
		(fp_rect
			(start -0.508 0.9398)
			(end 0.508 -0.9398)
			(stroke
				(width 0)
				(type default)
			)
			(fill no)
			(layer "F.CrtYd")
		)
		(fp_rect
			(start -0.508 0.9398)
			(end 0.508 -0.9398)
			(stroke
				(width 0)
				(type default)
			)
			(fill no)
			(layer "F.Fab")
		)
		(pad "1" smd custom
			(at 0 -0.4445 90)
			(size 0.1397 0.1397)
			(layers "F.Cu" "F.Mask" "F.Paste")
			(net "P1V8_E")
			(options
				(clearance outline)
				(anchor circle)
			)
			(primitives
				(gr_poly
					(pts
						(arc
							(start -0.1778 -0.2794)
							(mid -0.249642 -0.249642)
							(end -0.2794 -0.1778)
						)
						(arc
							(start -0.2794 0.1778)
							(mid -0.249642 0.249642)
							(end -0.1778 0.2794)
						)
						(arc
							(start 0.1778 0.2794)
							(mid 0.249642 0.249642)
							(end 0.2794 0.1778)
						)
						(arc
							(start 0.2794 -0.1778)
							(mid 0.249642 -0.249642)
							(end 0.1778 -0.2794)
						)
					)
					(width 0)
					(fill yes)
				)
			)
		)
		(pad "2" smd custom
			(at 0 0.4445 90)
			(size 0.1397 0.1397)
			(layers "F.Cu" "F.Mask" "F.Paste")
			(net "SMART_UART_EN")
			(options
				(clearance outline)
				(anchor circle)
			)
			(primitives
				(gr_poly
					(pts
						(arc
							(start -0.1778 -0.2794)
							(mid -0.249642 -0.249642)
							(end -0.2794 -0.1778)
						)
						(arc
							(start -0.2794 0.1778)
							(mid -0.249642 0.249642)
							(end -0.1778 0.2794)
						)
						(arc
							(start 0.1778 0.2794)
							(mid 0.249642 0.249642)
							(end 0.2794 0.1778)
						)
						(arc
							(start 0.2794 -0.1778)
							(mid 0.249642 -0.249642)
							(end 0.1778 -0.2794)
						)
					)
					(width 0)
					(fill yes)
				)
			)
		)
	)
	(footprint ""
		(layer "F.Cu")
		(at 310.896 -185.674 -90)
		(property "Reference" "SR943"
			(at 0 0 270)
			(layer "F.SilkS")
			(hide yes)
			(effects
				(font
					(size 1.27 1.27)
				)
			)
		)
		(property "Value" "4K75R2F-1-GP"
			(at 0.064008 -3.993896 270)
			(unlocked yes)
			(layer "F.Fab")
			(hide yes)
			(effects
				(font
					(size 1.016 1.016)
					(thickness 0.1524)
				)
			)
		)
		(property "Device Type" "R402H16"
			(at 0.064008 -5.517896 270)
			(unlocked yes)
			(layer "F.Fab")
			(hide yes)
			(effects
				(font
					(size 1.016 1.016)
					(thickness 0.1524)
				)
			)
		)
		(duplicate_pad_numbers_are_jumpers no)
		(fp_line
			(start -0.508 -0.9398)
			(end -0.508 0.9398)
			(stroke
				(width 0.1524)
				(type default)
			)
			(layer "F.SilkS")
		)
		(fp_line
			(start 0.508 -0.9398)
			(end -0.508 -0.9398)
			(stroke
				(width 0.1524)
				(type default)
			)
			(layer "F.SilkS")
		)
		(fp_rect
			(start -0.508 0.9398)
			(end 0.508 -0.9398)
			(stroke
				(width 0)
				(type default)
			)
			(fill no)
			(layer "F.CrtYd")
		)
		(fp_rect
			(start -0.508 0.9398)
			(end 0.508 -0.9398)
			(stroke
				(width 0)
				(type default)
			)
			(fill no)
			(layer "F.Fab")
		)
		(pad "1" smd custom
			(at 0 -0.4445 270)
			(size 0.1397 0.1397)
			(layers "F.Cu" "F.Mask" "F.Paste")
			(net "P3V3_STBY")
			(options
				(clearance outline)
				(anchor circle)
			)
			(primitives
				(gr_poly
					(pts
						(arc
							(start -0.1778 -0.2794)
							(mid -0.249642 -0.249642)
							(end -0.2794 -0.1778)
						)
						(arc
							(start -0.2794 0.1778)
							(mid -0.249642 0.249642)
							(end -0.1778 0.2794)
						)
						(arc
							(start 0.1778 0.2794)
							(mid 0.249642 0.249642)
							(end 0.2794 0.1778)
						)
						(arc
							(start 0.2794 -0.1778)
							(mid 0.249642 -0.249642)
							(end 0.1778 -0.2794)
						)
					)
					(width 0)
					(fill yes)
				)
			)
		)
		(pad "2" smd custom
			(at 0 0.4445 270)
			(size 0.1397 0.1397)
			(layers "F.Cu" "F.Mask" "F.Paste")
			(net "BMC_FW_DET_BOARD_VER_1")
			(options
				(clearance outline)
				(anchor circle)
			)
			(primitives
				(gr_poly
					(pts
						(arc
							(start -0.1778 -0.2794)
							(mid -0.249642 -0.249642)
							(end -0.2794 -0.1778)
						)
						(arc
							(start -0.2794 0.1778)
							(mid -0.249642 0.249642)
							(end -0.1778 0.2794)
						)
						(arc
							(start 0.1778 0.2794)
							(mid 0.249642 0.249642)
							(end 0.2794 0.1778)
						)
						(arc
							(start 0.2794 -0.1778)
							(mid 0.249642 -0.249642)
							(end 0.1778 -0.2794)
						)
					)
					(width 0)
					(fill yes)
				)
			)
		)
	)
	(footprint ""
		(layer "F.Cu")
		(at 204.793596 -116.097812 180)
		(property "Reference" "PR9008"
			(at 0 0 180)
			(layer "F.SilkS")
			(hide yes)
			(effects
				(font
					(size 1.27 1.27)
				)
			)
		)
		(property "Value" "2D2R3J-2-GP"
			(at -0.0254 -2.5146 180)
			(unlocked yes)
			(layer "F.Fab")
			(hide yes)
			(effects
				(font
					(size 1.016 1.016)
					(thickness 0.1524)
				)
			)
		)
		(property "Device Type" "R603H22"
			(at -0.0254 -4.0386 180)
			(unlocked yes)
			(layer "F.Fab")
			(hide yes)
			(effects
				(font
					(size 1.016 1.016)
					(thickness 0.1524)
				)
			)
		)
		(duplicate_pad_numbers_are_jumpers no)
		(fp_line
			(start 0.2032 0)
			(end 0.4826 0)
			(stroke
				(width 0.2032)
				(type default)
			)
			(layer "F.SilkS")
		)
		(fp_line
			(start -0.4826 0)
			(end -0.2032 0)
			(stroke
				(width 0.2032)
				(type default)
			)
			(layer "F.SilkS")
		)
		(fp_rect
			(start -0.5842 1.3335)
			(end 0.5842 -1.3335)
			(stroke
				(width 0)
				(type default)
			)
			(fill no)
			(layer "F.CrtYd")
		)
		(fp_rect
			(start -0.5842 1.3335)
			(end 0.5842 -1.3335)
			(stroke
				(width 0)
				(type default)
			)
			(fill no)
			(layer "F.Fab")
		)
		(pad "1" smd custom
			(at 0 -0.762 180)
			(size 0.2159 0.2159)
			(layers "F.Cu" "F.Mask" "F.Paste")
			(net "P1V5_E_VIN")
			(options
				(clearance outline)
				(anchor circle)
			)
			(primitives
				(gr_poly
					(pts
						(arc
							(start -0.3302 -0.4318)
							(mid -0.402042 -0.402042)
							(end -0.4318 -0.3302)
						)
						(arc
							(start -0.4318 0.3302)
							(mid -0.402042 0.402042)
							(end -0.3302 0.4318)
						)
						(arc
							(start 0.3302 0.4318)
							(mid 0.402042 0.402042)
							(end 0.4318 0.3302)
						)
						(arc
							(start 0.4318 -0.3302)
							(mid 0.402042 -0.402042)
							(end 0.3302 -0.4318)
						)
					)
					(width 0)
					(fill yes)
				)
			)
		)
		(pad "2" smd custom
			(at 0 0.762 180)
			(size 0.2159 0.2159)
			(layers "F.Cu" "F.Mask" "F.Paste")
			(net "P1V5_E_VCC")
			(options
				(clearance outline)
				(anchor circle)
			)
			(primitives
				(gr_poly
					(pts
						(arc
							(start -0.3302 -0.4318)
							(mid -0.402042 -0.402042)
							(end -0.4318 -0.3302)
						)
						(arc
							(start -0.4318 0.3302)
							(mid -0.402042 0.402042)
							(end -0.3302 0.4318)
						)
						(arc
							(start 0.3302 0.4318)
							(mid 0.402042 0.402042)
							(end 0.4318 0.3302)
						)
						(arc
							(start 0.4318 -0.3302)
							(mid 0.402042 -0.402042)
							(end 0.3302 -0.4318)
						)
					)
					(width 0)
					(fill yes)
				)
			)
		)
	)
	(footprint ""
		(layer "F.Cu")
		(at 281.178 -161.544)
		(property "Reference" "R258"
			(at 0 0 0)
			(layer "F.SilkS")
			(hide yes)
			(effects
				(font
					(size 1.27 1.27)
				)
			)
		)
		(property "Value" "100KR2F-L1-GP"
			(at 0.064008 -3.993896 0)
			(unlocked yes)
			(layer "F.Fab")
			(hide yes)
			(effects
				(font
					(size 1.016 1.016)
					(thickness 0.1524)
				)
			)
		)
		(property "Device Type" "R402H16"
			(at 0.064008 -5.517896 0)
			(unlocked yes)
			(layer "F.Fab")
			(hide yes)
			(effects
				(font
					(size 1.016 1.016)
					(thickness 0.1524)
				)
			)
		)
		(duplicate_pad_numbers_are_jumpers no)
		(fp_line
			(start -0.508 -0.9398)
			(end -0.508 0.9398)
			(stroke
				(width 0.1524)
				(type default)
			)
			(layer "F.SilkS")
		)
		(fp_line
			(start 0.508 -0.9398)
			(end -0.508 -0.9398)
			(stroke
				(width 0.1524)
				(type default)
			)
			(layer "F.SilkS")
		)
		(fp_rect
			(start -0.508 0.9398)
			(end 0.508 -0.9398)
			(stroke
				(width 0)
				(type default)
			)
			(fill no)
			(layer "F.CrtYd")
		)
		(fp_rect
			(start -0.508 0.9398)
			(end 0.508 -0.9398)
			(stroke
				(width 0)
				(type default)
			)
			(fill no)
			(layer "F.Fab")
		)
		(pad "1" smd custom
			(at 0 -0.4445)
			(size 0.1397 0.1397)
			(layers "F.Cu" "F.Mask" "F.Paste")
			(net "TP_LPC_CPU_FRAME_N")
			(options
				(clearance outline)
				(anchor circle)
			)
			(primitives
				(gr_poly
					(pts
						(arc
							(start -0.1778 -0.2794)
							(mid -0.249642 -0.249642)
							(end -0.2794 -0.1778)
						)
						(arc
							(start -0.2794 0.1778)
							(mid -0.249642 0.249642)
							(end -0.1778 0.2794)
						)
						(arc
							(start 0.1778 0.2794)
							(mid 0.249642 0.249642)
							(end 0.2794 0.1778)
						)
						(arc
							(start 0.2794 -0.1778)
							(mid 0.249642 -0.249642)
							(end 0.1778 -0.2794)
						)
					)
					(width 0)
					(fill yes)
				)
			)
		)
		(pad "2" smd custom
			(at 0 0.4445)
			(size 0.1397 0.1397)
			(layers "F.Cu" "F.Mask" "F.Paste")
			(net "GND")
			(options
				(clearance outline)
				(anchor circle)
			)
			(primitives
				(gr_poly
					(pts
						(arc
							(start -0.1778 -0.2794)
							(mid -0.249642 -0.249642)
							(end -0.2794 -0.1778)
						)
						(arc
							(start -0.2794 0.1778)
							(mid -0.249642 0.249642)
							(end -0.1778 0.2794)
						)
						(arc
							(start 0.1778 0.2794)
							(mid 0.249642 0.249642)
							(end 0.2794 0.1778)
						)
						(arc
							(start 0.2794 -0.1778)
							(mid 0.249642 -0.249642)
							(end 0.1778 -0.2794)
						)
					)
					(width 0)
					(fill yes)
				)
			)
		)
	)
	(footprint ""
		(layer "F.Cu")
		(at 264.033 -31.496 90)
		(property "Reference" "PC53"
			(at 0 0 90)
			(layer "F.SilkS")
			(hide yes)
			(effects
				(font
					(size 1.27 1.27)
				)
			)
		)
		(property "Value" "SC1U10V2KX-1GP"
			(at 1.1811 -2.7051 90)
			(unlocked yes)
			(layer "F.Fab")
			(hide yes)
			(effects
				(font
					(size 1.016 1.016)
					(thickness 0.1524)
				)
			)
		)
		(property "Device Type" "C402H22"
			(at 1.1811 -4.2291 90)
			(unlocked yes)
			(layer "F.Fab")
			(hide yes)
			(effects
				(font
					(size 1.016 1.016)
					(thickness 0.1524)
				)
			)
		)
		(duplicate_pad_numbers_are_jumpers no)
		(fp_rect
			(start -0.4318 0.9525)
			(end 0.4318 -0.9525)
			(stroke
				(width 0)
				(type default)
			)
			(fill no)
			(layer "F.CrtYd")
		)
		(fp_rect
			(start -0.4318 0.9525)
			(end 0.4318 -0.9525)
			(stroke
				(width 0)
				(type default)
			)
			(fill no)
			(layer "F.Fab")
		)
		(pad "1" smd custom
			(at 0 -0.4445 90)
			(size 0.1524 0.1524)
			(layers "F.Cu" "F.Mask" "F.Paste")
			(net "AGND_P1V8_STBY")
			(options
				(clearance outline)
				(anchor circle)
			)
			(primitives
				(gr_poly
					(pts
						(arc
							(start 0.3048 -0.2032)
							(mid 0.275042 -0.275042)
							(end 0.2032 -0.3048)
						)
						(arc
							(start -0.2032 -0.3048)
							(mid -0.275042 -0.275042)
							(end -0.3048 -0.2032)
						)
						(arc
							(start -0.3048 0.2032)
							(mid -0.275042 0.275042)
							(end -0.2032 0.3048)
						)
						(arc
							(start 0.2032 0.3048)
							(mid 0.275042 0.275042)
							(end 0.3048 0.2032)
						)
					)
					(width 0)
					(fill yes)
				)
			)
		)
		(pad "2" smd custom
			(at 0 0.4445 90)
			(size 0.1524 0.1524)
			(layers "F.Cu" "F.Mask" "F.Paste")
			(net "P1V8_STBY_ROVP")
			(options
				(clearance outline)
				(anchor circle)
			)
			(primitives
				(gr_poly
					(pts
						(arc
							(start 0.3048 -0.2032)
							(mid 0.275042 -0.275042)
							(end 0.2032 -0.3048)
						)
						(arc
							(start -0.2032 -0.3048)
							(mid -0.275042 -0.275042)
							(end -0.3048 -0.2032)
						)
						(arc
							(start -0.3048 0.2032)
							(mid -0.275042 0.275042)
							(end -0.2032 0.3048)
						)
						(arc
							(start 0.2032 0.3048)
							(mid 0.275042 0.275042)
							(end 0.3048 0.2032)
						)
					)
					(width 0)
					(fill yes)
				)
			)
		)
	)
	(footprint ""
		(layer "F.Cu")
		(at 223.139 -161.671 90)
		(property "Reference" "C88"
			(at 0 0 90)
			(layer "F.SilkS")
			(hide yes)
			(effects
				(font
					(size 1.27 1.27)
				)
			)
		)
		(property "Value" "SCD1U16V2KX-3GP"
			(at 1.1811 -2.7051 90)
			(unlocked yes)
			(layer "F.Fab")
			(hide yes)
			(effects
				(font
					(size 1.016 1.016)
					(thickness 0.1524)
				)
			)
		)
		(property "Device Type" "C402H22"
			(at 1.1811 -4.2291 90)
			(unlocked yes)
			(layer "F.Fab")
			(hide yes)
			(effects
				(font
					(size 1.016 1.016)
					(thickness 0.1524)
				)
			)
		)
		(duplicate_pad_numbers_are_jumpers no)
		(fp_rect
			(start -0.4318 0.9525)
			(end 0.4318 -0.9525)
			(stroke
				(width 0)
				(type default)
			)
			(fill no)
			(layer "F.CrtYd")
		)
		(fp_rect
			(start -0.4318 0.9525)
			(end 0.4318 -0.9525)
			(stroke
				(width 0)
				(type default)
			)
			(fill no)
			(layer "F.Fab")
		)
		(pad "1" smd custom
			(at 0 -0.4445 90)
			(size 0.1524 0.1524)
			(layers "F.Cu" "F.Mask" "F.Paste")
			(net "P3V3_STBY")
			(options
				(clearance outline)
				(anchor circle)
			)
			(primitives
				(gr_poly
					(pts
						(arc
							(start 0.3048 -0.2032)
							(mid 0.275042 -0.275042)
							(end 0.2032 -0.3048)
						)
						(arc
							(start -0.2032 -0.3048)
							(mid -0.275042 -0.275042)
							(end -0.3048 -0.2032)
						)
						(arc
							(start -0.3048 0.2032)
							(mid -0.275042 0.275042)
							(end -0.2032 0.3048)
						)
						(arc
							(start 0.2032 0.3048)
							(mid 0.275042 0.275042)
							(end 0.3048 0.2032)
						)
					)
					(width 0)
					(fill yes)
				)
			)
		)
		(pad "2" smd custom
			(at 0 0.4445 90)
			(size 0.1524 0.1524)
			(layers "F.Cu" "F.Mask" "F.Paste")
			(net "GND")
			(options
				(clearance outline)
				(anchor circle)
			)
			(primitives
				(gr_poly
					(pts
						(arc
							(start 0.3048 -0.2032)
							(mid 0.275042 -0.275042)
							(end 0.2032 -0.3048)
						)
						(arc
							(start -0.2032 -0.3048)
							(mid -0.275042 -0.275042)
							(end -0.3048 -0.2032)
						)
						(arc
							(start -0.3048 0.2032)
							(mid -0.275042 0.275042)
							(end -0.2032 0.3048)
						)
						(arc
							(start 0.2032 0.3048)
							(mid 0.275042 0.275042)
							(end 0.3048 0.2032)
						)
					)
					(width 0)
					(fill yes)
				)
			)
		)
	)
	(footprint ""
		(layer "F.Cu")
		(at 131.069842 -85.034882 90)
		(property "Reference" "SC1261"
			(at 0 0 90)
			(layer "F.SilkS")
			(hide yes)
			(effects
				(font
					(size 1.27 1.27)
				)
			)
		)
		(property "Value" "SCD01U10V1KX-GP"
			(at -2.8321 -1.7399 90)
			(unlocked yes)
			(layer "F.Fab")
			(hide yes)
			(effects
				(font
					(size 1.016 1.016)
					(thickness 0.1524)
				)
			)
		)
		(property "Device Type" "C0201H13"
			(at -2.8321 -3.2639 90)
			(unlocked yes)
			(layer "F.Fab")
			(hide yes)
			(effects
				(font
					(size 1.016 1.016)
					(thickness 0.1524)
				)
			)
		)
		(duplicate_pad_numbers_are_jumpers no)
		(fp_rect
			(start -0.2794 0.6477)
			(end 0.2794 -0.6477)
			(stroke
				(width 0)
				(type default)
			)
			(fill no)
			(layer "F.CrtYd")
		)
		(fp_rect
			(start -0.2794 0.6477)
			(end 0.2794 -0.6477)
			(stroke
				(width 0)
				(type default)
			)
			(fill no)
			(layer "F.Fab")
		)
		(pad "1" smd custom
			(at 0 -0.2794 90)
			(size 0.0762 0.0762)
			(layers "F.Cu" "F.Mask" "F.Paste")
			(net "SAS_HDD_TX15_P")
			(options
				(clearance outline)
				(anchor circle)
			)
			(primitives
				(gr_poly
					(pts
						(arc
							(start 0.1524 -0.127)
							(mid 0.137521 -0.162921)
							(end 0.1016 -0.1778)
						)
						(arc
							(start -0.1016 -0.1778)
							(mid -0.137521 -0.162921)
							(end -0.1524 -0.127)
						)
						(arc
							(start -0.1524 0.127)
							(mid -0.137521 0.162921)
							(end -0.1016 0.1778)
						)
						(arc
							(start 0.1016 0.1778)
							(mid 0.137521 0.162921)
							(end 0.1524 0.127)
						)
					)
					(width 0)
					(fill yes)
				)
			)
		)
		(pad "2" smd custom
			(at 0 0.2794 90)
			(size 0.0762 0.0762)
			(layers "F.Cu" "F.Mask" "F.Paste")
			(net "3008_SAS_RX_P3")
			(options
				(clearance outline)
				(anchor circle)
			)
			(primitives
				(gr_poly
					(pts
						(arc
							(start 0.1524 -0.127)
							(mid 0.137521 -0.162921)
							(end 0.1016 -0.1778)
						)
						(arc
							(start -0.1016 -0.1778)
							(mid -0.137521 -0.162921)
							(end -0.1524 -0.127)
						)
						(arc
							(start -0.1524 0.127)
							(mid -0.137521 0.162921)
							(end -0.1016 0.1778)
						)
						(arc
							(start 0.1016 0.1778)
							(mid 0.137521 0.162921)
							(end 0.1524 0.127)
						)
					)
					(width 0)
					(fill yes)
				)
			)
		)
	)
	(footprint ""
		(layer "F.Cu")
		(at 111.76 -29.21)
		(property "Reference" "STP40"
			(at 0 0 0)
			(layer "F.SilkS")
			(hide yes)
			(effects
				(font
					(size 1.27 1.27)
				)
			)
		)
		(property "Value" "TPAD28"
			(at 0.0127 -1.8034 0)
			(unlocked yes)
			(layer "F.Fab")
			(hide yes)
			(effects
				(font
					(size 1.016 1.016)
					(thickness 0.1524)
				)
			)
		)
		(property "Device Type" "TPAD28"
			(at 0.0127 -3.3274 0)
			(unlocked yes)
			(layer "F.Fab")
			(hide yes)
			(effects
				(font
					(size 1.016 1.016)
					(thickness 0.1524)
				)
			)
		)
		(duplicate_pad_numbers_are_jumpers no)
		(fp_poly
			(pts
				(arc
					(start 0.3556 0)
					(mid -0.3556 0)
					(end 0.3556 0)
				)
			)
			(stroke
				(width 0)
				(type default)
			)
			(fill no)
			(layer "F.CrtYd")
		)
		(fp_poly
			(pts
				(arc
					(start 0.6096 0)
					(mid -0.6096 0)
					(end 0.6096 0)
				)
			)
			(stroke
				(width 0)
				(type default)
			)
			(fill no)
			(layer "F.Fab")
		)
		(pad "1" smd circle
			(at 0 0)
			(size 0.7112 0.7112)
			(layers "F.Cu" "F.Mask" "F.Paste")
			(net "SYS_HALT0#")
		)
	)
	(footprint ""
		(layer "F.Cu")
		(at 240.053876 -13.156438 90)
		(property "Reference" "R305"
			(at 0 0 90)
			(layer "F.SilkS")
			(hide yes)
			(effects
				(font
					(size 1.27 1.27)
				)
			)
		)
		(property "Value" "0R2J-2-GP"
			(at 0.064008 -3.993896 90)
			(unlocked yes)
			(layer "F.Fab")
			(hide yes)
			(effects
				(font
					(size 1.016 1.016)
					(thickness 0.1524)
				)
			)
		)
		(property "Device Type" "R402H16"
			(at 0.064008 -5.517896 90)
			(unlocked yes)
			(layer "F.Fab")
			(hide yes)
			(effects
				(font
					(size 1.016 1.016)
					(thickness 0.1524)
				)
			)
		)
		(duplicate_pad_numbers_are_jumpers no)
		(fp_line
			(start 0.508 -0.9398)
			(end -0.508 -0.9398)
			(stroke
				(width 0.1524)
				(type default)
			)
			(layer "F.SilkS")
		)
		(fp_line
			(start -0.508 -0.9398)
			(end -0.508 0.9398)
			(stroke
				(width 0.1524)
				(type default)
			)
			(layer "F.SilkS")
		)
		(fp_rect
			(start -0.508 0.9398)
			(end 0.508 -0.9398)
			(stroke
				(width 0)
				(type default)
			)
			(fill no)
			(layer "F.CrtYd")
		)
		(fp_rect
			(start -0.508 0.9398)
			(end 0.508 -0.9398)
			(stroke
				(width 0)
				(type default)
			)
			(fill no)
			(layer "F.Fab")
		)
		(pad "1" smd custom
			(at 0 -0.4445 90)
			(size 0.1397 0.1397)
			(layers "F.Cu" "F.Mask" "F.Paste")
			(net "HB_OUT_R")
			(options
				(clearance outline)
				(anchor circle)
			)
			(primitives
				(gr_poly
					(pts
						(arc
							(start -0.1778 -0.2794)
							(mid -0.249642 -0.249642)
							(end -0.2794 -0.1778)
						)
						(arc
							(start -0.2794 0.1778)
							(mid -0.249642 0.249642)
							(end -0.1778 0.2794)
						)
						(arc
							(start 0.1778 0.2794)
							(mid 0.249642 0.249642)
							(end 0.2794 0.1778)
						)
						(arc
							(start 0.2794 -0.1778)
							(mid 0.249642 -0.249642)
							(end 0.1778 -0.2794)
						)
					)
					(width 0)
					(fill yes)
				)
			)
		)
		(pad "2" smd custom
			(at 0 0.4445 90)
			(size 0.1397 0.1397)
			(layers "F.Cu" "F.Mask" "F.Paste")
			(net "HB_OUT")
			(options
				(clearance outline)
				(anchor circle)
			)
			(primitives
				(gr_poly
					(pts
						(arc
							(start -0.1778 -0.2794)
							(mid -0.249642 -0.249642)
							(end -0.2794 -0.1778)
						)
						(arc
							(start -0.2794 0.1778)
							(mid -0.249642 0.249642)
							(end -0.1778 0.2794)
						)
						(arc
							(start 0.1778 0.2794)
							(mid 0.249642 0.249642)
							(end 0.2794 0.1778)
						)
						(arc
							(start 0.2794 -0.1778)
							(mid 0.249642 -0.249642)
							(end 0.1778 -0.2794)
						)
					)
					(width 0)
					(fill yes)
				)
			)
		)
	)
	(footprint ""
		(layer "F.Cu")
		(at 306.959 -180.467)
		(property "Reference" "TP102"
			(at 0 0 0)
			(layer "F.SilkS")
			(hide yes)
			(effects
				(font
					(size 1.27 1.27)
				)
			)
		)
		(property "Value" "TPAD28"
			(at 0.0127 -1.8034 0)
			(unlocked yes)
			(layer "F.Fab")
			(hide yes)
			(effects
				(font
					(size 1.016 1.016)
					(thickness 0.1524)
				)
			)
		)
		(property "Device Type" "TPAD28"
			(at 0.0127 -3.3274 0)
			(unlocked yes)
			(layer "F.Fab")
			(hide yes)
			(effects
				(font
					(size 1.016 1.016)
					(thickness 0.1524)
				)
			)
		)
		(duplicate_pad_numbers_are_jumpers no)
		(fp_poly
			(pts
				(arc
					(start 0.3556 0)
					(mid -0.3556 0)
					(end 0.3556 0)
				)
			)
			(stroke
				(width 0)
				(type default)
			)
			(fill no)
			(layer "F.CrtYd")
		)
		(fp_poly
			(pts
				(arc
					(start 0.6096 0)
					(mid -0.6096 0)
					(end 0.6096 0)
				)
			)
			(stroke
				(width 0)
				(type default)
			)
			(fill no)
			(layer "F.Fab")
		)
		(pad "1" smd circle
			(at 0 0)
			(size 0.7112 0.7112)
			(layers "F.Cu" "F.Mask" "F.Paste")
			(net "TP_BMC_GPIOL5")
		)
	)
	(footprint ""
		(layer "F.Cu")
		(at 220.472 -185.547 180)
		(property "Reference" "U36"
			(at 0 0 180)
			(layer "F.SilkS")
			(hide yes)
			(effects
				(font
					(size 1.27 1.27)
				)
			)
		)
		(property "Value" "LM393ADR-1-GP"
			(at -3.707384 -1.5367 180)
			(unlocked yes)
			(layer "F.Fab")
			(hide yes)
			(effects
				(font
					(size 1.016 1.016)
					(thickness 0.1524)
				)
			)
		)
		(property "Device Type" "SOIC8H69"
			(at -3.707384 -3.0607 180)
			(unlocked yes)
			(layer "F.Fab")
			(hide yes)
			(effects
				(font
					(size 1.016 1.016)
					(thickness 0.1524)
				)
			)
		)
		(duplicate_pad_numbers_are_jumpers no)
		(fp_line
			(start 2.1336 1.4224)
			(end 2.1336 -1.4224)
			(stroke
				(width 0.1524)
				(type default)
			)
			(layer "F.SilkS")
		)
		(fp_line
			(start 2.1336 -1.4224)
			(end -2.7432 -1.4224)
			(stroke
				(width 0.1524)
				(type default)
			)
			(layer "F.SilkS")
		)
		(fp_line
			(start -2.1844 -0.0508)
			(end -2.7178 0.508)
			(stroke
				(width 0.1524)
				(type default)
			)
			(layer "F.SilkS")
		)
		(fp_line
			(start -2.6289 3.4417)
			(end -2.6289 1.4732)
			(stroke
				(width 0.381)
				(type default)
			)
			(layer "F.SilkS")
		)
		(fp_line
			(start -2.7178 -0.508)
			(end -2.1844 -0.0508)
			(stroke
				(width 0.1524)
				(type default)
			)
			(layer "F.SilkS")
		)
		(fp_line
			(start -2.7432 1.4224)
			(end 2.1336 1.4224)
			(stroke
				(width 0.1524)
				(type default)
			)
			(layer "F.SilkS")
		)
		(fp_line
			(start -2.7432 1.4224)
			(end -2.6416 1.4224)
			(stroke
				(width 0.1524)
				(type default)
			)
			(layer "F.SilkS")
		)
		(fp_line
			(start -2.7432 -1.4224)
			(end -2.7432 1.4224)
			(stroke
				(width 0.1524)
				(type default)
			)
			(layer "F.SilkS")
		)
		(fp_poly
			(pts
				(xy -2.2098 -1.4224) (xy -2.2098 1.4224) (xy 2.2098 1.4224) (xy 2.2098 -1.4224)
			)
			(stroke
				(width 0)
				(type default)
			)
			(fill yes)
			(layer "F.SilkS")
		)
		(fp_rect
			(start -2.450084 2.999994)
			(end 2.450084 -2.999994)
			(stroke
				(width 0)
				(type default)
			)
			(fill no)
			(layer "F.CrtYd")
		)
		(fp_poly
			(pts
				(xy -2.8194 3.6322) (xy -2.8194 -3.6322) (xy 2.8194 -3.6322) (xy 2.8194 1.18364) (xy 2.450084 1.18364)
				(xy 2.450084 -2.999994) (xy -2.450084 -2.999994) (xy -2.450084 2.999994) (xy 2.450084 2.999994)
				(xy 2.450084 1.18618) (xy 2.8194 1.18618) (xy 2.8194 3.6322)
			)
			(stroke
				(width 0)
				(type default)
			)
			(fill no)
			(layer "F.CrtYd")
		)
		(fp_rect
			(start -2.8194 3.6322)
			(end 2.8194 -3.6322)
			(stroke
				(width 0)
				(type default)
			)
			(fill no)
			(layer "F.Fab")
		)
		(pad "1" smd rect
			(at -1.905 2.54 180)
			(size 0.635 1.651)
			(layers "F.Cu" "F.Mask" "F.Paste")
			(net "HB_A_OUT_EXP")
		)
		(pad "2" smd rect
			(at -0.635 2.54 180)
			(size 0.635 1.651)
			(layers "F.Cu" "F.Mask" "F.Paste")
			(net "HB_A_IN_EXP")
		)
		(pad "3" smd rect
			(at 0.635 2.54 180)
			(size 0.635 1.651)
			(layers "F.Cu" "F.Mask" "F.Paste")
			(net "DIVIDER 1_IN_EXP")
		)
		(pad "4" smd rect
			(at 1.905 2.54 180)
			(size 0.635 1.651)
			(layers "F.Cu" "F.Mask" "F.Paste")
			(net "GND")
		)
		(pad "5" smd rect
			(at 1.905 -2.54 180)
			(size 0.635 1.651)
			(layers "F.Cu" "F.Mask" "F.Paste")
			(net "HB_A_IN_EXP")
		)
		(pad "6" smd rect
			(at 0.635 -2.54 180)
			(size 0.635 1.651)
			(layers "F.Cu" "F.Mask" "F.Paste")
			(net "DIVIDER 2_IN_EXP")
		)
		(pad "7" smd rect
			(at -0.635 -2.54 180)
			(size 0.635 1.651)
			(layers "F.Cu" "F.Mask" "F.Paste")
			(net "HB_A_OUT_EXP")
		)
		(pad "8" smd rect
			(at -1.905 -2.54 180)
			(size 0.635 1.651)
			(layers "F.Cu" "F.Mask" "F.Paste")
			(net "P3V3_STBY")
		)
	)
	(footprint ""
		(layer "F.Cu")
		(at 145.034 -38.862)
		(property "Reference" "SR701"
			(at 0 0 0)
			(layer "F.SilkS")
			(hide yes)
			(effects
				(font
					(size 1.27 1.27)
				)
			)
		)
		(property "Value" "10KR2F-2-GP"
			(at 0.064008 -3.993896 0)
			(unlocked yes)
			(layer "F.Fab")
			(hide yes)
			(effects
				(font
					(size 1.016 1.016)
					(thickness 0.1524)
				)
			)
		)
		(property "Device Type" "R402H16"
			(at 0.064008 -5.517896 0)
			(unlocked yes)
			(layer "F.Fab")
			(hide yes)
			(effects
				(font
					(size 1.016 1.016)
					(thickness 0.1524)
				)
			)
		)
		(duplicate_pad_numbers_are_jumpers no)
		(fp_line
			(start -0.508 -0.9398)
			(end -0.508 0.9398)
			(stroke
				(width 0.1524)
				(type default)
			)
			(layer "F.SilkS")
		)
		(fp_line
			(start 0.508 -0.9398)
			(end -0.508 -0.9398)
			(stroke
				(width 0.1524)
				(type default)
			)
			(layer "F.SilkS")
		)
		(fp_rect
			(start -0.508 0.9398)
			(end 0.508 -0.9398)
			(stroke
				(width 0)
				(type default)
			)
			(fill no)
			(layer "F.CrtYd")
		)
		(fp_rect
			(start -0.508 0.9398)
			(end 0.508 -0.9398)
			(stroke
				(width 0)
				(type default)
			)
			(fill no)
			(layer "F.Fab")
		)
		(pad "1" smd custom
			(at 0 -0.4445)
			(size 0.1397 0.1397)
			(layers "F.Cu" "F.Mask" "F.Paste")
			(net "XM_ADDR_8")
			(options
				(clearance outline)
				(anchor circle)
			)
			(primitives
				(gr_poly
					(pts
						(arc
							(start -0.1778 -0.2794)
							(mid -0.249642 -0.249642)
							(end -0.2794 -0.1778)
						)
						(arc
							(start -0.2794 0.1778)
							(mid -0.249642 0.249642)
							(end -0.1778 0.2794)
						)
						(arc
							(start 0.1778 0.2794)
							(mid 0.249642 0.249642)
							(end 0.2794 0.1778)
						)
						(arc
							(start 0.2794 -0.1778)
							(mid 0.249642 -0.249642)
							(end 0.1778 -0.2794)
						)
					)
					(width 0)
					(fill yes)
				)
			)
		)
		(pad "2" smd custom
			(at 0 0.4445)
			(size 0.1397 0.1397)
			(layers "F.Cu" "F.Mask" "F.Paste")
			(net "GND")
			(options
				(clearance outline)
				(anchor circle)
			)
			(primitives
				(gr_poly
					(pts
						(arc
							(start -0.1778 -0.2794)
							(mid -0.249642 -0.249642)
							(end -0.2794 -0.1778)
						)
						(arc
							(start -0.2794 0.1778)
							(mid -0.249642 0.249642)
							(end -0.1778 0.2794)
						)
						(arc
							(start 0.1778 0.2794)
							(mid 0.249642 0.249642)
							(end 0.2794 0.1778)
						)
						(arc
							(start 0.2794 -0.1778)
							(mid 0.249642 -0.249642)
							(end 0.1778 -0.2794)
						)
					)
					(width 0)
					(fill yes)
				)
			)
		)
	)
	(footprint ""
		(layer "F.Cu")
		(at 266.437872 -39.442136 180)
		(property "Reference" "PU3"
			(at 0 0 180)
			(layer "F.SilkS")
			(hide yes)
			(effects
				(font
					(size 1.27 1.27)
				)
			)
		)
		(property "Value" "TPS53318DQPR-GP"
			(at -5.022088 -6.851904 180)
			(unlocked yes)
			(layer "F.Fab")
			(hide yes)
			(effects
				(font
					(size 1.016 1.016)
					(thickness 0.1524)
				)
			)
		)
		(property "Device Type" "DFN22G6050-G6133H60"
			(at -5.022088 -8.375904 180)
			(unlocked yes)
			(layer "F.Fab")
			(hide yes)
			(effects
				(font
					(size 1.016 1.016)
					(thickness 0.1524)
				)
			)
		)
		(duplicate_pad_numbers_are_jumpers no)
		(fp_line
			(start 3.5052 3.5179)
			(end 3.5052 2.2479)
			(stroke
				(width 0.1524)
				(type default)
			)
			(layer "F.SilkS")
		)
		(fp_line
			(start 2.2352 3.5179)
			(end 3.5052 3.5179)
			(stroke
				(width 0.1524)
				(type default)
			)
			(layer "F.SilkS")
		)
		(fp_line
			(start 1.500124 3.262122)
			(end 1.500124 4.024122)
			(stroke
				(width 0.1524)
				(type default)
			)
			(layer "F.SilkS")
		)
		(fp_line
			(start 0.500126 -3.262122)
			(end 0.500126 -3.770122)
			(stroke
				(width 0.1524)
				(type default)
			)
			(layer "F.SilkS")
		)
		(fp_line
			(start -0.999998 3.262122)
			(end -0.999998 3.770122)
			(stroke
				(width 0.1524)
				(type default)
			)
			(layer "F.SilkS")
		)
		(fp_line
			(start -1.999996 -3.262122)
			(end -1.999996 -4.024122)
			(stroke
				(width 0.1524)
				(type default)
			)
			(layer "F.SilkS")
		)
		(fp_line
			(start -2.2352 -3.5179)
			(end -3.5052 -3.5179)
			(stroke
				(width 0.1524)
				(type default)
			)
			(layer "F.SilkS")
		)
		(fp_line
			(start -3.5052 3.5179)
			(end -2.2352 3.5179)
			(stroke
				(width 0.1524)
				(type default)
			)
			(layer "F.SilkS")
		)
		(fp_line
			(start -3.5052 2.2479)
			(end -3.5052 3.5179)
			(stroke
				(width 0.1524)
				(type default)
			)
			(layer "F.SilkS")
		)
		(fp_line
			(start -3.5052 -3.5179)
			(end -3.5052 -2.2479)
			(stroke
				(width 0.1524)
				(type default)
			)
			(layer "F.SilkS")
		)
		(fp_poly
			(pts
				(xy 3.5052 -3.5179) (xy 2.4765 -3.5179) (xy 3.5052 -2.4892)
			)
			(stroke
				(width 0)
				(type default)
			)
			(fill yes)
			(layer "F.SilkS")
		)
		(fp_rect
			(start -2.9972 2.5019)
			(end 2.9972 -2.5019)
			(stroke
				(width 0)
				(type default)
			)
			(fill no)
			(layer "F.CrtYd")
		)
		(fp_poly
			(pts
				(xy 3.556 -2.5019) (xy -2.9972 -2.5019) (xy -2.9972 2.5019) (xy 2.9972 2.5019) (xy 2.9972 -2.4892)
				(xy 3.556 -2.4892) (xy 3.556 3.5179) (xy -3.556 3.5179) (xy -3.556 -3.5179) (xy 3.556 -3.5179)
			)
			(stroke
				(width 0)
				(type default)
			)
			(fill no)
			(layer "F.CrtYd")
		)
		(fp_rect
			(start -3.556 3.5179)
			(end 3.556 -3.5179)
			(stroke
				(width 0)
				(type default)
			)
			(fill no)
			(layer "F.Fab")
		)
		(pad "1" smd rect
			(at 2.500122 -2.449322 180)
			(size 0.3048 1.1176)
			(layers "F.Cu" "F.Mask" "F.Paste")
			(net "P1V8_STBY_VFB")
		)
		(pad "2" smd rect
			(at 1.999996 -2.449322 180)
			(size 0.3048 1.1176)
			(layers "F.Cu" "F.Mask" "F.Paste")
			(net "P1V8_STBY_EN")
		)
		(pad "3" smd rect
			(at 1.500124 -2.449322 180)
			(size 0.3048 1.1176)
			(layers "F.Cu" "F.Mask" "F.Paste")
			(net "P1V8_STBY_PG")
		)
		(pad "4" smd rect
			(at 0.999998 -2.449322 180)
			(size 0.3048 1.1176)
			(layers "F.Cu" "F.Mask" "F.Paste")
			(net "P1V8_STBY_VBST")
		)
		(pad "5" smd rect
			(at 0.500126 -2.449322 180)
			(size 0.3048 1.1176)
			(layers "F.Cu" "F.Mask" "F.Paste")
			(net "P1V8_STBY_ROVP")
		)
		(pad "6" smd rect
			(at 0 -2.449322 180)
			(size 0.3048 1.1176)
			(layers "F.Cu" "F.Mask" "F.Paste")
			(net "P1V8_STBY_LL")
		)
		(pad "7" smd rect
			(at -0.500126 -2.449322 180)
			(size 0.3048 1.1176)
			(layers "F.Cu" "F.Mask" "F.Paste")
			(net "P1V8_STBY_LL")
		)
		(pad "8" smd rect
			(at -0.999998 -2.449322 180)
			(size 0.3048 1.1176)
			(layers "F.Cu" "F.Mask" "F.Paste")
			(net "P1V8_STBY_LL")
		)
		(pad "9" smd rect
			(at -1.500124 -2.449322 180)
			(size 0.3048 1.1176)
			(layers "F.Cu" "F.Mask" "F.Paste")
			(net "P1V8_STBY_LL")
		)
		(pad "10" smd rect
			(at -1.999996 -2.449322 180)
			(size 0.3048 1.1176)
			(layers "F.Cu" "F.Mask" "F.Paste")
			(net "P1V8_STBY_LL")
		)
		(pad "11" smd rect
			(at -2.500122 -2.449322 180)
			(size 0.3048 1.1176)
			(layers "F.Cu" "F.Mask" "F.Paste")
			(net "P1V8_STBY_LL")
		)
		(pad "12" smd rect
			(at -2.500122 2.449322 180)
			(size 0.3048 1.1176)
			(layers "F.Cu" "F.Mask" "F.Paste")
			(net "P1V8_STBY_VIN")
		)
		(pad "13" smd rect
			(at -1.999996 2.449322 180)
			(size 0.3048 1.1176)
			(layers "F.Cu" "F.Mask" "F.Paste")
			(net "P1V8_STBY_VIN")
		)
		(pad "14" smd rect
			(at -1.500124 2.449322 180)
			(size 0.3048 1.1176)
			(layers "F.Cu" "F.Mask" "F.Paste")
			(net "P1V8_STBY_VIN")
		)
		(pad "15" smd rect
			(at -0.999998 2.449322 180)
			(size 0.3048 1.1176)
			(layers "F.Cu" "F.Mask" "F.Paste")
			(net "P1V8_STBY_VIN")
		)
		(pad "16" smd rect
			(at -0.500126 2.449322 180)
			(size 0.3048 1.1176)
			(layers "F.Cu" "F.Mask" "F.Paste")
			(net "P1V8_STBY_VIN")
		)
		(pad "17" smd rect
			(at 0 2.449322 180)
			(size 0.3048 1.1176)
			(layers "F.Cu" "F.Mask" "F.Paste")
			(net "P1V8_STBY_VIN")
		)
		(pad "18" smd rect
			(at 0.500126 2.449322 180)
			(size 0.3048 1.1176)
			(layers "F.Cu" "F.Mask" "F.Paste")
			(net "P1V8_STBY_VREG")
		)
		(pad "19" smd rect
			(at 0.999998 2.449322 180)
			(size 0.3048 1.1176)
			(layers "F.Cu" "F.Mask" "F.Paste")
			(net "P1V8_STBY_VDD")
		)
		(pad "20" smd rect
			(at 1.500124 2.449322 180)
			(size 0.3048 1.1176)
			(layers "F.Cu" "F.Mask" "F.Paste")
			(net "P1V8_STBY_MODE")
		)
		(pad "21" smd rect
			(at 1.999996 2.449322 180)
			(size 0.3048 1.1176)
			(layers "F.Cu" "F.Mask" "F.Paste")
			(net "P1V8_STBY_TRIP")
		)
		(pad "22" smd rect
			(at 2.500122 2.449322 180)
			(size 0.3048 1.1176)
			(layers "F.Cu" "F.Mask" "F.Paste")
			(net "P1V8_STBY_RF")
		)
		(pad "23" smd custom
			(at 0 0 180)
			(size 0.83185 0.83185)
			(layers "F.Cu" "F.Mask" "F.Paste")
			(net "GND")
			(options
				(clearance outline)
				(anchor circle)
			)
			(primitives
				(gr_poly
					(pts
						(xy -2.7813 1.6637) (xy -2.7813 1.2954) (xy -3.048 1.2954) (xy -3.048 0.9525) (xy -2.7813 0.9525)
						(xy -2.7813 -0.9525) (xy -3.048 -0.9525) (xy -3.048 -1.2954) (xy -2.7813 -1.2954) (xy -2.7813 -1.6637)
						(xy 2.7813 -1.6637) (xy 2.7813 -1.2954) (xy 3.048 -1.2954) (xy 3.048 -0.9525) (xy 2.7813 -0.9525)
						(xy 2.7813 0.9525) (xy 3.048 0.9525) (xy 3.048 1.2954) (xy 2.7813 1.2954) (xy 2.7813 1.6637)
					)
					(width 0)
					(fill yes)
				)
			)
		)
	)
	(footprint ""
		(layer "F.Cu")
		(at 95.89897 -91.948 90)
		(property "Reference" "SR774"
			(at 0 0 90)
			(layer "F.SilkS")
			(hide yes)
			(effects
				(font
					(size 1.27 1.27)
				)
			)
		)
		(property "Value" "34KR2F-GP"
			(at 0.064008 -3.993896 90)
			(unlocked yes)
			(layer "F.Fab")
			(hide yes)
			(effects
				(font
					(size 1.016 1.016)
					(thickness 0.1524)
				)
			)
		)
		(property "Device Type" "R402H16"
			(at 0.064008 -5.517896 90)
			(unlocked yes)
			(layer "F.Fab")
			(hide yes)
			(effects
				(font
					(size 1.016 1.016)
					(thickness 0.1524)
				)
			)
		)
		(duplicate_pad_numbers_are_jumpers no)
		(fp_line
			(start 0.508 -0.9398)
			(end -0.508 -0.9398)
			(stroke
				(width 0.1524)
				(type default)
			)
			(layer "F.SilkS")
		)
		(fp_line
			(start -0.508 -0.9398)
			(end -0.508 0.9398)
			(stroke
				(width 0.1524)
				(type default)
			)
			(layer "F.SilkS")
		)
		(fp_rect
			(start -0.508 0.9398)
			(end 0.508 -0.9398)
			(stroke
				(width 0)
				(type default)
			)
			(fill no)
			(layer "F.CrtYd")
		)
		(fp_rect
			(start -0.508 0.9398)
			(end 0.508 -0.9398)
			(stroke
				(width 0)
				(type default)
			)
			(fill no)
			(layer "F.Fab")
		)
		(pad "1" smd custom
			(at 0 -0.4445 90)
			(size 0.1397 0.1397)
			(layers "F.Cu" "F.Mask" "F.Paste")
			(net "P1V8_E")
			(options
				(clearance outline)
				(anchor circle)
			)
			(primitives
				(gr_poly
					(pts
						(arc
							(start -0.1778 -0.2794)
							(mid -0.249642 -0.249642)
							(end -0.2794 -0.1778)
						)
						(arc
							(start -0.2794 0.1778)
							(mid -0.249642 0.249642)
							(end -0.1778 0.2794)
						)
						(arc
							(start 0.1778 0.2794)
							(mid 0.249642 0.249642)
							(end 0.2794 0.1778)
						)
						(arc
							(start 0.2794 -0.1778)
							(mid 0.249642 -0.249642)
							(end 0.1778 -0.2794)
						)
					)
					(width 0)
					(fill yes)
				)
			)
		)
		(pad "2" smd custom
			(at 0 0.4445 90)
			(size 0.1397 0.1397)
			(layers "F.Cu" "F.Mask" "F.Paste")
			(net "EXP_XM_BUSY_N")
			(options
				(clearance outline)
				(anchor circle)
			)
			(primitives
				(gr_poly
					(pts
						(arc
							(start -0.1778 -0.2794)
							(mid -0.249642 -0.249642)
							(end -0.2794 -0.1778)
						)
						(arc
							(start -0.2794 0.1778)
							(mid -0.249642 0.249642)
							(end -0.1778 0.2794)
						)
						(arc
							(start 0.1778 0.2794)
							(mid 0.249642 0.249642)
							(end 0.2794 0.1778)
						)
						(arc
							(start 0.2794 -0.1778)
							(mid 0.249642 -0.249642)
							(end 0.1778 -0.2794)
						)
					)
					(width 0)
					(fill yes)
				)
			)
		)
	)
	(footprint ""
		(layer "F.Cu")
		(at 331.978 -80.391 90)
		(property "Reference" "R339"
			(at 0 0 90)
			(layer "F.SilkS")
			(hide yes)
			(effects
				(font
					(size 1.27 1.27)
				)
			)
		)
		(property "Value" "3K3R2F-2-GP"
			(at 0.064008 -3.993896 90)
			(unlocked yes)
			(layer "F.Fab")
			(hide yes)
			(effects
				(font
					(size 1.016 1.016)
					(thickness 0.1524)
				)
			)
		)
		(property "Device Type" "R402H16"
			(at 0.064008 -5.517896 90)
			(unlocked yes)
			(layer "F.Fab")
			(hide yes)
			(effects
				(font
					(size 1.016 1.016)
					(thickness 0.1524)
				)
			)
		)
		(duplicate_pad_numbers_are_jumpers no)
		(fp_line
			(start 0.508 -0.9398)
			(end -0.508 -0.9398)
			(stroke
				(width 0.1524)
				(type default)
			)
			(layer "F.SilkS")
		)
		(fp_line
			(start -0.508 -0.9398)
			(end -0.508 0.9398)
			(stroke
				(width 0.1524)
				(type default)
			)
			(layer "F.SilkS")
		)
		(fp_rect
			(start -0.508 0.9398)
			(end 0.508 -0.9398)
			(stroke
				(width 0)
				(type default)
			)
			(fill no)
			(layer "F.CrtYd")
		)
		(fp_rect
			(start -0.508 0.9398)
			(end 0.508 -0.9398)
			(stroke
				(width 0)
				(type default)
			)
			(fill no)
			(layer "F.Fab")
		)
		(pad "1" smd custom
			(at 0 -0.4445 90)
			(size 0.1397 0.1397)
			(layers "F.Cu" "F.Mask" "F.Paste")
			(net "AS_ROMA0_R")
			(options
				(clearance outline)
				(anchor circle)
			)
			(primitives
				(gr_poly
					(pts
						(arc
							(start -0.1778 -0.2794)
							(mid -0.249642 -0.249642)
							(end -0.2794 -0.1778)
						)
						(arc
							(start -0.2794 0.1778)
							(mid -0.249642 0.249642)
							(end -0.1778 0.2794)
						)
						(arc
							(start 0.1778 0.2794)
							(mid 0.249642 0.249642)
							(end 0.2794 0.1778)
						)
						(arc
							(start 0.2794 -0.1778)
							(mid 0.249642 -0.249642)
							(end 0.1778 -0.2794)
						)
					)
					(width 0)
					(fill yes)
				)
			)
		)
		(pad "2" smd custom
			(at 0 0.4445 90)
			(size 0.1397 0.1397)
			(layers "F.Cu" "F.Mask" "F.Paste")
			(net "P3V3_STBY")
			(options
				(clearance outline)
				(anchor circle)
			)
			(primitives
				(gr_poly
					(pts
						(arc
							(start -0.1778 -0.2794)
							(mid -0.249642 -0.249642)
							(end -0.2794 -0.1778)
						)
						(arc
							(start -0.2794 0.1778)
							(mid -0.249642 0.249642)
							(end -0.1778 0.2794)
						)
						(arc
							(start 0.1778 0.2794)
							(mid 0.249642 0.249642)
							(end 0.2794 0.1778)
						)
						(arc
							(start 0.2794 -0.1778)
							(mid 0.249642 -0.249642)
							(end 0.1778 -0.2794)
						)
					)
					(width 0)
					(fill yes)
				)
			)
		)
	)
	(footprint ""
		(layer "F.Cu")
		(at 336.423 -78.232 180)
		(property "Reference" "C333"
			(at 0 0 180)
			(layer "F.SilkS")
			(hide yes)
			(effects
				(font
					(size 1.27 1.27)
				)
			)
		)
		(property "Value" "SCD1U16V2KX-3GP"
			(at 1.1811 -2.7051 180)
			(unlocked yes)
			(layer "F.Fab")
			(hide yes)
			(effects
				(font
					(size 1.016 1.016)
					(thickness 0.1524)
				)
			)
		)
		(property "Device Type" "C402H22"
			(at 1.1811 -4.2291 180)
			(unlocked yes)
			(layer "F.Fab")
			(hide yes)
			(effects
				(font
					(size 1.016 1.016)
					(thickness 0.1524)
				)
			)
		)
		(duplicate_pad_numbers_are_jumpers no)
		(fp_rect
			(start -0.4318 0.9525)
			(end 0.4318 -0.9525)
			(stroke
				(width 0)
				(type default)
			)
			(fill no)
			(layer "F.CrtYd")
		)
		(fp_rect
			(start -0.4318 0.9525)
			(end 0.4318 -0.9525)
			(stroke
				(width 0)
				(type default)
			)
			(fill no)
			(layer "F.Fab")
		)
		(pad "1" smd custom
			(at 0 -0.4445 180)
			(size 0.1524 0.1524)
			(layers "F.Cu" "F.Mask" "F.Paste")
			(net "P3V3_STBY")
			(options
				(clearance outline)
				(anchor circle)
			)
			(primitives
				(gr_poly
					(pts
						(arc
							(start 0.3048 -0.2032)
							(mid 0.275042 -0.275042)
							(end 0.2032 -0.3048)
						)
						(arc
							(start -0.2032 -0.3048)
							(mid -0.275042 -0.275042)
							(end -0.3048 -0.2032)
						)
						(arc
							(start -0.3048 0.2032)
							(mid -0.275042 0.275042)
							(end -0.2032 0.3048)
						)
						(arc
							(start 0.2032 0.3048)
							(mid 0.275042 0.275042)
							(end 0.3048 0.2032)
						)
					)
					(width 0)
					(fill yes)
				)
			)
		)
		(pad "2" smd custom
			(at 0 0.4445 180)
			(size 0.1524 0.1524)
			(layers "F.Cu" "F.Mask" "F.Paste")
			(net "GND")
			(options
				(clearance outline)
				(anchor circle)
			)
			(primitives
				(gr_poly
					(pts
						(arc
							(start 0.3048 -0.2032)
							(mid 0.275042 -0.275042)
							(end 0.2032 -0.3048)
						)
						(arc
							(start -0.2032 -0.3048)
							(mid -0.275042 -0.275042)
							(end -0.3048 -0.2032)
						)
						(arc
							(start -0.3048 0.2032)
							(mid -0.275042 0.275042)
							(end -0.2032 0.3048)
						)
						(arc
							(start 0.2032 0.3048)
							(mid 0.275042 0.275042)
							(end 0.3048 0.2032)
						)
					)
					(width 0)
					(fill yes)
				)
			)
		)
	)
	(footprint ""
		(layer "F.Cu")
		(at 173.981872 -203.830936 90)
		(property "Reference" "R423"
			(at 0 0 90)
			(layer "F.SilkS")
			(hide yes)
			(effects
				(font
					(size 1.27 1.27)
				)
			)
		)
		(property "Value" "4K7R2J-2-GP"
			(at 0.064008 -3.993896 90)
			(unlocked yes)
			(layer "F.Fab")
			(hide yes)
			(effects
				(font
					(size 1.016 1.016)
					(thickness 0.1524)
				)
			)
		)
		(property "Device Type" "R402H16"
			(at 0.064008 -5.517896 90)
			(unlocked yes)
			(layer "F.Fab")
			(hide yes)
			(effects
				(font
					(size 1.016 1.016)
					(thickness 0.1524)
				)
			)
		)
		(duplicate_pad_numbers_are_jumpers no)
		(fp_line
			(start 0.508 -0.9398)
			(end -0.508 -0.9398)
			(stroke
				(width 0.1524)
				(type default)
			)
			(layer "F.SilkS")
		)
		(fp_line
			(start -0.508 -0.9398)
			(end -0.508 0.9398)
			(stroke
				(width 0.1524)
				(type default)
			)
			(layer "F.SilkS")
		)
		(fp_rect
			(start -0.508 0.9398)
			(end 0.508 -0.9398)
			(stroke
				(width 0)
				(type default)
			)
			(fill no)
			(layer "F.CrtYd")
		)
		(fp_rect
			(start -0.508 0.9398)
			(end 0.508 -0.9398)
			(stroke
				(width 0)
				(type default)
			)
			(fill no)
			(layer "F.Fab")
		)
		(pad "1" smd custom
			(at 0 -0.4445 90)
			(size 0.1397 0.1397)
			(layers "F.Cu" "F.Mask" "F.Paste")
			(net "P3V3_STBY")
			(options
				(clearance outline)
				(anchor circle)
			)
			(primitives
				(gr_poly
					(pts
						(arc
							(start -0.1778 -0.2794)
							(mid -0.249642 -0.249642)
							(end -0.2794 -0.1778)
						)
						(arc
							(start -0.2794 0.1778)
							(mid -0.249642 0.249642)
							(end -0.1778 0.2794)
						)
						(arc
							(start 0.1778 0.2794)
							(mid 0.249642 0.249642)
							(end 0.2794 0.1778)
						)
						(arc
							(start 0.2794 -0.1778)
							(mid 0.249642 -0.249642)
							(end 0.1778 -0.2794)
						)
					)
					(width 0)
					(fill yes)
				)
			)
		)
		(pad "2" smd custom
			(at 0 0.4445 90)
			(size 0.1397 0.1397)
			(layers "F.Cu" "F.Mask" "F.Paste")
			(net "SAS_I2C_B_BUF_SCL")
			(options
				(clearance outline)
				(anchor circle)
			)
			(primitives
				(gr_poly
					(pts
						(arc
							(start -0.1778 -0.2794)
							(mid -0.249642 -0.249642)
							(end -0.2794 -0.1778)
						)
						(arc
							(start -0.2794 0.1778)
							(mid -0.249642 0.249642)
							(end -0.1778 0.2794)
						)
						(arc
							(start 0.1778 0.2794)
							(mid 0.249642 0.249642)
							(end 0.2794 0.1778)
						)
						(arc
							(start 0.2794 -0.1778)
							(mid 0.249642 -0.249642)
							(end 0.1778 -0.2794)
						)
					)
					(width 0)
					(fill yes)
				)
			)
		)
	)
	(footprint ""
		(layer "F.Cu")
		(at 88.392 -18.669 180)
		(property "Reference" "PC218"
			(at 0 0 180)
			(layer "F.SilkS")
			(hide yes)
			(effects
				(font
					(size 1.27 1.27)
				)
			)
		)
		(property "Value" "SCD01U50V3KX-4GP"
			(at 0 -2.8194 180)
			(unlocked yes)
			(layer "F.Fab")
			(hide yes)
			(effects
				(font
					(size 1.016 1.016)
					(thickness 0.1524)
				)
			)
		)
		(property "Device Type" "C603H36"
			(at 0 -4.3434 180)
			(unlocked yes)
			(layer "F.Fab")
			(hide yes)
			(effects
				(font
					(size 1.016 1.016)
					(thickness 0.1524)
				)
			)
		)
		(duplicate_pad_numbers_are_jumpers no)
		(fp_line
			(start 0.508 0)
			(end -0.508 0)
			(stroke
				(width 0.2032)
				(type default)
			)
			(layer "F.SilkS")
		)
		(fp_rect
			(start -0.5842 1.3335)
			(end 0.5842 -1.3335)
			(stroke
				(width 0)
				(type default)
			)
			(fill no)
			(layer "F.CrtYd")
		)
		(fp_rect
			(start -0.5842 1.3335)
			(end 0.5842 -1.3335)
			(stroke
				(width 0)
				(type default)
			)
			(fill no)
			(layer "F.Fab")
		)
		(pad "1" smd custom
			(at 0 -0.762 180)
			(size 0.2159 0.2159)
			(layers "F.Cu" "F.Mask" "F.Paste")
			(net "VT235_VDES")
			(options
				(clearance outline)
				(anchor circle)
			)
			(primitives
				(gr_poly
					(pts
						(arc
							(start -0.3302 -0.4318)
							(mid -0.402042 -0.402042)
							(end -0.4318 -0.3302)
						)
						(arc
							(start -0.4318 0.3302)
							(mid -0.402042 0.402042)
							(end -0.3302 0.4318)
						)
						(arc
							(start 0.3302 0.4318)
							(mid 0.402042 0.402042)
							(end 0.4318 0.3302)
						)
						(arc
							(start 0.4318 -0.3302)
							(mid 0.402042 -0.402042)
							(end 0.3302 -0.4318)
						)
					)
					(width 0)
					(fill yes)
				)
			)
		)
		(pad "2" smd custom
			(at 0 0.762 180)
			(size 0.2159 0.2159)
			(layers "F.Cu" "F.Mask" "F.Paste")
			(net "VT235_VDES_RCC")
			(options
				(clearance outline)
				(anchor circle)
			)
			(primitives
				(gr_poly
					(pts
						(arc
							(start -0.3302 -0.4318)
							(mid -0.402042 -0.402042)
							(end -0.4318 -0.3302)
						)
						(arc
							(start -0.4318 0.3302)
							(mid -0.402042 0.402042)
							(end -0.3302 0.4318)
						)
						(arc
							(start 0.3302 0.4318)
							(mid 0.402042 0.402042)
							(end 0.4318 0.3302)
						)
						(arc
							(start 0.4318 -0.3302)
							(mid 0.402042 -0.402042)
							(end 0.3302 -0.4318)
						)
					)
					(width 0)
					(fill yes)
				)
			)
		)
	)
	(footprint ""
		(layer "F.Cu")
		(at 112.40897 -114.3 180)
		(property "Reference" "SC1078"
			(at 0 0 180)
			(layer "F.SilkS")
			(hide yes)
			(effects
				(font
					(size 1.27 1.27)
				)
			)
		)
		(property "Value" "SCD01U10V1KX-GP"
			(at -2.8321 -1.7399 180)
			(unlocked yes)
			(layer "F.Fab")
			(hide yes)
			(effects
				(font
					(size 1.016 1.016)
					(thickness 0.1524)
				)
			)
		)
		(property "Device Type" "C0201H13"
			(at -2.8321 -3.2639 180)
			(unlocked yes)
			(layer "F.Fab")
			(hide yes)
			(effects
				(font
					(size 1.016 1.016)
					(thickness 0.1524)
				)
			)
		)
		(duplicate_pad_numbers_are_jumpers no)
		(fp_rect
			(start -0.2794 0.6477)
			(end 0.2794 -0.6477)
			(stroke
				(width 0)
				(type default)
			)
			(fill no)
			(layer "F.CrtYd")
		)
		(fp_rect
			(start -0.2794 0.6477)
			(end 0.2794 -0.6477)
			(stroke
				(width 0)
				(type default)
			)
			(fill no)
			(layer "F.Fab")
		)
		(pad "1" smd custom
			(at 0 -0.2794 180)
			(size 0.0762 0.0762)
			(layers "F.Cu" "F.Mask" "F.Paste")
			(net "SAS_HDD_TX5_N")
			(options
				(clearance outline)
				(anchor circle)
			)
			(primitives
				(gr_poly
					(pts
						(arc
							(start 0.1524 -0.127)
							(mid 0.137521 -0.162921)
							(end 0.1016 -0.1778)
						)
						(arc
							(start -0.1016 -0.1778)
							(mid -0.137521 -0.162921)
							(end -0.1524 -0.127)
						)
						(arc
							(start -0.1524 0.127)
							(mid -0.137521 0.162921)
							(end -0.1016 0.1778)
						)
						(arc
							(start 0.1016 0.1778)
							(mid 0.137521 0.162921)
							(end 0.1524 0.127)
						)
					)
					(width 0)
					(fill yes)
				)
			)
		)
		(pad "2" smd custom
			(at 0 0.2794 180)
			(size 0.0762 0.0762)
			(layers "F.Cu" "F.Mask" "F.Paste")
			(net "SAS_EXP_GF_TX_DN9")
			(options
				(clearance outline)
				(anchor circle)
			)
			(primitives
				(gr_poly
					(pts
						(arc
							(start 0.1524 -0.127)
							(mid 0.137521 -0.162921)
							(end 0.1016 -0.1778)
						)
						(arc
							(start -0.1016 -0.1778)
							(mid -0.137521 -0.162921)
							(end -0.1524 -0.127)
						)
						(arc
							(start -0.1524 0.127)
							(mid -0.137521 0.162921)
							(end -0.1016 0.1778)
						)
						(arc
							(start 0.1016 0.1778)
							(mid 0.137521 0.162921)
							(end 0.1524 0.127)
						)
					)
					(width 0)
					(fill yes)
				)
			)
		)
	)
	(footprint ""
		(layer "F.Cu")
		(at 183.134 -50.165 90)
		(property "Reference" "R45"
			(at 0 0 90)
			(layer "F.SilkS")
			(hide yes)
			(effects
				(font
					(size 1.27 1.27)
				)
			)
		)
		(property "Value" "0R2J-2-GP"
			(at 0.064008 -3.993896 90)
			(unlocked yes)
			(layer "F.Fab")
			(hide yes)
			(effects
				(font
					(size 1.016 1.016)
					(thickness 0.1524)
				)
			)
		)
		(property "Device Type" "R402H16"
			(at 0.064008 -5.517896 90)
			(unlocked yes)
			(layer "F.Fab")
			(hide yes)
			(effects
				(font
					(size 1.016 1.016)
					(thickness 0.1524)
				)
			)
		)
		(duplicate_pad_numbers_are_jumpers no)
		(fp_line
			(start 0.508 -0.9398)
			(end -0.508 -0.9398)
			(stroke
				(width 0.1524)
				(type default)
			)
			(layer "F.SilkS")
		)
		(fp_line
			(start -0.508 -0.9398)
			(end -0.508 0.9398)
			(stroke
				(width 0.1524)
				(type default)
			)
			(layer "F.SilkS")
		)
		(fp_rect
			(start -0.508 0.9398)
			(end 0.508 -0.9398)
			(stroke
				(width 0)
				(type default)
			)
			(fill no)
			(layer "F.CrtYd")
		)
		(fp_rect
			(start -0.508 0.9398)
			(end 0.508 -0.9398)
			(stroke
				(width 0)
				(type default)
			)
			(fill no)
			(layer "F.Fab")
		)
		(pad "1" smd custom
			(at 0 -0.4445 90)
			(size 0.1397 0.1397)
			(layers "F.Cu" "F.Mask" "F.Paste")
			(net "PRSNT_CONTROL_BMC")
			(options
				(clearance outline)
				(anchor circle)
			)
			(primitives
				(gr_poly
					(pts
						(arc
							(start -0.1778 -0.2794)
							(mid -0.249642 -0.249642)
							(end -0.2794 -0.1778)
						)
						(arc
							(start -0.2794 0.1778)
							(mid -0.249642 0.249642)
							(end -0.1778 0.2794)
						)
						(arc
							(start 0.1778 0.2794)
							(mid 0.249642 0.249642)
							(end 0.2794 0.1778)
						)
						(arc
							(start 0.2794 -0.1778)
							(mid 0.249642 -0.249642)
							(end 0.1778 -0.2794)
						)
					)
					(width 0)
					(fill yes)
				)
			)
		)
		(pad "2" smd custom
			(at 0 0.4445 90)
			(size 0.1397 0.1397)
			(layers "F.Cu" "F.Mask" "F.Paste")
			(net "PRSNT_AND_2")
			(options
				(clearance outline)
				(anchor circle)
			)
			(primitives
				(gr_poly
					(pts
						(arc
							(start -0.1778 -0.2794)
							(mid -0.249642 -0.249642)
							(end -0.2794 -0.1778)
						)
						(arc
							(start -0.2794 0.1778)
							(mid -0.249642 0.249642)
							(end -0.1778 0.2794)
						)
						(arc
							(start 0.1778 0.2794)
							(mid 0.249642 0.249642)
							(end 0.2794 0.1778)
						)
						(arc
							(start 0.2794 -0.1778)
							(mid 0.249642 -0.249642)
							(end 0.1778 -0.2794)
						)
					)
					(width 0)
					(fill yes)
				)
			)
		)
	)
	(footprint ""
		(layer "F.Cu")
		(at 87.103966 -60.325 90)
		(property "Reference" "SR922"
			(at 0 0 90)
			(layer "F.SilkS")
			(hide yes)
			(effects
				(font
					(size 1.27 1.27)
				)
			)
		)
		(property "Value" "0R2J-2-GP"
			(at 0.064008 -3.993896 90)
			(unlocked yes)
			(layer "F.Fab")
			(hide yes)
			(effects
				(font
					(size 1.016 1.016)
					(thickness 0.1524)
				)
			)
		)
		(property "Device Type" "R402H16"
			(at 0.064008 -5.517896 90)
			(unlocked yes)
			(layer "F.Fab")
			(hide yes)
			(effects
				(font
					(size 1.016 1.016)
					(thickness 0.1524)
				)
			)
		)
		(duplicate_pad_numbers_are_jumpers no)
		(fp_line
			(start 0.508 -0.9398)
			(end -0.508 -0.9398)
			(stroke
				(width 0.1524)
				(type default)
			)
			(layer "F.SilkS")
		)
		(fp_line
			(start -0.508 -0.9398)
			(end -0.508 0.9398)
			(stroke
				(width 0.1524)
				(type default)
			)
			(layer "F.SilkS")
		)
		(fp_rect
			(start -0.508 0.9398)
			(end 0.508 -0.9398)
			(stroke
				(width 0)
				(type default)
			)
			(fill no)
			(layer "F.CrtYd")
		)
		(fp_rect
			(start -0.508 0.9398)
			(end 0.508 -0.9398)
			(stroke
				(width 0)
				(type default)
			)
			(fill no)
			(layer "F.Fab")
		)
		(pad "1" smd custom
			(at 0 -0.4445 90)
			(size 0.1397 0.1397)
			(layers "F.Cu" "F.Mask" "F.Paste")
			(net "REF_CLK")
			(options
				(clearance outline)
				(anchor circle)
			)
			(primitives
				(gr_poly
					(pts
						(arc
							(start -0.1778 -0.2794)
							(mid -0.249642 -0.249642)
							(end -0.2794 -0.1778)
						)
						(arc
							(start -0.2794 0.1778)
							(mid -0.249642 0.249642)
							(end -0.1778 0.2794)
						)
						(arc
							(start 0.1778 0.2794)
							(mid 0.249642 0.249642)
							(end 0.2794 0.1778)
						)
						(arc
							(start 0.2794 -0.1778)
							(mid 0.249642 -0.249642)
							(end 0.1778 -0.2794)
						)
					)
					(width 0)
					(fill yes)
				)
			)
		)
		(pad "2" smd custom
			(at 0 0.4445 90)
			(size 0.1397 0.1397)
			(layers "F.Cu" "F.Mask" "F.Paste")
			(net "IOC_REF_CLK_N")
			(options
				(clearance outline)
				(anchor circle)
			)
			(primitives
				(gr_poly
					(pts
						(arc
							(start -0.1778 -0.2794)
							(mid -0.249642 -0.249642)
							(end -0.2794 -0.1778)
						)
						(arc
							(start -0.2794 0.1778)
							(mid -0.249642 0.249642)
							(end -0.1778 0.2794)
						)
						(arc
							(start 0.1778 0.2794)
							(mid 0.249642 0.249642)
							(end 0.2794 0.1778)
						)
						(arc
							(start 0.2794 -0.1778)
							(mid 0.249642 -0.249642)
							(end 0.1778 -0.2794)
						)
					)
					(width 0)
					(fill yes)
				)
			)
		)
	)
	(footprint ""
		(layer "F.Cu")
		(at 95.358966 -60.325)
		(property "Reference" "STP34"
			(at 0 0 0)
			(layer "F.SilkS")
			(hide yes)
			(effects
				(font
					(size 1.27 1.27)
				)
			)
		)
		(property "Value" "TPAD28"
			(at 0.0127 -1.8034 0)
			(unlocked yes)
			(layer "F.Fab")
			(hide yes)
			(effects
				(font
					(size 1.016 1.016)
					(thickness 0.1524)
				)
			)
		)
		(property "Device Type" "TPAD28"
			(at 0.0127 -3.3274 0)
			(unlocked yes)
			(layer "F.Fab")
			(hide yes)
			(effects
				(font
					(size 1.016 1.016)
					(thickness 0.1524)
				)
			)
		)
		(duplicate_pad_numbers_are_jumpers no)
		(fp_poly
			(pts
				(arc
					(start 0.3556 0)
					(mid -0.3556 0)
					(end 0.3556 0)
				)
			)
			(stroke
				(width 0)
				(type default)
			)
			(fill no)
			(layer "F.CrtYd")
		)
		(fp_poly
			(pts
				(arc
					(start 0.6096 0)
					(mid -0.6096 0)
					(end 0.6096 0)
				)
			)
			(stroke
				(width 0)
				(type default)
			)
			(fill no)
			(layer "F.Fab")
		)
		(pad "1" smd circle
			(at 0 0)
			(size 0.7112 0.7112)
			(layers "F.Cu" "F.Mask" "F.Paste")
			(net "ICE0_TRST#")
		)
	)
	(footprint ""
		(layer "F.Cu")
		(at 82.92719 -59.911488 90)
		(property "Reference" "SC919"
			(at 0 0 90)
			(layer "F.SilkS")
			(hide yes)
			(effects
				(font
					(size 1.27 1.27)
				)
			)
		)
		(property "Value" "SC22U6D3V5MX-2GP"
			(at -0.0762 -6.1214 90)
			(unlocked yes)
			(layer "F.Fab")
			(hide yes)
			(effects
				(font
					(size 1.016 1.016)
					(thickness 0.1524)
				)
			)
		)
		(property "Device Type" "C805H58"
			(at -0.0762 -8.1534 90)
			(unlocked yes)
			(layer "F.Fab")
			(hide yes)
			(effects
				(font
					(size 1.016 1.016)
					(thickness 0.1524)
				)
			)
		)
		(duplicate_pad_numbers_are_jumpers no)
		(fp_line
			(start 0.635 0)
			(end -0.635 0)
			(stroke
				(width 0.508)
				(type default)
			)
			(layer "F.SilkS")
		)
		(fp_rect
			(start -0.9652 1.778)
			(end 0.9652 -1.778)
			(stroke
				(width 0)
				(type default)
			)
			(fill no)
			(layer "F.CrtYd")
		)
		(fp_poly
			(pts
				(xy -0.9652 -1.778) (xy 0.9652 -1.778) (xy 0.9652 1.778) (xy -0.9652 1.778)
			)
			(stroke
				(width 0)
				(type default)
			)
			(fill no)
			(layer "F.Fab")
		)
		(pad "1" smd rect
			(at 0 -0.9652 90)
			(size 1.397 1.143)
			(layers "F.Cu" "F.Mask" "F.Paste")
			(net "SYS_PLL_VDD")
		)
		(pad "2" smd rect
			(at 0 0.9652 90)
			(size 1.397 1.143)
			(layers "F.Cu" "F.Mask" "F.Paste")
			(net "GND")
		)
	)
	(footprint ""
		(layer "F.Cu")
		(at 88.143842 -128.976882)
		(property "Reference" "SC1117"
			(at 0 0 0)
			(layer "F.SilkS")
			(hide yes)
			(effects
				(font
					(size 1.27 1.27)
				)
			)
		)
		(property "Value" "SCD1U16V2KX-3GP"
			(at 1.1811 -2.7051 0)
			(unlocked yes)
			(layer "F.Fab")
			(hide yes)
			(effects
				(font
					(size 1.016 1.016)
					(thickness 0.1524)
				)
			)
		)
		(property "Device Type" "C402H22"
			(at 1.1811 -4.2291 0)
			(unlocked yes)
			(layer "F.Fab")
			(hide yes)
			(effects
				(font
					(size 1.016 1.016)
					(thickness 0.1524)
				)
			)
		)
		(duplicate_pad_numbers_are_jumpers no)
		(fp_rect
			(start -0.4318 0.9525)
			(end 0.4318 -0.9525)
			(stroke
				(width 0)
				(type default)
			)
			(fill no)
			(layer "F.CrtYd")
		)
		(fp_rect
			(start -0.4318 0.9525)
			(end 0.4318 -0.9525)
			(stroke
				(width 0)
				(type default)
			)
			(fill no)
			(layer "F.Fab")
		)
		(pad "1" smd custom
			(at 0 -0.4445)
			(size 0.1524 0.1524)
			(layers "F.Cu" "F.Mask" "F.Paste")
			(net "P1V8_E")
			(options
				(clearance outline)
				(anchor circle)
			)
			(primitives
				(gr_poly
					(pts
						(arc
							(start 0.3048 -0.2032)
							(mid 0.275042 -0.275042)
							(end 0.2032 -0.3048)
						)
						(arc
							(start -0.2032 -0.3048)
							(mid -0.275042 -0.275042)
							(end -0.3048 -0.2032)
						)
						(arc
							(start -0.3048 0.2032)
							(mid -0.275042 0.275042)
							(end -0.2032 0.3048)
						)
						(arc
							(start 0.2032 0.3048)
							(mid 0.275042 0.275042)
							(end 0.3048 0.2032)
						)
					)
					(width 0)
					(fill yes)
				)
			)
		)
		(pad "2" smd custom
			(at 0 0.4445)
			(size 0.1524 0.1524)
			(layers "F.Cu" "F.Mask" "F.Paste")
			(net "GND")
			(options
				(clearance outline)
				(anchor circle)
			)
			(primitives
				(gr_poly
					(pts
						(arc
							(start 0.3048 -0.2032)
							(mid 0.275042 -0.275042)
							(end 0.2032 -0.3048)
						)
						(arc
							(start -0.2032 -0.3048)
							(mid -0.275042 -0.275042)
							(end -0.3048 -0.2032)
						)
						(arc
							(start -0.3048 0.2032)
							(mid -0.275042 0.275042)
							(end -0.2032 0.3048)
						)
						(arc
							(start 0.2032 0.3048)
							(mid 0.275042 0.275042)
							(end 0.3048 0.2032)
						)
					)
					(width 0)
					(fill yes)
				)
			)
		)
	)
	(footprint ""
		(layer "F.Cu")
		(at 215.773 -182.88 -90)
		(property "Reference" "C305"
			(at 0 0 270)
			(layer "F.SilkS")
			(hide yes)
			(effects
				(font
					(size 1.27 1.27)
				)
			)
		)
		(property "Value" "SC1U10V3KX-4GP-U"
			(at 0 -2.8194 270)
			(unlocked yes)
			(layer "F.Fab")
			(hide yes)
			(effects
				(font
					(size 1.016 1.016)
					(thickness 0.1524)
				)
			)
		)
		(property "Device Type" "C603H36"
			(at 0 -4.3434 270)
			(unlocked yes)
			(layer "F.Fab")
			(hide yes)
			(effects
				(font
					(size 1.016 1.016)
					(thickness 0.1524)
				)
			)
		)
		(duplicate_pad_numbers_are_jumpers no)
		(fp_line
			(start 0.508 0)
			(end -0.508 0)
			(stroke
				(width 0.2032)
				(type default)
			)
			(layer "F.SilkS")
		)
		(fp_rect
			(start -0.5842 1.3335)
			(end 0.5842 -1.3335)
			(stroke
				(width 0)
				(type default)
			)
			(fill no)
			(layer "F.CrtYd")
		)
		(fp_rect
			(start -0.5842 1.3335)
			(end 0.5842 -1.3335)
			(stroke
				(width 0)
				(type default)
			)
			(fill no)
			(layer "F.Fab")
		)
		(pad "1" smd custom
			(at 0 -0.762 270)
			(size 0.2159 0.2159)
			(layers "F.Cu" "F.Mask" "F.Paste")
			(net "HB_A_IN_EXP")
			(options
				(clearance outline)
				(anchor circle)
			)
			(primitives
				(gr_poly
					(pts
						(arc
							(start -0.3302 -0.4318)
							(mid -0.402042 -0.402042)
							(end -0.4318 -0.3302)
						)
						(arc
							(start -0.4318 0.3302)
							(mid -0.402042 0.402042)
							(end -0.3302 0.4318)
						)
						(arc
							(start 0.3302 0.4318)
							(mid 0.402042 0.402042)
							(end 0.4318 0.3302)
						)
						(arc
							(start 0.4318 -0.3302)
							(mid 0.402042 -0.402042)
							(end 0.3302 -0.4318)
						)
					)
					(width 0)
					(fill yes)
				)
			)
		)
		(pad "2" smd custom
			(at 0 0.762 270)
			(size 0.2159 0.2159)
			(layers "F.Cu" "F.Mask" "F.Paste")
			(net "GND")
			(options
				(clearance outline)
				(anchor circle)
			)
			(primitives
				(gr_poly
					(pts
						(arc
							(start -0.3302 -0.4318)
							(mid -0.402042 -0.402042)
							(end -0.4318 -0.3302)
						)
						(arc
							(start -0.4318 0.3302)
							(mid -0.402042 0.402042)
							(end -0.3302 0.4318)
						)
						(arc
							(start 0.3302 0.4318)
							(mid 0.402042 0.402042)
							(end 0.4318 0.3302)
						)
						(arc
							(start 0.4318 -0.3302)
							(mid 0.402042 -0.402042)
							(end 0.3302 -0.4318)
						)
					)
					(width 0)
					(fill yes)
				)
			)
		)
	)
	(footprint ""
		(layer "F.Cu")
		(at 189.611 -26.67)
		(property "Reference" "TP127"
			(at 0 0 0)
			(layer "F.SilkS")
			(hide yes)
			(effects
				(font
					(size 1.27 1.27)
				)
			)
		)
		(property "Value" "TPAD28"
			(at 0.0127 -1.8034 0)
			(unlocked yes)
			(layer "F.Fab")
			(hide yes)
			(effects
				(font
					(size 1.016 1.016)
					(thickness 0.1524)
				)
			)
		)
		(property "Device Type" "TPAD28"
			(at 0.0127 -3.3274 0)
			(unlocked yes)
			(layer "F.Fab")
			(hide yes)
			(effects
				(font
					(size 1.016 1.016)
					(thickness 0.1524)
				)
			)
		)
		(duplicate_pad_numbers_are_jumpers no)
		(fp_poly
			(pts
				(arc
					(start 0.3556 0)
					(mid -0.3556 0)
					(end 0.3556 0)
				)
			)
			(stroke
				(width 0)
				(type default)
			)
			(fill no)
			(layer "F.CrtYd")
		)
		(fp_poly
			(pts
				(arc
					(start 0.6096 0)
					(mid -0.6096 0)
					(end 0.6096 0)
				)
			)
			(stroke
				(width 0)
				(type default)
			)
			(fill no)
			(layer "F.Fab")
		)
		(pad "1" smd circle
			(at 0 0)
			(size 0.7112 0.7112)
			(layers "F.Cu" "F.Mask" "F.Paste")
			(net "NC_PHY_RXC")
		)
	)
	(footprint ""
		(layer "F.Cu")
		(at 111.89716 -26.924 -90)
		(property "Reference" "SR685"
			(at 0 0 270)
			(layer "F.SilkS")
			(hide yes)
			(effects
				(font
					(size 1.27 1.27)
				)
			)
		)
		(property "Value" "10KR2F-2-GP"
			(at 0.064008 -3.993896 270)
			(unlocked yes)
			(layer "F.Fab")
			(hide yes)
			(effects
				(font
					(size 1.016 1.016)
					(thickness 0.1524)
				)
			)
		)
		(property "Device Type" "R402H16"
			(at 0.064008 -5.517896 270)
			(unlocked yes)
			(layer "F.Fab")
			(hide yes)
			(effects
				(font
					(size 1.016 1.016)
					(thickness 0.1524)
				)
			)
		)
		(duplicate_pad_numbers_are_jumpers no)
		(fp_line
			(start -0.508 -0.9398)
			(end -0.508 0.9398)
			(stroke
				(width 0.1524)
				(type default)
			)
			(layer "F.SilkS")
		)
		(fp_line
			(start 0.508 -0.9398)
			(end -0.508 -0.9398)
			(stroke
				(width 0.1524)
				(type default)
			)
			(layer "F.SilkS")
		)
		(fp_rect
			(start -0.508 0.9398)
			(end 0.508 -0.9398)
			(stroke
				(width 0)
				(type default)
			)
			(fill no)
			(layer "F.CrtYd")
		)
		(fp_rect
			(start -0.508 0.9398)
			(end 0.508 -0.9398)
			(stroke
				(width 0)
				(type default)
			)
			(fill no)
			(layer "F.Fab")
		)
		(pad "1" smd custom
			(at 0 -0.4445 270)
			(size 0.1397 0.1397)
			(layers "F.Cu" "F.Mask" "F.Paste")
			(net "SYS_DBMODE1")
			(options
				(clearance outline)
				(anchor circle)
			)
			(primitives
				(gr_poly
					(pts
						(arc
							(start -0.1778 -0.2794)
							(mid -0.249642 -0.249642)
							(end -0.2794 -0.1778)
						)
						(arc
							(start -0.2794 0.1778)
							(mid -0.249642 0.249642)
							(end -0.1778 0.2794)
						)
						(arc
							(start 0.1778 0.2794)
							(mid 0.249642 0.249642)
							(end 0.2794 0.1778)
						)
						(arc
							(start 0.2794 -0.1778)
							(mid 0.249642 -0.249642)
							(end 0.1778 -0.2794)
						)
					)
					(width 0)
					(fill yes)
				)
			)
		)
		(pad "2" smd custom
			(at 0 0.4445 270)
			(size 0.1397 0.1397)
			(layers "F.Cu" "F.Mask" "F.Paste")
			(net "GND")
			(options
				(clearance outline)
				(anchor circle)
			)
			(primitives
				(gr_poly
					(pts
						(arc
							(start -0.1778 -0.2794)
							(mid -0.249642 -0.249642)
							(end -0.2794 -0.1778)
						)
						(arc
							(start -0.2794 0.1778)
							(mid -0.249642 0.249642)
							(end -0.1778 0.2794)
						)
						(arc
							(start 0.1778 0.2794)
							(mid 0.249642 0.249642)
							(end 0.2794 0.1778)
						)
						(arc
							(start 0.2794 -0.1778)
							(mid 0.249642 -0.249642)
							(end 0.1778 -0.2794)
						)
					)
					(width 0)
					(fill yes)
				)
			)
		)
	)
	(footprint ""
		(layer "F.Cu")
		(at 107.931966 -65.8876)
		(property "Reference" "SR658"
			(at 0 0 0)
			(layer "F.SilkS")
			(hide yes)
			(effects
				(font
					(size 1.27 1.27)
				)
			)
		)
		(property "Value" "4K7R2F-GP"
			(at 0.064008 -3.993896 0)
			(unlocked yes)
			(layer "F.Fab")
			(hide yes)
			(effects
				(font
					(size 1.016 1.016)
					(thickness 0.1524)
				)
			)
		)
		(property "Device Type" "R402H16"
			(at 0.064008 -5.517896 0)
			(unlocked yes)
			(layer "F.Fab")
			(hide yes)
			(effects
				(font
					(size 1.016 1.016)
					(thickness 0.1524)
				)
			)
		)
		(duplicate_pad_numbers_are_jumpers no)
		(fp_line
			(start -0.508 -0.9398)
			(end -0.508 0.9398)
			(stroke
				(width 0.1524)
				(type default)
			)
			(layer "F.SilkS")
		)
		(fp_line
			(start 0.508 -0.9398)
			(end -0.508 -0.9398)
			(stroke
				(width 0.1524)
				(type default)
			)
			(layer "F.SilkS")
		)
		(fp_rect
			(start -0.508 0.9398)
			(end 0.508 -0.9398)
			(stroke
				(width 0)
				(type default)
			)
			(fill no)
			(layer "F.CrtYd")
		)
		(fp_rect
			(start -0.508 0.9398)
			(end 0.508 -0.9398)
			(stroke
				(width 0)
				(type default)
			)
			(fill no)
			(layer "F.Fab")
		)
		(pad "1" smd custom
			(at 0 -0.4445)
			(size 0.1397 0.1397)
			(layers "F.Cu" "F.Mask" "F.Paste")
			(net "P1V8_C")
			(options
				(clearance outline)
				(anchor circle)
			)
			(primitives
				(gr_poly
					(pts
						(arc
							(start -0.1778 -0.2794)
							(mid -0.249642 -0.249642)
							(end -0.2794 -0.1778)
						)
						(arc
							(start -0.2794 0.1778)
							(mid -0.249642 0.249642)
							(end -0.1778 0.2794)
						)
						(arc
							(start 0.1778 0.2794)
							(mid 0.249642 0.249642)
							(end 0.2794 0.1778)
						)
						(arc
							(start 0.2794 -0.1778)
							(mid 0.249642 -0.249642)
							(end 0.1778 -0.2794)
						)
					)
					(width 0)
					(fill yes)
				)
			)
		)
		(pad "2" smd custom
			(at 0 0.4445)
			(size 0.1397 0.1397)
			(layers "F.Cu" "F.Mask" "F.Paste")
			(net "LSI_SCAN_EN")
			(options
				(clearance outline)
				(anchor circle)
			)
			(primitives
				(gr_poly
					(pts
						(arc
							(start -0.1778 -0.2794)
							(mid -0.249642 -0.249642)
							(end -0.2794 -0.1778)
						)
						(arc
							(start -0.2794 0.1778)
							(mid -0.249642 0.249642)
							(end -0.1778 0.2794)
						)
						(arc
							(start 0.1778 0.2794)
							(mid 0.249642 0.249642)
							(end 0.2794 0.1778)
						)
						(arc
							(start 0.2794 -0.1778)
							(mid 0.249642 -0.249642)
							(end 0.1778 -0.2794)
						)
					)
					(width 0)
					(fill yes)
				)
			)
		)
	)
	(footprint ""
		(layer "F.Cu")
		(at 140.47597 -83.566 180)
		(property "Reference" "R167"
			(at 0 0 180)
			(layer "F.SilkS")
			(hide yes)
			(effects
				(font
					(size 1.27 1.27)
				)
			)
		)
		(property "Value" "4K7R2F-GP"
			(at 0.064008 -3.993896 180)
			(unlocked yes)
			(layer "F.Fab")
			(hide yes)
			(effects
				(font
					(size 1.016 1.016)
					(thickness 0.1524)
				)
			)
		)
		(property "Device Type" "R402H16"
			(at 0.064008 -5.517896 180)
			(unlocked yes)
			(layer "F.Fab")
			(hide yes)
			(effects
				(font
					(size 1.016 1.016)
					(thickness 0.1524)
				)
			)
		)
		(duplicate_pad_numbers_are_jumpers no)
		(fp_line
			(start 0.508 -0.9398)
			(end -0.508 -0.9398)
			(stroke
				(width 0.1524)
				(type default)
			)
			(layer "F.SilkS")
		)
		(fp_line
			(start -0.508 -0.9398)
			(end -0.508 0.9398)
			(stroke
				(width 0.1524)
				(type default)
			)
			(layer "F.SilkS")
		)
		(fp_rect
			(start -0.508 0.9398)
			(end 0.508 -0.9398)
			(stroke
				(width 0)
				(type default)
			)
			(fill no)
			(layer "F.CrtYd")
		)
		(fp_rect
			(start -0.508 0.9398)
			(end 0.508 -0.9398)
			(stroke
				(width 0)
				(type default)
			)
			(fill no)
			(layer "F.Fab")
		)
		(pad "1" smd custom
			(at 0 -0.4445 180)
			(size 0.1397 0.1397)
			(layers "F.Cu" "F.Mask" "F.Paste")
			(net "P3V3_STBY")
			(options
				(clearance outline)
				(anchor circle)
			)
			(primitives
				(gr_poly
					(pts
						(arc
							(start -0.1778 -0.2794)
							(mid -0.249642 -0.249642)
							(end -0.2794 -0.1778)
						)
						(arc
							(start -0.2794 0.1778)
							(mid -0.249642 0.249642)
							(end -0.1778 0.2794)
						)
						(arc
							(start 0.1778 0.2794)
							(mid 0.249642 0.249642)
							(end 0.2794 0.1778)
						)
						(arc
							(start 0.2794 -0.1778)
							(mid 0.249642 -0.249642)
							(end 0.1778 -0.2794)
						)
					)
					(width 0)
					(fill yes)
				)
			)
		)
		(pad "2" smd custom
			(at 0 0.4445 180)
			(size 0.1397 0.1397)
			(layers "F.Cu" "F.Mask" "F.Paste")
			(net "TEMP_3_A1")
			(options
				(clearance outline)
				(anchor circle)
			)
			(primitives
				(gr_poly
					(pts
						(arc
							(start -0.1778 -0.2794)
							(mid -0.249642 -0.249642)
							(end -0.2794 -0.1778)
						)
						(arc
							(start -0.2794 0.1778)
							(mid -0.249642 0.249642)
							(end -0.1778 0.2794)
						)
						(arc
							(start 0.1778 0.2794)
							(mid 0.249642 0.249642)
							(end 0.2794 0.1778)
						)
						(arc
							(start 0.2794 -0.1778)
							(mid 0.249642 -0.249642)
							(end 0.1778 -0.2794)
						)
					)
					(width 0)
					(fill yes)
				)
			)
		)
	)
	(footprint ""
		(layer "F.Cu")
		(at 110.37316 -27.432)
		(property "Reference" "SR687"
			(at 0 0 0)
			(layer "F.SilkS")
			(hide yes)
			(effects
				(font
					(size 1.27 1.27)
				)
			)
		)
		(property "Value" "10KR2F-2-GP"
			(at 0.064008 -3.993896 0)
			(unlocked yes)
			(layer "F.Fab")
			(hide yes)
			(effects
				(font
					(size 1.016 1.016)
					(thickness 0.1524)
				)
			)
		)
		(property "Device Type" "R402H16"
			(at 0.064008 -5.517896 0)
			(unlocked yes)
			(layer "F.Fab")
			(hide yes)
			(effects
				(font
					(size 1.016 1.016)
					(thickness 0.1524)
				)
			)
		)
		(duplicate_pad_numbers_are_jumpers no)
		(fp_line
			(start -0.508 -0.9398)
			(end -0.508 0.9398)
			(stroke
				(width 0.1524)
				(type default)
			)
			(layer "F.SilkS")
		)
		(fp_line
			(start 0.508 -0.9398)
			(end -0.508 -0.9398)
			(stroke
				(width 0.1524)
				(type default)
			)
			(layer "F.SilkS")
		)
		(fp_rect
			(start -0.508 0.9398)
			(end 0.508 -0.9398)
			(stroke
				(width 0)
				(type default)
			)
			(fill no)
			(layer "F.CrtYd")
		)
		(fp_rect
			(start -0.508 0.9398)
			(end 0.508 -0.9398)
			(stroke
				(width 0)
				(type default)
			)
			(fill no)
			(layer "F.Fab")
		)
		(pad "1" smd custom
			(at 0 -0.4445)
			(size 0.1397 0.1397)
			(layers "F.Cu" "F.Mask" "F.Paste")
			(net "SYS_DBMODE4")
			(options
				(clearance outline)
				(anchor circle)
			)
			(primitives
				(gr_poly
					(pts
						(arc
							(start -0.1778 -0.2794)
							(mid -0.249642 -0.249642)
							(end -0.2794 -0.1778)
						)
						(arc
							(start -0.2794 0.1778)
							(mid -0.249642 0.249642)
							(end -0.1778 0.2794)
						)
						(arc
							(start 0.1778 0.2794)
							(mid 0.249642 0.249642)
							(end 0.2794 0.1778)
						)
						(arc
							(start 0.2794 -0.1778)
							(mid 0.249642 -0.249642)
							(end 0.1778 -0.2794)
						)
					)
					(width 0)
					(fill yes)
				)
			)
		)
		(pad "2" smd custom
			(at 0 0.4445)
			(size 0.1397 0.1397)
			(layers "F.Cu" "F.Mask" "F.Paste")
			(net "GND")
			(options
				(clearance outline)
				(anchor circle)
			)
			(primitives
				(gr_poly
					(pts
						(arc
							(start -0.1778 -0.2794)
							(mid -0.249642 -0.249642)
							(end -0.2794 -0.1778)
						)
						(arc
							(start -0.2794 0.1778)
							(mid -0.249642 0.249642)
							(end -0.1778 0.2794)
						)
						(arc
							(start 0.1778 0.2794)
							(mid 0.249642 0.249642)
							(end 0.2794 0.1778)
						)
						(arc
							(start 0.2794 -0.1778)
							(mid 0.249642 -0.249642)
							(end 0.1778 -0.2794)
						)
					)
					(width 0)
					(fill yes)
				)
			)
		)
	)
	(footprint ""
		(layer "F.Cu")
		(at 90.297 -231.775 180)
		(property "Reference" "R619"
			(at 0 0 180)
			(layer "F.SilkS")
			(hide yes)
			(effects
				(font
					(size 1.27 1.27)
				)
			)
		)
		(property "Value" "0R2J-2-GP"
			(at 0.064008 -3.993896 180)
			(unlocked yes)
			(layer "F.Fab")
			(hide yes)
			(effects
				(font
					(size 1.016 1.016)
					(thickness 0.1524)
				)
			)
		)
		(property "Device Type" "R402H16"
			(at 0.064008 -5.517896 180)
			(unlocked yes)
			(layer "F.Fab")
			(hide yes)
			(effects
				(font
					(size 1.016 1.016)
					(thickness 0.1524)
				)
			)
		)
		(duplicate_pad_numbers_are_jumpers no)
		(fp_line
			(start 0.508 -0.9398)
			(end -0.508 -0.9398)
			(stroke
				(width 0.1524)
				(type default)
			)
			(layer "F.SilkS")
		)
		(fp_line
			(start -0.508 -0.9398)
			(end -0.508 0.9398)
			(stroke
				(width 0.1524)
				(type default)
			)
			(layer "F.SilkS")
		)
		(fp_rect
			(start -0.508 0.9398)
			(end 0.508 -0.9398)
			(stroke
				(width 0)
				(type default)
			)
			(fill no)
			(layer "F.CrtYd")
		)
		(fp_rect
			(start -0.508 0.9398)
			(end 0.508 -0.9398)
			(stroke
				(width 0)
				(type default)
			)
			(fill no)
			(layer "F.Fab")
		)
		(pad "1" smd custom
			(at 0 -0.4445 180)
			(size 0.1397 0.1397)
			(layers "F.Cu" "F.Mask" "F.Paste")
			(net "SAS_FAULT_LED14")
			(options
				(clearance outline)
				(anchor circle)
			)
			(primitives
				(gr_poly
					(pts
						(arc
							(start -0.1778 -0.2794)
							(mid -0.249642 -0.249642)
							(end -0.2794 -0.1778)
						)
						(arc
							(start -0.2794 0.1778)
							(mid -0.249642 0.249642)
							(end -0.1778 0.2794)
						)
						(arc
							(start 0.1778 0.2794)
							(mid 0.249642 0.249642)
							(end 0.2794 0.1778)
						)
						(arc
							(start 0.2794 -0.1778)
							(mid 0.249642 -0.249642)
							(end 0.1778 -0.2794)
						)
					)
					(width 0)
					(fill yes)
				)
			)
		)
		(pad "2" smd custom
			(at 0 0.4445 180)
			(size 0.1397 0.1397)
			(layers "F.Cu" "F.Mask" "F.Paste")
			(net "SAS_HDD_LED_14")
			(options
				(clearance outline)
				(anchor circle)
			)
			(primitives
				(gr_poly
					(pts
						(arc
							(start -0.1778 -0.2794)
							(mid -0.249642 -0.249642)
							(end -0.2794 -0.1778)
						)
						(arc
							(start -0.2794 0.1778)
							(mid -0.249642 0.249642)
							(end -0.1778 0.2794)
						)
						(arc
							(start 0.1778 0.2794)
							(mid 0.249642 0.249642)
							(end 0.2794 0.1778)
						)
						(arc
							(start 0.2794 -0.1778)
							(mid 0.249642 -0.249642)
							(end 0.1778 -0.2794)
						)
					)
					(width 0)
					(fill yes)
				)
			)
		)
	)
	(footprint ""
		(layer "F.Cu")
		(at 139.446 -38.862)
		(property "Reference" "SR702"
			(at 0 0 0)
			(layer "F.SilkS")
			(hide yes)
			(effects
				(font
					(size 1.27 1.27)
				)
			)
		)
		(property "Value" "10KR2F-2-GP"
			(at 0.064008 -3.993896 0)
			(unlocked yes)
			(layer "F.Fab")
			(hide yes)
			(effects
				(font
					(size 1.016 1.016)
					(thickness 0.1524)
				)
			)
		)
		(property "Device Type" "R402H16"
			(at 0.064008 -5.517896 0)
			(unlocked yes)
			(layer "F.Fab")
			(hide yes)
			(effects
				(font
					(size 1.016 1.016)
					(thickness 0.1524)
				)
			)
		)
		(duplicate_pad_numbers_are_jumpers no)
		(fp_line
			(start -0.508 -0.9398)
			(end -0.508 0.9398)
			(stroke
				(width 0.1524)
				(type default)
			)
			(layer "F.SilkS")
		)
		(fp_line
			(start 0.508 -0.9398)
			(end -0.508 -0.9398)
			(stroke
				(width 0.1524)
				(type default)
			)
			(layer "F.SilkS")
		)
		(fp_rect
			(start -0.508 0.9398)
			(end 0.508 -0.9398)
			(stroke
				(width 0)
				(type default)
			)
			(fill no)
			(layer "F.CrtYd")
		)
		(fp_rect
			(start -0.508 0.9398)
			(end 0.508 -0.9398)
			(stroke
				(width 0)
				(type default)
			)
			(fill no)
			(layer "F.Fab")
		)
		(pad "1" smd custom
			(at 0 -0.4445)
			(size 0.1397 0.1397)
			(layers "F.Cu" "F.Mask" "F.Paste")
			(net "XM_ADDR_11")
			(options
				(clearance outline)
				(anchor circle)
			)
			(primitives
				(gr_poly
					(pts
						(arc
							(start -0.1778 -0.2794)
							(mid -0.249642 -0.249642)
							(end -0.2794 -0.1778)
						)
						(arc
							(start -0.2794 0.1778)
							(mid -0.249642 0.249642)
							(end -0.1778 0.2794)
						)
						(arc
							(start 0.1778 0.2794)
							(mid 0.249642 0.249642)
							(end 0.2794 0.1778)
						)
						(arc
							(start 0.2794 -0.1778)
							(mid 0.249642 -0.249642)
							(end 0.1778 -0.2794)
						)
					)
					(width 0)
					(fill yes)
				)
			)
		)
		(pad "2" smd custom
			(at 0 0.4445)
			(size 0.1397 0.1397)
			(layers "F.Cu" "F.Mask" "F.Paste")
			(net "GND")
			(options
				(clearance outline)
				(anchor circle)
			)
			(primitives
				(gr_poly
					(pts
						(arc
							(start -0.1778 -0.2794)
							(mid -0.249642 -0.249642)
							(end -0.2794 -0.1778)
						)
						(arc
							(start -0.2794 0.1778)
							(mid -0.249642 0.249642)
							(end -0.1778 0.2794)
						)
						(arc
							(start 0.1778 0.2794)
							(mid 0.249642 0.249642)
							(end 0.2794 0.1778)
						)
						(arc
							(start 0.2794 -0.1778)
							(mid 0.249642 -0.249642)
							(end 0.1778 -0.2794)
						)
					)
					(width 0)
					(fill yes)
				)
			)
		)
	)
	(footprint ""
		(layer "F.Cu")
		(at 345.567 -26.924 -90)
		(property "Reference" "R454"
			(at 0 0 270)
			(layer "F.SilkS")
			(hide yes)
			(effects
				(font
					(size 1.27 1.27)
				)
			)
		)
		(property "Value" "0R2J-2-GP"
			(at 0.064008 -3.993896 270)
			(unlocked yes)
			(layer "F.Fab")
			(hide yes)
			(effects
				(font
					(size 1.016 1.016)
					(thickness 0.1524)
				)
			)
		)
		(property "Device Type" "R402H16"
			(at 0.064008 -5.517896 270)
			(unlocked yes)
			(layer "F.Fab")
			(hide yes)
			(effects
				(font
					(size 1.016 1.016)
					(thickness 0.1524)
				)
			)
		)
		(duplicate_pad_numbers_are_jumpers no)
		(fp_line
			(start -0.508 -0.9398)
			(end -0.508 0.9398)
			(stroke
				(width 0.1524)
				(type default)
			)
			(layer "F.SilkS")
		)
		(fp_line
			(start 0.508 -0.9398)
			(end -0.508 -0.9398)
			(stroke
				(width 0.1524)
				(type default)
			)
			(layer "F.SilkS")
		)
		(fp_rect
			(start -0.508 0.9398)
			(end 0.508 -0.9398)
			(stroke
				(width 0)
				(type default)
			)
			(fill no)
			(layer "F.CrtYd")
		)
		(fp_rect
			(start -0.508 0.9398)
			(end 0.508 -0.9398)
			(stroke
				(width 0)
				(type default)
			)
			(fill no)
			(layer "F.Fab")
		)
		(pad "1" smd custom
			(at 0 -0.4445 270)
			(size 0.1397 0.1397)
			(layers "F.Cu" "F.Mask" "F.Paste")
			(net "BMC_UART_SWITCH_1")
			(options
				(clearance outline)
				(anchor circle)
			)
			(primitives
				(gr_poly
					(pts
						(arc
							(start -0.1778 -0.2794)
							(mid -0.249642 -0.249642)
							(end -0.2794 -0.1778)
						)
						(arc
							(start -0.2794 0.1778)
							(mid -0.249642 0.249642)
							(end -0.1778 0.2794)
						)
						(arc
							(start 0.1778 0.2794)
							(mid 0.249642 0.249642)
							(end 0.2794 0.1778)
						)
						(arc
							(start 0.2794 -0.1778)
							(mid 0.249642 -0.249642)
							(end 0.1778 -0.2794)
						)
					)
					(width 0)
					(fill yes)
				)
			)
		)
		(pad "2" smd custom
			(at 0 0.4445 270)
			(size 0.1397 0.1397)
			(layers "F.Cu" "F.Mask" "F.Paste")
			(net "BMC_CONSOLE_LED0_R")
			(options
				(clearance outline)
				(anchor circle)
			)
			(primitives
				(gr_poly
					(pts
						(arc
							(start -0.1778 -0.2794)
							(mid -0.249642 -0.249642)
							(end -0.2794 -0.1778)
						)
						(arc
							(start -0.2794 0.1778)
							(mid -0.249642 0.249642)
							(end -0.1778 0.2794)
						)
						(arc
							(start 0.1778 0.2794)
							(mid 0.249642 0.249642)
							(end 0.2794 0.1778)
						)
						(arc
							(start 0.2794 -0.1778)
							(mid 0.249642 -0.249642)
							(end 0.1778 -0.2794)
						)
					)
					(width 0)
					(fill yes)
				)
			)
		)
	)
	(footprint ""
		(layer "F.Cu")
		(at 86.67877 -114.25936 90)
		(property "Reference" "SC1107"
			(at 0 0 90)
			(layer "F.SilkS")
			(hide yes)
			(effects
				(font
					(size 1.27 1.27)
				)
			)
		)
		(property "Value" "SCD1U16V2KX-3GP"
			(at 1.1811 -2.7051 90)
			(unlocked yes)
			(layer "F.Fab")
			(hide yes)
			(effects
				(font
					(size 1.016 1.016)
					(thickness 0.1524)
				)
			)
		)
		(property "Device Type" "C402H22"
			(at 1.1811 -4.2291 90)
			(unlocked yes)
			(layer "F.Fab")
			(hide yes)
			(effects
				(font
					(size 1.016 1.016)
					(thickness 0.1524)
				)
			)
		)
		(duplicate_pad_numbers_are_jumpers no)
		(fp_rect
			(start -0.4318 0.9525)
			(end 0.4318 -0.9525)
			(stroke
				(width 0)
				(type default)
			)
			(fill no)
			(layer "F.CrtYd")
		)
		(fp_rect
			(start -0.4318 0.9525)
			(end 0.4318 -0.9525)
			(stroke
				(width 0)
				(type default)
			)
			(fill no)
			(layer "F.Fab")
		)
		(pad "1" smd custom
			(at 0 -0.4445 90)
			(size 0.1524 0.1524)
			(layers "F.Cu" "F.Mask" "F.Paste")
			(net "P1V8_E")
			(options
				(clearance outline)
				(anchor circle)
			)
			(primitives
				(gr_poly
					(pts
						(arc
							(start 0.3048 -0.2032)
							(mid 0.275042 -0.275042)
							(end 0.2032 -0.3048)
						)
						(arc
							(start -0.2032 -0.3048)
							(mid -0.275042 -0.275042)
							(end -0.3048 -0.2032)
						)
						(arc
							(start -0.3048 0.2032)
							(mid -0.275042 0.275042)
							(end -0.2032 0.3048)
						)
						(arc
							(start 0.2032 0.3048)
							(mid 0.275042 0.275042)
							(end 0.3048 0.2032)
						)
					)
					(width 0)
					(fill yes)
				)
			)
		)
		(pad "2" smd custom
			(at 0 0.4445 90)
			(size 0.1524 0.1524)
			(layers "F.Cu" "F.Mask" "F.Paste")
			(net "GND")
			(options
				(clearance outline)
				(anchor circle)
			)
			(primitives
				(gr_poly
					(pts
						(arc
							(start 0.3048 -0.2032)
							(mid 0.275042 -0.275042)
							(end 0.2032 -0.3048)
						)
						(arc
							(start -0.2032 -0.3048)
							(mid -0.275042 -0.275042)
							(end -0.3048 -0.2032)
						)
						(arc
							(start -0.3048 0.2032)
							(mid -0.275042 0.275042)
							(end -0.2032 0.3048)
						)
						(arc
							(start 0.2032 0.3048)
							(mid 0.275042 0.275042)
							(end 0.3048 0.2032)
						)
					)
					(width 0)
					(fill yes)
				)
			)
		)
	)
	(footprint ""
		(layer "F.Cu")
		(at 116.713 -28.321 180)
		(property "Reference" "SR671"
			(at 0 0 180)
			(layer "F.SilkS")
			(hide yes)
			(effects
				(font
					(size 1.27 1.27)
				)
			)
		)
		(property "Value" "4K7R2F-GP"
			(at 0.064008 -3.993896 180)
			(unlocked yes)
			(layer "F.Fab")
			(hide yes)
			(effects
				(font
					(size 1.016 1.016)
					(thickness 0.1524)
				)
			)
		)
		(property "Device Type" "R402H16"
			(at 0.064008 -5.517896 180)
			(unlocked yes)
			(layer "F.Fab")
			(hide yes)
			(effects
				(font
					(size 1.016 1.016)
					(thickness 0.1524)
				)
			)
		)
		(duplicate_pad_numbers_are_jumpers no)
		(fp_line
			(start 0.508 -0.9398)
			(end -0.508 -0.9398)
			(stroke
				(width 0.1524)
				(type default)
			)
			(layer "F.SilkS")
		)
		(fp_line
			(start -0.508 -0.9398)
			(end -0.508 0.9398)
			(stroke
				(width 0.1524)
				(type default)
			)
			(layer "F.SilkS")
		)
		(fp_rect
			(start -0.508 0.9398)
			(end 0.508 -0.9398)
			(stroke
				(width 0)
				(type default)
			)
			(fill no)
			(layer "F.CrtYd")
		)
		(fp_rect
			(start -0.508 0.9398)
			(end 0.508 -0.9398)
			(stroke
				(width 0)
				(type default)
			)
			(fill no)
			(layer "F.Fab")
		)
		(pad "1" smd custom
			(at 0 -0.4445 180)
			(size 0.1397 0.1397)
			(layers "F.Cu" "F.Mask" "F.Paste")
			(net "P1V8_C")
			(options
				(clearance outline)
				(anchor circle)
			)
			(primitives
				(gr_poly
					(pts
						(arc
							(start -0.1778 -0.2794)
							(mid -0.249642 -0.249642)
							(end -0.2794 -0.1778)
						)
						(arc
							(start -0.2794 0.1778)
							(mid -0.249642 0.249642)
							(end -0.1778 0.2794)
						)
						(arc
							(start 0.1778 0.2794)
							(mid 0.249642 0.249642)
							(end 0.2794 0.1778)
						)
						(arc
							(start 0.2794 -0.1778)
							(mid 0.249642 -0.249642)
							(end 0.1778 -0.2794)
						)
					)
					(width 0)
					(fill yes)
				)
			)
		)
		(pad "2" smd custom
			(at 0 0.4445 180)
			(size 0.1397 0.1397)
			(layers "F.Cu" "F.Mask" "F.Paste")
			(net "SYS_HALT1#")
			(options
				(clearance outline)
				(anchor circle)
			)
			(primitives
				(gr_poly
					(pts
						(arc
							(start -0.1778 -0.2794)
							(mid -0.249642 -0.249642)
							(end -0.2794 -0.1778)
						)
						(arc
							(start -0.2794 0.1778)
							(mid -0.249642 0.249642)
							(end -0.1778 0.2794)
						)
						(arc
							(start 0.1778 0.2794)
							(mid 0.249642 0.249642)
							(end 0.2794 0.1778)
						)
						(arc
							(start 0.2794 -0.1778)
							(mid 0.249642 -0.249642)
							(end 0.1778 -0.2794)
						)
					)
					(width 0)
					(fill yes)
				)
			)
		)
	)
	(footprint ""
		(layer "F.Cu")
		(at 103.105966 -62.3316 90)
		(property "Reference" "SC918"
			(at 0 0 90)
			(layer "F.SilkS")
			(hide yes)
			(effects
				(font
					(size 1.27 1.27)
				)
			)
		)
		(property "Value" "SCD1U6D3V1KX-GP"
			(at -2.8321 -1.7399 90)
			(unlocked yes)
			(layer "F.Fab")
			(hide yes)
			(effects
				(font
					(size 1.016 1.016)
					(thickness 0.1524)
				)
			)
		)
		(property "Device Type" "C0201H13"
			(at -2.8321 -3.2639 90)
			(unlocked yes)
			(layer "F.Fab")
			(hide yes)
			(effects
				(font
					(size 1.016 1.016)
					(thickness 0.1524)
				)
			)
		)
		(duplicate_pad_numbers_are_jumpers no)
		(fp_rect
			(start -0.2794 0.6477)
			(end 0.2794 -0.6477)
			(stroke
				(width 0)
				(type default)
			)
			(fill no)
			(layer "F.CrtYd")
		)
		(fp_rect
			(start -0.2794 0.6477)
			(end 0.2794 -0.6477)
			(stroke
				(width 0)
				(type default)
			)
			(fill no)
			(layer "F.Fab")
		)
		(pad "1" smd custom
			(at 0 -0.2794 90)
			(size 0.0762 0.0762)
			(layers "F.Cu" "F.Mask" "F.Paste")
			(net "HM40ADC_VDDA")
			(options
				(clearance outline)
				(anchor circle)
			)
			(primitives
				(gr_poly
					(pts
						(arc
							(start 0.1524 -0.127)
							(mid 0.137521 -0.162921)
							(end 0.1016 -0.1778)
						)
						(arc
							(start -0.1016 -0.1778)
							(mid -0.137521 -0.162921)
							(end -0.1524 -0.127)
						)
						(arc
							(start -0.1524 0.127)
							(mid -0.137521 0.162921)
							(end -0.1016 0.1778)
						)
						(arc
							(start 0.1016 0.1778)
							(mid 0.137521 0.162921)
							(end 0.1524 0.127)
						)
					)
					(width 0)
					(fill yes)
				)
			)
		)
		(pad "2" smd custom
			(at 0 0.2794 90)
			(size 0.0762 0.0762)
			(layers "F.Cu" "F.Mask" "F.Paste")
			(net "GND")
			(options
				(clearance outline)
				(anchor circle)
			)
			(primitives
				(gr_poly
					(pts
						(arc
							(start 0.1524 -0.127)
							(mid 0.137521 -0.162921)
							(end 0.1016 -0.1778)
						)
						(arc
							(start -0.1016 -0.1778)
							(mid -0.137521 -0.162921)
							(end -0.1524 -0.127)
						)
						(arc
							(start -0.1524 0.127)
							(mid -0.137521 0.162921)
							(end -0.1016 0.1778)
						)
						(arc
							(start 0.1016 0.1778)
							(mid 0.137521 0.162921)
							(end 0.1524 0.127)
						)
					)
					(width 0)
					(fill yes)
				)
			)
		)
	)
	(footprint ""
		(layer "F.Cu")
		(at 80.772 -33.401)
		(property "Reference" "SC957"
			(at 0 0 0)
			(layer "F.SilkS")
			(hide yes)
			(effects
				(font
					(size 1.27 1.27)
				)
			)
		)
		(property "Value" "SC100U6D3V0MX-2GP"
			(at -0.00254 -4.78536 0)
			(unlocked yes)
			(layer "F.Fab")
			(hide yes)
			(effects
				(font
					(size 1.016 1.016)
					(thickness 0.1524)
				)
			)
		)
		(property "Device Type" "C1210H107"
			(at -0.00254 -6.38048 0)
			(unlocked yes)
			(layer "F.Fab")
			(hide yes)
			(effects
				(font
					(size 1.016 1.016)
					(thickness 0.1524)
				)
			)
		)
		(duplicate_pad_numbers_are_jumpers no)
		(fp_line
			(start -1.5748 -2.3368)
			(end -1.5748 -0.762)
			(stroke
				(width 0.1524)
				(type default)
			)
			(layer "F.SilkS")
		)
		(fp_line
			(start -1.5748 0.762)
			(end -1.5748 2.3368)
			(stroke
				(width 0.1524)
				(type default)
			)
			(layer "F.SilkS")
		)
		(fp_line
			(start -1.5748 2.3368)
			(end 1.5748 2.3368)
			(stroke
				(width 0.1524)
				(type default)
			)
			(layer "F.SilkS")
		)
		(fp_line
			(start 1.5748 -2.3368)
			(end -1.5748 -2.3368)
			(stroke
				(width 0.1524)
				(type default)
			)
			(layer "F.SilkS")
		)
		(fp_line
			(start 1.5748 -0.762)
			(end 1.5748 -2.3368)
			(stroke
				(width 0.1524)
				(type default)
			)
			(layer "F.SilkS")
		)
		(fp_line
			(start 1.5748 2.3368)
			(end 1.5748 0.762)
			(stroke
				(width 0.1524)
				(type default)
			)
			(layer "F.SilkS")
		)
		(fp_rect
			(start -1.651 2.413)
			(end 1.651 -2.413)
			(stroke
				(width 0)
				(type default)
			)
			(fill no)
			(layer "F.CrtYd")
		)
		(fp_poly
			(pts
				(xy 1.651 2.413) (xy 1.651 -2.413) (xy -1.651 -2.413) (xy -1.651 2.413)
			)
			(stroke
				(width 0)
				(type default)
			)
			(fill no)
			(layer "F.Fab")
		)
		(pad "1" smd rect
			(at 0 -1.4732)
			(size 2.794 1.397)
			(layers "F.Cu" "F.Mask" "F.Paste")
			(net "GND")
		)
		(pad "2" smd rect
			(at 0 1.4732)
			(size 2.794 1.397)
			(layers "F.Cu" "F.Mask" "F.Paste")
			(net "SAS0_AVDD")
		)
	)
	(footprint ""
		(layer "F.Cu")
		(at 274.193 -180.721 90)
		(property "Reference" "R347"
			(at 0 0 90)
			(layer "F.SilkS")
			(hide yes)
			(effects
				(font
					(size 1.27 1.27)
				)
			)
		)
		(property "Value" "3K3R2F-2-GP"
			(at 0.064008 -3.993896 90)
			(unlocked yes)
			(layer "F.Fab")
			(hide yes)
			(effects
				(font
					(size 1.016 1.016)
					(thickness 0.1524)
				)
			)
		)
		(property "Device Type" "R402H16"
			(at 0.064008 -5.517896 90)
			(unlocked yes)
			(layer "F.Fab")
			(hide yes)
			(effects
				(font
					(size 1.016 1.016)
					(thickness 0.1524)
				)
			)
		)
		(duplicate_pad_numbers_are_jumpers no)
		(fp_line
			(start 0.508 -0.9398)
			(end -0.508 -0.9398)
			(stroke
				(width 0.1524)
				(type default)
			)
			(layer "F.SilkS")
		)
		(fp_line
			(start -0.508 -0.9398)
			(end -0.508 0.9398)
			(stroke
				(width 0.1524)
				(type default)
			)
			(layer "F.SilkS")
		)
		(fp_rect
			(start -0.508 0.9398)
			(end 0.508 -0.9398)
			(stroke
				(width 0)
				(type default)
			)
			(fill no)
			(layer "F.CrtYd")
		)
		(fp_rect
			(start -0.508 0.9398)
			(end 0.508 -0.9398)
			(stroke
				(width 0)
				(type default)
			)
			(fill no)
			(layer "F.Fab")
		)
		(pad "1" smd custom
			(at 0 -0.4445 90)
			(size 0.1397 0.1397)
			(layers "F.Cu" "F.Mask" "F.Paste")
			(net "P3V3_STBY")
			(options
				(clearance outline)
				(anchor circle)
			)
			(primitives
				(gr_poly
					(pts
						(arc
							(start -0.1778 -0.2794)
							(mid -0.249642 -0.249642)
							(end -0.2794 -0.1778)
						)
						(arc
							(start -0.2794 0.1778)
							(mid -0.249642 0.249642)
							(end -0.1778 0.2794)
						)
						(arc
							(start 0.1778 0.2794)
							(mid 0.249642 0.249642)
							(end 0.2794 0.1778)
						)
						(arc
							(start 0.2794 -0.1778)
							(mid 0.249642 -0.249642)
							(end 0.1778 -0.2794)
						)
					)
					(width 0)
					(fill yes)
				)
			)
		)
		(pad "2" smd custom
			(at 0 0.4445 90)
			(size 0.1397 0.1397)
			(layers "F.Cu" "F.Mask" "F.Paste")
			(net "ROMA2")
			(options
				(clearance outline)
				(anchor circle)
			)
			(primitives
				(gr_poly
					(pts
						(arc
							(start -0.1778 -0.2794)
							(mid -0.249642 -0.249642)
							(end -0.2794 -0.1778)
						)
						(arc
							(start -0.2794 0.1778)
							(mid -0.249642 0.249642)
							(end -0.1778 0.2794)
						)
						(arc
							(start 0.1778 0.2794)
							(mid 0.249642 0.249642)
							(end 0.2794 0.1778)
						)
						(arc
							(start 0.2794 -0.1778)
							(mid 0.249642 -0.249642)
							(end 0.1778 -0.2794)
						)
					)
					(width 0)
					(fill yes)
				)
			)
		)
	)
	(footprint ""
		(layer "F.Cu")
		(at 262.001 -32.639 90)
		(property "Reference" "PR38"
			(at 0 0 90)
			(layer "F.SilkS")
			(hide yes)
			(effects
				(font
					(size 1.27 1.27)
				)
			)
		)
		(property "Value" "1K4R2F-1-GP"
			(at 0.064008 -3.993896 90)
			(unlocked yes)
			(layer "F.Fab")
			(hide yes)
			(effects
				(font
					(size 1.016 1.016)
					(thickness 0.1524)
				)
			)
		)
		(property "Device Type" "R402H16"
			(at 0.064008 -5.517896 90)
			(unlocked yes)
			(layer "F.Fab")
			(hide yes)
			(effects
				(font
					(size 1.016 1.016)
					(thickness 0.1524)
				)
			)
		)
		(duplicate_pad_numbers_are_jumpers no)
		(fp_line
			(start 0.508 -0.9398)
			(end -0.508 -0.9398)
			(stroke
				(width 0.1524)
				(type default)
			)
			(layer "F.SilkS")
		)
		(fp_line
			(start -0.508 -0.9398)
			(end -0.508 0.9398)
			(stroke
				(width 0.1524)
				(type default)
			)
			(layer "F.SilkS")
		)
		(fp_rect
			(start -0.508 0.9398)
			(end 0.508 -0.9398)
			(stroke
				(width 0)
				(type default)
			)
			(fill no)
			(layer "F.CrtYd")
		)
		(fp_rect
			(start -0.508 0.9398)
			(end 0.508 -0.9398)
			(stroke
				(width 0)
				(type default)
			)
			(fill no)
			(layer "F.Fab")
		)
		(pad "1" smd custom
			(at 0 -0.4445 90)
			(size 0.1397 0.1397)
			(layers "F.Cu" "F.Mask" "F.Paste")
			(net "P5V_STBY")
			(options
				(clearance outline)
				(anchor circle)
			)
			(primitives
				(gr_poly
					(pts
						(arc
							(start -0.1778 -0.2794)
							(mid -0.249642 -0.249642)
							(end -0.2794 -0.1778)
						)
						(arc
							(start -0.2794 0.1778)
							(mid -0.249642 0.249642)
							(end -0.1778 0.2794)
						)
						(arc
							(start 0.1778 0.2794)
							(mid 0.249642 0.249642)
							(end 0.2794 0.1778)
						)
						(arc
							(start 0.2794 -0.1778)
							(mid 0.249642 -0.249642)
							(end 0.1778 -0.2794)
						)
					)
					(width 0)
					(fill yes)
				)
			)
		)
		(pad "2" smd custom
			(at 0 0.4445 90)
			(size 0.1397 0.1397)
			(layers "F.Cu" "F.Mask" "F.Paste")
			(net "P1V8_STBY_EN")
			(options
				(clearance outline)
				(anchor circle)
			)
			(primitives
				(gr_poly
					(pts
						(arc
							(start -0.1778 -0.2794)
							(mid -0.249642 -0.249642)
							(end -0.2794 -0.1778)
						)
						(arc
							(start -0.2794 0.1778)
							(mid -0.249642 0.249642)
							(end -0.1778 0.2794)
						)
						(arc
							(start 0.1778 0.2794)
							(mid 0.249642 0.249642)
							(end 0.2794 0.1778)
						)
						(arc
							(start 0.2794 -0.1778)
							(mid 0.249642 -0.249642)
							(end 0.1778 -0.2794)
						)
					)
					(width 0)
					(fill yes)
				)
			)
		)
	)
	(footprint ""
		(layer "F.Cu")
		(at 97.54997 -79.121)
		(property "Reference" "STP150"
			(at 0 0 0)
			(layer "F.SilkS")
			(hide yes)
			(effects
				(font
					(size 1.27 1.27)
				)
			)
		)
		(property "Value" "TPAD28"
			(at 0.0127 -1.8034 0)
			(unlocked yes)
			(layer "F.Fab")
			(hide yes)
			(effects
				(font
					(size 1.016 1.016)
					(thickness 0.1524)
				)
			)
		)
		(property "Device Type" "TPAD28"
			(at 0.0127 -3.3274 0)
			(unlocked yes)
			(layer "F.Fab")
			(hide yes)
			(effects
				(font
					(size 1.016 1.016)
					(thickness 0.1524)
				)
			)
		)
		(duplicate_pad_numbers_are_jumpers no)
		(fp_poly
			(pts
				(arc
					(start 0.3556 0)
					(mid -0.3556 0)
					(end 0.3556 0)
				)
			)
			(stroke
				(width 0)
				(type default)
			)
			(fill no)
			(layer "F.CrtYd")
		)
		(fp_poly
			(pts
				(arc
					(start 0.6096 0)
					(mid -0.6096 0)
					(end 0.6096 0)
				)
			)
			(stroke
				(width 0)
				(type default)
			)
			(fill no)
			(layer "F.Fab")
		)
		(pad "1" smd circle
			(at 0 0)
			(size 0.7112 0.7112)
			(layers "F.Cu" "F.Mask" "F.Paste")
			(net "JTAG_EXP_TCK")
		)
	)
	(footprint ""
		(layer "F.Cu")
		(at 316.611 -114.681 90)
		(property "Reference" "PR35"
			(at 0 0 90)
			(layer "F.SilkS")
			(hide yes)
			(effects
				(font
					(size 1.27 1.27)
				)
			)
		)
		(property "Value" "619KR2F-GP"
			(at 0.064008 -3.993896 90)
			(unlocked yes)
			(layer "F.Fab")
			(hide yes)
			(effects
				(font
					(size 1.016 1.016)
					(thickness 0.1524)
				)
			)
		)
		(property "Device Type" "R402H16"
			(at 0.064008 -5.517896 90)
			(unlocked yes)
			(layer "F.Fab")
			(hide yes)
			(effects
				(font
					(size 1.016 1.016)
					(thickness 0.1524)
				)
			)
		)
		(duplicate_pad_numbers_are_jumpers no)
		(fp_line
			(start 0.508 -0.9398)
			(end -0.508 -0.9398)
			(stroke
				(width 0.1524)
				(type default)
			)
			(layer "F.SilkS")
		)
		(fp_line
			(start -0.508 -0.9398)
			(end -0.508 0.9398)
			(stroke
				(width 0.1524)
				(type default)
			)
			(layer "F.SilkS")
		)
		(fp_rect
			(start -0.508 0.9398)
			(end 0.508 -0.9398)
			(stroke
				(width 0)
				(type default)
			)
			(fill no)
			(layer "F.CrtYd")
		)
		(fp_rect
			(start -0.508 0.9398)
			(end 0.508 -0.9398)
			(stroke
				(width 0)
				(type default)
			)
			(fill no)
			(layer "F.Fab")
		)
		(pad "1" smd custom
			(at 0 -0.4445 90)
			(size 0.1397 0.1397)
			(layers "F.Cu" "F.Mask" "F.Paste")
			(net "AGND_P3V3_STBY")
			(options
				(clearance outline)
				(anchor circle)
			)
			(primitives
				(gr_poly
					(pts
						(arc
							(start -0.1778 -0.2794)
							(mid -0.249642 -0.249642)
							(end -0.2794 -0.1778)
						)
						(arc
							(start -0.2794 0.1778)
							(mid -0.249642 0.249642)
							(end -0.1778 0.2794)
						)
						(arc
							(start 0.1778 0.2794)
							(mid 0.249642 0.249642)
							(end 0.2794 0.1778)
						)
						(arc
							(start 0.2794 -0.1778)
							(mid 0.249642 -0.249642)
							(end 0.1778 -0.2794)
						)
					)
					(width 0)
					(fill yes)
				)
			)
		)
		(pad "2" smd custom
			(at 0 0.4445 90)
			(size 0.1397 0.1397)
			(layers "F.Cu" "F.Mask" "F.Paste")
			(net "P3V3_STBY_RF")
			(options
				(clearance outline)
				(anchor circle)
			)
			(primitives
				(gr_poly
					(pts
						(arc
							(start -0.1778 -0.2794)
							(mid -0.249642 -0.249642)
							(end -0.2794 -0.1778)
						)
						(arc
							(start -0.2794 0.1778)
							(mid -0.249642 0.249642)
							(end -0.1778 0.2794)
						)
						(arc
							(start 0.1778 0.2794)
							(mid 0.249642 0.249642)
							(end 0.2794 0.1778)
						)
						(arc
							(start 0.2794 -0.1778)
							(mid 0.249642 -0.249642)
							(end 0.1778 -0.2794)
						)
					)
					(width 0)
					(fill yes)
				)
			)
		)
	)
	(footprint ""
		(layer "F.Cu")
		(at 319.913 -146.558 90)
		(property "Reference" "R655"
			(at 0 0 90)
			(layer "F.SilkS")
			(hide yes)
			(effects
				(font
					(size 1.27 1.27)
				)
			)
		)
		(property "Value" "4K7R2F-GP"
			(at 0.064008 -3.993896 90)
			(unlocked yes)
			(layer "F.Fab")
			(hide yes)
			(effects
				(font
					(size 1.016 1.016)
					(thickness 0.1524)
				)
			)
		)
		(property "Device Type" "R402H16"
			(at 0.064008 -5.517896 90)
			(unlocked yes)
			(layer "F.Fab")
			(hide yes)
			(effects
				(font
					(size 1.016 1.016)
					(thickness 0.1524)
				)
			)
		)
		(duplicate_pad_numbers_are_jumpers no)
		(fp_line
			(start 0.508 -0.9398)
			(end -0.508 -0.9398)
			(stroke
				(width 0.1524)
				(type default)
			)
			(layer "F.SilkS")
		)
		(fp_line
			(start -0.508 -0.9398)
			(end -0.508 0.9398)
			(stroke
				(width 0.1524)
				(type default)
			)
			(layer "F.SilkS")
		)
		(fp_rect
			(start -0.508 0.9398)
			(end 0.508 -0.9398)
			(stroke
				(width 0)
				(type default)
			)
			(fill no)
			(layer "F.CrtYd")
		)
		(fp_rect
			(start -0.508 0.9398)
			(end 0.508 -0.9398)
			(stroke
				(width 0)
				(type default)
			)
			(fill no)
			(layer "F.Fab")
		)
		(pad "1" smd custom
			(at 0 -0.4445 90)
			(size 0.1397 0.1397)
			(layers "F.Cu" "F.Mask" "F.Paste")
			(net "P3V3_RTC")
			(options
				(clearance outline)
				(anchor circle)
			)
			(primitives
				(gr_poly
					(pts
						(arc
							(start -0.1778 -0.2794)
							(mid -0.249642 -0.249642)
							(end -0.2794 -0.1778)
						)
						(arc
							(start -0.2794 0.1778)
							(mid -0.249642 0.249642)
							(end -0.1778 0.2794)
						)
						(arc
							(start 0.1778 0.2794)
							(mid 0.249642 0.249642)
							(end 0.2794 0.1778)
						)
						(arc
							(start 0.2794 -0.1778)
							(mid 0.249642 -0.249642)
							(end 0.1778 -0.2794)
						)
					)
					(width 0)
					(fill yes)
				)
			)
		)
		(pad "2" smd custom
			(at 0 0.4445 90)
			(size 0.1397 0.1397)
			(layers "F.Cu" "F.Mask" "F.Paste")
			(net "RTC_INT_N")
			(options
				(clearance outline)
				(anchor circle)
			)
			(primitives
				(gr_poly
					(pts
						(arc
							(start -0.1778 -0.2794)
							(mid -0.249642 -0.249642)
							(end -0.2794 -0.1778)
						)
						(arc
							(start -0.2794 0.1778)
							(mid -0.249642 0.249642)
							(end -0.1778 0.2794)
						)
						(arc
							(start 0.1778 0.2794)
							(mid 0.249642 0.249642)
							(end 0.2794 0.1778)
						)
						(arc
							(start 0.2794 -0.1778)
							(mid 0.249642 -0.249642)
							(end 0.1778 -0.2794)
						)
					)
					(width 0)
					(fill yes)
				)
			)
		)
	)
	(footprint ""
		(layer "F.Cu")
		(at 68.834 -224.663 -90)
		(property "Reference" "R2115"
			(at 0 0 270)
			(layer "F.SilkS")
			(hide yes)
			(effects
				(font
					(size 1.27 1.27)
				)
			)
		)
		(property "Value" "0R2J-2-GP"
			(at 0.064008 -3.993896 270)
			(unlocked yes)
			(layer "F.Fab")
			(hide yes)
			(effects
				(font
					(size 1.016 1.016)
					(thickness 0.1524)
				)
			)
		)
		(property "Device Type" "R402H16"
			(at 0.064008 -5.517896 270)
			(unlocked yes)
			(layer "F.Fab")
			(hide yes)
			(effects
				(font
					(size 1.016 1.016)
					(thickness 0.1524)
				)
			)
		)
		(duplicate_pad_numbers_are_jumpers no)
		(fp_line
			(start -0.508 -0.9398)
			(end -0.508 0.9398)
			(stroke
				(width 0.1524)
				(type default)
			)
			(layer "F.SilkS")
		)
		(fp_line
			(start 0.508 -0.9398)
			(end -0.508 -0.9398)
			(stroke
				(width 0.1524)
				(type default)
			)
			(layer "F.SilkS")
		)
		(fp_rect
			(start -0.508 0.9398)
			(end 0.508 -0.9398)
			(stroke
				(width 0)
				(type default)
			)
			(fill no)
			(layer "F.CrtYd")
		)
		(fp_rect
			(start -0.508 0.9398)
			(end 0.508 -0.9398)
			(stroke
				(width 0)
				(type default)
			)
			(fill no)
			(layer "F.Fab")
		)
		(pad "1" smd custom
			(at 0 -0.4445 270)
			(size 0.1397 0.1397)
			(layers "F.Cu" "F.Mask" "F.Paste")
			(net "MB0_P12V_R")
			(options
				(clearance outline)
				(anchor circle)
			)
			(primitives
				(gr_poly
					(pts
						(arc
							(start -0.1778 -0.2794)
							(mid -0.249642 -0.249642)
							(end -0.2794 -0.1778)
						)
						(arc
							(start -0.2794 0.1778)
							(mid -0.249642 0.249642)
							(end -0.1778 0.2794)
						)
						(arc
							(start 0.1778 0.2794)
							(mid 0.249642 0.249642)
							(end 0.2794 0.1778)
						)
						(arc
							(start 0.2794 -0.1778)
							(mid 0.249642 -0.249642)
							(end 0.1778 -0.2794)
						)
					)
					(width 0)
					(fill yes)
				)
			)
		)
		(pad "2" smd custom
			(at 0 0.4445 270)
			(size 0.1397 0.1397)
			(layers "F.Cu" "F.Mask" "F.Paste")
			(net "P12V")
			(options
				(clearance outline)
				(anchor circle)
			)
			(primitives
				(gr_poly
					(pts
						(arc
							(start -0.1778 -0.2794)
							(mid -0.249642 -0.249642)
							(end -0.2794 -0.1778)
						)
						(arc
							(start -0.2794 0.1778)
							(mid -0.249642 0.249642)
							(end -0.1778 0.2794)
						)
						(arc
							(start 0.1778 0.2794)
							(mid 0.249642 0.249642)
							(end 0.2794 0.1778)
						)
						(arc
							(start 0.2794 -0.1778)
							(mid 0.249642 -0.249642)
							(end 0.1778 -0.2794)
						)
					)
					(width 0)
					(fill yes)
				)
			)
		)
	)
	(footprint ""
		(layer "F.Cu")
		(at 158.369 -108.966 90)
		(property "Reference" "SC1208"
			(at 0 0 90)
			(layer "F.SilkS")
			(hide yes)
			(effects
				(font
					(size 1.27 1.27)
				)
			)
		)
		(property "Value" "SC10U6D3V5KX-4GP"
			(at -0.0762 -6.1214 90)
			(unlocked yes)
			(layer "F.Fab")
			(hide yes)
			(effects
				(font
					(size 1.016 1.016)
					(thickness 0.1524)
				)
			)
		)
		(property "Device Type" "C805H58"
			(at -0.0762 -8.1534 90)
			(unlocked yes)
			(layer "F.Fab")
			(hide yes)
			(effects
				(font
					(size 1.016 1.016)
					(thickness 0.1524)
				)
			)
		)
		(duplicate_pad_numbers_are_jumpers no)
		(fp_line
			(start 0.635 0)
			(end -0.635 0)
			(stroke
				(width 0.508)
				(type default)
			)
			(layer "F.SilkS")
		)
		(fp_rect
			(start -0.9652 1.778)
			(end 0.9652 -1.778)
			(stroke
				(width 0)
				(type default)
			)
			(fill no)
			(layer "F.CrtYd")
		)
		(fp_poly
			(pts
				(xy -0.9652 -1.778) (xy 0.9652 -1.778) (xy 0.9652 1.778) (xy -0.9652 1.778)
			)
			(stroke
				(width 0)
				(type default)
			)
			(fill no)
			(layer "F.Fab")
		)
		(pad "1" smd rect
			(at 0 -0.9652 90)
			(size 1.397 1.143)
			(layers "F.Cu" "F.Mask" "F.Paste")
			(net "P0V9_E")
		)
		(pad "2" smd rect
			(at 0 0.9652 90)
			(size 1.397 1.143)
			(layers "F.Cu" "F.Mask" "F.Paste")
			(net "GND")
		)
	)
	(footprint ""
		(layer "F.Cu")
		(at 86.49716 -33.02 -90)
		(property "Reference" "SC879"
			(at 0 0 270)
			(layer "F.SilkS")
			(hide yes)
			(effects
				(font
					(size 1.27 1.27)
				)
			)
		)
		(property "Value" "SCD01U10V1KX-GP"
			(at -2.8321 -1.7399 270)
			(unlocked yes)
			(layer "F.Fab")
			(hide yes)
			(effects
				(font
					(size 1.016 1.016)
					(thickness 0.1524)
				)
			)
		)
		(property "Device Type" "C0201H13"
			(at -2.8321 -3.2639 270)
			(unlocked yes)
			(layer "F.Fab")
			(hide yes)
			(effects
				(font
					(size 1.016 1.016)
					(thickness 0.1524)
				)
			)
		)
		(duplicate_pad_numbers_are_jumpers no)
		(fp_rect
			(start -0.2794 0.6477)
			(end 0.2794 -0.6477)
			(stroke
				(width 0)
				(type default)
			)
			(fill no)
			(layer "F.CrtYd")
		)
		(fp_rect
			(start -0.2794 0.6477)
			(end 0.2794 -0.6477)
			(stroke
				(width 0)
				(type default)
			)
			(fill no)
			(layer "F.Fab")
		)
		(pad "1" smd custom
			(at 0 -0.2794 270)
			(size 0.0762 0.0762)
			(layers "F.Cu" "F.Mask" "F.Paste")
			(net "SAS3008_RAID_TX_C_N0")
			(options
				(clearance outline)
				(anchor circle)
			)
			(primitives
				(gr_poly
					(pts
						(arc
							(start 0.1524 -0.127)
							(mid 0.137521 -0.162921)
							(end 0.1016 -0.1778)
						)
						(arc
							(start -0.1016 -0.1778)
							(mid -0.137521 -0.162921)
							(end -0.1524 -0.127)
						)
						(arc
							(start -0.1524 0.127)
							(mid -0.137521 0.162921)
							(end -0.1016 0.1778)
						)
						(arc
							(start 0.1016 0.1778)
							(mid 0.137521 0.162921)
							(end 0.1524 0.127)
						)
					)
					(width 0)
					(fill yes)
				)
			)
		)
		(pad "2" smd custom
			(at 0 0.2794 270)
			(size 0.0762 0.0762)
			(layers "F.Cu" "F.Mask" "F.Paste")
			(net "SAS3008_RAID_TX_N0")
			(options
				(clearance outline)
				(anchor circle)
			)
			(primitives
				(gr_poly
					(pts
						(arc
							(start 0.1524 -0.127)
							(mid 0.137521 -0.162921)
							(end 0.1016 -0.1778)
						)
						(arc
							(start -0.1016 -0.1778)
							(mid -0.137521 -0.162921)
							(end -0.1524 -0.127)
						)
						(arc
							(start -0.1524 0.127)
							(mid -0.137521 0.162921)
							(end -0.1016 0.1778)
						)
						(arc
							(start 0.1016 0.1778)
							(mid 0.137521 0.162921)
							(end 0.1524 0.127)
						)
					)
					(width 0)
					(fill yes)
				)
			)
		)
	)
	(footprint ""
		(layer "F.Cu")
		(at 131.318 -87.884 90)
		(property "Reference" "SC1263"
			(at 0 0 90)
			(layer "F.SilkS")
			(hide yes)
			(effects
				(font
					(size 1.27 1.27)
				)
			)
		)
		(property "Value" "SCD01U10V1KX-GP"
			(at -2.8321 -1.7399 90)
			(unlocked yes)
			(layer "F.Fab")
			(hide yes)
			(effects
				(font
					(size 1.016 1.016)
					(thickness 0.1524)
				)
			)
		)
		(property "Device Type" "C0201H13"
			(at -2.8321 -3.2639 90)
			(unlocked yes)
			(layer "F.Fab")
			(hide yes)
			(effects
				(font
					(size 1.016 1.016)
					(thickness 0.1524)
				)
			)
		)
		(duplicate_pad_numbers_are_jumpers no)
		(fp_rect
			(start -0.2794 0.6477)
			(end 0.2794 -0.6477)
			(stroke
				(width 0)
				(type default)
			)
			(fill no)
			(layer "F.CrtYd")
		)
		(fp_rect
			(start -0.2794 0.6477)
			(end 0.2794 -0.6477)
			(stroke
				(width 0)
				(type default)
			)
			(fill no)
			(layer "F.Fab")
		)
		(pad "1" smd custom
			(at 0 -0.2794 90)
			(size 0.0762 0.0762)
			(layers "F.Cu" "F.Mask" "F.Paste")
			(net "3X24_SAS_TX16_N")
			(options
				(clearance outline)
				(anchor circle)
			)
			(primitives
				(gr_poly
					(pts
						(arc
							(start 0.1524 -0.127)
							(mid 0.137521 -0.162921)
							(end 0.1016 -0.1778)
						)
						(arc
							(start -0.1016 -0.1778)
							(mid -0.137521 -0.162921)
							(end -0.1524 -0.127)
						)
						(arc
							(start -0.1524 0.127)
							(mid -0.137521 0.162921)
							(end -0.1016 0.1778)
						)
						(arc
							(start 0.1016 0.1778)
							(mid 0.137521 0.162921)
							(end 0.1524 0.127)
						)
					)
					(width 0)
					(fill yes)
				)
			)
		)
		(pad "2" smd custom
			(at 0 0.2794 90)
			(size 0.0762 0.0762)
			(layers "F.Cu" "F.Mask" "F.Paste")
			(net "SAS_EXP2CONN_TX_N_20")
			(options
				(clearance outline)
				(anchor circle)
			)
			(primitives
				(gr_poly
					(pts
						(arc
							(start 0.1524 -0.127)
							(mid 0.137521 -0.162921)
							(end 0.1016 -0.1778)
						)
						(arc
							(start -0.1016 -0.1778)
							(mid -0.137521 -0.162921)
							(end -0.1524 -0.127)
						)
						(arc
							(start -0.1524 0.127)
							(mid -0.137521 0.162921)
							(end -0.1016 0.1778)
						)
						(arc
							(start 0.1016 0.1778)
							(mid 0.137521 0.162921)
							(end 0.1524 0.127)
						)
					)
					(width 0)
					(fill yes)
				)
			)
		)
	)
	(footprint ""
		(layer "F.Cu")
		(at 335.661 -217.3605)
		(property "Reference" "R5303"
			(at 0 0 0)
			(layer "F.SilkS")
			(hide yes)
			(effects
				(font
					(size 1.27 1.27)
				)
			)
		)
		(property "Value" "0R2J-2-GP"
			(at 0.064008 -3.993896 0)
			(unlocked yes)
			(layer "F.Fab")
			(hide yes)
			(effects
				(font
					(size 1.016 1.016)
					(thickness 0.1524)
				)
			)
		)
		(property "Device Type" "R402H16"
			(at 0.064008 -5.517896 0)
			(unlocked yes)
			(layer "F.Fab")
			(hide yes)
			(effects
				(font
					(size 1.016 1.016)
					(thickness 0.1524)
				)
			)
		)
		(duplicate_pad_numbers_are_jumpers no)
		(fp_line
			(start -0.508 -0.9398)
			(end -0.508 0.9398)
			(stroke
				(width 0.1524)
				(type default)
			)
			(layer "F.SilkS")
		)
		(fp_line
			(start 0.508 -0.9398)
			(end -0.508 -0.9398)
			(stroke
				(width 0.1524)
				(type default)
			)
			(layer "F.SilkS")
		)
		(fp_rect
			(start -0.508 0.9398)
			(end 0.508 -0.9398)
			(stroke
				(width 0)
				(type default)
			)
			(fill no)
			(layer "F.CrtYd")
		)
		(fp_rect
			(start -0.508 0.9398)
			(end 0.508 -0.9398)
			(stroke
				(width 0)
				(type default)
			)
			(fill no)
			(layer "F.Fab")
		)
		(pad "1" smd custom
			(at 0 -0.4445)
			(size 0.1397 0.1397)
			(layers "F.Cu" "F.Mask" "F.Paste")
			(net "VOL_SEN_SCL")
			(options
				(clearance outline)
				(anchor circle)
			)
			(primitives
				(gr_poly
					(pts
						(arc
							(start -0.1778 -0.2794)
							(mid -0.249642 -0.249642)
							(end -0.2794 -0.1778)
						)
						(arc
							(start -0.2794 0.1778)
							(mid -0.249642 0.249642)
							(end -0.1778 0.2794)
						)
						(arc
							(start 0.1778 0.2794)
							(mid 0.249642 0.249642)
							(end 0.2794 0.1778)
						)
						(arc
							(start 0.2794 -0.1778)
							(mid 0.249642 -0.249642)
							(end 0.1778 -0.2794)
						)
					)
					(width 0)
					(fill yes)
				)
			)
		)
		(pad "2" smd custom
			(at 0 0.4445)
			(size 0.1397 0.1397)
			(layers "F.Cu" "F.Mask" "F.Paste")
			(net "BMC_I2C_SCL_10")
			(options
				(clearance outline)
				(anchor circle)
			)
			(primitives
				(gr_poly
					(pts
						(arc
							(start -0.1778 -0.2794)
							(mid -0.249642 -0.249642)
							(end -0.2794 -0.1778)
						)
						(arc
							(start -0.2794 0.1778)
							(mid -0.249642 0.249642)
							(end -0.1778 0.2794)
						)
						(arc
							(start 0.1778 0.2794)
							(mid 0.249642 0.249642)
							(end 0.2794 0.1778)
						)
						(arc
							(start 0.2794 -0.1778)
							(mid 0.249642 -0.249642)
							(end 0.1778 -0.2794)
						)
					)
					(width 0)
					(fill yes)
				)
			)
		)
	)
	(footprint ""
		(layer "F.Cu")
		(at 163.322 -154.9146 -90)
		(property "Reference" "SU63"
			(at 0 0 270)
			(layer "F.SilkS")
			(hide yes)
			(effects
				(font
					(size 1.27 1.27)
				)
			)
		)
		(property "Value" "2N7002DW-7F-GP"
			(at -2.3622 -8.2042 270)
			(unlocked yes)
			(layer "F.Fab")
			(hide yes)
			(effects
				(font
					(size 1.016 1.016)
					(thickness 0.1524)
				)
			)
		)
		(property "Device Type" "SOT-363H44"
			(at -2.3622 -10.1092 270)
			(unlocked yes)
			(layer "F.Fab")
			(hide yes)
			(effects
				(font
					(size 1.016 1.016)
					(thickness 0.1524)
				)
			)
		)
		(duplicate_pad_numbers_are_jumpers no)
		(fp_line
			(start -1.4478 1.7018)
			(end 1.4478 1.7018)
			(stroke
				(width 0.1524)
				(type default)
			)
			(layer "F.SilkS")
		)
		(fp_line
			(start 1.4478 1.7018)
			(end 1.4478 -1.7018)
			(stroke
				(width 0.1524)
				(type default)
			)
			(layer "F.SilkS")
		)
		(fp_line
			(start -1.27 1.524)
			(end -1.27 0.6604)
			(stroke
				(width 0.4826)
				(type default)
			)
			(layer "F.SilkS")
		)
		(fp_line
			(start -1.4478 -1.7018)
			(end -1.4478 1.7018)
			(stroke
				(width 0.1524)
				(type default)
			)
			(layer "F.SilkS")
		)
		(fp_line
			(start 1.4478 -1.7018)
			(end -1.4478 -1.7018)
			(stroke
				(width 0.1524)
				(type default)
			)
			(layer "F.SilkS")
		)
		(fp_poly
			(pts
				(xy -1.524 -1.778) (xy 1.524 -1.778) (xy 1.524 1.778) (xy -1.524 1.778)
			)
			(stroke
				(width 0)
				(type default)
			)
			(fill no)
			(layer "F.CrtYd")
		)
		(fp_poly
			(pts
				(xy -1.524 -1.778) (xy 1.524 -1.778) (xy 1.524 1.778) (xy -1.524 1.778)
			)
			(stroke
				(width 0)
				(type default)
			)
			(fill no)
			(layer "F.Fab")
		)
		(pad "1" smd rect
			(at -0.65024 0.9398 270)
			(size 0.4064 1.016)
			(layers "F.Cu" "F.Mask" "F.Paste")
			(net "IOC_P3V3_R_SCL_14")
		)
		(pad "2" smd rect
			(at 0 0.9398 270)
			(size 0.4064 1.016)
			(layers "F.Cu" "F.Mask" "F.Paste")
			(net "PMU_PLTRST_N")
		)
		(pad "3" smd rect
			(at 0.65024 0.9398 270)
			(size 0.4064 1.016)
			(layers "F.Cu" "F.Mask" "F.Paste")
			(net "EXP_IOC_BMC_R_SDA_14")
		)
		(pad "4" smd rect
			(at 0.65024 -0.9398 270)
			(size 0.4064 1.016)
			(layers "F.Cu" "F.Mask" "F.Paste")
			(net "IOC_P3V3_R_SDA_14")
		)
		(pad "5" smd rect
			(at 0 -0.9398 270)
			(size 0.4064 1.016)
			(layers "F.Cu" "F.Mask" "F.Paste")
			(net "PMU_PLTRST_N")
		)
		(pad "6" smd rect
			(at -0.65024 -0.9398 270)
			(size 0.4064 1.016)
			(layers "F.Cu" "F.Mask" "F.Paste")
			(net "EXP_IOC_BMC_R_SCL_14")
		)
	)
	(footprint ""
		(layer "F.Cu")
		(at 88.138 -27.159966 180)
		(property "Reference" "SR588"
			(at 0 0 180)
			(layer "F.SilkS")
			(hide yes)
			(effects
				(font
					(size 1.27 1.27)
				)
			)
		)
		(property "Value" "0R2J-2-GP"
			(at 0.064008 -3.993896 180)
			(unlocked yes)
			(layer "F.Fab")
			(hide yes)
			(effects
				(font
					(size 1.016 1.016)
					(thickness 0.1524)
				)
			)
		)
		(property "Device Type" "R402H16"
			(at 0.064008 -5.517896 180)
			(unlocked yes)
			(layer "F.Fab")
			(hide yes)
			(effects
				(font
					(size 1.016 1.016)
					(thickness 0.1524)
				)
			)
		)
		(duplicate_pad_numbers_are_jumpers no)
		(fp_line
			(start 0.508 -0.9398)
			(end -0.508 -0.9398)
			(stroke
				(width 0.1524)
				(type default)
			)
			(layer "F.SilkS")
		)
		(fp_line
			(start -0.508 -0.9398)
			(end -0.508 0.9398)
			(stroke
				(width 0.1524)
				(type default)
			)
			(layer "F.SilkS")
		)
		(fp_rect
			(start -0.508 0.9398)
			(end 0.508 -0.9398)
			(stroke
				(width 0)
				(type default)
			)
			(fill no)
			(layer "F.CrtYd")
		)
		(fp_rect
			(start -0.508 0.9398)
			(end 0.508 -0.9398)
			(stroke
				(width 0)
				(type default)
			)
			(fill no)
			(layer "F.Fab")
		)
		(pad "1" smd custom
			(at 0 -0.4445 180)
			(size 0.1397 0.1397)
			(layers "F.Cu" "F.Mask" "F.Paste")
			(net "CLK_100M_PCIE_SAS_C_N")
			(options
				(clearance outline)
				(anchor circle)
			)
			(primitives
				(gr_poly
					(pts
						(arc
							(start -0.1778 -0.2794)
							(mid -0.249642 -0.249642)
							(end -0.2794 -0.1778)
						)
						(arc
							(start -0.2794 0.1778)
							(mid -0.249642 0.249642)
							(end -0.1778 0.2794)
						)
						(arc
							(start 0.1778 0.2794)
							(mid 0.249642 0.249642)
							(end 0.2794 0.1778)
						)
						(arc
							(start 0.2794 -0.1778)
							(mid 0.249642 -0.249642)
							(end 0.1778 -0.2794)
						)
					)
					(width 0)
					(fill yes)
				)
			)
		)
		(pad "2" smd custom
			(at 0 0.4445 180)
			(size 0.1397 0.1397)
			(layers "F.Cu" "F.Mask" "F.Paste")
			(net "CLK_100M_PCIE_N")
			(options
				(clearance outline)
				(anchor circle)
			)
			(primitives
				(gr_poly
					(pts
						(arc
							(start -0.1778 -0.2794)
							(mid -0.249642 -0.249642)
							(end -0.2794 -0.1778)
						)
						(arc
							(start -0.2794 0.1778)
							(mid -0.249642 0.249642)
							(end -0.1778 0.2794)
						)
						(arc
							(start 0.1778 0.2794)
							(mid 0.249642 0.249642)
							(end 0.2794 0.1778)
						)
						(arc
							(start 0.2794 -0.1778)
							(mid 0.249642 -0.249642)
							(end 0.1778 -0.2794)
						)
					)
					(width 0)
					(fill yes)
				)
			)
		)
	)
	(footprint ""
		(layer "F.Cu")
		(at 48.7172 -114.7572 180)
		(property "Reference" "SR941"
			(at 0 0 180)
			(layer "F.SilkS")
			(hide yes)
			(effects
				(font
					(size 1.27 1.27)
				)
			)
		)
		(property "Value" "0R2J-2-GP"
			(at 0.064008 -3.993896 180)
			(unlocked yes)
			(layer "F.Fab")
			(hide yes)
			(effects
				(font
					(size 1.016 1.016)
					(thickness 0.1524)
				)
			)
		)
		(property "Device Type" "R402H16"
			(at 0.064008 -5.517896 180)
			(unlocked yes)
			(layer "F.Fab")
			(hide yes)
			(effects
				(font
					(size 1.016 1.016)
					(thickness 0.1524)
				)
			)
		)
		(duplicate_pad_numbers_are_jumpers no)
		(fp_line
			(start 0.508 -0.9398)
			(end -0.508 -0.9398)
			(stroke
				(width 0.1524)
				(type default)
			)
			(layer "F.SilkS")
		)
		(fp_line
			(start -0.508 -0.9398)
			(end -0.508 0.9398)
			(stroke
				(width 0.1524)
				(type default)
			)
			(layer "F.SilkS")
		)
		(fp_rect
			(start -0.508 0.9398)
			(end 0.508 -0.9398)
			(stroke
				(width 0)
				(type default)
			)
			(fill no)
			(layer "F.CrtYd")
		)
		(fp_rect
			(start -0.508 0.9398)
			(end 0.508 -0.9398)
			(stroke
				(width 0)
				(type default)
			)
			(fill no)
			(layer "F.Fab")
		)
		(pad "1" smd custom
			(at 0 -0.4445 180)
			(size 0.1397 0.1397)
			(layers "F.Cu" "F.Mask" "F.Paste")
			(net "BMC_R_RXD5")
			(options
				(clearance outline)
				(anchor circle)
			)
			(primitives
				(gr_poly
					(pts
						(arc
							(start -0.1778 -0.2794)
							(mid -0.249642 -0.249642)
							(end -0.2794 -0.1778)
						)
						(arc
							(start -0.2794 0.1778)
							(mid -0.249642 0.249642)
							(end -0.1778 0.2794)
						)
						(arc
							(start 0.1778 0.2794)
							(mid 0.249642 0.249642)
							(end 0.2794 0.1778)
						)
						(arc
							(start 0.2794 -0.1778)
							(mid 0.249642 -0.249642)
							(end 0.1778 -0.2794)
						)
					)
					(width 0)
					(fill yes)
				)
			)
		)
		(pad "2" smd custom
			(at 0 0.4445 180)
			(size 0.1397 0.1397)
			(layers "F.Cu" "F.Mask" "F.Paste")
			(net "BMC_RXD5")
			(options
				(clearance outline)
				(anchor circle)
			)
			(primitives
				(gr_poly
					(pts
						(arc
							(start -0.1778 -0.2794)
							(mid -0.249642 -0.249642)
							(end -0.2794 -0.1778)
						)
						(arc
							(start -0.2794 0.1778)
							(mid -0.249642 0.249642)
							(end -0.1778 0.2794)
						)
						(arc
							(start 0.1778 0.2794)
							(mid 0.249642 0.249642)
							(end 0.2794 0.1778)
						)
						(arc
							(start 0.2794 -0.1778)
							(mid 0.249642 -0.249642)
							(end 0.1778 -0.2794)
						)
					)
					(width 0)
					(fill yes)
				)
			)
		)
	)
	(footprint ""
		(layer "F.Cu")
		(at 184.031128 -14.151864)
		(property "Reference" "R195"
			(at 0 0 0)
			(layer "F.SilkS")
			(hide yes)
			(effects
				(font
					(size 1.27 1.27)
				)
			)
		)
		(property "Value" "4K7R2F-GP"
			(at 0.064008 -3.993896 0)
			(unlocked yes)
			(layer "F.Fab")
			(hide yes)
			(effects
				(font
					(size 1.016 1.016)
					(thickness 0.1524)
				)
			)
		)
		(property "Device Type" "R402H16"
			(at 0.064008 -5.517896 0)
			(unlocked yes)
			(layer "F.Fab")
			(hide yes)
			(effects
				(font
					(size 1.016 1.016)
					(thickness 0.1524)
				)
			)
		)
		(duplicate_pad_numbers_are_jumpers no)
		(fp_line
			(start -0.508 -0.9398)
			(end -0.508 0.9398)
			(stroke
				(width 0.1524)
				(type default)
			)
			(layer "F.SilkS")
		)
		(fp_line
			(start 0.508 -0.9398)
			(end -0.508 -0.9398)
			(stroke
				(width 0.1524)
				(type default)
			)
			(layer "F.SilkS")
		)
		(fp_rect
			(start -0.508 0.9398)
			(end 0.508 -0.9398)
			(stroke
				(width 0)
				(type default)
			)
			(fill no)
			(layer "F.CrtYd")
		)
		(fp_rect
			(start -0.508 0.9398)
			(end 0.508 -0.9398)
			(stroke
				(width 0)
				(type default)
			)
			(fill no)
			(layer "F.Fab")
		)
		(pad "1" smd custom
			(at 0 -0.4445)
			(size 0.1397 0.1397)
			(layers "F.Cu" "F.Mask" "F.Paste")
			(net "TEMP_1_A0")
			(options
				(clearance outline)
				(anchor circle)
			)
			(primitives
				(gr_poly
					(pts
						(arc
							(start -0.1778 -0.2794)
							(mid -0.249642 -0.249642)
							(end -0.2794 -0.1778)
						)
						(arc
							(start -0.2794 0.1778)
							(mid -0.249642 0.249642)
							(end -0.1778 0.2794)
						)
						(arc
							(start 0.1778 0.2794)
							(mid 0.249642 0.249642)
							(end 0.2794 0.1778)
						)
						(arc
							(start 0.2794 -0.1778)
							(mid 0.249642 -0.249642)
							(end 0.1778 -0.2794)
						)
					)
					(width 0)
					(fill yes)
				)
			)
		)
		(pad "2" smd custom
			(at 0 0.4445)
			(size 0.1397 0.1397)
			(layers "F.Cu" "F.Mask" "F.Paste")
			(net "GND")
			(options
				(clearance outline)
				(anchor circle)
			)
			(primitives
				(gr_poly
					(pts
						(arc
							(start -0.1778 -0.2794)
							(mid -0.249642 -0.249642)
							(end -0.2794 -0.1778)
						)
						(arc
							(start -0.2794 0.1778)
							(mid -0.249642 0.249642)
							(end -0.1778 0.2794)
						)
						(arc
							(start 0.1778 0.2794)
							(mid 0.249642 0.249642)
							(end 0.2794 0.1778)
						)
						(arc
							(start 0.2794 -0.1778)
							(mid 0.249642 -0.249642)
							(end 0.1778 -0.2794)
						)
					)
					(width 0)
					(fill yes)
				)
			)
		)
	)
	(footprint ""
		(layer "F.Cu")
		(at 260.477 -34.29)
		(property "Reference" "PR57"
			(at 0 0 0)
			(layer "F.SilkS")
			(hide yes)
			(effects
				(font
					(size 1.27 1.27)
				)
			)
		)
		(property "Value" "10KR2F-2-GP"
			(at 0.064008 -3.993896 0)
			(unlocked yes)
			(layer "F.Fab")
			(hide yes)
			(effects
				(font
					(size 1.016 1.016)
					(thickness 0.1524)
				)
			)
		)
		(property "Device Type" "R402H16"
			(at 0.064008 -5.517896 0)
			(unlocked yes)
			(layer "F.Fab")
			(hide yes)
			(effects
				(font
					(size 1.016 1.016)
					(thickness 0.1524)
				)
			)
		)
		(duplicate_pad_numbers_are_jumpers no)
		(fp_line
			(start -0.508 -0.9398)
			(end -0.508 0.9398)
			(stroke
				(width 0.1524)
				(type default)
			)
			(layer "F.SilkS")
		)
		(fp_line
			(start 0.508 -0.9398)
			(end -0.508 -0.9398)
			(stroke
				(width 0.1524)
				(type default)
			)
			(layer "F.SilkS")
		)
		(fp_rect
			(start -0.508 0.9398)
			(end 0.508 -0.9398)
			(stroke
				(width 0)
				(type default)
			)
			(fill no)
			(layer "F.CrtYd")
		)
		(fp_rect
			(start -0.508 0.9398)
			(end 0.508 -0.9398)
			(stroke
				(width 0)
				(type default)
			)
			(fill no)
			(layer "F.Fab")
		)
		(pad "1" smd custom
			(at 0 -0.4445)
			(size 0.1397 0.1397)
			(layers "F.Cu" "F.Mask" "F.Paste")
			(net "P1V8_STBY_VFB")
			(options
				(clearance outline)
				(anchor circle)
			)
			(primitives
				(gr_poly
					(pts
						(arc
							(start -0.1778 -0.2794)
							(mid -0.249642 -0.249642)
							(end -0.2794 -0.1778)
						)
						(arc
							(start -0.2794 0.1778)
							(mid -0.249642 0.249642)
							(end -0.1778 0.2794)
						)
						(arc
							(start 0.1778 0.2794)
							(mid 0.249642 0.249642)
							(end 0.2794 0.1778)
						)
						(arc
							(start 0.2794 -0.1778)
							(mid 0.249642 -0.249642)
							(end 0.1778 -0.2794)
						)
					)
					(width 0)
					(fill yes)
				)
			)
		)
		(pad "2" smd custom
			(at 0 0.4445)
			(size 0.1397 0.1397)
			(layers "F.Cu" "F.Mask" "F.Paste")
			(net "AGND_P1V8_STBY")
			(options
				(clearance outline)
				(anchor circle)
			)
			(primitives
				(gr_poly
					(pts
						(arc
							(start -0.1778 -0.2794)
							(mid -0.249642 -0.249642)
							(end -0.2794 -0.1778)
						)
						(arc
							(start -0.2794 0.1778)
							(mid -0.249642 0.249642)
							(end -0.1778 0.2794)
						)
						(arc
							(start 0.1778 0.2794)
							(mid 0.249642 0.249642)
							(end 0.2794 0.1778)
						)
						(arc
							(start 0.2794 -0.1778)
							(mid 0.249642 -0.249642)
							(end 0.1778 -0.2794)
						)
					)
					(width 0)
					(fill yes)
				)
			)
		)
	)
	(footprint ""
		(layer "F.Cu")
		(at 173.99 -88.519 90)
		(property "Reference" "PTC5"
			(at 0 0 90)
			(layer "F.SilkS")
			(hide yes)
			(effects
				(font
					(size 1.27 1.27)
				)
			)
		)
		(property "Value" "SE470UF2VDM-GP"
			(at 0 -9.6012 90)
			(unlocked yes)
			(layer "F.Fab")
			(hide yes)
			(effects
				(font
					(size 1.016 1.016)
					(thickness 0.1524)
				)
			)
		)
		(property "Device Type" "CT7343H83"
			(at 0 -11.1252 90)
			(unlocked yes)
			(layer "F.Fab")
			(hide yes)
			(effects
				(font
					(size 1.016 1.016)
					(thickness 0.1524)
				)
			)
		)
		(duplicate_pad_numbers_are_jumpers no)
		(fp_line
			(start 2.286 -4.8768)
			(end -2.286 -4.8768)
			(stroke
				(width 0.1524)
				(type default)
			)
			(layer "F.SilkS")
		)
		(fp_line
			(start -2.286 -4.8768)
			(end -2.286 -2.032)
			(stroke
				(width 0.1524)
				(type default)
			)
			(layer "F.SilkS")
		)
		(fp_line
			(start 2.1082 -4.699)
			(end -2.1082 -4.699)
			(stroke
				(width 0.508)
				(type default)
			)
			(layer "F.SilkS")
		)
		(fp_line
			(start 2.286 -2.032)
			(end 2.286 -4.8768)
			(stroke
				(width 0.1524)
				(type default)
			)
			(layer "F.SilkS")
		)
		(fp_line
			(start 2.286 2.032)
			(end 2.286 4.8768)
			(stroke
				(width 0.1524)
				(type default)
			)
			(layer "F.SilkS")
		)
		(fp_line
			(start 2.286 4.8768)
			(end -2.286 4.8768)
			(stroke
				(width 0.1524)
				(type default)
			)
			(layer "F.SilkS")
		)
		(fp_line
			(start -2.286 4.8768)
			(end -2.286 2.032)
			(stroke
				(width 0.1524)
				(type default)
			)
			(layer "F.SilkS")
		)
		(fp_rect
			(start -2.1463 3.6449)
			(end 2.1463 -3.6449)
			(stroke
				(width 0)
				(type default)
			)
			(fill no)
			(layer "F.CrtYd")
		)
		(fp_poly
			(pts
				(xy -2.54 4.953) (xy -2.54 4.2926) (xy -3.81 4.2926) (xy -3.81 -4.2926) (xy -2.54 -4.2926) (xy -2.54 -4.953)
				(xy 2.54 -4.953) (xy 2.54 -4.2926) (xy 3.81 -4.2926) (xy 3.81 -1.6256) (xy 2.1463 -1.6256) (xy 2.1463 -3.6449)
				(xy -2.1463 -3.6449) (xy -2.1463 3.6449) (xy 2.1463 3.6449) (xy 2.1463 -1.6129) (xy 3.81 -1.6129)
				(xy 3.81 4.2926) (xy 2.54 4.2926) (xy 2.54 4.953)
			)
			(stroke
				(width 0)
				(type default)
			)
			(fill no)
			(layer "F.CrtYd")
		)
		(fp_rect
			(start 2.54 4.2926)
			(end 3.81 -4.2926)
			(stroke
				(width 0)
				(type default)
			)
			(fill no)
			(layer "F.Fab")
		)
		(fp_rect
			(start -3.81 4.2926)
			(end -2.54 -4.2926)
			(stroke
				(width 0)
				(type default)
			)
			(fill no)
			(layer "F.Fab")
		)
		(fp_rect
			(start -2.54 4.953)
			(end 2.54 -4.953)
			(stroke
				(width 0)
				(type default)
			)
			(fill no)
			(layer "F.Fab")
		)
		(pad "1" smd rect
			(at 0 -3.1496 90)
			(size 2.413 2.286)
			(layers "F.Cu" "F.Mask" "F.Paste")
			(net "P0V9_E")
		)
		(pad "2" smd rect
			(at 0 3.1496 90)
			(size 2.413 2.286)
			(layers "F.Cu" "F.Mask" "F.Paste")
			(net "GND")
		)
		(zone
			(layer "F.Cu")
			(hatch none 0.5)
			(connect_pads
				(clearance 0)
			)
			(min_thickness 0.25)
			(keepout
				(tracks allowed)
				(vias not_allowed)
				(pads allowed)
				(copperpour not_allowed)
				(footprints allowed)
			)
			(placement
				(enabled no)
				(sheetname "")
			)
			(fill
				(thermal_gap 0.5)
				(thermal_bridge_width 0.5)
				(island_removal_mode 0)
			)
			(polygon
				(pts
					(xy 172.3009 -90.0303) (xy 169.3926 -90.0303) (xy 169.3926 -87.0077) (xy 172.2882 -87.0077) (xy 172.6184 -87.0077)
					(xy 172.6184 -90.0303)
				)
			)
		)
		(zone
			(layer "F.Cu")
			(hatch none 0.5)
			(connect_pads
				(clearance 0)
			)
			(min_thickness 0.25)
			(keepout
				(tracks allowed)
				(vias not_allowed)
				(pads allowed)
				(copperpour not_allowed)
				(footprints allowed)
			)
			(placement
				(enabled no)
				(sheetname "")
			)
			(fill
				(thermal_gap 0.5)
				(thermal_bridge_width 0.5)
				(island_removal_mode 0)
			)
			(polygon
				(pts
					(xy 178.5874 -87.0077) (xy 178.5874 -90.0303) (xy 175.6918 -90.0303) (xy 175.3616 -90.0303) (xy 175.3616 -87.0077)
					(xy 175.6918 -87.0077)
				)
			)
		)
	)
	(footprint ""
		(layer "F.Cu")
		(at 188.722 -145.669)
		(property "Reference" "SC1294"
			(at 0 0 0)
			(layer "F.SilkS")
			(hide yes)
			(effects
				(font
					(size 1.27 1.27)
				)
			)
		)
		(property "Value" "SCD1U16V2KX-3GP"
			(at 1.1811 -2.7051 0)
			(unlocked yes)
			(layer "F.Fab")
			(hide yes)
			(effects
				(font
					(size 1.016 1.016)
					(thickness 0.1524)
				)
			)
		)
		(property "Device Type" "C402H22"
			(at 1.1811 -4.2291 0)
			(unlocked yes)
			(layer "F.Fab")
			(hide yes)
			(effects
				(font
					(size 1.016 1.016)
					(thickness 0.1524)
				)
			)
		)
		(duplicate_pad_numbers_are_jumpers no)
		(fp_rect
			(start -0.4318 0.9525)
			(end 0.4318 -0.9525)
			(stroke
				(width 0)
				(type default)
			)
			(fill no)
			(layer "F.CrtYd")
		)
		(fp_rect
			(start -0.4318 0.9525)
			(end 0.4318 -0.9525)
			(stroke
				(width 0)
				(type default)
			)
			(fill no)
			(layer "F.Fab")
		)
		(pad "1" smd custom
			(at 0 -0.4445)
			(size 0.1524 0.1524)
			(layers "F.Cu" "F.Mask" "F.Paste")
			(net "P1V8_E")
			(options
				(clearance outline)
				(anchor circle)
			)
			(primitives
				(gr_poly
					(pts
						(arc
							(start 0.3048 -0.2032)
							(mid 0.275042 -0.275042)
							(end 0.2032 -0.3048)
						)
						(arc
							(start -0.2032 -0.3048)
							(mid -0.275042 -0.275042)
							(end -0.3048 -0.2032)
						)
						(arc
							(start -0.3048 0.2032)
							(mid -0.275042 0.275042)
							(end -0.2032 0.3048)
						)
						(arc
							(start 0.2032 0.3048)
							(mid 0.275042 0.275042)
							(end 0.3048 0.2032)
						)
					)
					(width 0)
					(fill yes)
				)
			)
		)
		(pad "2" smd custom
			(at 0 0.4445)
			(size 0.1524 0.1524)
			(layers "F.Cu" "F.Mask" "F.Paste")
			(net "GND")
			(options
				(clearance outline)
				(anchor circle)
			)
			(primitives
				(gr_poly
					(pts
						(arc
							(start 0.3048 -0.2032)
							(mid 0.275042 -0.275042)
							(end 0.2032 -0.3048)
						)
						(arc
							(start -0.2032 -0.3048)
							(mid -0.275042 -0.275042)
							(end -0.3048 -0.2032)
						)
						(arc
							(start -0.3048 0.2032)
							(mid -0.275042 0.275042)
							(end -0.2032 0.3048)
						)
						(arc
							(start 0.2032 0.3048)
							(mid 0.275042 0.275042)
							(end 0.3048 0.2032)
						)
					)
					(width 0)
					(fill yes)
				)
			)
		)
	)
	(footprint ""
		(layer "F.Cu")
		(at 282.058872 -215.591136)
		(property "Reference" "PC89"
			(at 0 0 0)
			(layer "F.SilkS")
			(hide yes)
			(effects
				(font
					(size 1.27 1.27)
				)
			)
		)
		(property "Value" "SCD1U16V2KX-3GP"
			(at 1.1811 -2.7051 0)
			(unlocked yes)
			(layer "F.Fab")
			(hide yes)
			(effects
				(font
					(size 1.016 1.016)
					(thickness 0.1524)
				)
			)
		)
		(property "Device Type" "C402H22"
			(at 1.1811 -4.2291 0)
			(unlocked yes)
			(layer "F.Fab")
			(hide yes)
			(effects
				(font
					(size 1.016 1.016)
					(thickness 0.1524)
				)
			)
		)
		(duplicate_pad_numbers_are_jumpers no)
		(fp_rect
			(start -0.4318 0.9525)
			(end 0.4318 -0.9525)
			(stroke
				(width 0)
				(type default)
			)
			(fill no)
			(layer "F.CrtYd")
		)
		(fp_rect
			(start -0.4318 0.9525)
			(end 0.4318 -0.9525)
			(stroke
				(width 0)
				(type default)
			)
			(fill no)
			(layer "F.Fab")
		)
		(pad "1" smd custom
			(at 0 -0.4445)
			(size 0.1524 0.1524)
			(layers "F.Cu" "F.Mask" "F.Paste")
			(net "TPS74801_1V53_STBY_EN")
			(options
				(clearance outline)
				(anchor circle)
			)
			(primitives
				(gr_poly
					(pts
						(arc
							(start 0.3048 -0.2032)
							(mid 0.275042 -0.275042)
							(end 0.2032 -0.3048)
						)
						(arc
							(start -0.2032 -0.3048)
							(mid -0.275042 -0.275042)
							(end -0.3048 -0.2032)
						)
						(arc
							(start -0.3048 0.2032)
							(mid -0.275042 0.275042)
							(end -0.2032 0.3048)
						)
						(arc
							(start 0.2032 0.3048)
							(mid 0.275042 0.275042)
							(end 0.3048 0.2032)
						)
					)
					(width 0)
					(fill yes)
				)
			)
		)
		(pad "2" smd custom
			(at 0 0.4445)
			(size 0.1524 0.1524)
			(layers "F.Cu" "F.Mask" "F.Paste")
			(net "GND")
			(options
				(clearance outline)
				(anchor circle)
			)
			(primitives
				(gr_poly
					(pts
						(arc
							(start 0.3048 -0.2032)
							(mid 0.275042 -0.275042)
							(end 0.2032 -0.3048)
						)
						(arc
							(start -0.2032 -0.3048)
							(mid -0.275042 -0.275042)
							(end -0.3048 -0.2032)
						)
						(arc
							(start -0.3048 0.2032)
							(mid -0.275042 0.275042)
							(end -0.2032 0.3048)
						)
						(arc
							(start 0.2032 0.3048)
							(mid 0.275042 0.275042)
							(end 0.3048 0.2032)
						)
					)
					(width 0)
					(fill yes)
				)
			)
		)
	)
	(footprint ""
		(layer "F.Cu")
		(at 116.713 -69.342 -90)
		(property "Reference" "R587"
			(at 0 0 270)
			(layer "F.SilkS")
			(hide yes)
			(effects
				(font
					(size 1.27 1.27)
				)
			)
		)
		(property "Value" "0R2J-2-GP"
			(at 0.064008 -3.993896 270)
			(unlocked yes)
			(layer "F.Fab")
			(hide yes)
			(effects
				(font
					(size 1.016 1.016)
					(thickness 0.1524)
				)
			)
		)
		(property "Device Type" "R402H16"
			(at 0.064008 -5.517896 270)
			(unlocked yes)
			(layer "F.Fab")
			(hide yes)
			(effects
				(font
					(size 1.016 1.016)
					(thickness 0.1524)
				)
			)
		)
		(duplicate_pad_numbers_are_jumpers no)
		(fp_line
			(start -0.508 -0.9398)
			(end -0.508 0.9398)
			(stroke
				(width 0.1524)
				(type default)
			)
			(layer "F.SilkS")
		)
		(fp_line
			(start 0.508 -0.9398)
			(end -0.508 -0.9398)
			(stroke
				(width 0.1524)
				(type default)
			)
			(layer "F.SilkS")
		)
		(fp_rect
			(start -0.508 0.9398)
			(end 0.508 -0.9398)
			(stroke
				(width 0)
				(type default)
			)
			(fill no)
			(layer "F.CrtYd")
		)
		(fp_rect
			(start -0.508 0.9398)
			(end 0.508 -0.9398)
			(stroke
				(width 0)
				(type default)
			)
			(fill no)
			(layer "F.Fab")
		)
		(pad "1" smd custom
			(at 0 -0.4445 270)
			(size 0.1397 0.1397)
			(layers "F.Cu" "F.Mask" "F.Paste")
			(net "BMC_I2C_D_SDA")
			(options
				(clearance outline)
				(anchor circle)
			)
			(primitives
				(gr_poly
					(pts
						(arc
							(start -0.1778 -0.2794)
							(mid -0.249642 -0.249642)
							(end -0.2794 -0.1778)
						)
						(arc
							(start -0.2794 0.1778)
							(mid -0.249642 0.249642)
							(end -0.1778 0.2794)
						)
						(arc
							(start 0.1778 0.2794)
							(mid 0.249642 0.249642)
							(end 0.2794 0.1778)
						)
						(arc
							(start 0.2794 -0.1778)
							(mid 0.249642 -0.249642)
							(end 0.1778 -0.2794)
						)
					)
					(width 0)
					(fill yes)
				)
			)
		)
		(pad "2" smd custom
			(at 0 0.4445 270)
			(size 0.1397 0.1397)
			(layers "F.Cu" "F.Mask" "F.Paste")
			(net "TEMP_4_SDA")
			(options
				(clearance outline)
				(anchor circle)
			)
			(primitives
				(gr_poly
					(pts
						(arc
							(start -0.1778 -0.2794)
							(mid -0.249642 -0.249642)
							(end -0.2794 -0.1778)
						)
						(arc
							(start -0.2794 0.1778)
							(mid -0.249642 0.249642)
							(end -0.1778 0.2794)
						)
						(arc
							(start 0.1778 0.2794)
							(mid 0.249642 0.249642)
							(end 0.2794 0.1778)
						)
						(arc
							(start 0.2794 -0.1778)
							(mid 0.249642 -0.249642)
							(end 0.1778 -0.2794)
						)
					)
					(width 0)
					(fill yes)
				)
			)
		)
	)
	(footprint ""
		(layer "F.Cu")
		(at 98.56597 -78.105)
		(property "Reference" "STP145"
			(at 0 0 0)
			(layer "F.SilkS")
			(hide yes)
			(effects
				(font
					(size 1.27 1.27)
				)
			)
		)
		(property "Value" "TPAD28"
			(at 0.0127 -1.8034 0)
			(unlocked yes)
			(layer "F.Fab")
			(hide yes)
			(effects
				(font
					(size 1.016 1.016)
					(thickness 0.1524)
				)
			)
		)
		(property "Device Type" "TPAD28"
			(at 0.0127 -3.3274 0)
			(unlocked yes)
			(layer "F.Fab")
			(hide yes)
			(effects
				(font
					(size 1.016 1.016)
					(thickness 0.1524)
				)
			)
		)
		(duplicate_pad_numbers_are_jumpers no)
		(fp_poly
			(pts
				(arc
					(start 0.3556 0)
					(mid -0.3556 0)
					(end 0.3556 0)
				)
			)
			(stroke
				(width 0)
				(type default)
			)
			(fill no)
			(layer "F.CrtYd")
		)
		(fp_poly
			(pts
				(arc
					(start 0.6096 0)
					(mid -0.6096 0)
					(end 0.6096 0)
				)
			)
			(stroke
				(width 0)
				(type default)
			)
			(fill no)
			(layer "F.Fab")
		)
		(pad "1" smd circle
			(at 0 0)
			(size 0.7112 0.7112)
			(layers "F.Cu" "F.Mask" "F.Paste")
			(net "SXP_ACTIVE_0")
		)
	)
	(footprint ""
		(layer "F.Cu")
		(at 164.719 -101.473 180)
		(property "Reference" "PC180"
			(at 0 0 180)
			(layer "F.SilkS")
			(hide yes)
			(effects
				(font
					(size 1.27 1.27)
				)
			)
		)
		(property "Value" "SC47U6D3V5MX-1-GP"
			(at -0.0762 -6.1214 180)
			(unlocked yes)
			(layer "F.Fab")
			(hide yes)
			(effects
				(font
					(size 1.016 1.016)
					(thickness 0.1524)
				)
			)
		)
		(property "Device Type" "C805H54"
			(at -0.0762 -8.1534 180)
			(unlocked yes)
			(layer "F.Fab")
			(hide yes)
			(effects
				(font
					(size 1.016 1.016)
					(thickness 0.1524)
				)
			)
		)
		(duplicate_pad_numbers_are_jumpers no)
		(fp_line
			(start 0.635 0)
			(end -0.635 0)
			(stroke
				(width 0.508)
				(type default)
			)
			(layer "F.SilkS")
		)
		(fp_rect
			(start -0.9652 1.778)
			(end 0.9652 -1.778)
			(stroke
				(width 0)
				(type default)
			)
			(fill no)
			(layer "F.CrtYd")
		)
		(fp_poly
			(pts
				(xy -0.9652 -1.778) (xy 0.9652 -1.778) (xy 0.9652 1.778) (xy -0.9652 1.778)
			)
			(stroke
				(width 0)
				(type default)
			)
			(fill no)
			(layer "F.Fab")
		)
		(pad "1" smd rect
			(at 0 -0.9652 180)
			(size 1.397 1.143)
			(layers "F.Cu" "F.Mask" "F.Paste")
			(net "P0V9_E")
		)
		(pad "2" smd rect
			(at 0 0.9652 180)
			(size 1.397 1.143)
			(layers "F.Cu" "F.Mask" "F.Paste")
			(net "GND")
		)
	)
	(footprint ""
		(layer "F.Cu")
		(at 331.851 -218.059 -90)
		(property "Reference" "C145"
			(at 0 0 270)
			(layer "F.SilkS")
			(hide yes)
			(effects
				(font
					(size 1.27 1.27)
				)
			)
		)
		(property "Value" "SC1U10V2KX-4-GP"
			(at 1.1811 -2.7051 270)
			(unlocked yes)
			(layer "F.Fab")
			(hide yes)
			(effects
				(font
					(size 1.016 1.016)
					(thickness 0.1524)
				)
			)
		)
		(property "Device Type" "C402H22"
			(at 1.1811 -4.2291 270)
			(unlocked yes)
			(layer "F.Fab")
			(hide yes)
			(effects
				(font
					(size 1.016 1.016)
					(thickness 0.1524)
				)
			)
		)
		(duplicate_pad_numbers_are_jumpers no)
		(fp_rect
			(start -0.4318 0.9525)
			(end 0.4318 -0.9525)
			(stroke
				(width 0)
				(type default)
			)
			(fill no)
			(layer "F.CrtYd")
		)
		(fp_rect
			(start -0.4318 0.9525)
			(end 0.4318 -0.9525)
			(stroke
				(width 0)
				(type default)
			)
			(fill no)
			(layer "F.Fab")
		)
		(pad "1" smd custom
			(at 0 -0.4445 270)
			(size 0.1524 0.1524)
			(layers "F.Cu" "F.Mask" "F.Paste")
			(net "P3V3_STBY")
			(options
				(clearance outline)
				(anchor circle)
			)
			(primitives
				(gr_poly
					(pts
						(arc
							(start 0.3048 -0.2032)
							(mid 0.275042 -0.275042)
							(end 0.2032 -0.3048)
						)
						(arc
							(start -0.2032 -0.3048)
							(mid -0.275042 -0.275042)
							(end -0.3048 -0.2032)
						)
						(arc
							(start -0.3048 0.2032)
							(mid -0.275042 0.275042)
							(end -0.2032 0.3048)
						)
						(arc
							(start 0.2032 0.3048)
							(mid 0.275042 0.275042)
							(end 0.3048 0.2032)
						)
					)
					(width 0)
					(fill yes)
				)
			)
		)
		(pad "2" smd custom
			(at 0 0.4445 270)
			(size 0.1524 0.1524)
			(layers "F.Cu" "F.Mask" "F.Paste")
			(net "GND")
			(options
				(clearance outline)
				(anchor circle)
			)
			(primitives
				(gr_poly
					(pts
						(arc
							(start 0.3048 -0.2032)
							(mid 0.275042 -0.275042)
							(end 0.2032 -0.3048)
						)
						(arc
							(start -0.2032 -0.3048)
							(mid -0.275042 -0.275042)
							(end -0.3048 -0.2032)
						)
						(arc
							(start -0.3048 0.2032)
							(mid -0.275042 0.275042)
							(end -0.2032 0.3048)
						)
						(arc
							(start 0.2032 0.3048)
							(mid 0.275042 0.275042)
							(end 0.3048 0.2032)
						)
					)
					(width 0)
					(fill yes)
				)
			)
		)
	)
	(footprint ""
		(layer "F.Cu")
		(at 87.865966 -88.011 180)
		(property "Reference" "SC1149"
			(at 0 0 180)
			(layer "F.SilkS")
			(hide yes)
			(effects
				(font
					(size 1.27 1.27)
				)
			)
		)
		(property "Value" "SCD1U6D3V1KX-GP"
			(at -2.8321 -1.7399 180)
			(unlocked yes)
			(layer "F.Fab")
			(hide yes)
			(effects
				(font
					(size 1.016 1.016)
					(thickness 0.1524)
				)
			)
		)
		(property "Device Type" "C0201H13"
			(at -2.8321 -3.2639 180)
			(unlocked yes)
			(layer "F.Fab")
			(hide yes)
			(effects
				(font
					(size 1.016 1.016)
					(thickness 0.1524)
				)
			)
		)
		(duplicate_pad_numbers_are_jumpers no)
		(fp_rect
			(start -0.2794 0.6477)
			(end 0.2794 -0.6477)
			(stroke
				(width 0)
				(type default)
			)
			(fill no)
			(layer "F.CrtYd")
		)
		(fp_rect
			(start -0.2794 0.6477)
			(end 0.2794 -0.6477)
			(stroke
				(width 0)
				(type default)
			)
			(fill no)
			(layer "F.Fab")
		)
		(pad "1" smd custom
			(at 0 -0.2794 180)
			(size 0.0762 0.0762)
			(layers "F.Cu" "F.Mask" "F.Paste")
			(net "SYSPLL_VDDA18")
			(options
				(clearance outline)
				(anchor circle)
			)
			(primitives
				(gr_poly
					(pts
						(arc
							(start 0.1524 -0.127)
							(mid 0.137521 -0.162921)
							(end 0.1016 -0.1778)
						)
						(arc
							(start -0.1016 -0.1778)
							(mid -0.137521 -0.162921)
							(end -0.1524 -0.127)
						)
						(arc
							(start -0.1524 0.127)
							(mid -0.137521 0.162921)
							(end -0.1016 0.1778)
						)
						(arc
							(start 0.1016 0.1778)
							(mid 0.137521 0.162921)
							(end 0.1524 0.127)
						)
					)
					(width 0)
					(fill yes)
				)
			)
		)
		(pad "2" smd custom
			(at 0 0.2794 180)
			(size 0.0762 0.0762)
			(layers "F.Cu" "F.Mask" "F.Paste")
			(net "GND")
			(options
				(clearance outline)
				(anchor circle)
			)
			(primitives
				(gr_poly
					(pts
						(arc
							(start 0.1524 -0.127)
							(mid 0.137521 -0.162921)
							(end 0.1016 -0.1778)
						)
						(arc
							(start -0.1016 -0.1778)
							(mid -0.137521 -0.162921)
							(end -0.1524 -0.127)
						)
						(arc
							(start -0.1524 0.127)
							(mid -0.137521 0.162921)
							(end -0.1016 0.1778)
						)
						(arc
							(start 0.1016 0.1778)
							(mid 0.137521 0.162921)
							(end 0.1524 0.127)
						)
					)
					(width 0)
					(fill yes)
				)
			)
		)
	)
	(footprint ""
		(layer "F.Cu")
		(at 68.707 -54.102 180)
		(property "Reference" "SC967"
			(at 0 0 180)
			(layer "F.SilkS")
			(hide yes)
			(effects
				(font
					(size 1.27 1.27)
				)
			)
		)
		(property "Value" "SC1U10V2KX-4-GP"
			(at 1.1811 -2.7051 180)
			(unlocked yes)
			(layer "F.Fab")
			(hide yes)
			(effects
				(font
					(size 1.016 1.016)
					(thickness 0.1524)
				)
			)
		)
		(property "Device Type" "C402H22"
			(at 1.1811 -4.2291 180)
			(unlocked yes)
			(layer "F.Fab")
			(hide yes)
			(effects
				(font
					(size 1.016 1.016)
					(thickness 0.1524)
				)
			)
		)
		(duplicate_pad_numbers_are_jumpers no)
		(fp_rect
			(start -0.4318 0.9525)
			(end 0.4318 -0.9525)
			(stroke
				(width 0)
				(type default)
			)
			(fill no)
			(layer "F.CrtYd")
		)
		(fp_rect
			(start -0.4318 0.9525)
			(end 0.4318 -0.9525)
			(stroke
				(width 0)
				(type default)
			)
			(fill no)
			(layer "F.Fab")
		)
		(pad "1" smd custom
			(at 0 -0.4445 180)
			(size 0.1524 0.1524)
			(layers "F.Cu" "F.Mask" "F.Paste")
			(net "P1V8_C")
			(options
				(clearance outline)
				(anchor circle)
			)
			(primitives
				(gr_poly
					(pts
						(arc
							(start 0.3048 -0.2032)
							(mid 0.275042 -0.275042)
							(end 0.2032 -0.3048)
						)
						(arc
							(start -0.2032 -0.3048)
							(mid -0.275042 -0.275042)
							(end -0.3048 -0.2032)
						)
						(arc
							(start -0.3048 0.2032)
							(mid -0.275042 0.275042)
							(end -0.2032 0.3048)
						)
						(arc
							(start 0.2032 0.3048)
							(mid 0.275042 0.275042)
							(end 0.3048 0.2032)
						)
					)
					(width 0)
					(fill yes)
				)
			)
		)
		(pad "2" smd custom
			(at 0 0.4445 180)
			(size 0.1524 0.1524)
			(layers "F.Cu" "F.Mask" "F.Paste")
			(net "GND")
			(options
				(clearance outline)
				(anchor circle)
			)
			(primitives
				(gr_poly
					(pts
						(arc
							(start 0.3048 -0.2032)
							(mid 0.275042 -0.275042)
							(end 0.2032 -0.3048)
						)
						(arc
							(start -0.2032 -0.3048)
							(mid -0.275042 -0.275042)
							(end -0.3048 -0.2032)
						)
						(arc
							(start -0.3048 0.2032)
							(mid -0.275042 0.275042)
							(end -0.2032 0.3048)
						)
						(arc
							(start 0.2032 0.3048)
							(mid 0.275042 0.275042)
							(end 0.3048 0.2032)
						)
					)
					(width 0)
					(fill yes)
				)
			)
		)
	)
	(footprint ""
		(layer "F.Cu")
		(at 53.218842 -132.380482 90)
		(property "Reference" "SR784"
			(at 0 0 90)
			(layer "F.SilkS")
			(hide yes)
			(effects
				(font
					(size 1.27 1.27)
				)
			)
		)
		(property "Value" "10KR2F-2-GP"
			(at 0.064008 -3.993896 90)
			(unlocked yes)
			(layer "F.Fab")
			(hide yes)
			(effects
				(font
					(size 1.016 1.016)
					(thickness 0.1524)
				)
			)
		)
		(property "Device Type" "R402H16"
			(at 0.064008 -5.517896 90)
			(unlocked yes)
			(layer "F.Fab")
			(hide yes)
			(effects
				(font
					(size 1.016 1.016)
					(thickness 0.1524)
				)
			)
		)
		(duplicate_pad_numbers_are_jumpers no)
		(fp_line
			(start 0.508 -0.9398)
			(end -0.508 -0.9398)
			(stroke
				(width 0.1524)
				(type default)
			)
			(layer "F.SilkS")
		)
		(fp_line
			(start -0.508 -0.9398)
			(end -0.508 0.9398)
			(stroke
				(width 0.1524)
				(type default)
			)
			(layer "F.SilkS")
		)
		(fp_rect
			(start -0.508 0.9398)
			(end 0.508 -0.9398)
			(stroke
				(width 0)
				(type default)
			)
			(fill no)
			(layer "F.CrtYd")
		)
		(fp_rect
			(start -0.508 0.9398)
			(end 0.508 -0.9398)
			(stroke
				(width 0)
				(type default)
			)
			(fill no)
			(layer "F.Fab")
		)
		(pad "1" smd custom
			(at 0 -0.4445 90)
			(size 0.1397 0.1397)
			(layers "F.Cu" "F.Mask" "F.Paste")
			(net "P1V8_E")
			(options
				(clearance outline)
				(anchor circle)
			)
			(primitives
				(gr_poly
					(pts
						(arc
							(start -0.1778 -0.2794)
							(mid -0.249642 -0.249642)
							(end -0.2794 -0.1778)
						)
						(arc
							(start -0.2794 0.1778)
							(mid -0.249642 0.249642)
							(end -0.1778 0.2794)
						)
						(arc
							(start 0.1778 0.2794)
							(mid 0.249642 0.249642)
							(end 0.2794 0.1778)
						)
						(arc
							(start 0.2794 -0.1778)
							(mid 0.249642 -0.249642)
							(end 0.1778 -0.2794)
						)
					)
					(width 0)
					(fill yes)
				)
			)
		)
		(pad "2" smd custom
			(at 0 0.4445 90)
			(size 0.1397 0.1397)
			(layers "F.Cu" "F.Mask" "F.Paste")
			(net "EXP_WP_N")
			(options
				(clearance outline)
				(anchor circle)
			)
			(primitives
				(gr_poly
					(pts
						(arc
							(start -0.1778 -0.2794)
							(mid -0.249642 -0.249642)
							(end -0.2794 -0.1778)
						)
						(arc
							(start -0.2794 0.1778)
							(mid -0.249642 0.249642)
							(end -0.1778 0.2794)
						)
						(arc
							(start 0.1778 0.2794)
							(mid 0.249642 0.249642)
							(end 0.2794 0.1778)
						)
						(arc
							(start 0.2794 -0.1778)
							(mid 0.249642 -0.249642)
							(end 0.1778 -0.2794)
						)
					)
					(width 0)
					(fill yes)
				)
			)
		)
	)
	(footprint ""
		(layer "F.Cu")
		(at 19.508216 -181.91988 180)
		(property "Reference" "R650"
			(at 0 0 180)
			(layer "F.SilkS")
			(hide yes)
			(effects
				(font
					(size 1.27 1.27)
				)
			)
		)
		(property "Value" "4K7R2F-GP"
			(at 0.064008 -3.993896 180)
			(unlocked yes)
			(layer "F.Fab")
			(hide yes)
			(effects
				(font
					(size 1.016 1.016)
					(thickness 0.1524)
				)
			)
		)
		(property "Device Type" "R402H16"
			(at 0.064008 -5.517896 180)
			(unlocked yes)
			(layer "F.Fab")
			(hide yes)
			(effects
				(font
					(size 1.016 1.016)
					(thickness 0.1524)
				)
			)
		)
		(duplicate_pad_numbers_are_jumpers no)
		(fp_line
			(start 0.508 -0.9398)
			(end -0.508 -0.9398)
			(stroke
				(width 0.1524)
				(type default)
			)
			(layer "F.SilkS")
		)
		(fp_line
			(start -0.508 -0.9398)
			(end -0.508 0.9398)
			(stroke
				(width 0.1524)
				(type default)
			)
			(layer "F.SilkS")
		)
		(fp_rect
			(start -0.508 0.9398)
			(end 0.508 -0.9398)
			(stroke
				(width 0)
				(type default)
			)
			(fill no)
			(layer "F.CrtYd")
		)
		(fp_rect
			(start -0.508 0.9398)
			(end 0.508 -0.9398)
			(stroke
				(width 0)
				(type default)
			)
			(fill no)
			(layer "F.Fab")
		)
		(pad "1" smd custom
			(at 0 -0.4445 180)
			(size 0.1397 0.1397)
			(layers "F.Cu" "F.Mask" "F.Paste")
			(net "P3V3_STBY")
			(options
				(clearance outline)
				(anchor circle)
			)
			(primitives
				(gr_poly
					(pts
						(arc
							(start -0.1778 -0.2794)
							(mid -0.249642 -0.249642)
							(end -0.2794 -0.1778)
						)
						(arc
							(start -0.2794 0.1778)
							(mid -0.249642 0.249642)
							(end -0.1778 0.2794)
						)
						(arc
							(start 0.1778 0.2794)
							(mid 0.249642 0.249642)
							(end 0.2794 0.1778)
						)
						(arc
							(start 0.2794 -0.1778)
							(mid 0.249642 -0.249642)
							(end 0.1778 -0.2794)
						)
					)
					(width 0)
					(fill yes)
				)
			)
		)
		(pad "2" smd custom
			(at 0 0.4445 180)
			(size 0.1397 0.1397)
			(layers "F.Cu" "F.Mask" "F.Paste")
			(net "IO_EXP_HDD_PRE_A3")
			(options
				(clearance outline)
				(anchor circle)
			)
			(primitives
				(gr_poly
					(pts
						(arc
							(start -0.1778 -0.2794)
							(mid -0.249642 -0.249642)
							(end -0.2794 -0.1778)
						)
						(arc
							(start -0.2794 0.1778)
							(mid -0.249642 0.249642)
							(end -0.1778 0.2794)
						)
						(arc
							(start 0.1778 0.2794)
							(mid 0.249642 0.249642)
							(end 0.2794 0.1778)
						)
						(arc
							(start 0.2794 -0.1778)
							(mid 0.249642 -0.249642)
							(end 0.1778 -0.2794)
						)
					)
					(width 0)
					(fill yes)
				)
			)
		)
	)
	(footprint ""
		(layer "F.Cu")
		(at 292.481 -161.544)
		(property "Reference" "R612"
			(at 0 0 0)
			(layer "F.SilkS")
			(hide yes)
			(effects
				(font
					(size 1.27 1.27)
				)
			)
		)
		(property "Value" "0R2J-2-GP"
			(at 0.064008 -3.993896 0)
			(unlocked yes)
			(layer "F.Fab")
			(hide yes)
			(effects
				(font
					(size 1.016 1.016)
					(thickness 0.1524)
				)
			)
		)
		(property "Device Type" "R402H16"
			(at 0.064008 -5.517896 0)
			(unlocked yes)
			(layer "F.Fab")
			(hide yes)
			(effects
				(font
					(size 1.016 1.016)
					(thickness 0.1524)
				)
			)
		)
		(duplicate_pad_numbers_are_jumpers no)
		(fp_line
			(start -0.508 -0.9398)
			(end -0.508 0.9398)
			(stroke
				(width 0.1524)
				(type default)
			)
			(layer "F.SilkS")
		)
		(fp_line
			(start 0.508 -0.9398)
			(end -0.508 -0.9398)
			(stroke
				(width 0.1524)
				(type default)
			)
			(layer "F.SilkS")
		)
		(fp_rect
			(start -0.508 0.9398)
			(end 0.508 -0.9398)
			(stroke
				(width 0)
				(type default)
			)
			(fill no)
			(layer "F.CrtYd")
		)
		(fp_rect
			(start -0.508 0.9398)
			(end 0.508 -0.9398)
			(stroke
				(width 0)
				(type default)
			)
			(fill no)
			(layer "F.Fab")
		)
		(pad "1" smd custom
			(at 0 -0.4445)
			(size 0.1397 0.1397)
			(layers "F.Cu" "F.Mask" "F.Paste")
			(net "HDD_PRE_INT_R")
			(options
				(clearance outline)
				(anchor circle)
			)
			(primitives
				(gr_poly
					(pts
						(arc
							(start -0.1778 -0.2794)
							(mid -0.249642 -0.249642)
							(end -0.2794 -0.1778)
						)
						(arc
							(start -0.2794 0.1778)
							(mid -0.249642 0.249642)
							(end -0.1778 0.2794)
						)
						(arc
							(start 0.1778 0.2794)
							(mid 0.249642 0.249642)
							(end 0.2794 0.1778)
						)
						(arc
							(start 0.2794 -0.1778)
							(mid 0.249642 -0.249642)
							(end 0.1778 -0.2794)
						)
					)
					(width 0)
					(fill yes)
				)
			)
		)
		(pad "2" smd custom
			(at 0 0.4445)
			(size 0.1397 0.1397)
			(layers "F.Cu" "F.Mask" "F.Paste")
			(net "BMC_HDD_PRE_INT_N")
			(options
				(clearance outline)
				(anchor circle)
			)
			(primitives
				(gr_poly
					(pts
						(arc
							(start -0.1778 -0.2794)
							(mid -0.249642 -0.249642)
							(end -0.2794 -0.1778)
						)
						(arc
							(start -0.2794 0.1778)
							(mid -0.249642 0.249642)
							(end -0.1778 0.2794)
						)
						(arc
							(start 0.1778 0.2794)
							(mid 0.249642 0.249642)
							(end 0.2794 0.1778)
						)
						(arc
							(start 0.2794 -0.1778)
							(mid 0.249642 -0.249642)
							(end 0.1778 -0.2794)
						)
					)
					(width 0)
					(fill yes)
				)
			)
		)
	)
	(footprint ""
		(layer "F.Cu")
		(at 39.0652 -118.1862 -90)
		(property "Reference" "SC1301"
			(at 0 0 270)
			(layer "F.SilkS")
			(hide yes)
			(effects
				(font
					(size 1.27 1.27)
				)
			)
		)
		(property "Value" "SCD1U16V2KX-3GP"
			(at 1.1811 -2.7051 270)
			(unlocked yes)
			(layer "F.Fab")
			(hide yes)
			(effects
				(font
					(size 1.016 1.016)
					(thickness 0.1524)
				)
			)
		)
		(property "Device Type" "C402H22"
			(at 1.1811 -4.2291 270)
			(unlocked yes)
			(layer "F.Fab")
			(hide yes)
			(effects
				(font
					(size 1.016 1.016)
					(thickness 0.1524)
				)
			)
		)
		(duplicate_pad_numbers_are_jumpers no)
		(fp_rect
			(start -0.4318 0.9525)
			(end 0.4318 -0.9525)
			(stroke
				(width 0)
				(type default)
			)
			(fill no)
			(layer "F.CrtYd")
		)
		(fp_rect
			(start -0.4318 0.9525)
			(end 0.4318 -0.9525)
			(stroke
				(width 0)
				(type default)
			)
			(fill no)
			(layer "F.Fab")
		)
		(pad "1" smd custom
			(at 0 -0.4445 270)
			(size 0.1524 0.1524)
			(layers "F.Cu" "F.Mask" "F.Paste")
			(net "P3V3_STBY")
			(options
				(clearance outline)
				(anchor circle)
			)
			(primitives
				(gr_poly
					(pts
						(arc
							(start 0.3048 -0.2032)
							(mid 0.275042 -0.275042)
							(end 0.2032 -0.3048)
						)
						(arc
							(start -0.2032 -0.3048)
							(mid -0.275042 -0.275042)
							(end -0.3048 -0.2032)
						)
						(arc
							(start -0.3048 0.2032)
							(mid -0.275042 0.275042)
							(end -0.2032 0.3048)
						)
						(arc
							(start 0.2032 0.3048)
							(mid 0.275042 0.275042)
							(end 0.3048 0.2032)
						)
					)
					(width 0)
					(fill yes)
				)
			)
		)
		(pad "2" smd custom
			(at 0 0.4445 270)
			(size 0.1524 0.1524)
			(layers "F.Cu" "F.Mask" "F.Paste")
			(net "GND")
			(options
				(clearance outline)
				(anchor circle)
			)
			(primitives
				(gr_poly
					(pts
						(arc
							(start 0.3048 -0.2032)
							(mid 0.275042 -0.275042)
							(end 0.2032 -0.3048)
						)
						(arc
							(start -0.2032 -0.3048)
							(mid -0.275042 -0.275042)
							(end -0.3048 -0.2032)
						)
						(arc
							(start -0.3048 0.2032)
							(mid -0.275042 0.275042)
							(end -0.2032 0.3048)
						)
						(arc
							(start 0.2032 0.3048)
							(mid 0.275042 0.275042)
							(end 0.3048 0.2032)
						)
					)
					(width 0)
					(fill yes)
				)
			)
		)
	)
	(footprint ""
		(layer "F.Cu")
		(at 318.008 -161.29 -90)
		(property "Reference" "R310"
			(at 0 0 270)
			(layer "F.SilkS")
			(hide yes)
			(effects
				(font
					(size 1.27 1.27)
				)
			)
		)
		(property "Value" "10KR2F-2-GP"
			(at 0.064008 -3.993896 270)
			(unlocked yes)
			(layer "F.Fab")
			(hide yes)
			(effects
				(font
					(size 1.016 1.016)
					(thickness 0.1524)
				)
			)
		)
		(property "Device Type" "R402H16"
			(at 0.064008 -5.517896 270)
			(unlocked yes)
			(layer "F.Fab")
			(hide yes)
			(effects
				(font
					(size 1.016 1.016)
					(thickness 0.1524)
				)
			)
		)
		(duplicate_pad_numbers_are_jumpers no)
		(fp_line
			(start -0.508 -0.9398)
			(end -0.508 0.9398)
			(stroke
				(width 0.1524)
				(type default)
			)
			(layer "F.SilkS")
		)
		(fp_line
			(start 0.508 -0.9398)
			(end -0.508 -0.9398)
			(stroke
				(width 0.1524)
				(type default)
			)
			(layer "F.SilkS")
		)
		(fp_rect
			(start -0.508 0.9398)
			(end 0.508 -0.9398)
			(stroke
				(width 0)
				(type default)
			)
			(fill no)
			(layer "F.CrtYd")
		)
		(fp_rect
			(start -0.508 0.9398)
			(end 0.508 -0.9398)
			(stroke
				(width 0)
				(type default)
			)
			(fill no)
			(layer "F.Fab")
		)
		(pad "1" smd custom
			(at 0 -0.4445 270)
			(size 0.1397 0.1397)
			(layers "F.Cu" "F.Mask" "F.Paste")
			(net "P3V3_STBY")
			(options
				(clearance outline)
				(anchor circle)
			)
			(primitives
				(gr_poly
					(pts
						(arc
							(start -0.1778 -0.2794)
							(mid -0.249642 -0.249642)
							(end -0.2794 -0.1778)
						)
						(arc
							(start -0.2794 0.1778)
							(mid -0.249642 0.249642)
							(end -0.1778 0.2794)
						)
						(arc
							(start 0.1778 0.2794)
							(mid 0.249642 0.249642)
							(end 0.2794 0.1778)
						)
						(arc
							(start 0.2794 -0.1778)
							(mid 0.249642 -0.249642)
							(end 0.1778 -0.2794)
						)
					)
					(width 0)
					(fill yes)
				)
			)
		)
		(pad "2" smd custom
			(at 0 0.4445 270)
			(size 0.1397 0.1397)
			(layers "F.Cu" "F.Mask" "F.Paste")
			(net "PU_BMC0_SCL13")
			(options
				(clearance outline)
				(anchor circle)
			)
			(primitives
				(gr_poly
					(pts
						(arc
							(start -0.1778 -0.2794)
							(mid -0.249642 -0.249642)
							(end -0.2794 -0.1778)
						)
						(arc
							(start -0.2794 0.1778)
							(mid -0.249642 0.249642)
							(end -0.1778 0.2794)
						)
						(arc
							(start 0.1778 0.2794)
							(mid 0.249642 0.249642)
							(end 0.2794 0.1778)
						)
						(arc
							(start 0.2794 -0.1778)
							(mid 0.249642 -0.249642)
							(end 0.1778 -0.2794)
						)
					)
					(width 0)
					(fill yes)
				)
			)
		)
	)
	(footprint ""
		(layer "F.Cu")
		(at 283.582872 -221.052136)
		(property "Reference" "PU5"
			(at 0 0 0)
			(layer "F.SilkS")
			(hide yes)
			(effects
				(font
					(size 1.27 1.27)
				)
			)
		)
		(property "Value" "TPS74801RGW-GP"
			(at -4.7244 -6.223 0)
			(unlocked yes)
			(layer "F.Fab")
			(hide yes)
			(effects
				(font
					(size 1.016 1.016)
					(thickness 0.1524)
				)
			)
		)
		(property "Device Type" "QFN20-1G3D15H40"
			(at -4.7244 -7.747 0)
			(unlocked yes)
			(layer "F.Fab")
			(hide yes)
			(effects
				(font
					(size 1.016 1.016)
					(thickness 0.1524)
				)
			)
		)
		(duplicate_pad_numbers_are_jumpers no)
		(fp_line
			(start -3.5179 -3.5179)
			(end -3.5179 -2.2479)
			(stroke
				(width 0.1524)
				(type default)
			)
			(layer "F.SilkS")
		)
		(fp_line
			(start -3.5179 2.2479)
			(end -3.5179 3.5179)
			(stroke
				(width 0.1524)
				(type default)
			)
			(layer "F.SilkS")
		)
		(fp_line
			(start -3.5179 3.5179)
			(end -2.2479 3.5179)
			(stroke
				(width 0.1524)
				(type default)
			)
			(layer "F.SilkS")
		)
		(fp_line
			(start -3.160522 1.299972)
			(end -3.922522 1.299972)
			(stroke
				(width 0.1524)
				(type default)
			)
			(layer "F.SilkS")
		)
		(fp_line
			(start -2.2479 -3.5179)
			(end -3.5179 -3.5179)
			(stroke
				(width 0.1524)
				(type default)
			)
			(layer "F.SilkS")
		)
		(fp_line
			(start -1.299972 -3.160522)
			(end -1.299972 -3.668522)
			(stroke
				(width 0.1524)
				(type default)
			)
			(layer "F.SilkS")
		)
		(fp_line
			(start 1.299972 3.160522)
			(end 1.299972 3.668522)
			(stroke
				(width 0.1524)
				(type default)
			)
			(layer "F.SilkS")
		)
		(fp_line
			(start 2.2479 3.5179)
			(end 3.5179 3.5179)
			(stroke
				(width 0.1524)
				(type default)
			)
			(layer "F.SilkS")
		)
		(fp_line
			(start 3.160522 -1.299972)
			(end 3.922522 -1.299972)
			(stroke
				(width 0.1524)
				(type default)
			)
			(layer "F.SilkS")
		)
		(fp_line
			(start 3.5179 3.5179)
			(end 3.5179 2.2479)
			(stroke
				(width 0.1524)
				(type default)
			)
			(layer "F.SilkS")
		)
		(fp_poly
			(pts
				(xy 3.5179 -3.5179) (xy 2.2479 -3.5179) (xy 3.5179 -2.2479)
			)
			(stroke
				(width 0)
				(type default)
			)
			(fill yes)
			(layer "F.SilkS")
		)
		(fp_rect
			(start -2.5019 2.5019)
			(end 2.5019 -2.5019)
			(stroke
				(width 0)
				(type default)
			)
			(fill no)
			(layer "F.CrtYd")
		)
		(fp_poly
			(pts
				(xy -3.5179 3.5179) (xy -3.5179 -3.5179) (xy 3.5179 -3.5179) (xy 3.5179 -2.5019) (xy -2.5019 -2.5019)
				(xy -2.5019 2.5019) (xy 2.5019 2.5019) (xy 2.5019 -2.49682) (xy 3.5179 -2.49682) (xy 3.5179 3.5179)
			)
			(stroke
				(width 0)
				(type default)
			)
			(fill no)
			(layer "F.CrtYd")
		)
		(fp_rect
			(start -3.5179 3.5179)
			(end 3.5179 -3.5179)
			(stroke
				(width 0)
				(type default)
			)
			(fill no)
			(layer "F.Fab")
		)
		(pad "1" smd rect
			(at 1.299972 -2.474722)
			(size 0.3556 1.0668)
			(layers "F.Cu" "F.Mask" "F.Paste")
			(net "TPS74801_1V53_STBY_OUT")
		)
		(pad "2" smd rect
			(at 0.649986 -2.474722)
			(size 0.3556 1.0668)
			(layers "F.Cu" "F.Mask" "F.Paste")
			(net "GND")
		)
		(pad "3" smd rect
			(at 0 -2.474722)
			(size 0.3556 1.0668)
			(layers "F.Cu" "F.Mask" "F.Paste")
			(net "GND")
		)
		(pad "4" smd rect
			(at -0.649986 -2.474722)
			(size 0.3556 1.0668)
			(layers "F.Cu" "F.Mask" "F.Paste")
			(net "GND")
		)
		(pad "5" smd rect
			(at -1.299972 -2.474722)
			(size 0.3556 1.0668)
			(layers "F.Cu" "F.Mask" "F.Paste")
			(net "TPS74801_P1V53_STBY_IN")
		)
		(pad "6" smd rect
			(at -2.474722 -1.299972)
			(size 1.0668 0.3556)
			(layers "F.Cu" "F.Mask" "F.Paste")
			(net "TPS74801_P1V53_STBY_IN")
		)
		(pad "7" smd rect
			(at -2.474722 -0.649986)
			(size 1.0668 0.3556)
			(layers "F.Cu" "F.Mask" "F.Paste")
			(net "TPS74801_P1V53_STBY_IN")
		)
		(pad "8" smd rect
			(at -2.474722 0)
			(size 1.0668 0.3556)
			(layers "F.Cu" "F.Mask" "F.Paste")
			(net "TPS74801_P1V53_STBY_IN")
		)
		(pad "9" smd rect
			(at -2.474722 0.649986)
			(size 1.0668 0.3556)
			(layers "F.Cu" "F.Mask" "F.Paste")
			(net "P1V53_STBY_PG")
		)
		(pad "10" smd rect
			(at -2.474722 1.299972)
			(size 1.0668 0.3556)
			(layers "F.Cu" "F.Mask" "F.Paste")
			(net "TPS74801_1V53_STBY_BIAS")
		)
		(pad "11" smd rect
			(at -1.299972 2.474722)
			(size 0.3556 1.0668)
			(layers "F.Cu" "F.Mask" "F.Paste")
			(net "TPS74801_1V53_STBY_EN")
		)
		(pad "12" smd rect
			(at -0.649986 2.474722)
			(size 0.3556 1.0668)
			(layers "F.Cu" "F.Mask" "F.Paste")
			(net "GND")
		)
		(pad "13" smd rect
			(at 0 2.474722)
			(size 0.3556 1.0668)
			(layers "F.Cu" "F.Mask" "F.Paste")
			(net "GND")
		)
		(pad "14" smd rect
			(at 0.649986 2.474722)
			(size 0.3556 1.0668)
			(layers "F.Cu" "F.Mask" "F.Paste")
			(net "GND")
		)
		(pad "15" smd rect
			(at 1.299972 2.474722)
			(size 0.3556 1.0668)
			(layers "F.Cu" "F.Mask" "F.Paste")
			(net "TPS74801_1V53_STBY_SS")
		)
		(pad "16" smd rect
			(at 2.474722 1.299972)
			(size 1.0668 0.3556)
			(layers "F.Cu" "F.Mask" "F.Paste")
			(net "TPS74801_1V53_STBY_FB")
		)
		(pad "17" smd rect
			(at 2.474722 0.649986)
			(size 1.0668 0.3556)
			(layers "F.Cu" "F.Mask" "F.Paste")
			(net "GND")
		)
		(pad "18" smd rect
			(at 2.474722 0)
			(size 1.0668 0.3556)
			(layers "F.Cu" "F.Mask" "F.Paste")
			(net "TPS74801_1V53_STBY_OUT")
		)
		(pad "19" smd rect
			(at 2.474722 -0.649986)
			(size 1.0668 0.3556)
			(layers "F.Cu" "F.Mask" "F.Paste")
			(net "TPS74801_1V53_STBY_OUT")
		)
		(pad "20" smd rect
			(at 2.474722 -1.299972)
			(size 1.0668 0.3556)
			(layers "F.Cu" "F.Mask" "F.Paste")
			(net "TPS74801_1V53_STBY_OUT")
		)
		(pad "21" smd rect
			(at 0 0)
			(size 3.2512 3.2512)
			(layers "F.Cu" "F.Mask" "F.Paste")
			(net "GND")
		)
	)
	(footprint ""
		(layer "F.Cu")
		(at 199.898 -227.838 90)
		(property "Reference" "C370"
			(at 0 0 90)
			(layer "F.SilkS")
			(hide yes)
			(effects
				(font
					(size 1.27 1.27)
				)
			)
		)
		(property "Value" "SC1U6D3V3KX-2GP"
			(at 0 -2.8194 90)
			(unlocked yes)
			(layer "F.Fab")
			(hide yes)
			(effects
				(font
					(size 1.016 1.016)
					(thickness 0.1524)
				)
			)
		)
		(property "Device Type" "C603H36"
			(at 0 -4.3434 90)
			(unlocked yes)
			(layer "F.Fab")
			(hide yes)
			(effects
				(font
					(size 1.016 1.016)
					(thickness 0.1524)
				)
			)
		)
		(duplicate_pad_numbers_are_jumpers no)
		(fp_line
			(start 0.508 0)
			(end -0.508 0)
			(stroke
				(width 0.2032)
				(type default)
			)
			(layer "F.SilkS")
		)
		(fp_rect
			(start -0.5842 1.3335)
			(end 0.5842 -1.3335)
			(stroke
				(width 0)
				(type default)
			)
			(fill no)
			(layer "F.CrtYd")
		)
		(fp_rect
			(start -0.5842 1.3335)
			(end 0.5842 -1.3335)
			(stroke
				(width 0)
				(type default)
			)
			(fill no)
			(layer "F.Fab")
		)
		(pad "1" smd custom
			(at 0 -0.762 90)
			(size 0.2159 0.2159)
			(layers "F.Cu" "F.Mask" "F.Paste")
			(net "P3V3_STBY")
			(options
				(clearance outline)
				(anchor circle)
			)
			(primitives
				(gr_poly
					(pts
						(arc
							(start -0.3302 -0.4318)
							(mid -0.402042 -0.402042)
							(end -0.4318 -0.3302)
						)
						(arc
							(start -0.4318 0.3302)
							(mid -0.402042 0.402042)
							(end -0.3302 0.4318)
						)
						(arc
							(start 0.3302 0.4318)
							(mid 0.402042 0.402042)
							(end 0.4318 0.3302)
						)
						(arc
							(start 0.4318 -0.3302)
							(mid 0.402042 -0.402042)
							(end 0.3302 -0.4318)
						)
					)
					(width 0)
					(fill yes)
				)
			)
		)
		(pad "2" smd custom
			(at 0 0.762 90)
			(size 0.2159 0.2159)
			(layers "F.Cu" "F.Mask" "F.Paste")
			(net "GND")
			(options
				(clearance outline)
				(anchor circle)
			)
			(primitives
				(gr_poly
					(pts
						(arc
							(start -0.3302 -0.4318)
							(mid -0.402042 -0.402042)
							(end -0.4318 -0.3302)
						)
						(arc
							(start -0.4318 0.3302)
							(mid -0.402042 0.402042)
							(end -0.3302 0.4318)
						)
						(arc
							(start 0.3302 0.4318)
							(mid 0.402042 0.402042)
							(end 0.4318 0.3302)
						)
						(arc
							(start 0.4318 -0.3302)
							(mid 0.402042 -0.402042)
							(end 0.3302 -0.4318)
						)
					)
					(width 0)
					(fill yes)
				)
			)
		)
	)
	(footprint ""
		(layer "F.Cu")
		(at 80.118966 -67.564 180)
		(property "Reference" "SC984"
			(at 0 0 180)
			(layer "F.SilkS")
			(hide yes)
			(effects
				(font
					(size 1.27 1.27)
				)
			)
		)
		(property "Value" "SCD1U16V2KX-3GP"
			(at 1.1811 -2.7051 180)
			(unlocked yes)
			(layer "F.Fab")
			(hide yes)
			(effects
				(font
					(size 1.016 1.016)
					(thickness 0.1524)
				)
			)
		)
		(property "Device Type" "C402H22"
			(at 1.1811 -4.2291 180)
			(unlocked yes)
			(layer "F.Fab")
			(hide yes)
			(effects
				(font
					(size 1.016 1.016)
					(thickness 0.1524)
				)
			)
		)
		(duplicate_pad_numbers_are_jumpers no)
		(fp_rect
			(start -0.4318 0.9525)
			(end 0.4318 -0.9525)
			(stroke
				(width 0)
				(type default)
			)
			(fill no)
			(layer "F.CrtYd")
		)
		(fp_rect
			(start -0.4318 0.9525)
			(end 0.4318 -0.9525)
			(stroke
				(width 0)
				(type default)
			)
			(fill no)
			(layer "F.Fab")
		)
		(pad "1" smd custom
			(at 0 -0.4445 180)
			(size 0.1524 0.1524)
			(layers "F.Cu" "F.Mask" "F.Paste")
			(net "P1V8_C")
			(options
				(clearance outline)
				(anchor circle)
			)
			(primitives
				(gr_poly
					(pts
						(arc
							(start 0.3048 -0.2032)
							(mid 0.275042 -0.275042)
							(end 0.2032 -0.3048)
						)
						(arc
							(start -0.2032 -0.3048)
							(mid -0.275042 -0.275042)
							(end -0.3048 -0.2032)
						)
						(arc
							(start -0.3048 0.2032)
							(mid -0.275042 0.275042)
							(end -0.2032 0.3048)
						)
						(arc
							(start 0.2032 0.3048)
							(mid 0.275042 0.275042)
							(end 0.3048 0.2032)
						)
					)
					(width 0)
					(fill yes)
				)
			)
		)
		(pad "2" smd custom
			(at 0 0.4445 180)
			(size 0.1524 0.1524)
			(layers "F.Cu" "F.Mask" "F.Paste")
			(net "GND")
			(options
				(clearance outline)
				(anchor circle)
			)
			(primitives
				(gr_poly
					(pts
						(arc
							(start 0.3048 -0.2032)
							(mid 0.275042 -0.275042)
							(end 0.2032 -0.3048)
						)
						(arc
							(start -0.2032 -0.3048)
							(mid -0.275042 -0.275042)
							(end -0.3048 -0.2032)
						)
						(arc
							(start -0.3048 0.2032)
							(mid -0.275042 0.275042)
							(end -0.2032 0.3048)
						)
						(arc
							(start 0.2032 0.3048)
							(mid 0.275042 0.275042)
							(end 0.3048 0.2032)
						)
					)
					(width 0)
					(fill yes)
				)
			)
		)
	)
	(footprint ""
		(layer "F.Cu")
		(at 43.75023 -132.2705 -90)
		(property "Reference" "SQ13"
			(at 0 0 270)
			(layer "F.SilkS")
			(hide yes)
			(effects
				(font
					(size 1.27 1.27)
				)
			)
		)
		(property "Value" "2N7002A-7-GP"
			(at 0.127 -8.9662 270)
			(unlocked yes)
			(layer "F.Fab")
			(hide yes)
			(effects
				(font
					(size 1.016 1.016)
					(thickness 0.1524)
				)
			)
		)
		(property "Device Type" "SOT23DGS2D4H48"
			(at 0.127 -10.4902 270)
			(unlocked yes)
			(layer "F.Fab")
			(hide yes)
			(effects
				(font
					(size 1.016 1.016)
					(thickness 0.1524)
				)
			)
		)
		(duplicate_pad_numbers_are_jumpers no)
		(fp_line
			(start -1.651 1.778)
			(end 1.651 1.778)
			(stroke
				(width 0.1524)
				(type default)
			)
			(layer "F.SilkS")
		)
		(fp_line
			(start 1.651 1.778)
			(end 1.651 -1.778)
			(stroke
				(width 0.1524)
				(type default)
			)
			(layer "F.SilkS")
		)
		(fp_line
			(start -1.651 -1.778)
			(end -1.651 1.778)
			(stroke
				(width 0.1524)
				(type default)
			)
			(layer "F.SilkS")
		)
		(fp_line
			(start 1.651 -1.778)
			(end -1.651 -1.778)
			(stroke
				(width 0.1524)
				(type default)
			)
			(layer "F.SilkS")
		)
		(fp_poly
			(pts
				(xy -1.778 1.8796) (xy -1.778 -1.8796) (xy 1.778 -1.8796) (xy 1.778 1.8796)
			)
			(stroke
				(width 0)
				(type default)
			)
			(fill no)
			(layer "F.CrtYd")
		)
		(fp_poly
			(pts
				(xy -1.778 1.8796) (xy -1.778 -1.8796) (xy 1.778 -1.8796) (xy 1.778 1.8796)
			)
			(stroke
				(width 0)
				(type default)
			)
			(fill no)
			(layer "F.Fab")
		)
		(pad "D" smd custom
			(at 0 -0.9525 270)
			(size 0.1905 0.1905)
			(layers "F.Cu" "F.Mask" "F.Paste")
			(net "EXP_RST_R")
			(options
				(clearance outline)
				(anchor circle)
			)
			(primitives
				(gr_poly
					(pts
						(arc
							(start -0.1778 0.5715)
							(mid -0.321484 0.511984)
							(end -0.381 0.3683)
						)
						(arc
							(start -0.381 -0.3683)
							(mid -0.321484 -0.511984)
							(end -0.1778 -0.5715)
						)
						(arc
							(start 0.1778 -0.5715)
							(mid 0.321484 -0.511984)
							(end 0.381 -0.3683)
						)
						(arc
							(start 0.381 0.3683)
							(mid 0.321484 0.511984)
							(end 0.1778 0.5715)
						)
					)
					(width 0)
					(fill yes)
				)
			)
		)
		(pad "G" smd custom
			(at -0.98425 0.9525 270)
			(size 0.1905 0.1905)
			(layers "F.Cu" "F.Mask" "F.Paste")
			(net "P3V3_STBY_G5")
			(options
				(clearance outline)
				(anchor circle)
			)
			(primitives
				(gr_poly
					(pts
						(arc
							(start -0.1778 0.5715)
							(mid -0.321484 0.511984)
							(end -0.381 0.3683)
						)
						(arc
							(start -0.381 -0.3683)
							(mid -0.321484 -0.511984)
							(end -0.1778 -0.5715)
						)
						(arc
							(start 0.1778 -0.5715)
							(mid 0.321484 -0.511984)
							(end 0.381 -0.3683)
						)
						(arc
							(start 0.381 0.3683)
							(mid 0.321484 0.511984)
							(end 0.1778 0.5715)
						)
					)
					(width 0)
					(fill yes)
				)
			)
		)
		(pad "S" smd custom
			(at 0.98425 0.9525 270)
			(size 0.1905 0.1905)
			(layers "F.Cu" "F.Mask" "F.Paste")
			(net "GND")
			(options
				(clearance outline)
				(anchor circle)
			)
			(primitives
				(gr_poly
					(pts
						(arc
							(start -0.1778 0.5715)
							(mid -0.321484 0.511984)
							(end -0.381 0.3683)
						)
						(arc
							(start -0.381 -0.3683)
							(mid -0.321484 -0.511984)
							(end -0.1778 -0.5715)
						)
						(arc
							(start 0.1778 -0.5715)
							(mid 0.321484 -0.511984)
							(end 0.381 -0.3683)
						)
						(arc
							(start 0.381 0.3683)
							(mid 0.321484 0.511984)
							(end 0.1778 0.5715)
						)
					)
					(width 0)
					(fill yes)
				)
			)
		)
	)
	(footprint ""
		(layer "F.Cu")
		(at 202.565 -138.811 -90)
		(property "Reference" "SR758"
			(at 0 0 270)
			(layer "F.SilkS")
			(hide yes)
			(effects
				(font
					(size 1.27 1.27)
				)
			)
		)
		(property "Value" "4K7R2F-GP"
			(at 0.064008 -3.993896 270)
			(unlocked yes)
			(layer "F.Fab")
			(hide yes)
			(effects
				(font
					(size 1.016 1.016)
					(thickness 0.1524)
				)
			)
		)
		(property "Device Type" "R402H16"
			(at 0.064008 -5.517896 270)
			(unlocked yes)
			(layer "F.Fab")
			(hide yes)
			(effects
				(font
					(size 1.016 1.016)
					(thickness 0.1524)
				)
			)
		)
		(duplicate_pad_numbers_are_jumpers no)
		(fp_line
			(start -0.508 -0.9398)
			(end -0.508 0.9398)
			(stroke
				(width 0.1524)
				(type default)
			)
			(layer "F.SilkS")
		)
		(fp_line
			(start 0.508 -0.9398)
			(end -0.508 -0.9398)
			(stroke
				(width 0.1524)
				(type default)
			)
			(layer "F.SilkS")
		)
		(fp_rect
			(start -0.508 0.9398)
			(end 0.508 -0.9398)
			(stroke
				(width 0)
				(type default)
			)
			(fill no)
			(layer "F.CrtYd")
		)
		(fp_rect
			(start -0.508 0.9398)
			(end 0.508 -0.9398)
			(stroke
				(width 0)
				(type default)
			)
			(fill no)
			(layer "F.Fab")
		)
		(pad "1" smd custom
			(at 0 -0.4445 270)
			(size 0.1397 0.1397)
			(layers "F.Cu" "F.Mask" "F.Paste")
			(net "P1V8_E")
			(options
				(clearance outline)
				(anchor circle)
			)
			(primitives
				(gr_poly
					(pts
						(arc
							(start -0.1778 -0.2794)
							(mid -0.249642 -0.249642)
							(end -0.2794 -0.1778)
						)
						(arc
							(start -0.2794 0.1778)
							(mid -0.249642 0.249642)
							(end -0.1778 0.2794)
						)
						(arc
							(start 0.1778 0.2794)
							(mid 0.249642 0.249642)
							(end 0.2794 0.1778)
						)
						(arc
							(start 0.2794 -0.1778)
							(mid 0.249642 -0.249642)
							(end 0.1778 -0.2794)
						)
					)
					(width 0)
					(fill yes)
				)
			)
		)
		(pad "2" smd custom
			(at 0 0.4445 270)
			(size 0.1397 0.1397)
			(layers "F.Cu" "F.Mask" "F.Paste")
			(net "EXP_EEPROM_A0")
			(options
				(clearance outline)
				(anchor circle)
			)
			(primitives
				(gr_poly
					(pts
						(arc
							(start -0.1778 -0.2794)
							(mid -0.249642 -0.249642)
							(end -0.2794 -0.1778)
						)
						(arc
							(start -0.2794 0.1778)
							(mid -0.249642 0.249642)
							(end -0.1778 0.2794)
						)
						(arc
							(start 0.1778 0.2794)
							(mid 0.249642 0.249642)
							(end 0.2794 0.1778)
						)
						(arc
							(start 0.2794 -0.1778)
							(mid 0.249642 -0.249642)
							(end 0.1778 -0.2794)
						)
					)
					(width 0)
					(fill yes)
				)
			)
		)
	)
	(footprint ""
		(layer "F.Cu")
		(at 103.378 -236.855)
		(property "Reference" "SU18"
			(at 0 0 0)
			(layer "F.SilkS")
			(hide yes)
			(effects
				(font
					(size 1.27 1.27)
				)
			)
		)
		(property "Value" "PI3C3861-AQE-GP"
			(at 0 -13.1572 0)
			(unlocked yes)
			(layer "F.Fab")
			(hide yes)
			(effects
				(font
					(size 1.016 1.016)
					(thickness 0.1524)
				)
			)
		)
		(property "Device Type" "QSOIC24H69"
			(at 0 -15.1892 0)
			(unlocked yes)
			(layer "F.Fab")
			(hide yes)
			(effects
				(font
					(size 1.016 1.016)
					(thickness 0.1524)
				)
			)
		)
		(duplicate_pad_numbers_are_jumpers no)
		(fp_line
			(start -4.4958 -1.5748)
			(end 3.5814 -1.5748)
			(stroke
				(width 0.1524)
				(type default)
			)
			(layer "F.SilkS")
		)
		(fp_line
			(start -4.4958 -0.4318)
			(end -4.4958 -1.5748)
			(stroke
				(width 0.1524)
				(type default)
			)
			(layer "F.SilkS")
		)
		(fp_line
			(start -4.4958 -0.4318)
			(end -4.064 0)
			(stroke
				(width 0.1524)
				(type default)
			)
			(layer "F.SilkS")
		)
		(fp_line
			(start -4.4958 0.4318)
			(end -4.4958 -0.4318)
			(stroke
				(width 0.1524)
				(type default)
			)
			(layer "F.SilkS")
		)
		(fp_line
			(start -4.4958 0.4318)
			(end -4.4958 1.5748)
			(stroke
				(width 0.1524)
				(type default)
			)
			(layer "F.SilkS")
		)
		(fp_line
			(start -4.318 1.5748)
			(end -4.318 3.556)
			(stroke
				(width 0.508)
				(type default)
			)
			(layer "F.SilkS")
		)
		(fp_line
			(start -4.064 0)
			(end -4.4958 0.4318)
			(stroke
				(width 0.1524)
				(type default)
			)
			(layer "F.SilkS")
		)
		(fp_line
			(start 3.5814 -1.5748)
			(end 3.5814 1.5748)
			(stroke
				(width 0.1524)
				(type default)
			)
			(layer "F.SilkS")
		)
		(fp_line
			(start 3.5814 1.5748)
			(end -4.4958 1.5748)
			(stroke
				(width 0.1524)
				(type default)
			)
			(layer "F.SilkS")
		)
		(fp_line
			(start 3.5814 1.5748)
			(end 3.5814 -1.5748)
			(stroke
				(width 0.1524)
				(type default)
			)
			(layer "F.SilkS")
		)
		(fp_poly
			(pts
				(xy -3.683 -1.5748) (xy 3.5814 -1.5748) (xy 3.5814 1.5748) (xy -3.683 1.5748)
			)
			(stroke
				(width 0)
				(type default)
			)
			(fill yes)
			(layer "F.SilkS")
		)
		(fp_rect
			(start -4.572 3.81)
			(end 4.572 -3.81)
			(stroke
				(width 0)
				(type default)
			)
			(fill no)
			(layer "F.CrtYd")
		)
		(fp_poly
			(pts
				(xy -4.572 -3.81) (xy 4.572 -3.81) (xy 4.572 3.81) (xy -4.572 3.81)
			)
			(stroke
				(width 0)
				(type default)
			)
			(fill no)
			(layer "F.Fab")
		)
		(pad "1" smd rect
			(at -3.4925 2.6162)
			(size 0.3556 1.524)
			(layers "F.Cu" "F.Mask" "F.Paste")
			(net "Net_163")
		)
		(pad "2" smd rect
			(at -2.8575 2.6162)
			(size 0.3556 1.524)
			(layers "F.Cu" "F.Mask" "F.Paste")
			(net "SAS_HDD_LED_0")
		)
		(pad "3" smd rect
			(at -2.2225 2.6162)
			(size 0.3556 1.524)
			(layers "F.Cu" "F.Mask" "F.Paste")
			(net "SAS_HDD_LED_1")
		)
		(pad "4" smd rect
			(at -1.5875 2.6162)
			(size 0.3556 1.524)
			(layers "F.Cu" "F.Mask" "F.Paste")
			(net "SAS_HDD_LED_2")
		)
		(pad "5" smd rect
			(at -0.9525 2.6162)
			(size 0.3556 1.524)
			(layers "F.Cu" "F.Mask" "F.Paste")
			(net "SAS_HDD_LED_3")
		)
		(pad "6" smd rect
			(at -0.3175 2.6162)
			(size 0.3556 1.524)
			(layers "F.Cu" "F.Mask" "F.Paste")
			(net "SAS_HDD_LED_4")
		)
		(pad "7" smd rect
			(at 0.3175 2.6162)
			(size 0.3556 1.524)
			(layers "F.Cu" "F.Mask" "F.Paste")
			(net "SAS_HDD_LED_5")
		)
		(pad "8" smd rect
			(at 0.9525 2.6162)
			(size 0.3556 1.524)
			(layers "F.Cu" "F.Mask" "F.Paste")
			(net "SAS_HDD_LED_6")
		)
		(pad "9" smd rect
			(at 1.5875 2.6162)
			(size 0.3556 1.524)
			(layers "F.Cu" "F.Mask" "F.Paste")
			(net "SAS_HDD_LED_7")
		)
		(pad "10" smd rect
			(at 2.2225 2.6162)
			(size 0.3556 1.524)
			(layers "F.Cu" "F.Mask" "F.Paste")
			(net "SAS_HDD_LED_8")
		)
		(pad "11" smd rect
			(at 2.8575 2.6162)
			(size 0.3556 1.524)
			(layers "F.Cu" "F.Mask" "F.Paste")
			(net "SAS_HDD_LED_9")
		)
		(pad "12" smd rect
			(at 3.4925 2.6162)
			(size 0.3556 1.524)
			(layers "F.Cu" "F.Mask" "F.Paste")
			(net "GND")
		)
		(pad "13" smd rect
			(at 3.4925 -2.6162)
			(size 0.3556 1.524)
			(layers "F.Cu" "F.Mask" "F.Paste")
			(net "SAS_FAULT_LED9")
		)
		(pad "14" smd rect
			(at 2.8575 -2.6162)
			(size 0.3556 1.524)
			(layers "F.Cu" "F.Mask" "F.Paste")
			(net "SAS_FAULT_LED8")
		)
		(pad "15" smd rect
			(at 2.2225 -2.6162)
			(size 0.3556 1.524)
			(layers "F.Cu" "F.Mask" "F.Paste")
			(net "SAS_FAULT_LED7")
		)
		(pad "16" smd rect
			(at 1.5875 -2.6162)
			(size 0.3556 1.524)
			(layers "F.Cu" "F.Mask" "F.Paste")
			(net "SAS_FAULT_LED6")
		)
		(pad "17" smd rect
			(at 0.9525 -2.6162)
			(size 0.3556 1.524)
			(layers "F.Cu" "F.Mask" "F.Paste")
			(net "SAS_FAULT_LED5")
		)
		(pad "18" smd rect
			(at 0.3175 -2.6162)
			(size 0.3556 1.524)
			(layers "F.Cu" "F.Mask" "F.Paste")
			(net "SAS_FAULT_LED4")
		)
		(pad "19" smd rect
			(at -0.3175 -2.6162)
			(size 0.3556 1.524)
			(layers "F.Cu" "F.Mask" "F.Paste")
			(net "SAS_FAULT_LED3")
		)
		(pad "20" smd rect
			(at -0.9525 -2.6162)
			(size 0.3556 1.524)
			(layers "F.Cu" "F.Mask" "F.Paste")
			(net "SAS_FAULT_LED2")
		)
		(pad "21" smd rect
			(at -1.5875 -2.6162)
			(size 0.3556 1.524)
			(layers "F.Cu" "F.Mask" "F.Paste")
			(net "SAS_FAULT_LED1")
		)
		(pad "22" smd rect
			(at -2.2225 -2.6162)
			(size 0.3556 1.524)
			(layers "F.Cu" "F.Mask" "F.Paste")
			(net "SAS_FAULT_LED0")
		)
		(pad "23" smd rect
			(at -2.8575 -2.6162)
			(size 0.3556 1.524)
			(layers "F.Cu" "F.Mask" "F.Paste")
			(net "PCIE_MATED#_LED_CD")
		)
		(pad "24" smd rect
			(at -3.4925 -2.6162)
			(size 0.3556 1.524)
			(layers "F.Cu" "F.Mask" "F.Paste")
			(net "P3V3_STBY")
		)
	)
	(footprint ""
		(layer "F.Cu")
		(at 308.936136 -109.863128 -90)
		(property "Reference" "PR34"
			(at 0 0 270)
			(layer "F.SilkS")
			(hide yes)
			(effects
				(font
					(size 1.27 1.27)
				)
			)
		)
		(property "Value" "0R2J-2-GP"
			(at 0.064008 -3.993896 270)
			(unlocked yes)
			(layer "F.Fab")
			(hide yes)
			(effects
				(font
					(size 1.016 1.016)
					(thickness 0.1524)
				)
			)
		)
		(property "Device Type" "R402H16"
			(at 0.064008 -5.517896 270)
			(unlocked yes)
			(layer "F.Fab")
			(hide yes)
			(effects
				(font
					(size 1.016 1.016)
					(thickness 0.1524)
				)
			)
		)
		(duplicate_pad_numbers_are_jumpers no)
		(fp_line
			(start -0.508 -0.9398)
			(end -0.508 0.9398)
			(stroke
				(width 0.1524)
				(type default)
			)
			(layer "F.SilkS")
		)
		(fp_line
			(start 0.508 -0.9398)
			(end -0.508 -0.9398)
			(stroke
				(width 0.1524)
				(type default)
			)
			(layer "F.SilkS")
		)
		(fp_rect
			(start -0.508 0.9398)
			(end 0.508 -0.9398)
			(stroke
				(width 0)
				(type default)
			)
			(fill no)
			(layer "F.CrtYd")
		)
		(fp_rect
			(start -0.508 0.9398)
			(end 0.508 -0.9398)
			(stroke
				(width 0)
				(type default)
			)
			(fill no)
			(layer "F.Fab")
		)
		(pad "1" smd custom
			(at 0 -0.4445 270)
			(size 0.1397 0.1397)
			(layers "F.Cu" "F.Mask" "F.Paste")
			(net "P3V3_STBY_ROVP")
			(options
				(clearance outline)
				(anchor circle)
			)
			(primitives
				(gr_poly
					(pts
						(arc
							(start -0.1778 -0.2794)
							(mid -0.249642 -0.249642)
							(end -0.2794 -0.1778)
						)
						(arc
							(start -0.2794 0.1778)
							(mid -0.249642 0.249642)
							(end -0.1778 0.2794)
						)
						(arc
							(start 0.1778 0.2794)
							(mid 0.249642 0.249642)
							(end 0.2794 0.1778)
						)
						(arc
							(start 0.2794 -0.1778)
							(mid 0.249642 -0.249642)
							(end 0.1778 -0.2794)
						)
					)
					(width 0)
					(fill yes)
				)
			)
		)
		(pad "2" smd custom
			(at 0 0.4445 270)
			(size 0.1397 0.1397)
			(layers "F.Cu" "F.Mask" "F.Paste")
			(net "P3V3_STBY")
			(options
				(clearance outline)
				(anchor circle)
			)
			(primitives
				(gr_poly
					(pts
						(arc
							(start -0.1778 -0.2794)
							(mid -0.249642 -0.249642)
							(end -0.2794 -0.1778)
						)
						(arc
							(start -0.2794 0.1778)
							(mid -0.249642 0.249642)
							(end -0.1778 0.2794)
						)
						(arc
							(start 0.1778 0.2794)
							(mid 0.249642 0.249642)
							(end 0.2794 0.1778)
						)
						(arc
							(start 0.2794 -0.1778)
							(mid 0.249642 -0.249642)
							(end 0.1778 -0.2794)
						)
					)
					(width 0)
					(fill yes)
				)
			)
		)
	)
	(footprint ""
		(layer "F.Cu")
		(at 218.059 -110.363 180)
		(property "Reference" "PC149"
			(at 0 0 180)
			(layer "F.SilkS")
			(hide yes)
			(effects
				(font
					(size 1.27 1.27)
				)
			)
		)
		(property "Value" "SCD1U16V2KX-3GP"
			(at 1.1811 -2.7051 180)
			(unlocked yes)
			(layer "F.Fab")
			(hide yes)
			(effects
				(font
					(size 1.016 1.016)
					(thickness 0.1524)
				)
			)
		)
		(property "Device Type" "C402H22"
			(at 1.1811 -4.2291 180)
			(unlocked yes)
			(layer "F.Fab")
			(hide yes)
			(effects
				(font
					(size 1.016 1.016)
					(thickness 0.1524)
				)
			)
		)
		(duplicate_pad_numbers_are_jumpers no)
		(fp_rect
			(start -0.4318 0.9525)
			(end 0.4318 -0.9525)
			(stroke
				(width 0)
				(type default)
			)
			(fill no)
			(layer "F.CrtYd")
		)
		(fp_rect
			(start -0.4318 0.9525)
			(end 0.4318 -0.9525)
			(stroke
				(width 0)
				(type default)
			)
			(fill no)
			(layer "F.Fab")
		)
		(pad "1" smd custom
			(at 0 -0.4445 180)
			(size 0.1524 0.1524)
			(layers "F.Cu" "F.Mask" "F.Paste")
			(net "TPS74801_1V5_C_EN")
			(options
				(clearance outline)
				(anchor circle)
			)
			(primitives
				(gr_poly
					(pts
						(arc
							(start 0.3048 -0.2032)
							(mid 0.275042 -0.275042)
							(end 0.2032 -0.3048)
						)
						(arc
							(start -0.2032 -0.3048)
							(mid -0.275042 -0.275042)
							(end -0.3048 -0.2032)
						)
						(arc
							(start -0.3048 0.2032)
							(mid -0.275042 0.275042)
							(end -0.2032 0.3048)
						)
						(arc
							(start 0.2032 0.3048)
							(mid 0.275042 0.275042)
							(end 0.3048 0.2032)
						)
					)
					(width 0)
					(fill yes)
				)
			)
		)
		(pad "2" smd custom
			(at 0 0.4445 180)
			(size 0.1524 0.1524)
			(layers "F.Cu" "F.Mask" "F.Paste")
			(net "GND")
			(options
				(clearance outline)
				(anchor circle)
			)
			(primitives
				(gr_poly
					(pts
						(arc
							(start 0.3048 -0.2032)
							(mid 0.275042 -0.275042)
							(end 0.2032 -0.3048)
						)
						(arc
							(start -0.2032 -0.3048)
							(mid -0.275042 -0.275042)
							(end -0.3048 -0.2032)
						)
						(arc
							(start -0.3048 0.2032)
							(mid -0.275042 0.275042)
							(end -0.2032 0.3048)
						)
						(arc
							(start 0.2032 0.3048)
							(mid 0.275042 0.275042)
							(end 0.3048 0.2032)
						)
					)
					(width 0)
					(fill yes)
				)
			)
		)
	)
	(footprint ""
		(layer "F.Cu")
		(at 146.939 -15.748 -90)
		(property "Reference" "C325"
			(at 0 0 270)
			(layer "F.SilkS")
			(hide yes)
			(effects
				(font
					(size 1.27 1.27)
				)
			)
		)
		(property "Value" "SCD1U16V2KX-3GP"
			(at 1.1811 -2.7051 270)
			(unlocked yes)
			(layer "F.Fab")
			(hide yes)
			(effects
				(font
					(size 1.016 1.016)
					(thickness 0.1524)
				)
			)
		)
		(property "Device Type" "C402H22"
			(at 1.1811 -4.2291 270)
			(unlocked yes)
			(layer "F.Fab")
			(hide yes)
			(effects
				(font
					(size 1.016 1.016)
					(thickness 0.1524)
				)
			)
		)
		(duplicate_pad_numbers_are_jumpers no)
		(fp_rect
			(start -0.4318 0.9525)
			(end 0.4318 -0.9525)
			(stroke
				(width 0)
				(type default)
			)
			(fill no)
			(layer "F.CrtYd")
		)
		(fp_rect
			(start -0.4318 0.9525)
			(end 0.4318 -0.9525)
			(stroke
				(width 0)
				(type default)
			)
			(fill no)
			(layer "F.Fab")
		)
		(pad "1" smd custom
			(at 0 -0.4445 270)
			(size 0.1524 0.1524)
			(layers "F.Cu" "F.Mask" "F.Paste")
			(net "PHY_AVDD")
			(options
				(clearance outline)
				(anchor circle)
			)
			(primitives
				(gr_poly
					(pts
						(arc
							(start 0.3048 -0.2032)
							(mid 0.275042 -0.275042)
							(end 0.2032 -0.3048)
						)
						(arc
							(start -0.2032 -0.3048)
							(mid -0.275042 -0.275042)
							(end -0.3048 -0.2032)
						)
						(arc
							(start -0.3048 0.2032)
							(mid -0.275042 0.275042)
							(end -0.2032 0.3048)
						)
						(arc
							(start 0.2032 0.3048)
							(mid 0.275042 0.275042)
							(end 0.3048 0.2032)
						)
					)
					(width 0)
					(fill yes)
				)
			)
		)
		(pad "2" smd custom
			(at 0 0.4445 270)
			(size 0.1524 0.1524)
			(layers "F.Cu" "F.Mask" "F.Paste")
			(net "GND")
			(options
				(clearance outline)
				(anchor circle)
			)
			(primitives
				(gr_poly
					(pts
						(arc
							(start 0.3048 -0.2032)
							(mid 0.275042 -0.275042)
							(end 0.2032 -0.3048)
						)
						(arc
							(start -0.2032 -0.3048)
							(mid -0.275042 -0.275042)
							(end -0.3048 -0.2032)
						)
						(arc
							(start -0.3048 0.2032)
							(mid -0.275042 0.275042)
							(end -0.2032 0.3048)
						)
						(arc
							(start 0.2032 0.3048)
							(mid 0.275042 0.275042)
							(end 0.3048 0.2032)
						)
					)
					(width 0)
					(fill yes)
				)
			)
		)
	)
	(footprint ""
		(layer "F.Cu")
		(at 107.70997 -114.3 180)
		(property "Reference" "SC1083"
			(at 0 0 180)
			(layer "F.SilkS")
			(hide yes)
			(effects
				(font
					(size 1.27 1.27)
				)
			)
		)
		(property "Value" "SCD01U10V1KX-GP"
			(at -2.8321 -1.7399 180)
			(unlocked yes)
			(layer "F.Fab")
			(hide yes)
			(effects
				(font
					(size 1.016 1.016)
					(thickness 0.1524)
				)
			)
		)
		(property "Device Type" "C0201H13"
			(at -2.8321 -3.2639 180)
			(unlocked yes)
			(layer "F.Fab")
			(hide yes)
			(effects
				(font
					(size 1.016 1.016)
					(thickness 0.1524)
				)
			)
		)
		(duplicate_pad_numbers_are_jumpers no)
		(fp_rect
			(start -0.2794 0.6477)
			(end 0.2794 -0.6477)
			(stroke
				(width 0)
				(type default)
			)
			(fill no)
			(layer "F.CrtYd")
		)
		(fp_rect
			(start -0.2794 0.6477)
			(end 0.2794 -0.6477)
			(stroke
				(width 0)
				(type default)
			)
			(fill no)
			(layer "F.Fab")
		)
		(pad "1" smd custom
			(at 0 -0.2794 180)
			(size 0.0762 0.0762)
			(layers "F.Cu" "F.Mask" "F.Paste")
			(net "SAS_HDD_TX8_P")
			(options
				(clearance outline)
				(anchor circle)
			)
			(primitives
				(gr_poly
					(pts
						(arc
							(start 0.1524 -0.127)
							(mid 0.137521 -0.162921)
							(end 0.1016 -0.1778)
						)
						(arc
							(start -0.1016 -0.1778)
							(mid -0.137521 -0.162921)
							(end -0.1524 -0.127)
						)
						(arc
							(start -0.1524 0.127)
							(mid -0.137521 0.162921)
							(end -0.1016 0.1778)
						)
						(arc
							(start 0.1016 0.1778)
							(mid 0.137521 0.162921)
							(end 0.1524 0.127)
						)
					)
					(width 0)
					(fill yes)
				)
			)
		)
		(pad "2" smd custom
			(at 0 0.2794 180)
			(size 0.0762 0.0762)
			(layers "F.Cu" "F.Mask" "F.Paste")
			(net "SAS_EXP_GF_TX_DP12")
			(options
				(clearance outline)
				(anchor circle)
			)
			(primitives
				(gr_poly
					(pts
						(arc
							(start 0.1524 -0.127)
							(mid 0.137521 -0.162921)
							(end 0.1016 -0.1778)
						)
						(arc
							(start -0.1016 -0.1778)
							(mid -0.137521 -0.162921)
							(end -0.1524 -0.127)
						)
						(arc
							(start -0.1524 0.127)
							(mid -0.137521 0.162921)
							(end -0.1016 0.1778)
						)
						(arc
							(start 0.1016 0.1778)
							(mid 0.137521 0.162921)
							(end 0.1524 0.127)
						)
					)
					(width 0)
					(fill yes)
				)
			)
		)
	)
	(footprint ""
		(layer "F.Cu")
		(at 215.773 -181.737 90)
		(property "Reference" "R494"
			(at 0 0 90)
			(layer "F.SilkS")
			(hide yes)
			(effects
				(font
					(size 1.27 1.27)
				)
			)
		)
		(property "Value" "2MR2F-GP"
			(at 0.064008 -3.993896 90)
			(unlocked yes)
			(layer "F.Fab")
			(hide yes)
			(effects
				(font
					(size 1.016 1.016)
					(thickness 0.1524)
				)
			)
		)
		(property "Device Type" "R402H16"
			(at 0.064008 -5.517896 90)
			(unlocked yes)
			(layer "F.Fab")
			(hide yes)
			(effects
				(font
					(size 1.016 1.016)
					(thickness 0.1524)
				)
			)
		)
		(duplicate_pad_numbers_are_jumpers no)
		(fp_line
			(start 0.508 -0.9398)
			(end -0.508 -0.9398)
			(stroke
				(width 0.1524)
				(type default)
			)
			(layer "F.SilkS")
		)
		(fp_line
			(start -0.508 -0.9398)
			(end -0.508 0.9398)
			(stroke
				(width 0.1524)
				(type default)
			)
			(layer "F.SilkS")
		)
		(fp_rect
			(start -0.508 0.9398)
			(end 0.508 -0.9398)
			(stroke
				(width 0)
				(type default)
			)
			(fill no)
			(layer "F.CrtYd")
		)
		(fp_rect
			(start -0.508 0.9398)
			(end 0.508 -0.9398)
			(stroke
				(width 0)
				(type default)
			)
			(fill no)
			(layer "F.Fab")
		)
		(pad "1" smd custom
			(at 0 -0.4445 90)
			(size 0.1397 0.1397)
			(layers "F.Cu" "F.Mask" "F.Paste")
			(net "EXP_HB")
			(options
				(clearance outline)
				(anchor circle)
			)
			(primitives
				(gr_poly
					(pts
						(arc
							(start -0.1778 -0.2794)
							(mid -0.249642 -0.249642)
							(end -0.2794 -0.1778)
						)
						(arc
							(start -0.2794 0.1778)
							(mid -0.249642 0.249642)
							(end -0.1778 0.2794)
						)
						(arc
							(start 0.1778 0.2794)
							(mid 0.249642 0.249642)
							(end 0.2794 0.1778)
						)
						(arc
							(start 0.2794 -0.1778)
							(mid 0.249642 -0.249642)
							(end 0.1778 -0.2794)
						)
					)
					(width 0)
					(fill yes)
				)
			)
		)
		(pad "2" smd custom
			(at 0 0.4445 90)
			(size 0.1397 0.1397)
			(layers "F.Cu" "F.Mask" "F.Paste")
			(net "HB_A_IN_EXP")
			(options
				(clearance outline)
				(anchor circle)
			)
			(primitives
				(gr_poly
					(pts
						(arc
							(start -0.1778 -0.2794)
							(mid -0.249642 -0.249642)
							(end -0.2794 -0.1778)
						)
						(arc
							(start -0.2794 0.1778)
							(mid -0.249642 0.249642)
							(end -0.1778 0.2794)
						)
						(arc
							(start 0.1778 0.2794)
							(mid 0.249642 0.249642)
							(end 0.2794 0.1778)
						)
						(arc
							(start 0.2794 -0.1778)
							(mid 0.249642 -0.249642)
							(end 0.1778 -0.2794)
						)
					)
					(width 0)
					(fill yes)
				)
			)
		)
	)
	(footprint ""
		(layer "F.Cu")
		(at 274.438872 -53.158136 180)
		(property "Reference" "PR116"
			(at 0 0 180)
			(layer "F.SilkS")
			(hide yes)
			(effects
				(font
					(size 1.27 1.27)
				)
			)
		)
		(property "Value" "20KR2F-L-GP"
			(at 0.064008 -3.993896 180)
			(unlocked yes)
			(layer "F.Fab")
			(hide yes)
			(effects
				(font
					(size 1.016 1.016)
					(thickness 0.1524)
				)
			)
		)
		(property "Device Type" "R402H16"
			(at 0.064008 -5.517896 180)
			(unlocked yes)
			(layer "F.Fab")
			(hide yes)
			(effects
				(font
					(size 1.016 1.016)
					(thickness 0.1524)
				)
			)
		)
		(duplicate_pad_numbers_are_jumpers no)
		(fp_line
			(start 0.508 -0.9398)
			(end -0.508 -0.9398)
			(stroke
				(width 0.1524)
				(type default)
			)
			(layer "F.SilkS")
		)
		(fp_line
			(start -0.508 -0.9398)
			(end -0.508 0.9398)
			(stroke
				(width 0.1524)
				(type default)
			)
			(layer "F.SilkS")
		)
		(fp_rect
			(start -0.508 0.9398)
			(end 0.508 -0.9398)
			(stroke
				(width 0)
				(type default)
			)
			(fill no)
			(layer "F.CrtYd")
		)
		(fp_rect
			(start -0.508 0.9398)
			(end 0.508 -0.9398)
			(stroke
				(width 0)
				(type default)
			)
			(fill no)
			(layer "F.Fab")
		)
		(pad "1" smd custom
			(at 0 -0.4445 180)
			(size 0.1397 0.1397)
			(layers "F.Cu" "F.Mask" "F.Paste")
			(net "P12V")
			(options
				(clearance outline)
				(anchor circle)
			)
			(primitives
				(gr_poly
					(pts
						(arc
							(start -0.1778 -0.2794)
							(mid -0.249642 -0.249642)
							(end -0.2794 -0.1778)
						)
						(arc
							(start -0.2794 0.1778)
							(mid -0.249642 0.249642)
							(end -0.1778 0.2794)
						)
						(arc
							(start 0.1778 0.2794)
							(mid 0.249642 0.249642)
							(end 0.2794 0.1778)
						)
						(arc
							(start 0.2794 -0.1778)
							(mid 0.249642 -0.249642)
							(end 0.1778 -0.2794)
						)
					)
					(width 0)
					(fill yes)
				)
			)
		)
		(pad "2" smd custom
			(at 0 0.4445 180)
			(size 0.1397 0.1397)
			(layers "F.Cu" "F.Mask" "F.Paste")
			(net "P3V3_EN_LV")
			(options
				(clearance outline)
				(anchor circle)
			)
			(primitives
				(gr_poly
					(pts
						(arc
							(start -0.1778 -0.2794)
							(mid -0.249642 -0.249642)
							(end -0.2794 -0.1778)
						)
						(arc
							(start -0.2794 0.1778)
							(mid -0.249642 0.249642)
							(end -0.1778 0.2794)
						)
						(arc
							(start 0.1778 0.2794)
							(mid 0.249642 0.249642)
							(end 0.2794 0.1778)
						)
						(arc
							(start 0.2794 -0.1778)
							(mid 0.249642 -0.249642)
							(end 0.1778 -0.2794)
						)
					)
					(width 0)
					(fill yes)
				)
			)
		)
	)
	(footprint ""
		(layer "F.Cu")
		(at 147.290028 -69.469)
		(property "Reference" "C270"
			(at 0 0 0)
			(layer "F.SilkS")
			(hide yes)
			(effects
				(font
					(size 1.27 1.27)
				)
			)
		)
		(property "Value" "SC22U25V5MX-GP"
			(at -0.0762 -6.1214 0)
			(unlocked yes)
			(layer "F.Fab")
			(hide yes)
			(effects
				(font
					(size 1.016 1.016)
					(thickness 0.1524)
				)
			)
		)
		(property "Device Type" "C805H58"
			(at -0.0762 -8.1534 0)
			(unlocked yes)
			(layer "F.Fab")
			(hide yes)
			(effects
				(font
					(size 1.016 1.016)
					(thickness 0.1524)
				)
			)
		)
		(duplicate_pad_numbers_are_jumpers no)
		(fp_line
			(start 0.635 0)
			(end -0.635 0)
			(stroke
				(width 0.508)
				(type default)
			)
			(layer "F.SilkS")
		)
		(fp_rect
			(start -0.9652 1.778)
			(end 0.9652 -1.778)
			(stroke
				(width 0)
				(type default)
			)
			(fill no)
			(layer "F.CrtYd")
		)
		(fp_poly
			(pts
				(xy -0.9652 -1.778) (xy 0.9652 -1.778) (xy 0.9652 1.778) (xy -0.9652 1.778)
			)
			(stroke
				(width 0)
				(type default)
			)
			(fill no)
			(layer "F.Fab")
		)
		(pad "1" smd rect
			(at 0 -0.9652)
			(size 1.397 1.143)
			(layers "F.Cu" "F.Mask" "F.Paste")
			(net "P12V_MSB")
		)
		(pad "2" smd rect
			(at 0 0.9652)
			(size 1.397 1.143)
			(layers "F.Cu" "F.Mask" "F.Paste")
			(net "GND")
		)
	)
	(footprint ""
		(layer "F.Cu")
		(at 315.468 -150.622 -90)
		(property "Reference" "R5200"
			(at 0 0 270)
			(layer "F.SilkS")
			(hide yes)
			(effects
				(font
					(size 1.27 1.27)
				)
			)
		)
		(property "Value" "0R2J-2-GP"
			(at 0.064008 -3.993896 270)
			(unlocked yes)
			(layer "F.Fab")
			(hide yes)
			(effects
				(font
					(size 1.016 1.016)
					(thickness 0.1524)
				)
			)
		)
		(property "Device Type" "R402H16"
			(at 0.064008 -5.517896 270)
			(unlocked yes)
			(layer "F.Fab")
			(hide yes)
			(effects
				(font
					(size 1.016 1.016)
					(thickness 0.1524)
				)
			)
		)
		(duplicate_pad_numbers_are_jumpers no)
		(fp_line
			(start -0.508 -0.9398)
			(end -0.508 0.9398)
			(stroke
				(width 0.1524)
				(type default)
			)
			(layer "F.SilkS")
		)
		(fp_line
			(start 0.508 -0.9398)
			(end -0.508 -0.9398)
			(stroke
				(width 0.1524)
				(type default)
			)
			(layer "F.SilkS")
		)
		(fp_rect
			(start -0.508 0.9398)
			(end 0.508 -0.9398)
			(stroke
				(width 0)
				(type default)
			)
			(fill no)
			(layer "F.CrtYd")
		)
		(fp_rect
			(start -0.508 0.9398)
			(end 0.508 -0.9398)
			(stroke
				(width 0)
				(type default)
			)
			(fill no)
			(layer "F.Fab")
		)
		(pad "1" smd custom
			(at 0 -0.4445 270)
			(size 0.1397 0.1397)
			(layers "F.Cu" "F.Mask" "F.Paste")
			(net "RTC_I2C_SCL")
			(options
				(clearance outline)
				(anchor circle)
			)
			(primitives
				(gr_poly
					(pts
						(arc
							(start -0.1778 -0.2794)
							(mid -0.249642 -0.249642)
							(end -0.2794 -0.1778)
						)
						(arc
							(start -0.2794 0.1778)
							(mid -0.249642 0.249642)
							(end -0.1778 0.2794)
						)
						(arc
							(start 0.1778 0.2794)
							(mid 0.249642 0.249642)
							(end 0.2794 0.1778)
						)
						(arc
							(start 0.2794 -0.1778)
							(mid 0.249642 -0.249642)
							(end 0.1778 -0.2794)
						)
					)
					(width 0)
					(fill yes)
				)
			)
		)
		(pad "2" smd custom
			(at 0 0.4445 270)
			(size 0.1397 0.1397)
			(layers "F.Cu" "F.Mask" "F.Paste")
			(net "BMC_I2C_A_SCL")
			(options
				(clearance outline)
				(anchor circle)
			)
			(primitives
				(gr_poly
					(pts
						(arc
							(start -0.1778 -0.2794)
							(mid -0.249642 -0.249642)
							(end -0.2794 -0.1778)
						)
						(arc
							(start -0.2794 0.1778)
							(mid -0.249642 0.249642)
							(end -0.1778 0.2794)
						)
						(arc
							(start 0.1778 0.2794)
							(mid 0.249642 0.249642)
							(end 0.2794 0.1778)
						)
						(arc
							(start 0.2794 -0.1778)
							(mid 0.249642 -0.249642)
							(end 0.1778 -0.2794)
						)
					)
					(width 0)
					(fill yes)
				)
			)
		)
	)
	(footprint ""
		(layer "F.Cu")
		(at 83.18119 -56.355488 90)
		(property "Reference" "SC921"
			(at 0 0 90)
			(layer "F.SilkS")
			(hide yes)
			(effects
				(font
					(size 1.27 1.27)
				)
			)
		)
		(property "Value" "SC1U6D3V1MX-GP"
			(at 1.9177 2.0193 90)
			(unlocked yes)
			(layer "F.Fab")
			(hide yes)
			(effects
				(font
					(size 1.016 1.016)
					(thickness 0.1524)
				)
			)
		)
		(property "Device Type" "C0201H14"
			(at 1.9177 0.4953 90)
			(unlocked yes)
			(layer "F.Fab")
			(hide yes)
			(effects
				(font
					(size 1.016 1.016)
					(thickness 0.1524)
				)
			)
		)
		(duplicate_pad_numbers_are_jumpers no)
		(fp_rect
			(start -0.1524 0.3048)
			(end 0.1524 -0.3048)
			(stroke
				(width 0)
				(type default)
			)
			(fill no)
			(layer "F.CrtYd")
		)
		(fp_poly
			(pts
				(xy -0.2794 0.6477) (xy -0.2794 -0.6477) (xy 0.2794 -0.6477) (xy 0.2794 -0.1905) (xy 0.1524 -0.1905)
				(xy 0.1524 -0.3048) (xy -0.1524 -0.3048) (xy -0.1524 0.3048) (xy 0.1524 0.3048) (xy 0.1524 -0.1778)
				(xy 0.2794 -0.1778) (xy 0.2794 0.6477)
			)
			(stroke
				(width 0)
				(type default)
			)
			(fill no)
			(layer "F.CrtYd")
		)
		(fp_rect
			(start -0.2794 0.6477)
			(end 0.2794 -0.6477)
			(stroke
				(width 0)
				(type default)
			)
			(fill no)
			(layer "F.Fab")
		)
		(pad "1" smd custom
			(at 0 -0.2794 90)
			(size 0.0762 0.0762)
			(layers "F.Cu" "F.Mask" "F.Paste")
			(net "SYS_PLL_VDD")
			(options
				(clearance outline)
				(anchor circle)
			)
			(primitives
				(gr_poly
					(pts
						(arc
							(start 0.1524 -0.127)
							(mid 0.137521 -0.162921)
							(end 0.1016 -0.1778)
						)
						(arc
							(start -0.1016 -0.1778)
							(mid -0.137521 -0.162921)
							(end -0.1524 -0.127)
						)
						(arc
							(start -0.1524 0.127)
							(mid -0.137521 0.162921)
							(end -0.1016 0.1778)
						)
						(arc
							(start 0.1016 0.1778)
							(mid 0.137521 0.162921)
							(end 0.1524 0.127)
						)
					)
					(width 0)
					(fill yes)
				)
			)
		)
		(pad "2" smd custom
			(at 0 0.2794 90)
			(size 0.0762 0.0762)
			(layers "F.Cu" "F.Mask" "F.Paste")
			(net "GND")
			(options
				(clearance outline)
				(anchor circle)
			)
			(primitives
				(gr_poly
					(pts
						(arc
							(start 0.1524 -0.127)
							(mid 0.137521 -0.162921)
							(end 0.1016 -0.1778)
						)
						(arc
							(start -0.1016 -0.1778)
							(mid -0.137521 -0.162921)
							(end -0.1524 -0.127)
						)
						(arc
							(start -0.1524 0.127)
							(mid -0.137521 0.162921)
							(end -0.1016 0.1778)
						)
						(arc
							(start 0.1016 0.1778)
							(mid 0.137521 0.162921)
							(end 0.1524 0.127)
						)
					)
					(width 0)
					(fill yes)
				)
			)
		)
	)
	(footprint ""
		(layer "F.Cu")
		(at 25.282144 -193.351404 180)
		(property "Reference" "R652"
			(at 0 0 180)
			(layer "F.SilkS")
			(hide yes)
			(effects
				(font
					(size 1.27 1.27)
				)
			)
		)
		(property "Value" "4K7R2F-GP"
			(at 0.064008 -3.993896 180)
			(unlocked yes)
			(layer "F.Fab")
			(hide yes)
			(effects
				(font
					(size 1.016 1.016)
					(thickness 0.1524)
				)
			)
		)
		(property "Device Type" "R402H16"
			(at 0.064008 -5.517896 180)
			(unlocked yes)
			(layer "F.Fab")
			(hide yes)
			(effects
				(font
					(size 1.016 1.016)
					(thickness 0.1524)
				)
			)
		)
		(duplicate_pad_numbers_are_jumpers no)
		(fp_line
			(start 0.508 -0.9398)
			(end -0.508 -0.9398)
			(stroke
				(width 0.1524)
				(type default)
			)
			(layer "F.SilkS")
		)
		(fp_line
			(start -0.508 -0.9398)
			(end -0.508 0.9398)
			(stroke
				(width 0.1524)
				(type default)
			)
			(layer "F.SilkS")
		)
		(fp_rect
			(start -0.508 0.9398)
			(end 0.508 -0.9398)
			(stroke
				(width 0)
				(type default)
			)
			(fill no)
			(layer "F.CrtYd")
		)
		(fp_rect
			(start -0.508 0.9398)
			(end 0.508 -0.9398)
			(stroke
				(width 0)
				(type default)
			)
			(fill no)
			(layer "F.Fab")
		)
		(pad "1" smd custom
			(at 0 -0.4445 180)
			(size 0.1397 0.1397)
			(layers "F.Cu" "F.Mask" "F.Paste")
			(net "IO_EXP_HDD_PRE_A0")
			(options
				(clearance outline)
				(anchor circle)
			)
			(primitives
				(gr_poly
					(pts
						(arc
							(start -0.1778 -0.2794)
							(mid -0.249642 -0.249642)
							(end -0.2794 -0.1778)
						)
						(arc
							(start -0.2794 0.1778)
							(mid -0.249642 0.249642)
							(end -0.1778 0.2794)
						)
						(arc
							(start 0.1778 0.2794)
							(mid 0.249642 0.249642)
							(end 0.2794 0.1778)
						)
						(arc
							(start 0.2794 -0.1778)
							(mid 0.249642 -0.249642)
							(end 0.1778 -0.2794)
						)
					)
					(width 0)
					(fill yes)
				)
			)
		)
		(pad "2" smd custom
			(at 0 0.4445 180)
			(size 0.1397 0.1397)
			(layers "F.Cu" "F.Mask" "F.Paste")
			(net "GND")
			(options
				(clearance outline)
				(anchor circle)
			)
			(primitives
				(gr_poly
					(pts
						(arc
							(start -0.1778 -0.2794)
							(mid -0.249642 -0.249642)
							(end -0.2794 -0.1778)
						)
						(arc
							(start -0.2794 0.1778)
							(mid -0.249642 0.249642)
							(end -0.1778 0.2794)
						)
						(arc
							(start 0.1778 0.2794)
							(mid 0.249642 0.249642)
							(end 0.2794 0.1778)
						)
						(arc
							(start 0.2794 -0.1778)
							(mid 0.249642 -0.249642)
							(end 0.1778 -0.2794)
						)
					)
					(width 0)
					(fill yes)
				)
			)
		)
	)
	(footprint ""
		(layer "F.Cu")
		(at 347.345 -90.551)
		(property "Reference" "PG1"
			(at 0 0 0)
			(layer "F.SilkS")
			(hide yes)
			(effects
				(font
					(size 1.27 1.27)
				)
			)
		)
		(property "Value" "GAP-CLOSE-PWR-4-GP"
			(at -2.4638 -0.5461 0)
			(unlocked yes)
			(layer "F.Fab")
			(hide yes)
			(effects
				(font
					(size 1.016 1.016)
					(thickness 0.1524)
				)
			)
		)
		(property "Device Type" "GAP-CLOSE-PWR-4"
			(at -2.4638 -2.0701 0)
			(unlocked yes)
			(layer "F.Fab")
			(hide yes)
			(effects
				(font
					(size 1.016 1.016)
					(thickness 0.1524)
				)
			)
		)
		(duplicate_pad_numbers_are_jumpers no)
		(fp_rect
			(start -0.2794 0.254)
			(end 0.2794 -0.254)
			(stroke
				(width 0)
				(type default)
			)
			(fill no)
			(layer "F.CrtYd")
		)
		(fp_rect
			(start -0.2794 0.254)
			(end 0.2794 -0.254)
			(stroke
				(width 0)
				(type default)
			)
			(fill no)
			(layer "F.Fab")
		)
		(pad "1" smd rect
			(at -0.0635 0)
			(size 0.1778 0.254)
			(layers "F.Cu" "F.Mask" "F.Paste")
			(net "P5V_STBY")
		)
		(pad "2" smd rect
			(at 0.0635 0)
			(size 0.1778 0.254)
			(layers "F.Cu" "F.Mask" "F.Paste")
			(net "P5V_STBY_CC")
		)
	)
	(footprint ""
		(layer "F.Cu")
		(at 201.699876 -144.898872 90)
		(property "Reference" "SR762"
			(at 0 0 90)
			(layer "F.SilkS")
			(hide yes)
			(effects
				(font
					(size 1.27 1.27)
				)
			)
		)
		(property "Value" "4K7R2F-GP"
			(at 0.064008 -3.993896 90)
			(unlocked yes)
			(layer "F.Fab")
			(hide yes)
			(effects
				(font
					(size 1.016 1.016)
					(thickness 0.1524)
				)
			)
		)
		(property "Device Type" "R402H16"
			(at 0.064008 -5.517896 90)
			(unlocked yes)
			(layer "F.Fab")
			(hide yes)
			(effects
				(font
					(size 1.016 1.016)
					(thickness 0.1524)
				)
			)
		)
		(duplicate_pad_numbers_are_jumpers no)
		(fp_line
			(start 0.508 -0.9398)
			(end -0.508 -0.9398)
			(stroke
				(width 0.1524)
				(type default)
			)
			(layer "F.SilkS")
		)
		(fp_line
			(start -0.508 -0.9398)
			(end -0.508 0.9398)
			(stroke
				(width 0.1524)
				(type default)
			)
			(layer "F.SilkS")
		)
		(fp_rect
			(start -0.508 0.9398)
			(end 0.508 -0.9398)
			(stroke
				(width 0)
				(type default)
			)
			(fill no)
			(layer "F.CrtYd")
		)
		(fp_rect
			(start -0.508 0.9398)
			(end 0.508 -0.9398)
			(stroke
				(width 0)
				(type default)
			)
			(fill no)
			(layer "F.Fab")
		)
		(pad "1" smd custom
			(at 0 -0.4445 90)
			(size 0.1397 0.1397)
			(layers "F.Cu" "F.Mask" "F.Paste")
			(net "BMC_I2C_SDA_9")
			(options
				(clearance outline)
				(anchor circle)
			)
			(primitives
				(gr_poly
					(pts
						(arc
							(start -0.1778 -0.2794)
							(mid -0.249642 -0.249642)
							(end -0.2794 -0.1778)
						)
						(arc
							(start -0.2794 0.1778)
							(mid -0.249642 0.249642)
							(end -0.1778 0.2794)
						)
						(arc
							(start 0.1778 0.2794)
							(mid 0.249642 0.249642)
							(end 0.2794 0.1778)
						)
						(arc
							(start 0.2794 -0.1778)
							(mid 0.249642 -0.249642)
							(end 0.1778 -0.2794)
						)
					)
					(width 0)
					(fill yes)
				)
			)
		)
		(pad "2" smd custom
			(at 0 0.4445 90)
			(size 0.1397 0.1397)
			(layers "F.Cu" "F.Mask" "F.Paste")
			(net "P3V3_STBY")
			(options
				(clearance outline)
				(anchor circle)
			)
			(primitives
				(gr_poly
					(pts
						(arc
							(start -0.1778 -0.2794)
							(mid -0.249642 -0.249642)
							(end -0.2794 -0.1778)
						)
						(arc
							(start -0.2794 0.1778)
							(mid -0.249642 0.249642)
							(end -0.1778 0.2794)
						)
						(arc
							(start 0.1778 0.2794)
							(mid 0.249642 0.249642)
							(end 0.2794 0.1778)
						)
						(arc
							(start 0.2794 -0.1778)
							(mid 0.249642 -0.249642)
							(end 0.1778 -0.2794)
						)
					)
					(width 0)
					(fill yes)
				)
			)
		)
	)
	(footprint ""
		(layer "F.Cu")
		(at 90.786966 -63.119)
		(property "Reference" "SR672"
			(at 0 0 0)
			(layer "F.SilkS")
			(hide yes)
			(effects
				(font
					(size 1.27 1.27)
				)
			)
		)
		(property "Value" "4K7R2F-GP"
			(at 0.064008 -3.993896 0)
			(unlocked yes)
			(layer "F.Fab")
			(hide yes)
			(effects
				(font
					(size 1.016 1.016)
					(thickness 0.1524)
				)
			)
		)
		(property "Device Type" "R402H16"
			(at 0.064008 -5.517896 0)
			(unlocked yes)
			(layer "F.Fab")
			(hide yes)
			(effects
				(font
					(size 1.016 1.016)
					(thickness 0.1524)
				)
			)
		)
		(duplicate_pad_numbers_are_jumpers no)
		(fp_line
			(start -0.508 -0.9398)
			(end -0.508 0.9398)
			(stroke
				(width 0.1524)
				(type default)
			)
			(layer "F.SilkS")
		)
		(fp_line
			(start 0.508 -0.9398)
			(end -0.508 -0.9398)
			(stroke
				(width 0.1524)
				(type default)
			)
			(layer "F.SilkS")
		)
		(fp_rect
			(start -0.508 0.9398)
			(end 0.508 -0.9398)
			(stroke
				(width 0)
				(type default)
			)
			(fill no)
			(layer "F.CrtYd")
		)
		(fp_rect
			(start -0.508 0.9398)
			(end 0.508 -0.9398)
			(stroke
				(width 0)
				(type default)
			)
			(fill no)
			(layer "F.Fab")
		)
		(pad "1" smd custom
			(at 0 -0.4445)
			(size 0.1397 0.1397)
			(layers "F.Cu" "F.Mask" "F.Paste")
			(net "P1V8_C")
			(options
				(clearance outline)
				(anchor circle)
			)
			(primitives
				(gr_poly
					(pts
						(arc
							(start -0.1778 -0.2794)
							(mid -0.249642 -0.249642)
							(end -0.2794 -0.1778)
						)
						(arc
							(start -0.2794 0.1778)
							(mid -0.249642 0.249642)
							(end -0.1778 0.2794)
						)
						(arc
							(start 0.1778 0.2794)
							(mid 0.249642 0.249642)
							(end 0.2794 0.1778)
						)
						(arc
							(start 0.2794 -0.1778)
							(mid 0.249642 -0.249642)
							(end 0.1778 -0.2794)
						)
					)
					(width 0)
					(fill yes)
				)
			)
		)
		(pad "2" smd custom
			(at 0 0.4445)
			(size 0.1397 0.1397)
			(layers "F.Cu" "F.Mask" "F.Paste")
			(net "ICE1_TRST#")
			(options
				(clearance outline)
				(anchor circle)
			)
			(primitives
				(gr_poly
					(pts
						(arc
							(start -0.1778 -0.2794)
							(mid -0.249642 -0.249642)
							(end -0.2794 -0.1778)
						)
						(arc
							(start -0.2794 0.1778)
							(mid -0.249642 0.249642)
							(end -0.1778 0.2794)
						)
						(arc
							(start 0.1778 0.2794)
							(mid 0.249642 0.249642)
							(end 0.2794 0.1778)
						)
						(arc
							(start 0.2794 -0.1778)
							(mid 0.249642 -0.249642)
							(end 0.1778 -0.2794)
						)
					)
					(width 0)
					(fill yes)
				)
			)
		)
	)
	(footprint ""
		(layer "F.Cu")
		(at 342.138 -20.574 180)
		(property "Reference" "C255"
			(at 0 0 180)
			(layer "F.SilkS")
			(hide yes)
			(effects
				(font
					(size 1.27 1.27)
				)
			)
		)
		(property "Value" "SC1U6D3V3KX-2GP"
			(at 0 -2.8194 180)
			(unlocked yes)
			(layer "F.Fab")
			(hide yes)
			(effects
				(font
					(size 1.016 1.016)
					(thickness 0.1524)
				)
			)
		)
		(property "Device Type" "C603H36"
			(at 0 -4.3434 180)
			(unlocked yes)
			(layer "F.Fab")
			(hide yes)
			(effects
				(font
					(size 1.016 1.016)
					(thickness 0.1524)
				)
			)
		)
		(duplicate_pad_numbers_are_jumpers no)
		(fp_line
			(start 0.508 0)
			(end -0.508 0)
			(stroke
				(width 0.2032)
				(type default)
			)
			(layer "F.SilkS")
		)
		(fp_rect
			(start -0.5842 1.3335)
			(end 0.5842 -1.3335)
			(stroke
				(width 0)
				(type default)
			)
			(fill no)
			(layer "F.CrtYd")
		)
		(fp_rect
			(start -0.5842 1.3335)
			(end 0.5842 -1.3335)
			(stroke
				(width 0)
				(type default)
			)
			(fill no)
			(layer "F.Fab")
		)
		(pad "1" smd custom
			(at 0 -0.762 180)
			(size 0.2159 0.2159)
			(layers "F.Cu" "F.Mask" "F.Paste")
			(net "CPU_EXP_RST")
			(options
				(clearance outline)
				(anchor circle)
			)
			(primitives
				(gr_poly
					(pts
						(arc
							(start -0.3302 -0.4318)
							(mid -0.402042 -0.402042)
							(end -0.4318 -0.3302)
						)
						(arc
							(start -0.4318 0.3302)
							(mid -0.402042 0.402042)
							(end -0.3302 0.4318)
						)
						(arc
							(start 0.3302 0.4318)
							(mid 0.402042 0.402042)
							(end 0.4318 0.3302)
						)
						(arc
							(start 0.4318 -0.3302)
							(mid 0.402042 -0.402042)
							(end 0.3302 -0.4318)
						)
					)
					(width 0)
					(fill yes)
				)
			)
		)
		(pad "2" smd custom
			(at 0 0.762 180)
			(size 0.2159 0.2159)
			(layers "F.Cu" "F.Mask" "F.Paste")
			(net "GND")
			(options
				(clearance outline)
				(anchor circle)
			)
			(primitives
				(gr_poly
					(pts
						(arc
							(start -0.3302 -0.4318)
							(mid -0.402042 -0.402042)
							(end -0.4318 -0.3302)
						)
						(arc
							(start -0.4318 0.3302)
							(mid -0.402042 0.402042)
							(end -0.3302 0.4318)
						)
						(arc
							(start 0.3302 0.4318)
							(mid 0.402042 0.402042)
							(end 0.4318 0.3302)
						)
						(arc
							(start 0.4318 -0.3302)
							(mid 0.402042 -0.402042)
							(end 0.3302 -0.4318)
						)
					)
					(width 0)
					(fill yes)
				)
			)
		)
	)
	(footprint ""
		(layer "F.Cu")
		(at 97.663 -221.488)
		(property "Reference" "R639"
			(at 0 0 0)
			(layer "F.SilkS")
			(hide yes)
			(effects
				(font
					(size 1.27 1.27)
				)
			)
		)
		(property "Value" "4K7R2F-GP"
			(at 0.064008 -3.993896 0)
			(unlocked yes)
			(layer "F.Fab")
			(hide yes)
			(effects
				(font
					(size 1.016 1.016)
					(thickness 0.1524)
				)
			)
		)
		(property "Device Type" "R402H16"
			(at 0.064008 -5.517896 0)
			(unlocked yes)
			(layer "F.Fab")
			(hide yes)
			(effects
				(font
					(size 1.016 1.016)
					(thickness 0.1524)
				)
			)
		)
		(duplicate_pad_numbers_are_jumpers no)
		(fp_line
			(start -0.508 -0.9398)
			(end -0.508 0.9398)
			(stroke
				(width 0.1524)
				(type default)
			)
			(layer "F.SilkS")
		)
		(fp_line
			(start 0.508 -0.9398)
			(end -0.508 -0.9398)
			(stroke
				(width 0.1524)
				(type default)
			)
			(layer "F.SilkS")
		)
		(fp_rect
			(start -0.508 0.9398)
			(end 0.508 -0.9398)
			(stroke
				(width 0)
				(type default)
			)
			(fill no)
			(layer "F.CrtYd")
		)
		(fp_rect
			(start -0.508 0.9398)
			(end 0.508 -0.9398)
			(stroke
				(width 0)
				(type default)
			)
			(fill no)
			(layer "F.Fab")
		)
		(pad "1" smd custom
			(at 0 -0.4445)
			(size 0.1397 0.1397)
			(layers "F.Cu" "F.Mask" "F.Paste")
			(net "IO_EXP_HDD_FAULT_A0")
			(options
				(clearance outline)
				(anchor circle)
			)
			(primitives
				(gr_poly
					(pts
						(arc
							(start -0.1778 -0.2794)
							(mid -0.249642 -0.249642)
							(end -0.2794 -0.1778)
						)
						(arc
							(start -0.2794 0.1778)
							(mid -0.249642 0.249642)
							(end -0.1778 0.2794)
						)
						(arc
							(start 0.1778 0.2794)
							(mid 0.249642 0.249642)
							(end 0.2794 0.1778)
						)
						(arc
							(start 0.2794 -0.1778)
							(mid 0.249642 -0.249642)
							(end 0.1778 -0.2794)
						)
					)
					(width 0)
					(fill yes)
				)
			)
		)
		(pad "2" smd custom
			(at 0 0.4445)
			(size 0.1397 0.1397)
			(layers "F.Cu" "F.Mask" "F.Paste")
			(net "GND")
			(options
				(clearance outline)
				(anchor circle)
			)
			(primitives
				(gr_poly
					(pts
						(arc
							(start -0.1778 -0.2794)
							(mid -0.249642 -0.249642)
							(end -0.2794 -0.1778)
						)
						(arc
							(start -0.2794 0.1778)
							(mid -0.249642 0.249642)
							(end -0.1778 0.2794)
						)
						(arc
							(start 0.1778 0.2794)
							(mid 0.249642 0.249642)
							(end 0.2794 0.1778)
						)
						(arc
							(start 0.2794 -0.1778)
							(mid 0.249642 -0.249642)
							(end 0.1778 -0.2794)
						)
					)
					(width 0)
					(fill yes)
				)
			)
		)
	)
	(footprint ""
		(layer "F.Cu")
		(at 81.388966 -67.564 180)
		(property "Reference" "SC985"
			(at 0 0 180)
			(layer "F.SilkS")
			(hide yes)
			(effects
				(font
					(size 1.27 1.27)
				)
			)
		)
		(property "Value" "SCD1U16V2KX-3GP"
			(at 1.1811 -2.7051 180)
			(unlocked yes)
			(layer "F.Fab")
			(hide yes)
			(effects
				(font
					(size 1.016 1.016)
					(thickness 0.1524)
				)
			)
		)
		(property "Device Type" "C402H22"
			(at 1.1811 -4.2291 180)
			(unlocked yes)
			(layer "F.Fab")
			(hide yes)
			(effects
				(font
					(size 1.016 1.016)
					(thickness 0.1524)
				)
			)
		)
		(duplicate_pad_numbers_are_jumpers no)
		(fp_rect
			(start -0.4318 0.9525)
			(end 0.4318 -0.9525)
			(stroke
				(width 0)
				(type default)
			)
			(fill no)
			(layer "F.CrtYd")
		)
		(fp_rect
			(start -0.4318 0.9525)
			(end 0.4318 -0.9525)
			(stroke
				(width 0)
				(type default)
			)
			(fill no)
			(layer "F.Fab")
		)
		(pad "1" smd custom
			(at 0 -0.4445 180)
			(size 0.1524 0.1524)
			(layers "F.Cu" "F.Mask" "F.Paste")
			(net "P1V8_C")
			(options
				(clearance outline)
				(anchor circle)
			)
			(primitives
				(gr_poly
					(pts
						(arc
							(start 0.3048 -0.2032)
							(mid 0.275042 -0.275042)
							(end 0.2032 -0.3048)
						)
						(arc
							(start -0.2032 -0.3048)
							(mid -0.275042 -0.275042)
							(end -0.3048 -0.2032)
						)
						(arc
							(start -0.3048 0.2032)
							(mid -0.275042 0.275042)
							(end -0.2032 0.3048)
						)
						(arc
							(start 0.2032 0.3048)
							(mid 0.275042 0.275042)
							(end 0.3048 0.2032)
						)
					)
					(width 0)
					(fill yes)
				)
			)
		)
		(pad "2" smd custom
			(at 0 0.4445 180)
			(size 0.1524 0.1524)
			(layers "F.Cu" "F.Mask" "F.Paste")
			(net "GND")
			(options
				(clearance outline)
				(anchor circle)
			)
			(primitives
				(gr_poly
					(pts
						(arc
							(start 0.3048 -0.2032)
							(mid 0.275042 -0.275042)
							(end 0.2032 -0.3048)
						)
						(arc
							(start -0.2032 -0.3048)
							(mid -0.275042 -0.275042)
							(end -0.3048 -0.2032)
						)
						(arc
							(start -0.3048 0.2032)
							(mid -0.275042 0.275042)
							(end -0.2032 0.3048)
						)
						(arc
							(start 0.2032 0.3048)
							(mid 0.275042 0.275042)
							(end 0.3048 0.2032)
						)
					)
					(width 0)
					(fill yes)
				)
			)
		)
	)
	(footprint ""
		(layer "F.Cu")
		(at 336.169 -110.49)
		(property "Reference" "PR17"
			(at 0 0 0)
			(layer "F.SilkS")
			(hide yes)
			(effects
				(font
					(size 1.27 1.27)
				)
			)
		)
		(property "Value" "2K05R2F-GP"
			(at 0.064008 -3.993896 0)
			(unlocked yes)
			(layer "F.Fab")
			(hide yes)
			(effects
				(font
					(size 1.016 1.016)
					(thickness 0.1524)
				)
			)
		)
		(property "Device Type" "R402H16"
			(at 0.064008 -5.517896 0)
			(unlocked yes)
			(layer "F.Fab")
			(hide yes)
			(effects
				(font
					(size 1.016 1.016)
					(thickness 0.1524)
				)
			)
		)
		(duplicate_pad_numbers_are_jumpers no)
		(fp_line
			(start -0.508 -0.9398)
			(end -0.508 0.9398)
			(stroke
				(width 0.1524)
				(type default)
			)
			(layer "F.SilkS")
		)
		(fp_line
			(start 0.508 -0.9398)
			(end -0.508 -0.9398)
			(stroke
				(width 0.1524)
				(type default)
			)
			(layer "F.SilkS")
		)
		(fp_rect
			(start -0.508 0.9398)
			(end 0.508 -0.9398)
			(stroke
				(width 0)
				(type default)
			)
			(fill no)
			(layer "F.CrtYd")
		)
		(fp_rect
			(start -0.508 0.9398)
			(end 0.508 -0.9398)
			(stroke
				(width 0)
				(type default)
			)
			(fill no)
			(layer "F.Fab")
		)
		(pad "1" smd custom
			(at 0 -0.4445)
			(size 0.1397 0.1397)
			(layers "F.Cu" "F.Mask" "F.Paste")
			(net "P5V_STBY_EN_R")
			(options
				(clearance outline)
				(anchor circle)
			)
			(primitives
				(gr_poly
					(pts
						(arc
							(start -0.1778 -0.2794)
							(mid -0.249642 -0.249642)
							(end -0.2794 -0.1778)
						)
						(arc
							(start -0.2794 0.1778)
							(mid -0.249642 0.249642)
							(end -0.1778 0.2794)
						)
						(arc
							(start 0.1778 0.2794)
							(mid 0.249642 0.249642)
							(end 0.2794 0.1778)
						)
						(arc
							(start 0.2794 -0.1778)
							(mid 0.249642 -0.249642)
							(end 0.1778 -0.2794)
						)
					)
					(width 0)
					(fill yes)
				)
			)
		)
		(pad "2" smd custom
			(at 0 0.4445)
			(size 0.1397 0.1397)
			(layers "F.Cu" "F.Mask" "F.Paste")
			(net "GND")
			(options
				(clearance outline)
				(anchor circle)
			)
			(primitives
				(gr_poly
					(pts
						(arc
							(start -0.1778 -0.2794)
							(mid -0.249642 -0.249642)
							(end -0.2794 -0.1778)
						)
						(arc
							(start -0.2794 0.1778)
							(mid -0.249642 0.249642)
							(end -0.1778 0.2794)
						)
						(arc
							(start 0.1778 0.2794)
							(mid 0.249642 0.249642)
							(end 0.2794 0.1778)
						)
						(arc
							(start 0.2794 -0.1778)
							(mid 0.249642 -0.249642)
							(end 0.1778 -0.2794)
						)
					)
					(width 0)
					(fill yes)
				)
			)
		)
	)
	(footprint ""
		(layer "F.Cu")
		(at 95.504 -221.361)
		(property "Reference" "SR312"
			(at 0 0 0)
			(layer "F.SilkS")
			(hide yes)
			(effects
				(font
					(size 1.27 1.27)
				)
			)
		)
		(property "Value" "0R2J-2-GP"
			(at 0.064008 -3.993896 0)
			(unlocked yes)
			(layer "F.Fab")
			(hide yes)
			(effects
				(font
					(size 1.016 1.016)
					(thickness 0.1524)
				)
			)
		)
		(property "Device Type" "R402H16"
			(at 0.064008 -5.517896 0)
			(unlocked yes)
			(layer "F.Fab")
			(hide yes)
			(effects
				(font
					(size 1.016 1.016)
					(thickness 0.1524)
				)
			)
		)
		(duplicate_pad_numbers_are_jumpers no)
		(fp_line
			(start -0.508 -0.9398)
			(end -0.508 0.9398)
			(stroke
				(width 0.1524)
				(type default)
			)
			(layer "F.SilkS")
		)
		(fp_line
			(start 0.508 -0.9398)
			(end -0.508 -0.9398)
			(stroke
				(width 0.1524)
				(type default)
			)
			(layer "F.SilkS")
		)
		(fp_rect
			(start -0.508 0.9398)
			(end 0.508 -0.9398)
			(stroke
				(width 0)
				(type default)
			)
			(fill no)
			(layer "F.CrtYd")
		)
		(fp_rect
			(start -0.508 0.9398)
			(end 0.508 -0.9398)
			(stroke
				(width 0)
				(type default)
			)
			(fill no)
			(layer "F.Fab")
		)
		(pad "1" smd custom
			(at 0 -0.4445)
			(size 0.1397 0.1397)
			(layers "F.Cu" "F.Mask" "F.Paste")
			(net "FAULT_SCL")
			(options
				(clearance outline)
				(anchor circle)
			)
			(primitives
				(gr_poly
					(pts
						(arc
							(start -0.1778 -0.2794)
							(mid -0.249642 -0.249642)
							(end -0.2794 -0.1778)
						)
						(arc
							(start -0.2794 0.1778)
							(mid -0.249642 0.249642)
							(end -0.1778 0.2794)
						)
						(arc
							(start 0.1778 0.2794)
							(mid 0.249642 0.249642)
							(end 0.2794 0.1778)
						)
						(arc
							(start 0.2794 -0.1778)
							(mid 0.249642 -0.249642)
							(end 0.1778 -0.2794)
						)
					)
					(width 0)
					(fill yes)
				)
			)
		)
		(pad "2" smd custom
			(at 0 0.4445)
			(size 0.1397 0.1397)
			(layers "F.Cu" "F.Mask" "F.Paste")
			(net "BMC_I2C_SCL_10")
			(options
				(clearance outline)
				(anchor circle)
			)
			(primitives
				(gr_poly
					(pts
						(arc
							(start -0.1778 -0.2794)
							(mid -0.249642 -0.249642)
							(end -0.2794 -0.1778)
						)
						(arc
							(start -0.2794 0.1778)
							(mid -0.249642 0.249642)
							(end -0.1778 0.2794)
						)
						(arc
							(start 0.1778 0.2794)
							(mid 0.249642 0.249642)
							(end 0.2794 0.1778)
						)
						(arc
							(start 0.2794 -0.1778)
							(mid 0.249642 -0.249642)
							(end 0.1778 -0.2794)
						)
					)
					(width 0)
					(fill yes)
				)
			)
		)
	)
	(footprint ""
		(layer "F.Cu")
		(at 186.309 -51.054 180)
		(property "Reference" "U45"
			(at 0 0 180)
			(layer "F.SilkS")
			(hide yes)
			(effects
				(font
					(size 1.27 1.27)
				)
			)
		)
		(property "Value" "SN74LVC1G11DCKR-GP"
			(at 0.0508 -11.5824 180)
			(unlocked yes)
			(layer "F.Fab")
			(hide yes)
			(effects
				(font
					(size 1.016 1.016)
					(thickness 0.1524)
				)
			)
		)
		(property "Device Type" "UMT6H44"
			(at 0.0508 -13.1572 180)
			(unlocked yes)
			(layer "F.Fab")
			(hide yes)
			(effects
				(font
					(size 1.016 1.016)
					(thickness 0.1524)
				)
			)
		)
		(duplicate_pad_numbers_are_jumpers no)
		(fp_line
			(start 1.524 0.36449)
			(end -1.27 0.36449)
			(stroke
				(width 0.1524)
				(type default)
			)
			(layer "F.SilkS")
		)
		(fp_line
			(start 1.524 -0.36449)
			(end 1.524 0.36449)
			(stroke
				(width 0.1524)
				(type default)
			)
			(layer "F.SilkS")
		)
		(fp_line
			(start 1.524 -0.36449)
			(end 1.524 -1.82245)
			(stroke
				(width 0.508)
				(type default)
			)
			(layer "F.SilkS")
		)
		(fp_line
			(start 1.524 -0.36449)
			(end 1.45796 -0.36449)
			(stroke
				(width 0.1524)
				(type default)
			)
			(layer "F.SilkS")
		)
		(fp_line
			(start 1.45796 -0.36449)
			(end 1.09347 0)
			(stroke
				(width 0.1524)
				(type default)
			)
			(layer "F.SilkS")
		)
		(fp_line
			(start 1.09347 0)
			(end 1.45796 0.36449)
			(stroke
				(width 0.1524)
				(type default)
			)
			(layer "F.SilkS")
		)
		(fp_line
			(start -1.27 -0.36449)
			(end 1.524 -0.36449)
			(stroke
				(width 0.1524)
				(type default)
			)
			(layer "F.SilkS")
		)
		(fp_line
			(start -1.27 -0.36449)
			(end -1.27 0.36449)
			(stroke
				(width 0.1524)
				(type default)
			)
			(layer "F.SilkS")
		)
		(fp_poly
			(pts
				(xy -0.65024 0.36449) (xy -0.65024 -0.36449) (xy 0.65024 -0.36449) (xy 0.65024 0.36449)
			)
			(stroke
				(width 0)
				(type default)
			)
			(fill yes)
			(layer "F.SilkS")
		)
		(fp_poly
			(pts
				(xy 1.016 -1.0668) (xy 1.016 1.0668) (xy -1.016 1.0668) (xy -1.016 -1.0668)
			)
			(stroke
				(width 0)
				(type default)
			)
			(fill no)
			(layer "F.CrtYd")
		)
		(fp_poly
			(pts
				(xy -1.524 1.905) (xy 1.524 1.905) (xy 1.524 -1.06426) (xy 1.016 -1.06426) (xy 1.016 1.0668) (xy -1.016 1.0668)
				(xy -1.016 -1.0668) (xy 1.524 -1.0668) (xy 1.524 -1.905) (xy -1.524 -1.905)
			)
			(stroke
				(width 0)
				(type default)
			)
			(fill no)
			(layer "F.CrtYd")
		)
		(fp_poly
			(pts
				(xy -1.524 -1.905) (xy -1.524 1.905) (xy 1.524 1.905) (xy 1.524 -1.905)
			)
			(stroke
				(width 0)
				(type default)
			)
			(fill no)
			(layer "F.Fab")
		)
		(pad "1" smd rect
			(at 0.65024 -1.02489 180)
			(size 0.4064 0.8128)
			(layers "F.Cu" "F.Mask" "F.Paste")
			(net "PRSNT_AND_2")
		)
		(pad "2" smd rect
			(at 0 -1.02489 180)
			(size 0.4064 0.8128)
			(layers "F.Cu" "F.Mask" "F.Paste")
			(net "GND")
		)
		(pad "3" smd rect
			(at -0.65024 -1.02489 180)
			(size 0.4064 0.8128)
			(layers "F.Cu" "F.Mask" "F.Paste")
			(net "PRSNT_MSB_AND_1")
		)
		(pad "4" smd rect
			(at -0.65024 1.02489 180)
			(size 0.4064 0.8128)
			(layers "F.Cu" "F.Mask" "F.Paste")
			(net "PRSNT_EN_HPIC")
		)
		(pad "5" smd rect
			(at 0 1.02489 180)
			(size 0.4064 0.8128)
			(layers "F.Cu" "F.Mask" "F.Paste")
			(net "P3V3_STBY")
		)
		(pad "6" smd rect
			(at 0.65024 1.02489 180)
			(size 0.4064 0.8128)
			(layers "F.Cu" "F.Mask" "F.Paste")
			(net "MSB_PRSNT_AND_3")
		)
	)
	(footprint ""
		(layer "F.Cu")
		(at 307.975 -193.802 180)
		(property "Reference" "R171"
			(at 0 0 180)
			(layer "F.SilkS")
			(hide yes)
			(effects
				(font
					(size 1.27 1.27)
				)
			)
		)
		(property "Value" "100KR2F-L1-GP"
			(at 0.064008 -3.993896 180)
			(unlocked yes)
			(layer "F.Fab")
			(hide yes)
			(effects
				(font
					(size 1.016 1.016)
					(thickness 0.1524)
				)
			)
		)
		(property "Device Type" "R402H16"
			(at 0.064008 -5.517896 180)
			(unlocked yes)
			(layer "F.Fab")
			(hide yes)
			(effects
				(font
					(size 1.016 1.016)
					(thickness 0.1524)
				)
			)
		)
		(duplicate_pad_numbers_are_jumpers no)
		(fp_line
			(start 0.508 -0.9398)
			(end -0.508 -0.9398)
			(stroke
				(width 0.1524)
				(type default)
			)
			(layer "F.SilkS")
		)
		(fp_line
			(start -0.508 -0.9398)
			(end -0.508 0.9398)
			(stroke
				(width 0.1524)
				(type default)
			)
			(layer "F.SilkS")
		)
		(fp_rect
			(start -0.508 0.9398)
			(end 0.508 -0.9398)
			(stroke
				(width 0)
				(type default)
			)
			(fill no)
			(layer "F.CrtYd")
		)
		(fp_rect
			(start -0.508 0.9398)
			(end 0.508 -0.9398)
			(stroke
				(width 0)
				(type default)
			)
			(fill no)
			(layer "F.Fab")
		)
		(pad "1" smd custom
			(at 0 -0.4445 180)
			(size 0.1397 0.1397)
			(layers "F.Cu" "F.Mask" "F.Paste")
			(net "P3V3_STBY")
			(options
				(clearance outline)
				(anchor circle)
			)
			(primitives
				(gr_poly
					(pts
						(arc
							(start -0.1778 -0.2794)
							(mid -0.249642 -0.249642)
							(end -0.2794 -0.1778)
						)
						(arc
							(start -0.2794 0.1778)
							(mid -0.249642 0.249642)
							(end -0.1778 0.2794)
						)
						(arc
							(start 0.1778 0.2794)
							(mid 0.249642 0.249642)
							(end 0.2794 0.1778)
						)
						(arc
							(start 0.2794 -0.1778)
							(mid 0.249642 -0.249642)
							(end 0.1778 -0.2794)
						)
					)
					(width 0)
					(fill yes)
				)
			)
		)
		(pad "2" smd custom
			(at 0 0.4445 180)
			(size 0.1397 0.1397)
			(layers "F.Cu" "F.Mask" "F.Paste")
			(net "LED_DR_LED1")
			(options
				(clearance outline)
				(anchor circle)
			)
			(primitives
				(gr_poly
					(pts
						(arc
							(start -0.1778 -0.2794)
							(mid -0.249642 -0.249642)
							(end -0.2794 -0.1778)
						)
						(arc
							(start -0.2794 0.1778)
							(mid -0.249642 0.249642)
							(end -0.1778 0.2794)
						)
						(arc
							(start 0.1778 0.2794)
							(mid 0.249642 0.249642)
							(end 0.2794 0.1778)
						)
						(arc
							(start 0.2794 -0.1778)
							(mid 0.249642 -0.249642)
							(end 0.1778 -0.2794)
						)
					)
					(width 0)
					(fill yes)
				)
			)
		)
	)
	(footprint ""
		(layer "F.Cu")
		(at 56.388 -218.059 90)
		(property "Reference" "U2"
			(at 0 0 90)
			(layer "F.SilkS")
			(hide yes)
			(effects
				(font
					(size 1.27 1.27)
				)
			)
		)
		(property "Value" "ADM1278-2ACPZ-RL-1-GP"
			(at -4.7625 -7.4422 90)
			(unlocked yes)
			(layer "F.Fab")
			(hide yes)
			(effects
				(font
					(size 1.016 1.016)
					(thickness 0.1524)
				)
			)
		)
		(property "Device Type" "QFN32-G3D45-UH32"
			(at -4.7625 -8.9662 90)
			(unlocked yes)
			(layer "F.Fab")
			(hide yes)
			(effects
				(font
					(size 1.016 1.016)
					(thickness 0.1524)
				)
			)
		)
		(duplicate_pad_numbers_are_jumpers no)
		(fp_line
			(start -0.250698 -3.7973)
			(end -0.250698 -3.2893)
			(stroke
				(width 0.1524)
				(type default)
			)
			(layer "F.SilkS")
		)
		(fp_line
			(start -3.5179 -3.5179)
			(end -2.2479 -3.5179)
			(stroke
				(width 0.1524)
				(type default)
			)
			(layer "F.SilkS")
		)
		(fp_line
			(start -3.5179 -2.2479)
			(end -3.5179 -3.5179)
			(stroke
				(width 0.1524)
				(type default)
			)
			(layer "F.SilkS")
		)
		(fp_line
			(start -4.0513 -1.24968)
			(end -3.2893 -1.24968)
			(stroke
				(width 0.1524)
				(type default)
			)
			(layer "F.SilkS")
		)
		(fp_line
			(start 4.0513 -0.749808)
			(end 3.2893 -0.749808)
			(stroke
				(width 0.1524)
				(type default)
			)
			(layer "F.SilkS")
		)
		(fp_line
			(start -3.7973 1.24968)
			(end -3.2893 1.24968)
			(stroke
				(width 0.1524)
				(type default)
			)
			(layer "F.SilkS")
		)
		(fp_line
			(start 3.7973 1.749552)
			(end 3.2893 1.749552)
			(stroke
				(width 0.1524)
				(type default)
			)
			(layer "F.SilkS")
		)
		(fp_line
			(start 3.5179 2.2479)
			(end 3.5179 3.5179)
			(stroke
				(width 0.1524)
				(type default)
			)
			(layer "F.SilkS")
		)
		(fp_line
			(start -3.5179 2.2479)
			(end -3.5179 3.5179)
			(stroke
				(width 0.1524)
				(type default)
			)
			(layer "F.SilkS")
		)
		(fp_line
			(start 3.5179 3.5179)
			(end 2.2479 3.5179)
			(stroke
				(width 0.1524)
				(type default)
			)
			(layer "F.SilkS")
		)
		(fp_line
			(start -3.5179 3.5179)
			(end -2.2479 3.5179)
			(stroke
				(width 0.1524)
				(type default)
			)
			(layer "F.SilkS")
		)
		(fp_line
			(start -0.250698 4.0513)
			(end -0.250698 3.2893)
			(stroke
				(width 0.1524)
				(type default)
			)
			(layer "F.SilkS")
		)
		(fp_poly
			(pts
				(xy 2.2479 -3.5179) (xy 3.5179 -2.2479) (xy 3.5179 -3.5179)
			)
			(stroke
				(width 0)
				(type default)
			)
			(fill yes)
			(layer "F.SilkS")
		)
		(fp_rect
			(start -2.5019 2.5019)
			(end 2.5019 -2.5019)
			(stroke
				(width 0)
				(type default)
			)
			(fill no)
			(layer "F.CrtYd")
		)
		(fp_poly
			(pts
				(xy -3.5179 3.5179) (xy -3.5179 -3.5179) (xy 3.5179 -3.5179) (xy 3.5179 3.5179) (xy -2.49682 3.5179)
				(xy -2.49682 2.5019) (xy 2.5019 2.5019) (xy 2.5019 -2.5019) (xy -2.5019 -2.5019) (xy -2.5019 3.5179)
			)
			(stroke
				(width 0)
				(type default)
			)
			(fill no)
			(layer "F.CrtYd")
		)
		(fp_rect
			(start -3.5179 3.5179)
			(end 3.5179 -3.5179)
			(stroke
				(width 0)
				(type default)
			)
			(fill no)
			(layer "F.Fab")
		)
		(pad "1" smd rect
			(at 1.75006 -2.5527 90)
			(size 0.3048 0.9144)
			(layers "F.Cu" "F.Mask" "F.Paste")
			(net "MB0_PSET_R")
		)
		(pad "2" smd rect
			(at 1.249934 -2.4765 90)
			(size 0.3048 1.0668)
			(layers "F.Cu" "F.Mask" "F.Paste")
			(net "MB0_VCAP_R")
		)
		(pad "3" smd rect
			(at 0.750062 -2.4765 90)
			(size 0.3048 1.0668)
			(layers "F.Cu" "F.Mask" "F.Paste")
			(net "MB0_ISET_R")
		)
		(pad "4" smd rect
			(at 0.249936 -2.4765 90)
			(size 0.3048 1.0668)
			(layers "F.Cu" "F.Mask" "F.Paste")
			(net "MB0_ISTART_R")
		)
		(pad "5" smd rect
			(at -0.249936 -2.4765 90)
			(size 0.3048 1.0668)
			(layers "F.Cu" "F.Mask" "F.Paste")
			(net "MB0_TIME_R")
		)
		(pad "6" smd rect
			(at -0.750062 -2.4765 90)
			(size 0.3048 1.0668)
			(layers "F.Cu" "F.Mask" "F.Paste")
			(net "Net_88")
		)
		(pad "7" smd rect
			(at -1.249934 -2.4765 90)
			(size 0.3048 1.0668)
			(layers "F.Cu" "F.Mask" "F.Paste")
			(net "MB0_CM_ADR1_R")
		)
		(pad "8" smd rect
			(at -1.75006 -2.5527 90)
			(size 0.3048 0.9144)
			(layers "F.Cu" "F.Mask" "F.Paste")
			(net "MB0_CM_ADR2_R")
		)
		(pad "9" smd rect
			(at -2.5527 -1.75006 90)
			(size 0.9144 0.3048)
			(layers "F.Cu" "F.Mask" "F.Paste")
			(net "MB0_SPISS_PD")
		)
		(pad "10" smd rect
			(at -2.4765 -1.249934 90)
			(size 1.0668 0.3048)
			(layers "F.Cu" "F.Mask" "F.Paste")
			(net "Net_92")
		)
		(pad "11" smd rect
			(at -2.4765 -0.750062 90)
			(size 1.0668 0.3048)
			(layers "F.Cu" "F.Mask" "F.Paste")
			(net "Net_91")
		)
		(pad "12" smd rect
			(at -2.4765 -0.249936 90)
			(size 1.0668 0.3048)
			(layers "F.Cu" "F.Mask" "F.Paste")
			(net "MB0_HS_ENABLE")
		)
		(pad "13" smd rect
			(at -2.4765 0.249936 90)
			(size 1.0668 0.3048)
			(layers "F.Cu" "F.Mask" "F.Paste")
			(net "Net_90")
		)
		(pad "14" smd rect
			(at -2.4765 0.750062 90)
			(size 1.0668 0.3048)
			(layers "F.Cu" "F.Mask" "F.Paste")
			(net "Net_89")
		)
		(pad "15" smd rect
			(at -2.4765 1.249934 90)
			(size 1.0668 0.3048)
			(layers "F.Cu" "F.Mask" "F.Paste")
			(net "HSW_SDA_2")
		)
		(pad "16" smd rect
			(at -2.5527 1.75006 90)
			(size 0.9144 0.3048)
			(layers "F.Cu" "F.Mask" "F.Paste")
			(net "HSW_SCL_2")
		)
		(pad "17" smd rect
			(at -1.75006 2.5527 90)
			(size 0.3048 0.9144)
			(layers "F.Cu" "F.Mask" "F.Paste")
			(net "MB0_RETRY_R")
		)
		(pad "18" smd rect
			(at -1.249934 2.4765 90)
			(size 0.3048 1.0668)
			(layers "F.Cu" "F.Mask" "F.Paste")
			(net "MB0_P12V_PWRGOOD")
		)
		(pad "19" smd rect
			(at -0.750062 2.4765 90)
			(size 0.3048 1.0668)
			(layers "F.Cu" "F.Mask" "F.Paste")
			(net "Net_93")
		)
		(pad "20" smd rect
			(at -0.249936 2.4765 90)
			(size 0.3048 1.0668)
			(layers "F.Cu" "F.Mask" "F.Paste")
			(net "MB0_CM_VOUT_R")
		)
		(pad "21" smd rect
			(at 0.249936 2.4765 90)
			(size 0.3048 1.0668)
			(layers "F.Cu" "F.Mask" "F.Paste")
			(net "MB0_P12V_PWGIN_R")
		)
		(pad "22" smd rect
			(at 0.750062 2.4765 90)
			(size 0.3048 1.0668)
			(layers "F.Cu" "F.Mask" "F.Paste")
			(net "AGND_CURRENT_MON")
		)
		(pad "23" smd rect
			(at 1.249934 2.4765 90)
			(size 0.3048 1.0668)
			(layers "F.Cu" "F.Mask" "F.Paste")
			(net "GND")
		)
		(pad "24" smd rect
			(at 1.75006 2.5527 90)
			(size 0.3048 0.9144)
			(layers "F.Cu" "F.Mask" "F.Paste")
			(net "MB0_CM_GATE")
		)
		(pad "25" smd rect
			(at 2.5527 1.75006 90)
			(size 0.9144 0.3048)
			(layers "F.Cu" "F.Mask" "F.Paste")
			(net "MB0_TEMP")
		)
		(pad "26" smd rect
			(at 2.4765 1.249934 90)
			(size 1.0668 0.3048)
			(layers "F.Cu" "F.Mask" "F.Paste")
			(net "MB0_CM_SENSE_N")
		)
		(pad "27" smd rect
			(at 2.4765 0.750062 90)
			(size 1.0668 0.3048)
			(layers "F.Cu" "F.Mask" "F.Paste")
			(net "MB0_P12V_MAIN_R")
		)
		(pad "28" smd rect
			(at 2.4765 0.249936 90)
			(size 1.0668 0.3048)
			(layers "F.Cu" "F.Mask" "F.Paste")
			(net "P12V_PCIE")
		)
		(pad "29" smd rect
			(at 2.4765 -0.249936 90)
			(size 1.0668 0.3048)
			(layers "F.Cu" "F.Mask" "F.Paste")
			(net "MB0_CM_SENSE_P")
		)
		(pad "30" smd rect
			(at 2.4765 -0.750062 90)
			(size 1.0668 0.3048)
			(layers "F.Cu" "F.Mask" "F.Paste")
			(net "MB0_VCC")
		)
		(pad "31" smd rect
			(at 2.4765 -1.249934 90)
			(size 1.0668 0.3048)
			(layers "F.Cu" "F.Mask" "F.Paste")
			(net "MB0_CM_UV_R")
		)
		(pad "32" smd rect
			(at 2.5527 -1.75006 90)
			(size 0.9144 0.3048)
			(layers "F.Cu" "F.Mask" "F.Paste")
			(net "MB0_CM_OV_R")
		)
		(pad "33" smd rect
			(at 0 0 90)
			(size 3.4544 3.4544)
			(layers "F.Cu" "F.Mask" "F.Paste")
			(net "AGND_CURRENT_MON")
		)
	)
	(footprint ""
		(layer "F.Cu")
		(at 339.471 -34.798)
		(property "Reference" "R487"
			(at 0 0 0)
			(layer "F.SilkS")
			(hide yes)
			(effects
				(font
					(size 1.27 1.27)
				)
			)
		)
		(property "Value" "0R2J-2-GP"
			(at 0.064008 -3.993896 0)
			(unlocked yes)
			(layer "F.Fab")
			(hide yes)
			(effects
				(font
					(size 1.016 1.016)
					(thickness 0.1524)
				)
			)
		)
		(property "Device Type" "R402H16"
			(at 0.064008 -5.517896 0)
			(unlocked yes)
			(layer "F.Fab")
			(hide yes)
			(effects
				(font
					(size 1.016 1.016)
					(thickness 0.1524)
				)
			)
		)
		(duplicate_pad_numbers_are_jumpers no)
		(fp_line
			(start -0.508 -0.9398)
			(end -0.508 0.9398)
			(stroke
				(width 0.1524)
				(type default)
			)
			(layer "F.SilkS")
		)
		(fp_line
			(start 0.508 -0.9398)
			(end -0.508 -0.9398)
			(stroke
				(width 0.1524)
				(type default)
			)
			(layer "F.SilkS")
		)
		(fp_rect
			(start -0.508 0.9398)
			(end 0.508 -0.9398)
			(stroke
				(width 0)
				(type default)
			)
			(fill no)
			(layer "F.CrtYd")
		)
		(fp_rect
			(start -0.508 0.9398)
			(end 0.508 -0.9398)
			(stroke
				(width 0)
				(type default)
			)
			(fill no)
			(layer "F.Fab")
		)
		(pad "1" smd custom
			(at 0 -0.4445)
			(size 0.1397 0.1397)
			(layers "F.Cu" "F.Mask" "F.Paste")
			(net "BMC_UART_SWITCH_2")
			(options
				(clearance outline)
				(anchor circle)
			)
			(primitives
				(gr_poly
					(pts
						(arc
							(start -0.1778 -0.2794)
							(mid -0.249642 -0.249642)
							(end -0.2794 -0.1778)
						)
						(arc
							(start -0.2794 0.1778)
							(mid -0.249642 0.249642)
							(end -0.1778 0.2794)
						)
						(arc
							(start 0.1778 0.2794)
							(mid 0.249642 0.249642)
							(end 0.2794 0.1778)
						)
						(arc
							(start 0.2794 -0.1778)
							(mid 0.249642 -0.249642)
							(end 0.1778 -0.2794)
						)
					)
					(width 0)
					(fill yes)
				)
			)
		)
		(pad "2" smd custom
			(at 0 0.4445)
			(size 0.1397 0.1397)
			(layers "F.Cu" "F.Mask" "F.Paste")
			(net "BMC_CONSOLE_LED1_R")
			(options
				(clearance outline)
				(anchor circle)
			)
			(primitives
				(gr_poly
					(pts
						(arc
							(start -0.1778 -0.2794)
							(mid -0.249642 -0.249642)
							(end -0.2794 -0.1778)
						)
						(arc
							(start -0.2794 0.1778)
							(mid -0.249642 0.249642)
							(end -0.1778 0.2794)
						)
						(arc
							(start 0.1778 0.2794)
							(mid 0.249642 0.249642)
							(end 0.2794 0.1778)
						)
						(arc
							(start 0.2794 -0.1778)
							(mid 0.249642 -0.249642)
							(end 0.1778 -0.2794)
						)
					)
					(width 0)
					(fill yes)
				)
			)
		)
	)
	(footprint ""
		(layer "F.Cu")
		(at 85.452966 -80.391)
		(property "Reference" "SC1195"
			(at 0 0 0)
			(layer "F.SilkS")
			(hide yes)
			(effects
				(font
					(size 1.27 1.27)
				)
			)
		)
		(property "Value" "SC10U6D3V5KX-4GP"
			(at -0.0762 -6.1214 0)
			(unlocked yes)
			(layer "F.Fab")
			(hide yes)
			(effects
				(font
					(size 1.016 1.016)
					(thickness 0.1524)
				)
			)
		)
		(property "Device Type" "C805H58"
			(at -0.0762 -8.1534 0)
			(unlocked yes)
			(layer "F.Fab")
			(hide yes)
			(effects
				(font
					(size 1.016 1.016)
					(thickness 0.1524)
				)
			)
		)
		(duplicate_pad_numbers_are_jumpers no)
		(fp_line
			(start 0.635 0)
			(end -0.635 0)
			(stroke
				(width 0.508)
				(type default)
			)
			(layer "F.SilkS")
		)
		(fp_rect
			(start -0.9652 1.778)
			(end 0.9652 -1.778)
			(stroke
				(width 0)
				(type default)
			)
			(fill no)
			(layer "F.CrtYd")
		)
		(fp_poly
			(pts
				(xy -0.9652 -1.778) (xy 0.9652 -1.778) (xy 0.9652 1.778) (xy -0.9652 1.778)
			)
			(stroke
				(width 0)
				(type default)
			)
			(fill no)
			(layer "F.Fab")
		)
		(pad "1" smd rect
			(at 0 -0.9652)
			(size 1.397 1.143)
			(layers "F.Cu" "F.Mask" "F.Paste")
			(net "XTAL_VDDA09")
		)
		(pad "2" smd rect
			(at 0 0.9652)
			(size 1.397 1.143)
			(layers "F.Cu" "F.Mask" "F.Paste")
			(net "GND")
		)
	)
	(footprint ""
		(layer "F.Cu")
		(at 152.247092 -110.773464 -90)
		(property "Reference" "SR834"
			(at 0 0 270)
			(layer "F.SilkS")
			(hide yes)
			(effects
				(font
					(size 1.27 1.27)
				)
			)
		)
		(property "Value" "D51R3F-2-GP"
			(at -0.0254 -2.5146 270)
			(unlocked yes)
			(layer "F.Fab")
			(hide yes)
			(effects
				(font
					(size 1.016 1.016)
					(thickness 0.1524)
				)
			)
		)
		(property "Device Type" "R603H22"
			(at -0.0254 -4.0386 270)
			(unlocked yes)
			(layer "F.Fab")
			(hide yes)
			(effects
				(font
					(size 1.016 1.016)
					(thickness 0.1524)
				)
			)
		)
		(duplicate_pad_numbers_are_jumpers no)
		(fp_line
			(start -0.4826 0)
			(end -0.2032 0)
			(stroke
				(width 0.2032)
				(type default)
			)
			(layer "F.SilkS")
		)
		(fp_line
			(start 0.2032 0)
			(end 0.4826 0)
			(stroke
				(width 0.2032)
				(type default)
			)
			(layer "F.SilkS")
		)
		(fp_rect
			(start -0.5842 1.3335)
			(end 0.5842 -1.3335)
			(stroke
				(width 0)
				(type default)
			)
			(fill no)
			(layer "F.CrtYd")
		)
		(fp_rect
			(start -0.5842 1.3335)
			(end 0.5842 -1.3335)
			(stroke
				(width 0)
				(type default)
			)
			(fill no)
			(layer "F.Fab")
		)
		(pad "1" smd custom
			(at 0 -0.762 270)
			(size 0.2159 0.2159)
			(layers "F.Cu" "F.Mask" "F.Paste")
			(net "P0V9_E")
			(options
				(clearance outline)
				(anchor circle)
			)
			(primitives
				(gr_poly
					(pts
						(arc
							(start -0.3302 -0.4318)
							(mid -0.402042 -0.402042)
							(end -0.4318 -0.3302)
						)
						(arc
							(start -0.4318 0.3302)
							(mid -0.402042 0.402042)
							(end -0.3302 0.4318)
						)
						(arc
							(start 0.3302 0.4318)
							(mid 0.402042 0.402042)
							(end 0.4318 0.3302)
						)
						(arc
							(start 0.4318 -0.3302)
							(mid 0.402042 -0.402042)
							(end 0.3302 -0.4318)
						)
					)
					(width 0)
					(fill yes)
				)
			)
		)
		(pad "2" smd custom
			(at 0 0.762 270)
			(size 0.2159 0.2159)
			(layers "F.Cu" "F.Mask" "F.Paste")
			(net "GB_VDDA")
			(options
				(clearance outline)
				(anchor circle)
			)
			(primitives
				(gr_poly
					(pts
						(arc
							(start -0.3302 -0.4318)
							(mid -0.402042 -0.402042)
							(end -0.4318 -0.3302)
						)
						(arc
							(start -0.4318 0.3302)
							(mid -0.402042 0.402042)
							(end -0.3302 0.4318)
						)
						(arc
							(start 0.3302 0.4318)
							(mid 0.402042 0.402042)
							(end 0.4318 0.3302)
						)
						(arc
							(start 0.4318 -0.3302)
							(mid 0.402042 -0.402042)
							(end 0.3302 -0.4318)
						)
					)
					(width 0)
					(fill yes)
				)
			)
		)
	)
	(footprint ""
		(layer "F.Cu")
		(at 184.031128 -16.183864 180)
		(property "Reference" "R196"
			(at 0 0 180)
			(layer "F.SilkS")
			(hide yes)
			(effects
				(font
					(size 1.27 1.27)
				)
			)
		)
		(property "Value" "4K7R2F-GP"
			(at 0.064008 -3.993896 180)
			(unlocked yes)
			(layer "F.Fab")
			(hide yes)
			(effects
				(font
					(size 1.016 1.016)
					(thickness 0.1524)
				)
			)
		)
		(property "Device Type" "R402H16"
			(at 0.064008 -5.517896 180)
			(unlocked yes)
			(layer "F.Fab")
			(hide yes)
			(effects
				(font
					(size 1.016 1.016)
					(thickness 0.1524)
				)
			)
		)
		(duplicate_pad_numbers_are_jumpers no)
		(fp_line
			(start 0.508 -0.9398)
			(end -0.508 -0.9398)
			(stroke
				(width 0.1524)
				(type default)
			)
			(layer "F.SilkS")
		)
		(fp_line
			(start -0.508 -0.9398)
			(end -0.508 0.9398)
			(stroke
				(width 0.1524)
				(type default)
			)
			(layer "F.SilkS")
		)
		(fp_rect
			(start -0.508 0.9398)
			(end 0.508 -0.9398)
			(stroke
				(width 0)
				(type default)
			)
			(fill no)
			(layer "F.CrtYd")
		)
		(fp_rect
			(start -0.508 0.9398)
			(end 0.508 -0.9398)
			(stroke
				(width 0)
				(type default)
			)
			(fill no)
			(layer "F.Fab")
		)
		(pad "1" smd custom
			(at 0 -0.4445 180)
			(size 0.1397 0.1397)
			(layers "F.Cu" "F.Mask" "F.Paste")
			(net "TEMP_1_A1")
			(options
				(clearance outline)
				(anchor circle)
			)
			(primitives
				(gr_poly
					(pts
						(arc
							(start -0.1778 -0.2794)
							(mid -0.249642 -0.249642)
							(end -0.2794 -0.1778)
						)
						(arc
							(start -0.2794 0.1778)
							(mid -0.249642 0.249642)
							(end -0.1778 0.2794)
						)
						(arc
							(start 0.1778 0.2794)
							(mid 0.249642 0.249642)
							(end 0.2794 0.1778)
						)
						(arc
							(start 0.2794 -0.1778)
							(mid 0.249642 -0.249642)
							(end 0.1778 -0.2794)
						)
					)
					(width 0)
					(fill yes)
				)
			)
		)
		(pad "2" smd custom
			(at 0 0.4445 180)
			(size 0.1397 0.1397)
			(layers "F.Cu" "F.Mask" "F.Paste")
			(net "GND")
			(options
				(clearance outline)
				(anchor circle)
			)
			(primitives
				(gr_poly
					(pts
						(arc
							(start -0.1778 -0.2794)
							(mid -0.249642 -0.249642)
							(end -0.2794 -0.1778)
						)
						(arc
							(start -0.2794 0.1778)
							(mid -0.249642 0.249642)
							(end -0.1778 0.2794)
						)
						(arc
							(start 0.1778 0.2794)
							(mid 0.249642 0.249642)
							(end 0.2794 0.1778)
						)
						(arc
							(start 0.2794 -0.1778)
							(mid 0.249642 -0.249642)
							(end 0.1778 -0.2794)
						)
					)
					(width 0)
					(fill yes)
				)
			)
		)
	)
	(footprint ""
		(layer "F.Cu")
		(at 187.481718 -138.802872)
		(property "Reference" "SC1108"
			(at 0 0 0)
			(layer "F.SilkS")
			(hide yes)
			(effects
				(font
					(size 1.27 1.27)
				)
			)
		)
		(property "Value" "SCD1U16V2KX-3GP"
			(at 1.1811 -2.7051 0)
			(unlocked yes)
			(layer "F.Fab")
			(hide yes)
			(effects
				(font
					(size 1.016 1.016)
					(thickness 0.1524)
				)
			)
		)
		(property "Device Type" "C402H22"
			(at 1.1811 -4.2291 0)
			(unlocked yes)
			(layer "F.Fab")
			(hide yes)
			(effects
				(font
					(size 1.016 1.016)
					(thickness 0.1524)
				)
			)
		)
		(duplicate_pad_numbers_are_jumpers no)
		(fp_rect
			(start -0.4318 0.9525)
			(end 0.4318 -0.9525)
			(stroke
				(width 0)
				(type default)
			)
			(fill no)
			(layer "F.CrtYd")
		)
		(fp_rect
			(start -0.4318 0.9525)
			(end 0.4318 -0.9525)
			(stroke
				(width 0)
				(type default)
			)
			(fill no)
			(layer "F.Fab")
		)
		(pad "1" smd custom
			(at 0 -0.4445)
			(size 0.1524 0.1524)
			(layers "F.Cu" "F.Mask" "F.Paste")
			(net "P1V8_E")
			(options
				(clearance outline)
				(anchor circle)
			)
			(primitives
				(gr_poly
					(pts
						(arc
							(start 0.3048 -0.2032)
							(mid 0.275042 -0.275042)
							(end 0.2032 -0.3048)
						)
						(arc
							(start -0.2032 -0.3048)
							(mid -0.275042 -0.275042)
							(end -0.3048 -0.2032)
						)
						(arc
							(start -0.3048 0.2032)
							(mid -0.275042 0.275042)
							(end -0.2032 0.3048)
						)
						(arc
							(start 0.2032 0.3048)
							(mid 0.275042 0.275042)
							(end 0.3048 0.2032)
						)
					)
					(width 0)
					(fill yes)
				)
			)
		)
		(pad "2" smd custom
			(at 0 0.4445)
			(size 0.1524 0.1524)
			(layers "F.Cu" "F.Mask" "F.Paste")
			(net "GND")
			(options
				(clearance outline)
				(anchor circle)
			)
			(primitives
				(gr_poly
					(pts
						(arc
							(start 0.3048 -0.2032)
							(mid 0.275042 -0.275042)
							(end 0.2032 -0.3048)
						)
						(arc
							(start -0.2032 -0.3048)
							(mid -0.275042 -0.275042)
							(end -0.3048 -0.2032)
						)
						(arc
							(start -0.3048 0.2032)
							(mid -0.275042 0.275042)
							(end -0.2032 0.3048)
						)
						(arc
							(start 0.2032 0.3048)
							(mid 0.275042 0.275042)
							(end 0.3048 0.2032)
						)
					)
					(width 0)
					(fill yes)
				)
			)
		)
	)
	(footprint ""
		(layer "F.Cu")
		(at 242.6843 -114.4778 90)
		(property "Reference" "U185"
			(at 0 0 90)
			(layer "F.SilkS")
			(hide yes)
			(effects
				(font
					(size 1.27 1.27)
				)
			)
		)
		(property "Value" "TXS0102DCUR-1-GP"
			(at 0 -11.1252 90)
			(unlocked yes)
			(layer "F.Fab")
			(hide yes)
			(effects
				(font
					(size 1.016 1.016)
					(thickness 0.1524)
				)
			)
		)
		(property "Device Type" "SSOIC8-4H36"
			(at 0 -12.6492 90)
			(unlocked yes)
			(layer "F.Fab")
			(hide yes)
			(effects
				(font
					(size 1.016 1.016)
					(thickness 0.1524)
				)
			)
		)
		(duplicate_pad_numbers_are_jumpers no)
		(fp_line
			(start 1.2573 -2.1844)
			(end 1.2573 2.1844)
			(stroke
				(width 0.1524)
				(type default)
			)
			(layer "F.SilkS")
		)
		(fp_line
			(start -1.2573 -2.1844)
			(end 1.2573 -2.1844)
			(stroke
				(width 0.1524)
				(type default)
			)
			(layer "F.SilkS")
		)
		(fp_line
			(start -1.2192 -0.3556)
			(end -0.9017 -0.0381)
			(stroke
				(width 0.1524)
				(type default)
			)
			(layer "F.SilkS")
		)
		(fp_line
			(start -1.2573 -0.3556)
			(end -1.2192 -0.3556)
			(stroke
				(width 0.1524)
				(type default)
			)
			(layer "F.SilkS")
		)
		(fp_line
			(start -0.9017 -0.0381)
			(end -1.2065 0.2667)
			(stroke
				(width 0.1524)
				(type default)
			)
			(layer "F.SilkS")
		)
		(fp_line
			(start -1.2065 0.2667)
			(end -1.27 0.2667)
			(stroke
				(width 0.1524)
				(type default)
			)
			(layer "F.SilkS")
		)
		(fp_line
			(start -1.2954 0.4572)
			(end -1.2954 2.159)
			(stroke
				(width 0.4064)
				(type default)
			)
			(layer "F.SilkS")
		)
		(fp_line
			(start 1.2573 2.1844)
			(end -1.2573 2.1844)
			(stroke
				(width 0.1524)
				(type default)
			)
			(layer "F.SilkS")
		)
		(fp_line
			(start -1.2573 2.1844)
			(end -1.2573 -2.1844)
			(stroke
				(width 0.1524)
				(type default)
			)
			(layer "F.SilkS")
		)
		(fp_poly
			(pts
				(xy -1.5113 2.4384) (xy 1.5113 2.4384) (xy 1.5113 -2.4384) (xy -1.5113 -2.4384)
			)
			(stroke
				(width 0)
				(type default)
			)
			(fill no)
			(layer "F.CrtYd")
		)
		(fp_poly
			(pts
				(xy -1.5113 -2.4384) (xy 1.5113 -2.4384) (xy 1.5113 2.4384) (xy -1.5113 2.4384)
			)
			(stroke
				(width 0)
				(type default)
			)
			(fill no)
			(layer "F.Fab")
		)
		(pad "1" smd rect
			(at -0.75057 1.1684 90)
			(size 0.3048 1.524)
			(layers "F.Cu" "F.Mask" "F.Paste")
			(net "EXP_SMART_RX_R")
		)
		(pad "2" smd rect
			(at -0.25019 1.1684 90)
			(size 0.3048 1.524)
			(layers "F.Cu" "F.Mask" "F.Paste")
			(net "GND")
		)
		(pad "3" smd rect
			(at 0.25019 1.1684 90)
			(size 0.3048 1.524)
			(layers "F.Cu" "F.Mask" "F.Paste")
			(net "P1V8_E")
		)
		(pad "4" smd rect
			(at 0.75057 1.1684 90)
			(size 0.3048 1.524)
			(layers "F.Cu" "F.Mask" "F.Paste")
			(net "SAS_SMART_R_RX")
		)
		(pad "5" smd rect
			(at 0.75057 -1.1684 90)
			(size 0.3048 1.524)
			(layers "F.Cu" "F.Mask" "F.Paste")
			(net "SAS_SMART_R_TX")
		)
		(pad "6" smd rect
			(at 0.25019 -1.1684 90)
			(size 0.3048 1.524)
			(layers "F.Cu" "F.Mask" "F.Paste")
			(net "SMART_UART_EN")
		)
		(pad "7" smd rect
			(at -0.25019 -1.1684 90)
			(size 0.3048 1.524)
			(layers "F.Cu" "F.Mask" "F.Paste")
			(net "P3V3_STBY")
		)
		(pad "8" smd rect
			(at -0.75057 -1.1684 90)
			(size 0.3048 1.524)
			(layers "F.Cu" "F.Mask" "F.Paste")
			(net "EXP_SMART_TX_R")
		)
	)
	(footprint ""
		(layer "F.Cu")
		(at 48.387 -216.408 -90)
		(property "Reference" "C7317"
			(at 0 0 270)
			(layer "F.SilkS")
			(hide yes)
			(effects
				(font
					(size 1.27 1.27)
				)
			)
		)
		(property "Value" "SCD1U25V3JX-GP"
			(at 0 -2.8194 270)
			(unlocked yes)
			(layer "F.Fab")
			(hide yes)
			(effects
				(font
					(size 1.016 1.016)
					(thickness 0.1524)
				)
			)
		)
		(property "Device Type" "C603H36"
			(at 0 -4.3434 270)
			(unlocked yes)
			(layer "F.Fab")
			(hide yes)
			(effects
				(font
					(size 1.016 1.016)
					(thickness 0.1524)
				)
			)
		)
		(duplicate_pad_numbers_are_jumpers no)
		(fp_line
			(start 0.508 0)
			(end -0.508 0)
			(stroke
				(width 0.2032)
				(type default)
			)
			(layer "F.SilkS")
		)
		(fp_rect
			(start -0.5842 1.3335)
			(end 0.5842 -1.3335)
			(stroke
				(width 0)
				(type default)
			)
			(fill no)
			(layer "F.CrtYd")
		)
		(fp_rect
			(start -0.5842 1.3335)
			(end 0.5842 -1.3335)
			(stroke
				(width 0)
				(type default)
			)
			(fill no)
			(layer "F.Fab")
		)
		(pad "1" smd custom
			(at 0 -0.762 270)
			(size 0.2159 0.2159)
			(layers "F.Cu" "F.Mask" "F.Paste")
			(net "MB0_ISTART_R")
			(options
				(clearance outline)
				(anchor circle)
			)
			(primitives
				(gr_poly
					(pts
						(arc
							(start -0.3302 -0.4318)
							(mid -0.402042 -0.402042)
							(end -0.4318 -0.3302)
						)
						(arc
							(start -0.4318 0.3302)
							(mid -0.402042 0.402042)
							(end -0.3302 0.4318)
						)
						(arc
							(start 0.3302 0.4318)
							(mid 0.402042 0.402042)
							(end 0.4318 0.3302)
						)
						(arc
							(start 0.4318 -0.3302)
							(mid 0.402042 -0.402042)
							(end 0.3302 -0.4318)
						)
					)
					(width 0)
					(fill yes)
				)
			)
		)
		(pad "2" smd custom
			(at 0 0.762 270)
			(size 0.2159 0.2159)
			(layers "F.Cu" "F.Mask" "F.Paste")
			(net "AGND_CURRENT_MON")
			(options
				(clearance outline)
				(anchor circle)
			)
			(primitives
				(gr_poly
					(pts
						(arc
							(start -0.3302 -0.4318)
							(mid -0.402042 -0.402042)
							(end -0.4318 -0.3302)
						)
						(arc
							(start -0.4318 0.3302)
							(mid -0.402042 0.402042)
							(end -0.3302 0.4318)
						)
						(arc
							(start 0.3302 0.4318)
							(mid 0.402042 0.402042)
							(end 0.4318 0.3302)
						)
						(arc
							(start 0.4318 -0.3302)
							(mid 0.402042 -0.402042)
							(end 0.3302 -0.4318)
						)
					)
					(width 0)
					(fill yes)
				)
			)
		)
	)
	(footprint ""
		(layer "F.Cu")
		(at 261.239 -65.532)
		(property "Reference" "C257"
			(at 0 0 0)
			(layer "F.SilkS")
			(hide yes)
			(effects
				(font
					(size 1.27 1.27)
				)
			)
		)
		(property "Value" "SC22U25V5MX-GP"
			(at -0.0762 -6.1214 0)
			(unlocked yes)
			(layer "F.Fab")
			(hide yes)
			(effects
				(font
					(size 1.016 1.016)
					(thickness 0.1524)
				)
			)
		)
		(property "Device Type" "C805H58"
			(at -0.0762 -8.1534 0)
			(unlocked yes)
			(layer "F.Fab")
			(hide yes)
			(effects
				(font
					(size 1.016 1.016)
					(thickness 0.1524)
				)
			)
		)
		(duplicate_pad_numbers_are_jumpers no)
		(fp_line
			(start 0.635 0)
			(end -0.635 0)
			(stroke
				(width 0.508)
				(type default)
			)
			(layer "F.SilkS")
		)
		(fp_rect
			(start -0.9652 1.778)
			(end 0.9652 -1.778)
			(stroke
				(width 0)
				(type default)
			)
			(fill no)
			(layer "F.CrtYd")
		)
		(fp_poly
			(pts
				(xy -0.9652 -1.778) (xy 0.9652 -1.778) (xy 0.9652 1.778) (xy -0.9652 1.778)
			)
			(stroke
				(width 0)
				(type default)
			)
			(fill no)
			(layer "F.Fab")
		)
		(pad "1" smd rect
			(at 0 -0.9652)
			(size 1.397 1.143)
			(layers "F.Cu" "F.Mask" "F.Paste")
			(net "P12V_MSB")
		)
		(pad "2" smd rect
			(at 0 0.9652)
			(size 1.397 1.143)
			(layers "F.Cu" "F.Mask" "F.Paste")
			(net "GND")
		)
	)
	(footprint ""
		(layer "F.Cu")
		(at 314.198 -190.5)
		(property "Reference" "TP180"
			(at 0 0 0)
			(layer "F.SilkS")
			(hide yes)
			(effects
				(font
					(size 1.27 1.27)
				)
			)
		)
		(property "Value" "TPAD28"
			(at -0.0127 -1.6637 0)
			(unlocked yes)
			(layer "F.Fab")
			(hide yes)
			(effects
				(font
					(size 1.016 1.016)
					(thickness 0.1524)
				)
			)
		)
		(property "Device Type" "TPAD28"
			(at -0.0127 -3.1877 0)
			(unlocked yes)
			(layer "F.Fab")
			(hide yes)
			(effects
				(font
					(size 1.016 1.016)
					(thickness 0.1524)
				)
			)
		)
		(duplicate_pad_numbers_are_jumpers no)
		(fp_poly
			(pts
				(arc
					(start 0.3556 0)
					(mid -0.3556 0)
					(end 0.3556 0)
				)
			)
			(stroke
				(width 0)
				(type default)
			)
			(fill no)
			(layer "F.CrtYd")
		)
		(fp_poly
			(pts
				(arc
					(start 0.6096 0)
					(mid -0.6096 0)
					(end 0.6096 0)
				)
			)
			(stroke
				(width 0)
				(type default)
			)
			(fill no)
			(layer "F.Fab")
		)
		(pad "1" smd circle
			(at 0 0)
			(size 0.7112 0.7112)
			(layers "F.Cu" "F.Mask" "F.Paste")
			(net "JTAG_BMC_TDO")
		)
	)
	(footprint ""
		(layer "F.Cu")
		(at 166.360348 -122.545856 180)
		(property "Reference" "PR162"
			(at 0 0 180)
			(layer "F.SilkS")
			(hide yes)
			(effects
				(font
					(size 1.27 1.27)
				)
			)
		)
		(property "Value" "187KR2F-GP"
			(at 0.064008 -3.993896 180)
			(unlocked yes)
			(layer "F.Fab")
			(hide yes)
			(effects
				(font
					(size 1.016 1.016)
					(thickness 0.1524)
				)
			)
		)
		(property "Device Type" "R402H16"
			(at 0.064008 -5.517896 180)
			(unlocked yes)
			(layer "F.Fab")
			(hide yes)
			(effects
				(font
					(size 1.016 1.016)
					(thickness 0.1524)
				)
			)
		)
		(duplicate_pad_numbers_are_jumpers no)
		(fp_line
			(start 0.508 -0.9398)
			(end -0.508 -0.9398)
			(stroke
				(width 0.1524)
				(type default)
			)
			(layer "F.SilkS")
		)
		(fp_line
			(start -0.508 -0.9398)
			(end -0.508 0.9398)
			(stroke
				(width 0.1524)
				(type default)
			)
			(layer "F.SilkS")
		)
		(fp_rect
			(start -0.508 0.9398)
			(end 0.508 -0.9398)
			(stroke
				(width 0)
				(type default)
			)
			(fill no)
			(layer "F.CrtYd")
		)
		(fp_rect
			(start -0.508 0.9398)
			(end 0.508 -0.9398)
			(stroke
				(width 0)
				(type default)
			)
			(fill no)
			(layer "F.Fab")
		)
		(pad "1" smd custom
			(at 0 -0.4445 180)
			(size 0.1397 0.1397)
			(layers "F.Cu" "F.Mask" "F.Paste")
			(net "P0V9_E_RF")
			(options
				(clearance outline)
				(anchor circle)
			)
			(primitives
				(gr_poly
					(pts
						(arc
							(start -0.1778 -0.2794)
							(mid -0.249642 -0.249642)
							(end -0.2794 -0.1778)
						)
						(arc
							(start -0.2794 0.1778)
							(mid -0.249642 0.249642)
							(end -0.1778 0.2794)
						)
						(arc
							(start 0.1778 0.2794)
							(mid 0.249642 0.249642)
							(end 0.2794 0.1778)
						)
						(arc
							(start 0.2794 -0.1778)
							(mid 0.249642 -0.249642)
							(end 0.1778 -0.2794)
						)
					)
					(width 0)
					(fill yes)
				)
			)
		)
		(pad "2" smd custom
			(at 0 0.4445 180)
			(size 0.1397 0.1397)
			(layers "F.Cu" "F.Mask" "F.Paste")
			(net "AGND_P0V9_E")
			(options
				(clearance outline)
				(anchor circle)
			)
			(primitives
				(gr_poly
					(pts
						(arc
							(start -0.1778 -0.2794)
							(mid -0.249642 -0.249642)
							(end -0.2794 -0.1778)
						)
						(arc
							(start -0.2794 0.1778)
							(mid -0.249642 0.249642)
							(end -0.1778 0.2794)
						)
						(arc
							(start 0.1778 0.2794)
							(mid 0.249642 0.249642)
							(end 0.2794 0.1778)
						)
						(arc
							(start 0.2794 -0.1778)
							(mid 0.249642 -0.249642)
							(end 0.1778 -0.2794)
						)
					)
					(width 0)
					(fill yes)
				)
			)
		)
	)
	(footprint ""
		(layer "F.Cu")
		(at 86.614 -24.384)
		(property "Reference" "PR181"
			(at 0 0 0)
			(layer "F.SilkS")
			(hide yes)
			(effects
				(font
					(size 1.27 1.27)
				)
			)
		)
		(property "Value" "19K1R2F-GP"
			(at 0.064008 -3.993896 0)
			(unlocked yes)
			(layer "F.Fab")
			(hide yes)
			(effects
				(font
					(size 1.016 1.016)
					(thickness 0.1524)
				)
			)
		)
		(property "Device Type" "R402H16"
			(at 0.064008 -5.517896 0)
			(unlocked yes)
			(layer "F.Fab")
			(hide yes)
			(effects
				(font
					(size 1.016 1.016)
					(thickness 0.1524)
				)
			)
		)
		(duplicate_pad_numbers_are_jumpers no)
		(fp_line
			(start -0.508 -0.9398)
			(end -0.508 0.9398)
			(stroke
				(width 0.1524)
				(type default)
			)
			(layer "F.SilkS")
		)
		(fp_line
			(start 0.508 -0.9398)
			(end -0.508 -0.9398)
			(stroke
				(width 0.1524)
				(type default)
			)
			(layer "F.SilkS")
		)
		(fp_rect
			(start -0.508 0.9398)
			(end 0.508 -0.9398)
			(stroke
				(width 0)
				(type default)
			)
			(fill no)
			(layer "F.CrtYd")
		)
		(fp_rect
			(start -0.508 0.9398)
			(end 0.508 -0.9398)
			(stroke
				(width 0)
				(type default)
			)
			(fill no)
			(layer "F.Fab")
		)
		(pad "1" smd custom
			(at 0 -0.4445)
			(size 0.1397 0.1397)
			(layers "F.Cu" "F.Mask" "F.Paste")
			(net "P0V955_C")
			(options
				(clearance outline)
				(anchor circle)
			)
			(primitives
				(gr_poly
					(pts
						(arc
							(start -0.1778 -0.2794)
							(mid -0.249642 -0.249642)
							(end -0.2794 -0.1778)
						)
						(arc
							(start -0.2794 0.1778)
							(mid -0.249642 0.249642)
							(end -0.1778 0.2794)
						)
						(arc
							(start 0.1778 0.2794)
							(mid 0.249642 0.249642)
							(end 0.2794 0.1778)
						)
						(arc
							(start 0.2794 -0.1778)
							(mid 0.249642 -0.249642)
							(end 0.1778 -0.2794)
						)
					)
					(width 0)
					(fill yes)
				)
			)
		)
		(pad "2" smd custom
			(at 0 0.4445)
			(size 0.1397 0.1397)
			(layers "F.Cu" "F.Mask" "F.Paste")
			(net "VT235_PGIN")
			(options
				(clearance outline)
				(anchor circle)
			)
			(primitives
				(gr_poly
					(pts
						(arc
							(start -0.1778 -0.2794)
							(mid -0.249642 -0.249642)
							(end -0.2794 -0.1778)
						)
						(arc
							(start -0.2794 0.1778)
							(mid -0.249642 0.249642)
							(end -0.1778 0.2794)
						)
						(arc
							(start 0.1778 0.2794)
							(mid 0.249642 0.249642)
							(end 0.2794 0.1778)
						)
						(arc
							(start 0.2794 -0.1778)
							(mid 0.249642 -0.249642)
							(end 0.1778 -0.2794)
						)
					)
					(width 0)
					(fill yes)
				)
			)
		)
	)
	(footprint ""
		(layer "F.Cu")
		(at 88.138 -29.064966)
		(property "Reference" "SR586"
			(at 0 0 0)
			(layer "F.SilkS")
			(hide yes)
			(effects
				(font
					(size 1.27 1.27)
				)
			)
		)
		(property "Value" "51R2F-2-GP"
			(at 0.064008 -3.993896 0)
			(unlocked yes)
			(layer "F.Fab")
			(hide yes)
			(effects
				(font
					(size 1.016 1.016)
					(thickness 0.1524)
				)
			)
		)
		(property "Device Type" "R402H16"
			(at 0.064008 -5.517896 0)
			(unlocked yes)
			(layer "F.Fab")
			(hide yes)
			(effects
				(font
					(size 1.016 1.016)
					(thickness 0.1524)
				)
			)
		)
		(duplicate_pad_numbers_are_jumpers no)
		(fp_line
			(start -0.508 -0.9398)
			(end -0.508 0.9398)
			(stroke
				(width 0.1524)
				(type default)
			)
			(layer "F.SilkS")
		)
		(fp_line
			(start 0.508 -0.9398)
			(end -0.508 -0.9398)
			(stroke
				(width 0.1524)
				(type default)
			)
			(layer "F.SilkS")
		)
		(fp_rect
			(start -0.508 0.9398)
			(end 0.508 -0.9398)
			(stroke
				(width 0)
				(type default)
			)
			(fill no)
			(layer "F.CrtYd")
		)
		(fp_rect
			(start -0.508 0.9398)
			(end 0.508 -0.9398)
			(stroke
				(width 0)
				(type default)
			)
			(fill no)
			(layer "F.Fab")
		)
		(pad "1" smd custom
			(at 0 -0.4445)
			(size 0.1397 0.1397)
			(layers "F.Cu" "F.Mask" "F.Paste")
			(net "CK_100M_EXP_SAS")
			(options
				(clearance outline)
				(anchor circle)
			)
			(primitives
				(gr_poly
					(pts
						(arc
							(start -0.1778 -0.2794)
							(mid -0.249642 -0.249642)
							(end -0.2794 -0.1778)
						)
						(arc
							(start -0.2794 0.1778)
							(mid -0.249642 0.249642)
							(end -0.1778 0.2794)
						)
						(arc
							(start 0.1778 0.2794)
							(mid 0.249642 0.249642)
							(end 0.2794 0.1778)
						)
						(arc
							(start 0.2794 -0.1778)
							(mid 0.249642 -0.249642)
							(end 0.1778 -0.2794)
						)
					)
					(width 0)
					(fill yes)
				)
			)
		)
		(pad "2" smd custom
			(at 0 0.4445)
			(size 0.1397 0.1397)
			(layers "F.Cu" "F.Mask" "F.Paste")
			(net "CLK_100M_PCIE_N")
			(options
				(clearance outline)
				(anchor circle)
			)
			(primitives
				(gr_poly
					(pts
						(arc
							(start -0.1778 -0.2794)
							(mid -0.249642 -0.249642)
							(end -0.2794 -0.1778)
						)
						(arc
							(start -0.2794 0.1778)
							(mid -0.249642 0.249642)
							(end -0.1778 0.2794)
						)
						(arc
							(start 0.1778 0.2794)
							(mid 0.249642 0.249642)
							(end 0.2794 0.1778)
						)
						(arc
							(start 0.2794 -0.1778)
							(mid 0.249642 -0.249642)
							(end 0.1778 -0.2794)
						)
					)
					(width 0)
					(fill yes)
				)
			)
		)
	)
	(footprint ""
		(layer "F.Cu")
		(at 327.406 -94.234 -90)
		(property "Reference" "PC40"
			(at 0 0 270)
			(layer "F.SilkS")
			(hide yes)
			(effects
				(font
					(size 1.27 1.27)
				)
			)
		)
		(property "Value" "SC100U6D3V6MX-GP"
			(at -0.0762 -5.1308 270)
			(unlocked yes)
			(layer "F.Fab")
			(hide yes)
			(effects
				(font
					(size 1.016 1.016)
					(thickness 0.1524)
				)
			)
		)
		(property "Device Type" "C1206H71"
			(at -0.127 -6.6548 270)
			(unlocked yes)
			(layer "F.Fab")
			(hide yes)
			(effects
				(font
					(size 1.016 1.016)
					(thickness 0.1524)
				)
			)
		)
		(duplicate_pad_numbers_are_jumpers no)
		(fp_line
			(start -1.016 2.2352)
			(end -1.016 0.8382)
			(stroke
				(width 0.1524)
				(type default)
			)
			(layer "F.SilkS")
		)
		(fp_line
			(start 1.016 2.2352)
			(end -1.016 2.2352)
			(stroke
				(width 0.1524)
				(type default)
			)
			(layer "F.SilkS")
		)
		(fp_line
			(start 1.016 0.8382)
			(end 1.016 2.2352)
			(stroke
				(width 0.1524)
				(type default)
			)
			(layer "F.SilkS")
		)
		(fp_line
			(start -1.016 -0.8382)
			(end -1.016 -2.2352)
			(stroke
				(width 0.1524)
				(type default)
			)
			(layer "F.SilkS")
		)
		(fp_line
			(start -1.016 -2.2352)
			(end 1.016 -2.2352)
			(stroke
				(width 0.1524)
				(type default)
			)
			(layer "F.SilkS")
		)
		(fp_line
			(start 1.016 -2.2352)
			(end 1.016 -0.8382)
			(stroke
				(width 0.1524)
				(type default)
			)
			(layer "F.SilkS")
		)
		(fp_rect
			(start -1.0922 2.3114)
			(end 1.0922 -2.3114)
			(stroke
				(width 0)
				(type default)
			)
			(fill no)
			(layer "F.CrtYd")
		)
		(fp_poly
			(pts
				(xy 1.0922 -2.3114) (xy 1.0922 2.3114) (xy -1.0922 2.3114) (xy -1.0922 -2.3114)
			)
			(stroke
				(width 0)
				(type default)
			)
			(fill no)
			(layer "F.Fab")
		)
		(pad "1" smd rect
			(at 0 -1.397 270)
			(size 1.651 1.27)
			(layers "F.Cu" "F.Mask" "F.Paste")
			(net "P3V3_STBY")
		)
		(pad "2" smd rect
			(at 0 1.397 270)
			(size 1.651 1.27)
			(layers "F.Cu" "F.Mask" "F.Paste")
			(net "GND")
		)
	)
	(footprint ""
		(layer "F.Cu")
		(at 317.5 -109.601 -90)
		(property "Reference" "PR37"
			(at 0 0 270)
			(layer "F.SilkS")
			(hide yes)
			(effects
				(font
					(size 1.27 1.27)
				)
			)
		)
		(property "Value" "10KR2F-2-GP"
			(at 0.064008 -3.993896 270)
			(unlocked yes)
			(layer "F.Fab")
			(hide yes)
			(effects
				(font
					(size 1.016 1.016)
					(thickness 0.1524)
				)
			)
		)
		(property "Device Type" "R402H16"
			(at 0.064008 -5.517896 270)
			(unlocked yes)
			(layer "F.Fab")
			(hide yes)
			(effects
				(font
					(size 1.016 1.016)
					(thickness 0.1524)
				)
			)
		)
		(duplicate_pad_numbers_are_jumpers no)
		(fp_line
			(start -0.508 -0.9398)
			(end -0.508 0.9398)
			(stroke
				(width 0.1524)
				(type default)
			)
			(layer "F.SilkS")
		)
		(fp_line
			(start 0.508 -0.9398)
			(end -0.508 -0.9398)
			(stroke
				(width 0.1524)
				(type default)
			)
			(layer "F.SilkS")
		)
		(fp_rect
			(start -0.508 0.9398)
			(end 0.508 -0.9398)
			(stroke
				(width 0)
				(type default)
			)
			(fill no)
			(layer "F.CrtYd")
		)
		(fp_rect
			(start -0.508 0.9398)
			(end 0.508 -0.9398)
			(stroke
				(width 0)
				(type default)
			)
			(fill no)
			(layer "F.Fab")
		)
		(pad "1" smd custom
			(at 0 -0.4445 270)
			(size 0.1397 0.1397)
			(layers "F.Cu" "F.Mask" "F.Paste")
			(net "P3V3_STBY_VFB")
			(options
				(clearance outline)
				(anchor circle)
			)
			(primitives
				(gr_poly
					(pts
						(arc
							(start -0.1778 -0.2794)
							(mid -0.249642 -0.249642)
							(end -0.2794 -0.1778)
						)
						(arc
							(start -0.2794 0.1778)
							(mid -0.249642 0.249642)
							(end -0.1778 0.2794)
						)
						(arc
							(start 0.1778 0.2794)
							(mid 0.249642 0.249642)
							(end 0.2794 0.1778)
						)
						(arc
							(start 0.2794 -0.1778)
							(mid 0.249642 -0.249642)
							(end 0.1778 -0.2794)
						)
					)
					(width 0)
					(fill yes)
				)
			)
		)
		(pad "2" smd custom
			(at 0 0.4445 270)
			(size 0.1397 0.1397)
			(layers "F.Cu" "F.Mask" "F.Paste")
			(net "AGND_P3V3_STBY")
			(options
				(clearance outline)
				(anchor circle)
			)
			(primitives
				(gr_poly
					(pts
						(arc
							(start -0.1778 -0.2794)
							(mid -0.249642 -0.249642)
							(end -0.2794 -0.1778)
						)
						(arc
							(start -0.2794 0.1778)
							(mid -0.249642 0.249642)
							(end -0.1778 0.2794)
						)
						(arc
							(start 0.1778 0.2794)
							(mid 0.249642 0.249642)
							(end 0.2794 0.1778)
						)
						(arc
							(start 0.2794 -0.1778)
							(mid 0.249642 -0.249642)
							(end 0.1778 -0.2794)
						)
					)
					(width 0)
					(fill yes)
				)
			)
		)
	)
	(footprint ""
		(layer "F.Cu")
		(at 262.182864 -231.004872)
		(property "Reference" "PR89"
			(at 0 0 0)
			(layer "F.SilkS")
			(hide yes)
			(effects
				(font
					(size 1.27 1.27)
				)
			)
		)
		(property "Value" "2K7R2J-GP"
			(at 0.064008 -3.993896 0)
			(unlocked yes)
			(layer "F.Fab")
			(hide yes)
			(effects
				(font
					(size 1.016 1.016)
					(thickness 0.1524)
				)
			)
		)
		(property "Device Type" "R402H16"
			(at 0.064008 -5.517896 0)
			(unlocked yes)
			(layer "F.Fab")
			(hide yes)
			(effects
				(font
					(size 1.016 1.016)
					(thickness 0.1524)
				)
			)
		)
		(duplicate_pad_numbers_are_jumpers no)
		(fp_line
			(start -0.508 -0.9398)
			(end -0.508 0.9398)
			(stroke
				(width 0.1524)
				(type default)
			)
			(layer "F.SilkS")
		)
		(fp_line
			(start 0.508 -0.9398)
			(end -0.508 -0.9398)
			(stroke
				(width 0.1524)
				(type default)
			)
			(layer "F.SilkS")
		)
		(fp_rect
			(start -0.508 0.9398)
			(end 0.508 -0.9398)
			(stroke
				(width 0)
				(type default)
			)
			(fill no)
			(layer "F.CrtYd")
		)
		(fp_rect
			(start -0.508 0.9398)
			(end 0.508 -0.9398)
			(stroke
				(width 0)
				(type default)
			)
			(fill no)
			(layer "F.Fab")
		)
		(pad "1" smd custom
			(at 0 -0.4445)
			(size 0.1397 0.1397)
			(layers "F.Cu" "F.Mask" "F.Paste")
			(net "P3V3_STBY")
			(options
				(clearance outline)
				(anchor circle)
			)
			(primitives
				(gr_poly
					(pts
						(arc
							(start -0.1778 -0.2794)
							(mid -0.249642 -0.249642)
							(end -0.2794 -0.1778)
						)
						(arc
							(start -0.2794 0.1778)
							(mid -0.249642 0.249642)
							(end -0.1778 0.2794)
						)
						(arc
							(start 0.1778 0.2794)
							(mid 0.249642 0.249642)
							(end 0.2794 0.1778)
						)
						(arc
							(start 0.2794 -0.1778)
							(mid 0.249642 -0.249642)
							(end 0.1778 -0.2794)
						)
					)
					(width 0)
					(fill yes)
				)
			)
		)
		(pad "2" smd custom
			(at 0 0.4445)
			(size 0.1397 0.1397)
			(layers "F.Cu" "F.Mask" "F.Paste")
			(net "P1V26_STBY_PG")
			(options
				(clearance outline)
				(anchor circle)
			)
			(primitives
				(gr_poly
					(pts
						(arc
							(start -0.1778 -0.2794)
							(mid -0.249642 -0.249642)
							(end -0.2794 -0.1778)
						)
						(arc
							(start -0.2794 0.1778)
							(mid -0.249642 0.249642)
							(end -0.1778 0.2794)
						)
						(arc
							(start 0.1778 0.2794)
							(mid 0.249642 0.249642)
							(end 0.2794 0.1778)
						)
						(arc
							(start 0.2794 -0.1778)
							(mid 0.249642 -0.249642)
							(end 0.1778 -0.2794)
						)
					)
					(width 0)
					(fill yes)
				)
			)
		)
	)
	(footprint ""
		(layer "F.Cu")
		(at 165.1 -116.078 90)
		(property "Reference" "PC189"
			(at 0 0 90)
			(layer "F.SilkS")
			(hide yes)
			(effects
				(font
					(size 1.27 1.27)
				)
			)
		)
		(property "Value" "SC1KP50V2KX-1GP"
			(at 1.1811 -2.7051 90)
			(unlocked yes)
			(layer "F.Fab")
			(hide yes)
			(effects
				(font
					(size 1.016 1.016)
					(thickness 0.1524)
				)
			)
		)
		(property "Device Type" "C402H22"
			(at 1.1811 -4.2291 90)
			(unlocked yes)
			(layer "F.Fab")
			(hide yes)
			(effects
				(font
					(size 1.016 1.016)
					(thickness 0.1524)
				)
			)
		)
		(duplicate_pad_numbers_are_jumpers no)
		(fp_rect
			(start -0.4318 0.9525)
			(end 0.4318 -0.9525)
			(stroke
				(width 0)
				(type default)
			)
			(fill no)
			(layer "F.CrtYd")
		)
		(fp_rect
			(start -0.4318 0.9525)
			(end 0.4318 -0.9525)
			(stroke
				(width 0)
				(type default)
			)
			(fill no)
			(layer "F.Fab")
		)
		(pad "1" smd custom
			(at 0 -0.4445 90)
			(size 0.1524 0.1524)
			(layers "F.Cu" "F.Mask" "F.Paste")
			(net "P0V9_E_SW_R")
			(options
				(clearance outline)
				(anchor circle)
			)
			(primitives
				(gr_poly
					(pts
						(arc
							(start 0.3048 -0.2032)
							(mid 0.275042 -0.275042)
							(end 0.2032 -0.3048)
						)
						(arc
							(start -0.2032 -0.3048)
							(mid -0.275042 -0.275042)
							(end -0.3048 -0.2032)
						)
						(arc
							(start -0.3048 0.2032)
							(mid -0.275042 0.275042)
							(end -0.2032 0.3048)
						)
						(arc
							(start 0.2032 0.3048)
							(mid 0.275042 0.275042)
							(end 0.3048 0.2032)
						)
					)
					(width 0)
					(fill yes)
				)
			)
		)
		(pad "2" smd custom
			(at 0 0.4445 90)
			(size 0.1524 0.1524)
			(layers "F.Cu" "F.Mask" "F.Paste")
			(net "P0V9_E_VFB")
			(options
				(clearance outline)
				(anchor circle)
			)
			(primitives
				(gr_poly
					(pts
						(arc
							(start 0.3048 -0.2032)
							(mid 0.275042 -0.275042)
							(end 0.2032 -0.3048)
						)
						(arc
							(start -0.2032 -0.3048)
							(mid -0.275042 -0.275042)
							(end -0.3048 -0.2032)
						)
						(arc
							(start -0.3048 0.2032)
							(mid -0.275042 0.275042)
							(end -0.2032 0.3048)
						)
						(arc
							(start 0.2032 0.3048)
							(mid 0.275042 0.275042)
							(end 0.3048 0.2032)
						)
					)
					(width 0)
					(fill yes)
				)
			)
		)
	)
	(footprint ""
		(layer "F.Cu")
		(at 203.917296 -86.372192)
		(property "Reference" "SL11"
			(at 0 0 0)
			(layer "F.SilkS")
			(hide yes)
			(effects
				(font
					(size 1.27 1.27)
				)
			)
		)
		(property "Value" "MPZ2012S300AT-GP"
			(at 0 -4.2418 0)
			(unlocked yes)
			(layer "F.Fab")
			(hide yes)
			(effects
				(font
					(size 1.016 1.016)
					(thickness 0.1524)
				)
			)
		)
		(property "Device Type" "L805H42"
			(at 0 -5.7912 0)
			(unlocked yes)
			(layer "F.Fab")
			(hide yes)
			(effects
				(font
					(size 1.016 1.016)
					(thickness 0.1524)
				)
			)
		)
		(duplicate_pad_numbers_are_jumpers no)
		(fp_line
			(start -0.889 -1.7018)
			(end 0.889 -1.7018)
			(stroke
				(width 0.1524)
				(type default)
			)
			(layer "F.SilkS")
		)
		(fp_line
			(start -0.889 1.7018)
			(end -0.889 -1.7018)
			(stroke
				(width 0.1524)
				(type default)
			)
			(layer "F.SilkS")
		)
		(fp_line
			(start 0.889 -1.7018)
			(end 0.889 1.7018)
			(stroke
				(width 0.1524)
				(type default)
			)
			(layer "F.SilkS")
		)
		(fp_line
			(start 0.889 1.7018)
			(end -0.889 1.7018)
			(stroke
				(width 0.1524)
				(type default)
			)
			(layer "F.SilkS")
		)
		(fp_rect
			(start -0.9652 1.778)
			(end 0.9652 -1.778)
			(stroke
				(width 0)
				(type default)
			)
			(fill no)
			(layer "F.CrtYd")
		)
		(fp_rect
			(start -0.9652 1.778)
			(end 0.9652 -1.778)
			(stroke
				(width 0)
				(type default)
			)
			(fill no)
			(layer "F.Fab")
		)
		(pad "1" smd rect
			(at 0 -0.9652)
			(size 1.397 1.143)
			(layers "F.Cu" "F.Mask" "F.Paste")
			(net "P1V5_E")
		)
		(pad "2" smd rect
			(at 0 0.9652)
			(size 1.397 1.143)
			(layers "F.Cu" "F.Mask" "F.Paste")
			(net "GB_VDDH2")
		)
	)
	(footprint ""
		(layer "F.Cu")
		(at 91.739212 -249.936)
		(property "Reference" "R150"
			(at 0 0 0)
			(layer "F.SilkS")
			(hide yes)
			(effects
				(font
					(size 1.27 1.27)
				)
			)
		)
		(property "Value" "0R2J-2-GP"
			(at 0.064008 -3.993896 0)
			(unlocked yes)
			(layer "F.Fab")
			(hide yes)
			(effects
				(font
					(size 1.016 1.016)
					(thickness 0.1524)
				)
			)
		)
		(property "Device Type" "R402H16"
			(at 0.064008 -5.517896 0)
			(unlocked yes)
			(layer "F.Fab")
			(hide yes)
			(effects
				(font
					(size 1.016 1.016)
					(thickness 0.1524)
				)
			)
		)
		(duplicate_pad_numbers_are_jumpers no)
		(fp_line
			(start -0.508 -0.9398)
			(end -0.508 0.9398)
			(stroke
				(width 0.1524)
				(type default)
			)
			(layer "F.SilkS")
		)
		(fp_line
			(start 0.508 -0.9398)
			(end -0.508 -0.9398)
			(stroke
				(width 0.1524)
				(type default)
			)
			(layer "F.SilkS")
		)
		(fp_rect
			(start -0.508 0.9398)
			(end 0.508 -0.9398)
			(stroke
				(width 0)
				(type default)
			)
			(fill no)
			(layer "F.CrtYd")
		)
		(fp_rect
			(start -0.508 0.9398)
			(end 0.508 -0.9398)
			(stroke
				(width 0)
				(type default)
			)
			(fill no)
			(layer "F.Fab")
		)
		(pad "1" smd custom
			(at 0 -0.4445)
			(size 0.1397 0.1397)
			(layers "F.Cu" "F.Mask" "F.Paste")
			(net "ID_I2C_ADD")
			(options
				(clearance outline)
				(anchor circle)
			)
			(primitives
				(gr_poly
					(pts
						(arc
							(start -0.1778 -0.2794)
							(mid -0.249642 -0.249642)
							(end -0.2794 -0.1778)
						)
						(arc
							(start -0.2794 0.1778)
							(mid -0.249642 0.249642)
							(end -0.1778 0.2794)
						)
						(arc
							(start 0.1778 0.2794)
							(mid 0.249642 0.249642)
							(end 0.2794 0.1778)
						)
						(arc
							(start 0.2794 -0.1778)
							(mid 0.249642 -0.249642)
							(end 0.1778 -0.2794)
						)
					)
					(width 0)
					(fill yes)
				)
			)
		)
		(pad "2" smd custom
			(at 0 0.4445)
			(size 0.1397 0.1397)
			(layers "F.Cu" "F.Mask" "F.Paste")
			(net "EXP_ID")
			(options
				(clearance outline)
				(anchor circle)
			)
			(primitives
				(gr_poly
					(pts
						(arc
							(start -0.1778 -0.2794)
							(mid -0.249642 -0.249642)
							(end -0.2794 -0.1778)
						)
						(arc
							(start -0.2794 0.1778)
							(mid -0.249642 0.249642)
							(end -0.1778 0.2794)
						)
						(arc
							(start 0.1778 0.2794)
							(mid 0.249642 0.249642)
							(end 0.2794 0.1778)
						)
						(arc
							(start 0.2794 -0.1778)
							(mid 0.249642 -0.249642)
							(end 0.1778 -0.2794)
						)
					)
					(width 0)
					(fill yes)
				)
			)
		)
	)
	(footprint ""
		(layer "F.Cu")
		(at 274.193 -178.689 90)
		(property "Reference" "R367"
			(at 0 0 90)
			(layer "F.SilkS")
			(hide yes)
			(effects
				(font
					(size 1.27 1.27)
				)
			)
		)
		(property "Value" "3K3R2F-2-GP"
			(at 0.064008 -3.993896 90)
			(unlocked yes)
			(layer "F.Fab")
			(hide yes)
			(effects
				(font
					(size 1.016 1.016)
					(thickness 0.1524)
				)
			)
		)
		(property "Device Type" "R402H16"
			(at 0.064008 -5.517896 90)
			(unlocked yes)
			(layer "F.Fab")
			(hide yes)
			(effects
				(font
					(size 1.016 1.016)
					(thickness 0.1524)
				)
			)
		)
		(duplicate_pad_numbers_are_jumpers no)
		(fp_line
			(start 0.508 -0.9398)
			(end -0.508 -0.9398)
			(stroke
				(width 0.1524)
				(type default)
			)
			(layer "F.SilkS")
		)
		(fp_line
			(start -0.508 -0.9398)
			(end -0.508 0.9398)
			(stroke
				(width 0.1524)
				(type default)
			)
			(layer "F.SilkS")
		)
		(fp_rect
			(start -0.508 0.9398)
			(end 0.508 -0.9398)
			(stroke
				(width 0)
				(type default)
			)
			(fill no)
			(layer "F.CrtYd")
		)
		(fp_rect
			(start -0.508 0.9398)
			(end 0.508 -0.9398)
			(stroke
				(width 0)
				(type default)
			)
			(fill no)
			(layer "F.Fab")
		)
		(pad "1" smd custom
			(at 0 -0.4445 90)
			(size 0.1397 0.1397)
			(layers "F.Cu" "F.Mask" "F.Paste")
			(net "P3V3_STBY")
			(options
				(clearance outline)
				(anchor circle)
			)
			(primitives
				(gr_poly
					(pts
						(arc
							(start -0.1778 -0.2794)
							(mid -0.249642 -0.249642)
							(end -0.2794 -0.1778)
						)
						(arc
							(start -0.2794 0.1778)
							(mid -0.249642 0.249642)
							(end -0.1778 0.2794)
						)
						(arc
							(start 0.1778 0.2794)
							(mid 0.249642 0.249642)
							(end 0.2794 0.1778)
						)
						(arc
							(start 0.2794 -0.1778)
							(mid 0.249642 -0.249642)
							(end 0.1778 -0.2794)
						)
					)
					(width 0)
					(fill yes)
				)
			)
		)
		(pad "2" smd custom
			(at 0 0.4445 90)
			(size 0.1397 0.1397)
			(layers "F.Cu" "F.Mask" "F.Paste")
			(net "ROMA7")
			(options
				(clearance outline)
				(anchor circle)
			)
			(primitives
				(gr_poly
					(pts
						(arc
							(start -0.1778 -0.2794)
							(mid -0.249642 -0.249642)
							(end -0.2794 -0.1778)
						)
						(arc
							(start -0.2794 0.1778)
							(mid -0.249642 0.249642)
							(end -0.1778 0.2794)
						)
						(arc
							(start 0.1778 0.2794)
							(mid 0.249642 0.249642)
							(end 0.2794 0.1778)
						)
						(arc
							(start 0.2794 -0.1778)
							(mid 0.249642 -0.249642)
							(end 0.1778 -0.2794)
						)
					)
					(width 0)
					(fill yes)
				)
			)
		)
	)
	(footprint ""
		(layer "F.Cu")
		(at 305.308 -181.61)
		(property "Reference" "TP176"
			(at 0 0 0)
			(layer "F.SilkS")
			(hide yes)
			(effects
				(font
					(size 1.27 1.27)
				)
			)
		)
		(property "Value" "TPAD28"
			(at 0.0127 -1.8034 0)
			(unlocked yes)
			(layer "F.Fab")
			(hide yes)
			(effects
				(font
					(size 1.016 1.016)
					(thickness 0.1524)
				)
			)
		)
		(property "Device Type" "TPAD28"
			(at 0.0127 -3.3274 0)
			(unlocked yes)
			(layer "F.Fab")
			(hide yes)
			(effects
				(font
					(size 1.016 1.016)
					(thickness 0.1524)
				)
			)
		)
		(duplicate_pad_numbers_are_jumpers no)
		(fp_poly
			(pts
				(arc
					(start 0.3556 0)
					(mid -0.3556 0)
					(end 0.3556 0)
				)
			)
			(stroke
				(width 0)
				(type default)
			)
			(fill no)
			(layer "F.CrtYd")
		)
		(fp_poly
			(pts
				(arc
					(start 0.6096 0)
					(mid -0.6096 0)
					(end 0.6096 0)
				)
			)
			(stroke
				(width 0)
				(type default)
			)
			(fill no)
			(layer "F.Fab")
		)
		(pad "1" smd circle
			(at 0 0)
			(size 0.7112 0.7112)
			(layers "F.Cu" "F.Mask" "F.Paste")
			(net "TP_BMC_GPIOM1")
		)
	)
	(footprint ""
		(layer "F.Cu")
		(at 193.167 -17.145 90)
		(property "Reference" "C151"
			(at 0 0 90)
			(layer "F.SilkS")
			(hide yes)
			(effects
				(font
					(size 1.27 1.27)
				)
			)
		)
		(property "Value" "SCD1U16V2KX-3GP"
			(at 1.1811 -2.7051 90)
			(unlocked yes)
			(layer "F.Fab")
			(hide yes)
			(effects
				(font
					(size 1.016 1.016)
					(thickness 0.1524)
				)
			)
		)
		(property "Device Type" "C402H22"
			(at 1.1811 -4.2291 90)
			(unlocked yes)
			(layer "F.Fab")
			(hide yes)
			(effects
				(font
					(size 1.016 1.016)
					(thickness 0.1524)
				)
			)
		)
		(duplicate_pad_numbers_are_jumpers no)
		(fp_rect
			(start -0.4318 0.9525)
			(end 0.4318 -0.9525)
			(stroke
				(width 0)
				(type default)
			)
			(fill no)
			(layer "F.CrtYd")
		)
		(fp_rect
			(start -0.4318 0.9525)
			(end 0.4318 -0.9525)
			(stroke
				(width 0)
				(type default)
			)
			(fill no)
			(layer "F.Fab")
		)
		(pad "1" smd custom
			(at 0 -0.4445 90)
			(size 0.1524 0.1524)
			(layers "F.Cu" "F.Mask" "F.Paste")
			(net "P3V3_STBY")
			(options
				(clearance outline)
				(anchor circle)
			)
			(primitives
				(gr_poly
					(pts
						(arc
							(start 0.3048 -0.2032)
							(mid 0.275042 -0.275042)
							(end 0.2032 -0.3048)
						)
						(arc
							(start -0.2032 -0.3048)
							(mid -0.275042 -0.275042)
							(end -0.3048 -0.2032)
						)
						(arc
							(start -0.3048 0.2032)
							(mid -0.275042 0.275042)
							(end -0.2032 0.3048)
						)
						(arc
							(start 0.2032 0.3048)
							(mid 0.275042 0.275042)
							(end 0.3048 0.2032)
						)
					)
					(width 0)
					(fill yes)
				)
			)
		)
		(pad "2" smd custom
			(at 0 0.4445 90)
			(size 0.1524 0.1524)
			(layers "F.Cu" "F.Mask" "F.Paste")
			(net "GND")
			(options
				(clearance outline)
				(anchor circle)
			)
			(primitives
				(gr_poly
					(pts
						(arc
							(start 0.3048 -0.2032)
							(mid 0.275042 -0.275042)
							(end 0.2032 -0.3048)
						)
						(arc
							(start -0.2032 -0.3048)
							(mid -0.275042 -0.275042)
							(end -0.3048 -0.2032)
						)
						(arc
							(start -0.3048 0.2032)
							(mid -0.275042 0.275042)
							(end -0.2032 0.3048)
						)
						(arc
							(start 0.2032 0.3048)
							(mid 0.275042 0.275042)
							(end 0.3048 0.2032)
						)
					)
					(width 0)
					(fill yes)
				)
			)
		)
	)
	(footprint ""
		(layer "F.Cu")
		(at 229.743 -17.653)
		(property "Reference" "SC1123"
			(at 0 0 0)
			(layer "F.SilkS")
			(hide yes)
			(effects
				(font
					(size 1.27 1.27)
				)
			)
		)
		(property "Value" "SCD1U16V2KX-3GP"
			(at 1.1811 -2.7051 0)
			(unlocked yes)
			(layer "F.Fab")
			(hide yes)
			(effects
				(font
					(size 1.016 1.016)
					(thickness 0.1524)
				)
			)
		)
		(property "Device Type" "C402H22"
			(at 1.1811 -4.2291 0)
			(unlocked yes)
			(layer "F.Fab")
			(hide yes)
			(effects
				(font
					(size 1.016 1.016)
					(thickness 0.1524)
				)
			)
		)
		(duplicate_pad_numbers_are_jumpers no)
		(fp_rect
			(start -0.4318 0.9525)
			(end 0.4318 -0.9525)
			(stroke
				(width 0)
				(type default)
			)
			(fill no)
			(layer "F.CrtYd")
		)
		(fp_rect
			(start -0.4318 0.9525)
			(end 0.4318 -0.9525)
			(stroke
				(width 0)
				(type default)
			)
			(fill no)
			(layer "F.Fab")
		)
		(pad "1" smd custom
			(at 0 -0.4445)
			(size 0.1524 0.1524)
			(layers "F.Cu" "F.Mask" "F.Paste")
			(net "3D3V_ICE")
			(options
				(clearance outline)
				(anchor circle)
			)
			(primitives
				(gr_poly
					(pts
						(arc
							(start 0.3048 -0.2032)
							(mid 0.275042 -0.275042)
							(end 0.2032 -0.3048)
						)
						(arc
							(start -0.2032 -0.3048)
							(mid -0.275042 -0.275042)
							(end -0.3048 -0.2032)
						)
						(arc
							(start -0.3048 0.2032)
							(mid -0.275042 0.275042)
							(end -0.2032 0.3048)
						)
						(arc
							(start 0.2032 0.3048)
							(mid 0.275042 0.275042)
							(end 0.3048 0.2032)
						)
					)
					(width 0)
					(fill yes)
				)
			)
		)
		(pad "2" smd custom
			(at 0 0.4445)
			(size 0.1524 0.1524)
			(layers "F.Cu" "F.Mask" "F.Paste")
			(net "GND")
			(options
				(clearance outline)
				(anchor circle)
			)
			(primitives
				(gr_poly
					(pts
						(arc
							(start 0.3048 -0.2032)
							(mid 0.275042 -0.275042)
							(end 0.2032 -0.3048)
						)
						(arc
							(start -0.2032 -0.3048)
							(mid -0.275042 -0.275042)
							(end -0.3048 -0.2032)
						)
						(arc
							(start -0.3048 0.2032)
							(mid -0.275042 0.275042)
							(end -0.2032 0.3048)
						)
						(arc
							(start 0.2032 0.3048)
							(mid 0.275042 0.275042)
							(end 0.3048 0.2032)
						)
					)
					(width 0)
					(fill yes)
				)
			)
		)
	)
	(footprint ""
		(layer "F.Cu")
		(at 347.091 -108.204)
		(property "Reference" "PC7"
			(at 0 0 0)
			(layer "F.SilkS")
			(hide yes)
			(effects
				(font
					(size 1.27 1.27)
				)
			)
		)
		(property "Value" "SC22U25V5MX-GP"
			(at -0.0762 -6.1214 0)
			(unlocked yes)
			(layer "F.Fab")
			(hide yes)
			(effects
				(font
					(size 1.016 1.016)
					(thickness 0.1524)
				)
			)
		)
		(property "Device Type" "C805H58"
			(at -0.0762 -8.1534 0)
			(unlocked yes)
			(layer "F.Fab")
			(hide yes)
			(effects
				(font
					(size 1.016 1.016)
					(thickness 0.1524)
				)
			)
		)
		(duplicate_pad_numbers_are_jumpers no)
		(fp_line
			(start 0.635 0)
			(end -0.635 0)
			(stroke
				(width 0.508)
				(type default)
			)
			(layer "F.SilkS")
		)
		(fp_rect
			(start -0.9652 1.778)
			(end 0.9652 -1.778)
			(stroke
				(width 0)
				(type default)
			)
			(fill no)
			(layer "F.CrtYd")
		)
		(fp_poly
			(pts
				(xy -0.9652 -1.778) (xy 0.9652 -1.778) (xy 0.9652 1.778) (xy -0.9652 1.778)
			)
			(stroke
				(width 0)
				(type default)
			)
			(fill no)
			(layer "F.Fab")
		)
		(pad "1" smd rect
			(at 0 -0.9652)
			(size 1.397 1.143)
			(layers "F.Cu" "F.Mask" "F.Paste")
			(net "P5V_STBY_VIN")
		)
		(pad "2" smd rect
			(at 0 0.9652)
			(size 1.397 1.143)
			(layers "F.Cu" "F.Mask" "F.Paste")
			(net "GND")
		)
	)
	(footprint ""
		(layer "F.Cu")
		(at 310.900064 -72.00011 -90)
		(property "Reference" "MEZCN1"
			(at 0 0 270)
			(layer "F.SilkS")
			(hide yes)
			(effects
				(font
					(size 1.27 1.27)
				)
			)
		)
		(property "Value" "FCI-CONN120-GP"
			(at -29.345382 -6.235192 270)
			(unlocked yes)
			(layer "F.Fab")
			(hide yes)
			(effects
				(font
					(size 1.016 1.016)
					(thickness 0.1524)
				)
			)
		)
		(property "Device Type" "61082-121402LF-U"
			(at -29.345382 -7.759192 270)
			(unlocked yes)
			(layer "F.Fab")
			(hide yes)
			(effects
				(font
					(size 1.016 1.016)
					(thickness 0.1524)
				)
			)
		)
		(duplicate_pad_numbers_are_jumpers no)
		(fp_line
			(start -27.1526 3.5052)
			(end 27.1526 3.5052)
			(stroke
				(width 0.1524)
				(type default)
			)
			(layer "F.SilkS")
		)
		(fp_line
			(start 27.1526 3.5052)
			(end 27.1526 -3.5052)
			(stroke
				(width 0.1524)
				(type default)
			)
			(layer "F.SilkS")
		)
		(fp_line
			(start -27.1526 -3.5052)
			(end -27.1526 3.5052)
			(stroke
				(width 0.1524)
				(type default)
			)
			(layer "F.SilkS")
		)
		(fp_line
			(start 27.1526 -3.5052)
			(end -27.1526 -3.5052)
			(stroke
				(width 0.1524)
				(type default)
			)
			(layer "F.SilkS")
		)
		(fp_line
			(start 23.34895 -3.5941)
			(end 23.85695 -3.5941)
			(stroke
				(width 0.3302)
				(type default)
			)
			(layer "F.SilkS")
		)
		(fp_poly
			(pts
				(xy 23.597108 -3.578098) (xy 24.105108 -4.086098) (xy 23.089108 -4.086098)
			)
			(stroke
				(width 0)
				(type default)
			)
			(fill yes)
			(layer "F.SilkS")
		)
		(fp_poly
			(pts
				(xy -23.853902 0.99314) (xy 23.853902 0.99314) (xy 23.853902 -0.99314) (xy -23.853902 -0.99314)
			)
			(stroke
				(width 0)
				(type default)
			)
			(fill yes)
			(layer "F.SilkS")
		)
		(fp_rect
			(start -26.8986 2.9972)
			(end 26.8986 -2.9972)
			(stroke
				(width 0)
				(type default)
			)
			(fill no)
			(layer "F.CrtYd")
		)
		(fp_poly
			(pts
				(xy 27.4066 -2.9972) (xy -26.8986 -2.9972) (xy -26.8986 2.9972) (xy 26.8986 2.9972) (xy 26.8986 -2.9845)
				(xy 27.4066 -2.9845) (xy 27.4066 3.7592) (xy -27.4066 3.7592) (xy -27.4066 -3.7592) (xy 27.4066 -3.7592)
			)
			(stroke
				(width 0)
				(type default)
			)
			(fill no)
			(layer "F.CrtYd")
		)
		(fp_rect
			(start -27.4066 3.7592)
			(end 27.4066 -3.7592)
			(stroke
				(width 0)
				(type default)
			)
			(fill no)
			(layer "F.Fab")
		)
		(pad "" np_thru_hole circle
			(at -26.100024 0 270)
			(size 0.254 0.254)
			(drill 0.8636)
			(layers "*.Cu" "*.Mask")
			(clearance 0.6604)
			(thermal_gap 0.6604)
		)
		(pad "" np_thru_hole circle
			(at 26.100024 0 270)
			(size 0.254 0.254)
			(drill 1.2192)
			(layers "*.Cu" "*.Mask")
			(clearance 0.8382)
			(thermal_gap 0.8382)
		)
		(pad "1" smd rect
			(at 23.599902 -2.22504 270)
			(size 0.508 2.0574)
			(layers "F.Cu" "F.Mask" "F.Paste")
			(net "CONN_10G_PRSNT2_N")
		)
		(pad "2" smd rect
			(at 22.800056 -2.22504 270)
			(size 0.508 2.0574)
			(layers "F.Cu" "F.Mask" "F.Paste")
			(net "P5V_STBY")
		)
		(pad "3" smd rect
			(at 21.999956 -2.22504 270)
			(size 0.508 2.0574)
			(layers "F.Cu" "F.Mask" "F.Paste")
			(net "P5V_STBY")
		)
		(pad "4" smd rect
			(at 21.20011 -2.22504 270)
			(size 0.508 2.0574)
			(layers "F.Cu" "F.Mask" "F.Paste")
			(net "P5V_STBY")
		)
		(pad "5" smd rect
			(at 20.40001 -2.22504 270)
			(size 0.508 2.0574)
			(layers "F.Cu" "F.Mask" "F.Paste")
			(net "GND")
		)
		(pad "6" smd rect
			(at 19.59991 -2.22504 270)
			(size 0.508 2.0574)
			(layers "F.Cu" "F.Mask" "F.Paste")
			(net "GND")
		)
		(pad "7" smd rect
			(at 18.800064 -2.22504 270)
			(size 0.508 2.0574)
			(layers "F.Cu" "F.Mask" "F.Paste")
			(net "P3V3_STBY")
		)
		(pad "8" smd rect
			(at 17.999964 -2.22504 270)
			(size 0.508 2.0574)
			(layers "F.Cu" "F.Mask" "F.Paste")
			(net "GND")
		)
		(pad "9" smd rect
			(at 17.200118 -2.22504 270)
			(size 0.508 2.0574)
			(layers "F.Cu" "F.Mask" "F.Paste")
			(net "GND")
		)
		(pad "10" smd rect
			(at 16.400018 -2.22504 270)
			(size 0.508 2.0574)
			(layers "F.Cu" "F.Mask" "F.Paste")
			(net "P3V3")
		)
		(pad "11" smd rect
			(at 15.599918 -2.22504 270)
			(size 0.508 2.0574)
			(layers "F.Cu" "F.Mask" "F.Paste")
			(net "P3V3")
		)
		(pad "12" smd rect
			(at 14.800072 -2.22504 270)
			(size 0.508 2.0574)
			(layers "F.Cu" "F.Mask" "F.Paste")
			(net "P3V3")
		)
		(pad "13" smd rect
			(at 13.999972 -2.22504 270)
			(size 0.508 2.0574)
			(layers "F.Cu" "F.Mask" "F.Paste")
			(net "P3V3")
		)
		(pad "14" smd rect
			(at 13.200126 -2.22504 270)
			(size 0.508 2.0574)
			(layers "F.Cu" "F.Mask" "F.Paste")
			(net "NCSI_10G_RCSDV_R")
		)
		(pad "15" smd rect
			(at 12.400026 -2.22504 270)
			(size 0.508 2.0574)
			(layers "F.Cu" "F.Mask" "F.Paste")
			(net "NCSI_10G_RCLK_R")
		)
		(pad "16" smd rect
			(at 11.599926 -2.22504 270)
			(size 0.508 2.0574)
			(layers "F.Cu" "F.Mask" "F.Paste")
			(net "NCSI_10G_TXEN_R")
		)
		(pad "17" smd rect
			(at 10.80008 -2.22504 270)
			(size 0.508 2.0574)
			(layers "F.Cu" "F.Mask" "F.Paste")
			(net "PMU_PLTRST_N_10G")
		)
		(pad "18" smd rect
			(at 9.99998 -2.22504 270)
			(size 0.508 2.0574)
			(layers "F.Cu" "F.Mask" "F.Paste")
			(net "I2C_BMC_MSB_CLK_R")
		)
		(pad "19" smd rect
			(at 9.19988 -2.22504 270)
			(size 0.508 2.0574)
			(layers "F.Cu" "F.Mask" "F.Paste")
			(net "I2C_BMC_MSB_DATA_R")
		)
		(pad "20" smd rect
			(at 8.400034 -2.22504 270)
			(size 0.508 2.0574)
			(layers "F.Cu" "F.Mask" "F.Paste")
			(net "GND")
		)
		(pad "21" smd rect
			(at 7.599934 -2.22504 270)
			(size 0.508 2.0574)
			(layers "F.Cu" "F.Mask" "F.Paste")
			(net "GND")
		)
		(pad "22" smd rect
			(at 6.800088 -2.22504 270)
			(size 0.508 2.0574)
			(layers "F.Cu" "F.Mask" "F.Paste")
			(net "NCSI_10G_RXD0_R")
		)
		(pad "23" smd rect
			(at 5.999988 -2.22504 270)
			(size 0.508 2.0574)
			(layers "F.Cu" "F.Mask" "F.Paste")
			(net "NCSI_10G_RXD1_R")
		)
		(pad "24" smd rect
			(at 5.199888 -2.22504 270)
			(size 0.508 2.0574)
			(layers "F.Cu" "F.Mask" "F.Paste")
			(net "GND")
		)
		(pad "25" smd rect
			(at 4.400042 -2.22504 270)
			(size 0.508 2.0574)
			(layers "F.Cu" "F.Mask" "F.Paste")
			(net "GND")
		)
		(pad "26" smd rect
			(at 3.599942 -2.22504 270)
			(size 0.508 2.0574)
			(layers "F.Cu" "F.Mask" "F.Paste")
			(net "PCIE_10G_REFCLK_2_P")
		)
		(pad "27" smd rect
			(at 2.800096 -2.22504 270)
			(size 0.508 2.0574)
			(layers "F.Cu" "F.Mask" "F.Paste")
			(net "PCIE_10G_REFCLK_2_N")
		)
		(pad "28" smd rect
			(at 1.999996 -2.22504 270)
			(size 0.508 2.0574)
			(layers "F.Cu" "F.Mask" "F.Paste")
			(net "GND")
		)
		(pad "29" smd rect
			(at 1.199896 -2.22504 270)
			(size 0.508 2.0574)
			(layers "F.Cu" "F.Mask" "F.Paste")
			(net "GND")
		)
		(pad "30" smd rect
			(at 0.40005 -2.22504 270)
			(size 0.508 2.0574)
			(layers "F.Cu" "F.Mask" "F.Paste")
			(net "PCIE_10G_CPU_RX0_P")
		)
		(pad "31" smd rect
			(at -0.40005 -2.22504 270)
			(size 0.508 2.0574)
			(layers "F.Cu" "F.Mask" "F.Paste")
			(net "PCIE_10G_CPU_RX0_N")
		)
		(pad "32" smd rect
			(at -1.199896 -2.22504 270)
			(size 0.508 2.0574)
			(layers "F.Cu" "F.Mask" "F.Paste")
			(net "GND")
		)
		(pad "33" smd rect
			(at -1.999996 -2.22504 270)
			(size 0.508 2.0574)
			(layers "F.Cu" "F.Mask" "F.Paste")
			(net "GND")
		)
		(pad "34" smd rect
			(at -2.800096 -2.22504 270)
			(size 0.508 2.0574)
			(layers "F.Cu" "F.Mask" "F.Paste")
			(net "PCIE_10G_CPU_RX1_P")
		)
		(pad "35" smd rect
			(at -3.599942 -2.22504 270)
			(size 0.508 2.0574)
			(layers "F.Cu" "F.Mask" "F.Paste")
			(net "PCIE_10G_CPU_RX1_N")
		)
		(pad "36" smd rect
			(at -4.400042 -2.22504 270)
			(size 0.508 2.0574)
			(layers "F.Cu" "F.Mask" "F.Paste")
			(net "GND")
		)
		(pad "37" smd rect
			(at -5.199888 -2.22504 270)
			(size 0.508 2.0574)
			(layers "F.Cu" "F.Mask" "F.Paste")
			(net "GND")
		)
		(pad "38" smd rect
			(at -5.999988 -2.22504 270)
			(size 0.508 2.0574)
			(layers "F.Cu" "F.Mask" "F.Paste")
			(net "PCIE_10G_CPU_RX2_P")
		)
		(pad "39" smd rect
			(at -6.800088 -2.22504 270)
			(size 0.508 2.0574)
			(layers "F.Cu" "F.Mask" "F.Paste")
			(net "PCIE_10G_CPU_RX2_N")
		)
		(pad "40" smd rect
			(at -7.599934 -2.22504 270)
			(size 0.508 2.0574)
			(layers "F.Cu" "F.Mask" "F.Paste")
			(net "GND")
		)
		(pad "41" smd rect
			(at -8.400034 -2.22504 270)
			(size 0.508 2.0574)
			(layers "F.Cu" "F.Mask" "F.Paste")
			(net "GND")
		)
		(pad "42" smd rect
			(at -9.19988 -2.22504 270)
			(size 0.508 2.0574)
			(layers "F.Cu" "F.Mask" "F.Paste")
			(net "PCIE_10G_CPU_RX3_P")
		)
		(pad "43" smd rect
			(at -9.99998 -2.22504 270)
			(size 0.508 2.0574)
			(layers "F.Cu" "F.Mask" "F.Paste")
			(net "PCIE_10G_CPU_RX3_N")
		)
		(pad "44" smd rect
			(at -10.80008 -2.22504 270)
			(size 0.508 2.0574)
			(layers "F.Cu" "F.Mask" "F.Paste")
			(net "GND")
		)
		(pad "45" smd rect
			(at -11.599926 -2.22504 270)
			(size 0.508 2.0574)
			(layers "F.Cu" "F.Mask" "F.Paste")
			(net "GND")
		)
		(pad "46" smd rect
			(at -12.400026 -2.22504 270)
			(size 0.508 2.0574)
			(layers "F.Cu" "F.Mask" "F.Paste")
			(net "Net_1326")
		)
		(pad "47" smd rect
			(at -13.200126 -2.22504 270)
			(size 0.508 2.0574)
			(layers "F.Cu" "F.Mask" "F.Paste")
			(net "Net_1325")
		)
		(pad "48" smd rect
			(at -13.999972 -2.22504 270)
			(size 0.508 2.0574)
			(layers "F.Cu" "F.Mask" "F.Paste")
			(net "GND")
		)
		(pad "49" smd rect
			(at -14.800072 -2.22504 270)
			(size 0.508 2.0574)
			(layers "F.Cu" "F.Mask" "F.Paste")
			(net "GND")
		)
		(pad "50" smd rect
			(at -15.599918 -2.22504 270)
			(size 0.508 2.0574)
			(layers "F.Cu" "F.Mask" "F.Paste")
			(net "Net_1324")
		)
		(pad "51" smd rect
			(at -16.400018 -2.22504 270)
			(size 0.508 2.0574)
			(layers "F.Cu" "F.Mask" "F.Paste")
			(net "Net_1323")
		)
		(pad "52" smd rect
			(at -17.200118 -2.22504 270)
			(size 0.508 2.0574)
			(layers "F.Cu" "F.Mask" "F.Paste")
			(net "GND")
		)
		(pad "53" smd rect
			(at -17.999964 -2.22504 270)
			(size 0.508 2.0574)
			(layers "F.Cu" "F.Mask" "F.Paste")
			(net "GND")
		)
		(pad "54" smd rect
			(at -18.800064 -2.22504 270)
			(size 0.508 2.0574)
			(layers "F.Cu" "F.Mask" "F.Paste")
			(net "Net_1322")
		)
		(pad "55" smd rect
			(at -19.59991 -2.22504 270)
			(size 0.508 2.0574)
			(layers "F.Cu" "F.Mask" "F.Paste")
			(net "Net_1331")
		)
		(pad "56" smd rect
			(at -20.40001 -2.22504 270)
			(size 0.508 2.0574)
			(layers "F.Cu" "F.Mask" "F.Paste")
			(net "GND")
		)
		(pad "57" smd rect
			(at -21.20011 -2.22504 270)
			(size 0.508 2.0574)
			(layers "F.Cu" "F.Mask" "F.Paste")
			(net "GND")
		)
		(pad "58" smd rect
			(at -21.999956 -2.22504 270)
			(size 0.508 2.0574)
			(layers "F.Cu" "F.Mask" "F.Paste")
			(net "Net_1330")
		)
		(pad "59" smd rect
			(at -22.800056 -2.22504 270)
			(size 0.508 2.0574)
			(layers "F.Cu" "F.Mask" "F.Paste")
			(net "Net_1329")
		)
		(pad "60" smd rect
			(at -23.599902 -2.22504 270)
			(size 0.508 2.0574)
			(layers "F.Cu" "F.Mask" "F.Paste")
			(net "GND")
		)
		(pad "61" smd rect
			(at 23.599902 2.22504 270)
			(size 0.508 2.0574)
			(layers "F.Cu" "F.Mask" "F.Paste")
			(net "P12V")
		)
		(pad "62" smd rect
			(at 22.800056 2.22504 270)
			(size 0.508 2.0574)
			(layers "F.Cu" "F.Mask" "F.Paste")
			(net "P12V")
		)
		(pad "63" smd rect
			(at 21.999956 2.22504 270)
			(size 0.508 2.0574)
			(layers "F.Cu" "F.Mask" "F.Paste")
			(net "P12V")
		)
		(pad "64" smd rect
			(at 21.20011 2.22504 270)
			(size 0.508 2.0574)
			(layers "F.Cu" "F.Mask" "F.Paste")
			(net "GND")
		)
		(pad "65" smd rect
			(at 20.40001 2.22504 270)
			(size 0.508 2.0574)
			(layers "F.Cu" "F.Mask" "F.Paste")
			(net "GND")
		)
		(pad "66" smd rect
			(at 19.59991 2.22504 270)
			(size 0.508 2.0574)
			(layers "F.Cu" "F.Mask" "F.Paste")
			(net "P3V3_STBY")
		)
		(pad "67" smd rect
			(at 18.800064 2.22504 270)
			(size 0.508 2.0574)
			(layers "F.Cu" "F.Mask" "F.Paste")
			(net "GND")
		)
		(pad "68" smd rect
			(at 17.999964 2.22504 270)
			(size 0.508 2.0574)
			(layers "F.Cu" "F.Mask" "F.Paste")
			(net "GND")
		)
		(pad "69" smd rect
			(at 17.200118 2.22504 270)
			(size 0.508 2.0574)
			(layers "F.Cu" "F.Mask" "F.Paste")
			(net "P3V3")
		)
		(pad "70" smd rect
			(at 16.400018 2.22504 270)
			(size 0.508 2.0574)
			(layers "F.Cu" "F.Mask" "F.Paste")
			(net "P3V3")
		)
		(pad "71" smd rect
			(at 15.599918 2.22504 270)
			(size 0.508 2.0574)
			(layers "F.Cu" "F.Mask" "F.Paste")
			(net "P3V3")
		)
		(pad "72" smd rect
			(at 14.800072 2.22504 270)
			(size 0.508 2.0574)
			(layers "F.Cu" "F.Mask" "F.Paste")
			(net "P3V3")
		)
		(pad "73" smd rect
			(at 13.999972 2.22504 270)
			(size 0.508 2.0574)
			(layers "F.Cu" "F.Mask" "F.Paste")
			(net "GND")
		)
		(pad "74" smd rect
			(at 13.200126 2.22504 270)
			(size 0.508 2.0574)
			(layers "F.Cu" "F.Mask" "F.Paste")
			(net "SMB_LAN_ALERT_N")
		)
		(pad "75" smd rect
			(at 12.400026 2.22504 270)
			(size 0.508 2.0574)
			(layers "F.Cu" "F.Mask" "F.Paste")
			(net "SAS_I2C_C_10G_SCL")
		)
		(pad "76" smd rect
			(at 11.599926 2.22504 270)
			(size 0.508 2.0574)
			(layers "F.Cu" "F.Mask" "F.Paste")
			(net "SAS_I2C_C_10G_SDA")
		)
		(pad "77" smd rect
			(at 10.80008 2.22504 270)
			(size 0.508 2.0574)
			(layers "F.Cu" "F.Mask" "F.Paste")
			(net "PMU_WAKE_N_R")
		)
		(pad "78" smd rect
			(at 9.99998 2.22504 270)
			(size 0.508 2.0574)
			(layers "F.Cu" "F.Mask" "F.Paste")
			(net "NCSI_10G_RX_ER_R")
		)
		(pad "79" smd rect
			(at 9.19988 2.22504 270)
			(size 0.508 2.0574)
			(layers "F.Cu" "F.Mask" "F.Paste")
			(net "GND")
		)
		(pad "80" smd rect
			(at 8.400034 2.22504 270)
			(size 0.508 2.0574)
			(layers "F.Cu" "F.Mask" "F.Paste")
			(net "NCSI_10G_TXD0_R")
		)
		(pad "81" smd rect
			(at 7.599934 2.22504 270)
			(size 0.508 2.0574)
			(layers "F.Cu" "F.Mask" "F.Paste")
			(net "NCSI_10G_TXD1_R")
		)
		(pad "82" smd rect
			(at 6.800088 2.22504 270)
			(size 0.508 2.0574)
			(layers "F.Cu" "F.Mask" "F.Paste")
			(net "GND")
		)
		(pad "83" smd rect
			(at 5.999988 2.22504 270)
			(size 0.508 2.0574)
			(layers "F.Cu" "F.Mask" "F.Paste")
			(net "GND")
		)
		(pad "84" smd rect
			(at 5.199888 2.22504 270)
			(size 0.508 2.0574)
			(layers "F.Cu" "F.Mask" "F.Paste")
			(net "PCIE_10G_REFCLK_P")
		)
		(pad "85" smd rect
			(at 4.400042 2.22504 270)
			(size 0.508 2.0574)
			(layers "F.Cu" "F.Mask" "F.Paste")
			(net "PCIE_10G_REFCLK_N")
		)
		(pad "86" smd rect
			(at 3.599942 2.22504 270)
			(size 0.508 2.0574)
			(layers "F.Cu" "F.Mask" "F.Paste")
			(net "GND")
		)
		(pad "87" smd rect
			(at 2.800096 2.22504 270)
			(size 0.508 2.0574)
			(layers "F.Cu" "F.Mask" "F.Paste")
			(net "GND")
		)
		(pad "88" smd rect
			(at 1.999996 2.22504 270)
			(size 0.508 2.0574)
			(layers "F.Cu" "F.Mask" "F.Paste")
			(net "PCIE_10G_CPU_TX0_P")
		)
		(pad "89" smd rect
			(at 1.199896 2.22504 270)
			(size 0.508 2.0574)
			(layers "F.Cu" "F.Mask" "F.Paste")
			(net "PCIE_10G_CPU_TX0_N")
		)
		(pad "90" smd rect
			(at 0.40005 2.22504 270)
			(size 0.508 2.0574)
			(layers "F.Cu" "F.Mask" "F.Paste")
			(net "GND")
		)
		(pad "91" smd rect
			(at -0.40005 2.22504 270)
			(size 0.508 2.0574)
			(layers "F.Cu" "F.Mask" "F.Paste")
			(net "GND")
		)
		(pad "92" smd rect
			(at -1.199896 2.22504 270)
			(size 0.508 2.0574)
			(layers "F.Cu" "F.Mask" "F.Paste")
			(net "PCIE_10G_CPU_TX1_P")
		)
		(pad "93" smd rect
			(at -1.999996 2.22504 270)
			(size 0.508 2.0574)
			(layers "F.Cu" "F.Mask" "F.Paste")
			(net "PCIE_10G_CPU_TX1_N")
		)
		(pad "94" smd rect
			(at -2.800096 2.22504 270)
			(size 0.508 2.0574)
			(layers "F.Cu" "F.Mask" "F.Paste")
			(net "GND")
		)
		(pad "95" smd rect
			(at -3.599942 2.22504 270)
			(size 0.508 2.0574)
			(layers "F.Cu" "F.Mask" "F.Paste")
			(net "GND")
		)
		(pad "96" smd rect
			(at -4.400042 2.22504 270)
			(size 0.508 2.0574)
			(layers "F.Cu" "F.Mask" "F.Paste")
			(net "PCIE_10G_CPU_TX2_P")
		)
		(pad "97" smd rect
			(at -5.199888 2.22504 270)
			(size 0.508 2.0574)
			(layers "F.Cu" "F.Mask" "F.Paste")
			(net "PCIE_10G_CPU_TX2_N")
		)
		(pad "98" smd rect
			(at -5.999988 2.22504 270)
			(size 0.508 2.0574)
			(layers "F.Cu" "F.Mask" "F.Paste")
			(net "GND")
		)
		(pad "99" smd rect
			(at -6.800088 2.22504 270)
			(size 0.508 2.0574)
			(layers "F.Cu" "F.Mask" "F.Paste")
			(net "GND")
		)
		(pad "100" smd rect
			(at -7.599934 2.22504 270)
			(size 0.508 2.0574)
			(layers "F.Cu" "F.Mask" "F.Paste")
			(net "PCIE_10G_CPU_TX3_P")
		)
		(pad "101" smd rect
			(at -8.400034 2.22504 270)
			(size 0.508 2.0574)
			(layers "F.Cu" "F.Mask" "F.Paste")
			(net "PCIE_10G_CPU_TX3_N")
		)
		(pad "102" smd rect
			(at -9.19988 2.22504 270)
			(size 0.508 2.0574)
			(layers "F.Cu" "F.Mask" "F.Paste")
			(net "GND")
		)
		(pad "103" smd rect
			(at -9.99998 2.22504 270)
			(size 0.508 2.0574)
			(layers "F.Cu" "F.Mask" "F.Paste")
			(net "GND")
		)
		(pad "104" smd rect
			(at -10.80008 2.22504 270)
			(size 0.508 2.0574)
			(layers "F.Cu" "F.Mask" "F.Paste")
			(net "Net_1316")
		)
		(pad "105" smd rect
			(at -11.599926 2.22504 270)
			(size 0.508 2.0574)
			(layers "F.Cu" "F.Mask" "F.Paste")
			(net "Net_1321")
		)
		(pad "106" smd rect
			(at -12.400026 2.22504 270)
			(size 0.508 2.0574)
			(layers "F.Cu" "F.Mask" "F.Paste")
			(net "GND")
		)
		(pad "107" smd rect
			(at -13.200126 2.22504 270)
			(size 0.508 2.0574)
			(layers "F.Cu" "F.Mask" "F.Paste")
			(net "GND")
		)
		(pad "108" smd rect
			(at -13.999972 2.22504 270)
			(size 0.508 2.0574)
			(layers "F.Cu" "F.Mask" "F.Paste")
			(net "Net_1320")
		)
		(pad "109" smd rect
			(at -14.800072 2.22504 270)
			(size 0.508 2.0574)
			(layers "F.Cu" "F.Mask" "F.Paste")
			(net "Net_1319")
		)
		(pad "110" smd rect
			(at -15.599918 2.22504 270)
			(size 0.508 2.0574)
			(layers "F.Cu" "F.Mask" "F.Paste")
			(net "GND")
		)
		(pad "111" smd rect
			(at -16.400018 2.22504 270)
			(size 0.508 2.0574)
			(layers "F.Cu" "F.Mask" "F.Paste")
			(net "GND")
		)
		(pad "112" smd rect
			(at -17.200118 2.22504 270)
			(size 0.508 2.0574)
			(layers "F.Cu" "F.Mask" "F.Paste")
			(net "Net_1318")
		)
		(pad "113" smd rect
			(at -17.999964 2.22504 270)
			(size 0.508 2.0574)
			(layers "F.Cu" "F.Mask" "F.Paste")
			(net "Net_1317")
		)
		(pad "114" smd rect
			(at -18.800064 2.22504 270)
			(size 0.508 2.0574)
			(layers "F.Cu" "F.Mask" "F.Paste")
			(net "GND")
		)
		(pad "115" smd rect
			(at -19.59991 2.22504 270)
			(size 0.508 2.0574)
			(layers "F.Cu" "F.Mask" "F.Paste")
			(net "GND")
		)
		(pad "116" smd rect
			(at -20.40001 2.22504 270)
			(size 0.508 2.0574)
			(layers "F.Cu" "F.Mask" "F.Paste")
			(net "Net_1328")
		)
		(pad "117" smd rect
			(at -21.20011 2.22504 270)
			(size 0.508 2.0574)
			(layers "F.Cu" "F.Mask" "F.Paste")
			(net "Net_1327")
		)
		(pad "118" smd rect
			(at -21.999956 2.22504 270)
			(size 0.508 2.0574)
			(layers "F.Cu" "F.Mask" "F.Paste")
			(net "GND")
		)
		(pad "119" smd rect
			(at -22.800056 2.22504 270)
			(size 0.508 2.0574)
			(layers "F.Cu" "F.Mask" "F.Paste")
			(net "GND")
		)
		(pad "120" smd rect
			(at -23.599902 2.22504 270)
			(size 0.508 2.0574)
			(layers "F.Cu" "F.Mask" "F.Paste")
			(net "CONN_10G_PRSNT2_N")
		)
		(zone
			(layer "F.Cu")
			(hatch none 0.5)
			(connect_pads
				(clearance 0)
			)
			(min_thickness 0.25)
			(keepout
				(tracks allowed)
				(vias not_allowed)
				(pads allowed)
				(copperpour not_allowed)
				(footprints allowed)
			)
			(placement
				(enabled no)
				(sheetname "")
			)
			(fill
				(thermal_gap 0.5)
				(thermal_bridge_width 0.5)
				(island_removal_mode 0)
			)
			(polygon
				(pts
					(xy 309.703724 -95.854012) (xy 309.703724 -48.146208) (xy 310.211724 -48.146208) (xy 310.211724 -95.854012)
				)
			)
		)
		(zone
			(layer "F.Cu")
			(hatch none 0.5)
			(connect_pads
				(clearance 0)
			)
			(min_thickness 0.25)
			(keepout
				(tracks allowed)
				(vias not_allowed)
				(pads allowed)
				(copperpour not_allowed)
				(footprints allowed)
			)
			(placement
				(enabled no)
				(sheetname "")
			)
			(fill
				(thermal_gap 0.5)
				(thermal_bridge_width 0.5)
				(island_removal_mode 0)
			)
			(polygon
				(pts
					(xy 309.703724 -95.854012) (xy 309.703724 -48.146208) (xy 312.096404 -48.146208) (xy 312.096404 -95.854012)
				)
			)
		)
		(zone
			(layer "F.Cu")
			(hatch none 0.5)
			(connect_pads
				(clearance 0)
			)
			(min_thickness 0.25)
			(keepout
				(tracks not_allowed)
				(vias allowed)
				(pads allowed)
				(copperpour not_allowed)
				(footprints allowed)
			)
			(placement
				(enabled no)
				(sheetname "")
			)
			(fill
				(thermal_gap 0.5)
				(thermal_bridge_width 0.5)
				(island_removal_mode 0)
			)
			(polygon
				(pts
					(xy 309.703724 -95.854012) (xy 309.703724 -48.146208) (xy 312.096404 -48.146208) (xy 312.096404 -95.854012)
				)
			)
		)
		(zone
			(layer "F.Cu")
			(hatch none 0.5)
			(connect_pads
				(clearance 0)
			)
			(min_thickness 0.25)
			(keepout
				(tracks allowed)
				(vias not_allowed)
				(pads allowed)
				(copperpour not_allowed)
				(footprints allowed)
			)
			(placement
				(enabled no)
				(sheetname "")
			)
			(fill
				(thermal_gap 0.5)
				(thermal_bridge_width 0.5)
				(island_removal_mode 0)
			)
			(polygon
				(pts
					(xy 311.588404 -95.854012) (xy 311.588404 -48.146208) (xy 312.096404 -48.146208) (xy 312.096404 -95.854012)
				)
			)
		)
		(zone
			(layers "F.Cu" "B.Cu" "In1.Cu" "In2.Cu" "In3.Cu" "In4.Cu" "In5.Cu" "In6.Cu")
			(hatch none 0.5)
			(connect_pads
				(clearance 0)
			)
			(min_thickness 0.25)
			(keepout
				(tracks not_allowed)
				(vias allowed)
				(pads allowed)
				(copperpour not_allowed)
				(footprints allowed)
			)
			(placement
				(enabled no)
				(sheetname "")
			)
			(fill
				(thermal_gap 0.5)
				(thermal_bridge_width 0.5)
				(island_removal_mode 0)
			)
			(polygon
				(pts
					(arc
						(start 311.636664 -98.100134)
						(mid 310.163464 -98.100134)
						(end 311.636664 -98.100134)
					)
				)
			)
		)
		(zone
			(layers "F.Cu" "B.Cu" "In1.Cu" "In2.Cu" "In3.Cu" "In4.Cu" "In5.Cu" "In6.Cu")
			(hatch none 0.5)
			(connect_pads
				(clearance 0)
			)
			(min_thickness 0.25)
			(keepout
				(tracks not_allowed)
				(vias allowed)
				(pads allowed)
				(copperpour not_allowed)
				(footprints allowed)
			)
			(placement
				(enabled no)
				(sheetname "")
			)
			(fill
				(thermal_gap 0.5)
				(thermal_bridge_width 0.5)
				(island_removal_mode 0)
			)
			(polygon
				(pts
					(arc
						(start 311.814464 -45.900086)
						(mid 309.985664 -45.900086)
						(end 311.814464 -45.900086)
					)
				)
			)
		)
	)
	(footprint ""
		(layer "F.Cu")
		(at 115.57 -28.321 180)
		(property "Reference" "SR663"
			(at 0 0 180)
			(layer "F.SilkS")
			(hide yes)
			(effects
				(font
					(size 1.27 1.27)
				)
			)
		)
		(property "Value" "10KR2F-2-GP"
			(at 0.064008 -3.993896 180)
			(unlocked yes)
			(layer "F.Fab")
			(hide yes)
			(effects
				(font
					(size 1.016 1.016)
					(thickness 0.1524)
				)
			)
		)
		(property "Device Type" "R402H16"
			(at 0.064008 -5.517896 180)
			(unlocked yes)
			(layer "F.Fab")
			(hide yes)
			(effects
				(font
					(size 1.016 1.016)
					(thickness 0.1524)
				)
			)
		)
		(duplicate_pad_numbers_are_jumpers no)
		(fp_line
			(start 0.508 -0.9398)
			(end -0.508 -0.9398)
			(stroke
				(width 0.1524)
				(type default)
			)
			(layer "F.SilkS")
		)
		(fp_line
			(start -0.508 -0.9398)
			(end -0.508 0.9398)
			(stroke
				(width 0.1524)
				(type default)
			)
			(layer "F.SilkS")
		)
		(fp_rect
			(start -0.508 0.9398)
			(end 0.508 -0.9398)
			(stroke
				(width 0)
				(type default)
			)
			(fill no)
			(layer "F.CrtYd")
		)
		(fp_rect
			(start -0.508 0.9398)
			(end 0.508 -0.9398)
			(stroke
				(width 0)
				(type default)
			)
			(fill no)
			(layer "F.Fab")
		)
		(pad "1" smd custom
			(at 0 -0.4445 180)
			(size 0.1397 0.1397)
			(layers "F.Cu" "F.Mask" "F.Paste")
			(net "P1V8_C")
			(options
				(clearance outline)
				(anchor circle)
			)
			(primitives
				(gr_poly
					(pts
						(arc
							(start -0.1778 -0.2794)
							(mid -0.249642 -0.249642)
							(end -0.2794 -0.1778)
						)
						(arc
							(start -0.2794 0.1778)
							(mid -0.249642 0.249642)
							(end -0.1778 0.2794)
						)
						(arc
							(start 0.1778 0.2794)
							(mid 0.249642 0.249642)
							(end 0.2794 0.1778)
						)
						(arc
							(start 0.2794 -0.1778)
							(mid 0.249642 -0.249642)
							(end 0.1778 -0.2794)
						)
					)
					(width 0)
					(fill yes)
				)
			)
		)
		(pad "2" smd custom
			(at 0 0.4445 180)
			(size 0.1397 0.1397)
			(layers "F.Cu" "F.Mask" "F.Paste")
			(net "SYS_DBMODE2")
			(options
				(clearance outline)
				(anchor circle)
			)
			(primitives
				(gr_poly
					(pts
						(arc
							(start -0.1778 -0.2794)
							(mid -0.249642 -0.249642)
							(end -0.2794 -0.1778)
						)
						(arc
							(start -0.2794 0.1778)
							(mid -0.249642 0.249642)
							(end -0.1778 0.2794)
						)
						(arc
							(start 0.1778 0.2794)
							(mid 0.249642 0.249642)
							(end 0.2794 0.1778)
						)
						(arc
							(start 0.2794 -0.1778)
							(mid 0.249642 -0.249642)
							(end 0.1778 -0.2794)
						)
					)
					(width 0)
					(fill yes)
				)
			)
		)
	)
	(footprint ""
		(layer "F.Cu")
		(at 267.843 -73.025 90)
		(property "Reference" "C256"
			(at 0 0 90)
			(layer "F.SilkS")
			(hide yes)
			(effects
				(font
					(size 1.27 1.27)
				)
			)
		)
		(property "Value" "SCD1U25V2KX-2-GP"
			(at 1.1811 -2.7051 90)
			(unlocked yes)
			(layer "F.Fab")
			(hide yes)
			(effects
				(font
					(size 1.016 1.016)
					(thickness 0.1524)
				)
			)
		)
		(property "Device Type" "C402H22"
			(at 1.1811 -4.2291 90)
			(unlocked yes)
			(layer "F.Fab")
			(hide yes)
			(effects
				(font
					(size 1.016 1.016)
					(thickness 0.1524)
				)
			)
		)
		(duplicate_pad_numbers_are_jumpers no)
		(fp_rect
			(start -0.4318 0.9525)
			(end 0.4318 -0.9525)
			(stroke
				(width 0)
				(type default)
			)
			(fill no)
			(layer "F.CrtYd")
		)
		(fp_rect
			(start -0.4318 0.9525)
			(end 0.4318 -0.9525)
			(stroke
				(width 0)
				(type default)
			)
			(fill no)
			(layer "F.Fab")
		)
		(pad "1" smd custom
			(at 0 -0.4445 90)
			(size 0.1524 0.1524)
			(layers "F.Cu" "F.Mask" "F.Paste")
			(net "P12V_MSB")
			(options
				(clearance outline)
				(anchor circle)
			)
			(primitives
				(gr_poly
					(pts
						(arc
							(start 0.3048 -0.2032)
							(mid 0.275042 -0.275042)
							(end 0.2032 -0.3048)
						)
						(arc
							(start -0.2032 -0.3048)
							(mid -0.275042 -0.275042)
							(end -0.3048 -0.2032)
						)
						(arc
							(start -0.3048 0.2032)
							(mid -0.275042 0.275042)
							(end -0.2032 0.3048)
						)
						(arc
							(start 0.2032 0.3048)
							(mid 0.275042 0.275042)
							(end 0.3048 0.2032)
						)
					)
					(width 0)
					(fill yes)
				)
			)
		)
		(pad "2" smd custom
			(at 0 0.4445 90)
			(size 0.1524 0.1524)
			(layers "F.Cu" "F.Mask" "F.Paste")
			(net "GND")
			(options
				(clearance outline)
				(anchor circle)
			)
			(primitives
				(gr_poly
					(pts
						(arc
							(start 0.3048 -0.2032)
							(mid 0.275042 -0.275042)
							(end 0.2032 -0.3048)
						)
						(arc
							(start -0.2032 -0.3048)
							(mid -0.275042 -0.275042)
							(end -0.3048 -0.2032)
						)
						(arc
							(start -0.3048 0.2032)
							(mid -0.275042 0.275042)
							(end -0.2032 0.3048)
						)
						(arc
							(start 0.2032 0.3048)
							(mid 0.275042 0.275042)
							(end 0.3048 0.2032)
						)
					)
					(width 0)
					(fill yes)
				)
			)
		)
	)
	(footprint ""
		(layer "F.Cu")
		(at 184.077864 -24.075136)
		(property "Reference" "TP129"
			(at 0 0 0)
			(layer "F.SilkS")
			(hide yes)
			(effects
				(font
					(size 1.27 1.27)
				)
			)
		)
		(property "Value" "TPAD28"
			(at 0.0127 -1.8034 0)
			(unlocked yes)
			(layer "F.Fab")
			(hide yes)
			(effects
				(font
					(size 1.016 1.016)
					(thickness 0.1524)
				)
			)
		)
		(property "Device Type" "TPAD28"
			(at 0.0127 -3.3274 0)
			(unlocked yes)
			(layer "F.Fab")
			(hide yes)
			(effects
				(font
					(size 1.016 1.016)
					(thickness 0.1524)
				)
			)
		)
		(duplicate_pad_numbers_are_jumpers no)
		(fp_poly
			(pts
				(arc
					(start 0.3556 0)
					(mid -0.3556 0)
					(end 0.3556 0)
				)
			)
			(stroke
				(width 0)
				(type default)
			)
			(fill no)
			(layer "F.CrtYd")
		)
		(fp_poly
			(pts
				(arc
					(start 0.6096 0)
					(mid -0.6096 0)
					(end 0.6096 0)
				)
			)
			(stroke
				(width 0)
				(type default)
			)
			(fill no)
			(layer "F.Fab")
		)
		(pad "1" smd circle
			(at 0 0)
			(size 0.7112 0.7112)
			(layers "F.Cu" "F.Mask" "F.Paste")
			(net "RMII_BMC_MDIO_R")
		)
	)
	(footprint ""
		(layer "F.Cu")
		(at 186.055 -122.047 180)
		(property "Reference" "PR170"
			(at 0 0 180)
			(layer "F.SilkS")
			(hide yes)
			(effects
				(font
					(size 1.27 1.27)
				)
			)
		)
		(property "Value" "100KR2F-L1-GP"
			(at 0.064008 -3.993896 180)
			(unlocked yes)
			(layer "F.Fab")
			(hide yes)
			(effects
				(font
					(size 1.016 1.016)
					(thickness 0.1524)
				)
			)
		)
		(property "Device Type" "R402H16"
			(at 0.064008 -5.517896 180)
			(unlocked yes)
			(layer "F.Fab")
			(hide yes)
			(effects
				(font
					(size 1.016 1.016)
					(thickness 0.1524)
				)
			)
		)
		(duplicate_pad_numbers_are_jumpers no)
		(fp_line
			(start 0.508 -0.9398)
			(end -0.508 -0.9398)
			(stroke
				(width 0.1524)
				(type default)
			)
			(layer "F.SilkS")
		)
		(fp_line
			(start -0.508 -0.9398)
			(end -0.508 0.9398)
			(stroke
				(width 0.1524)
				(type default)
			)
			(layer "F.SilkS")
		)
		(fp_rect
			(start -0.508 0.9398)
			(end 0.508 -0.9398)
			(stroke
				(width 0)
				(type default)
			)
			(fill no)
			(layer "F.CrtYd")
		)
		(fp_rect
			(start -0.508 0.9398)
			(end 0.508 -0.9398)
			(stroke
				(width 0)
				(type default)
			)
			(fill no)
			(layer "F.Fab")
		)
		(pad "1" smd custom
			(at 0 -0.4445 180)
			(size 0.1397 0.1397)
			(layers "F.Cu" "F.Mask" "F.Paste")
			(net "PMU_PLTRST#")
			(options
				(clearance outline)
				(anchor circle)
			)
			(primitives
				(gr_poly
					(pts
						(arc
							(start -0.1778 -0.2794)
							(mid -0.249642 -0.249642)
							(end -0.2794 -0.1778)
						)
						(arc
							(start -0.2794 0.1778)
							(mid -0.249642 0.249642)
							(end -0.1778 0.2794)
						)
						(arc
							(start 0.1778 0.2794)
							(mid 0.249642 0.249642)
							(end 0.2794 0.1778)
						)
						(arc
							(start 0.2794 -0.1778)
							(mid 0.249642 -0.249642)
							(end 0.1778 -0.2794)
						)
					)
					(width 0)
					(fill yes)
				)
			)
		)
		(pad "2" smd custom
			(at 0 0.4445 180)
			(size 0.1397 0.1397)
			(layers "F.Cu" "F.Mask" "F.Paste")
			(net "GND")
			(options
				(clearance outline)
				(anchor circle)
			)
			(primitives
				(gr_poly
					(pts
						(arc
							(start -0.1778 -0.2794)
							(mid -0.249642 -0.249642)
							(end -0.2794 -0.1778)
						)
						(arc
							(start -0.2794 0.1778)
							(mid -0.249642 0.249642)
							(end -0.1778 0.2794)
						)
						(arc
							(start 0.1778 0.2794)
							(mid 0.249642 0.249642)
							(end 0.2794 0.1778)
						)
						(arc
							(start 0.2794 -0.1778)
							(mid 0.249642 -0.249642)
							(end 0.1778 -0.2794)
						)
					)
					(width 0)
					(fill yes)
				)
			)
		)
	)
	(footprint ""
		(layer "F.Cu")
		(at 266.319 -234.569 -90)
		(property "Reference" "PR84"
			(at 0 0 270)
			(layer "F.SilkS")
			(hide yes)
			(effects
				(font
					(size 1.27 1.27)
				)
			)
		)
		(property "Value" "0R6J-3-GP"
			(at -0.0508 -4.8514 270)
			(unlocked yes)
			(layer "F.Fab")
			(hide yes)
			(effects
				(font
					(size 1.016 1.016)
					(thickness 0.1524)
				)
			)
		)
		(property "Device Type" "R1206H28"
			(at 0 -6.3754 270)
			(unlocked yes)
			(layer "F.Fab")
			(hide yes)
			(effects
				(font
					(size 1.016 1.016)
					(thickness 0.1524)
				)
			)
		)
		(duplicate_pad_numbers_are_jumpers no)
		(fp_line
			(start -1.016 2.2352)
			(end -1.016 -2.2352)
			(stroke
				(width 0.1524)
				(type default)
			)
			(layer "F.SilkS")
		)
		(fp_line
			(start 1.016 2.2352)
			(end -1.016 2.2352)
			(stroke
				(width 0.1524)
				(type default)
			)
			(layer "F.SilkS")
		)
		(fp_line
			(start -1.016 -2.2352)
			(end 1.016 -2.2352)
			(stroke
				(width 0.1524)
				(type default)
			)
			(layer "F.SilkS")
		)
		(fp_line
			(start 1.016 -2.2352)
			(end 1.016 2.2352)
			(stroke
				(width 0.1524)
				(type default)
			)
			(layer "F.SilkS")
		)
		(fp_rect
			(start -1.0922 2.3114)
			(end 1.0922 -2.3114)
			(stroke
				(width 0)
				(type default)
			)
			(fill no)
			(layer "F.CrtYd")
		)
		(fp_poly
			(pts
				(xy -1.0922 -2.3114) (xy 1.0922 -2.3114) (xy 1.0922 2.3114) (xy -1.0922 2.3114)
			)
			(stroke
				(width 0)
				(type default)
			)
			(fill no)
			(layer "F.Fab")
		)
		(pad "1" smd rect
			(at 0 -1.397 270)
			(size 1.651 1.27)
			(layers "F.Cu" "F.Mask" "F.Paste")
			(net "P1V8_STBY")
		)
		(pad "2" smd rect
			(at 0 1.397 270)
			(size 1.651 1.27)
			(layers "F.Cu" "F.Mask" "F.Paste")
			(net "TPS74801_P1V26_STBY_IN")
		)
	)
	(footprint ""
		(layer "F.Cu")
		(at 93.472 -10.033 180)
		(property "Reference" "PC203"
			(at 0 0 180)
			(layer "F.SilkS")
			(hide yes)
			(effects
				(font
					(size 1.27 1.27)
				)
			)
		)
		(property "Value" "SC22U6D3V6KX-2-GP"
			(at -0.0762 -5.1308 180)
			(unlocked yes)
			(layer "F.Fab")
			(hide yes)
			(effects
				(font
					(size 1.016 1.016)
					(thickness 0.1524)
				)
			)
		)
		(property "Device Type" "C1206H71"
			(at -0.127 -6.6548 180)
			(unlocked yes)
			(layer "F.Fab")
			(hide yes)
			(effects
				(font
					(size 1.016 1.016)
					(thickness 0.1524)
				)
			)
		)
		(duplicate_pad_numbers_are_jumpers no)
		(fp_line
			(start 1.016 2.2352)
			(end -1.016 2.2352)
			(stroke
				(width 0.1524)
				(type default)
			)
			(layer "F.SilkS")
		)
		(fp_line
			(start 1.016 0.8382)
			(end 1.016 2.2352)
			(stroke
				(width 0.1524)
				(type default)
			)
			(layer "F.SilkS")
		)
		(fp_line
			(start 1.016 -2.2352)
			(end 1.016 -0.8382)
			(stroke
				(width 0.1524)
				(type default)
			)
			(layer "F.SilkS")
		)
		(fp_line
			(start -1.016 2.2352)
			(end -1.016 0.8382)
			(stroke
				(width 0.1524)
				(type default)
			)
			(layer "F.SilkS")
		)
		(fp_line
			(start -1.016 -0.8382)
			(end -1.016 -2.2352)
			(stroke
				(width 0.1524)
				(type default)
			)
			(layer "F.SilkS")
		)
		(fp_line
			(start -1.016 -2.2352)
			(end 1.016 -2.2352)
			(stroke
				(width 0.1524)
				(type default)
			)
			(layer "F.SilkS")
		)
		(fp_rect
			(start -1.0922 2.3114)
			(end 1.0922 -2.3114)
			(stroke
				(width 0)
				(type default)
			)
			(fill no)
			(layer "F.CrtYd")
		)
		(fp_poly
			(pts
				(xy 1.0922 -2.3114) (xy 1.0922 2.3114) (xy -1.0922 2.3114) (xy -1.0922 -2.3114)
			)
			(stroke
				(width 0)
				(type default)
			)
			(fill no)
			(layer "F.Fab")
		)
		(pad "1" smd rect
			(at 0 -1.397 180)
			(size 1.651 1.27)
			(layers "F.Cu" "F.Mask" "F.Paste")
			(net "P0V955_C")
		)
		(pad "2" smd rect
			(at 0 1.397 180)
			(size 1.651 1.27)
			(layers "F.Cu" "F.Mask" "F.Paste")
			(net "GND")
		)
	)
	(footprint ""
		(layer "F.Cu")
		(at 105.80497 -78.105)
		(property "Reference" "STP147"
			(at 0 0 0)
			(layer "F.SilkS")
			(hide yes)
			(effects
				(font
					(size 1.27 1.27)
				)
			)
		)
		(property "Value" "TPAD28"
			(at 0.0127 -1.8034 0)
			(unlocked yes)
			(layer "F.Fab")
			(hide yes)
			(effects
				(font
					(size 1.016 1.016)
					(thickness 0.1524)
				)
			)
		)
		(property "Device Type" "TPAD28"
			(at 0.0127 -3.3274 0)
			(unlocked yes)
			(layer "F.Fab")
			(hide yes)
			(effects
				(font
					(size 1.016 1.016)
					(thickness 0.1524)
				)
			)
		)
		(duplicate_pad_numbers_are_jumpers no)
		(fp_poly
			(pts
				(arc
					(start 0.3556 0)
					(mid -0.3556 0)
					(end 0.3556 0)
				)
			)
			(stroke
				(width 0)
				(type default)
			)
			(fill no)
			(layer "F.CrtYd")
		)
		(fp_poly
			(pts
				(arc
					(start 0.6096 0)
					(mid -0.6096 0)
					(end 0.6096 0)
				)
			)
			(stroke
				(width 0)
				(type default)
			)
			(fill no)
			(layer "F.Fab")
		)
		(pad "1" smd circle
			(at 0 0)
			(size 0.7112 0.7112)
			(layers "F.Cu" "F.Mask" "F.Paste")
			(net "LSI_TRST_N")
		)
	)
	(footprint ""
		(layer "F.Cu")
		(at 262.001 -33.782 -90)
		(property "Reference" "PR44"
			(at 0 0 270)
			(layer "F.SilkS")
			(hide yes)
			(effects
				(font
					(size 1.27 1.27)
				)
			)
		)
		(property "Value" "2K7R2J-GP"
			(at 0.064008 -3.993896 270)
			(unlocked yes)
			(layer "F.Fab")
			(hide yes)
			(effects
				(font
					(size 1.016 1.016)
					(thickness 0.1524)
				)
			)
		)
		(property "Device Type" "R402H16"
			(at 0.064008 -5.517896 270)
			(unlocked yes)
			(layer "F.Fab")
			(hide yes)
			(effects
				(font
					(size 1.016 1.016)
					(thickness 0.1524)
				)
			)
		)
		(duplicate_pad_numbers_are_jumpers no)
		(fp_line
			(start -0.508 -0.9398)
			(end -0.508 0.9398)
			(stroke
				(width 0.1524)
				(type default)
			)
			(layer "F.SilkS")
		)
		(fp_line
			(start 0.508 -0.9398)
			(end -0.508 -0.9398)
			(stroke
				(width 0.1524)
				(type default)
			)
			(layer "F.SilkS")
		)
		(fp_rect
			(start -0.508 0.9398)
			(end 0.508 -0.9398)
			(stroke
				(width 0)
				(type default)
			)
			(fill no)
			(layer "F.CrtYd")
		)
		(fp_rect
			(start -0.508 0.9398)
			(end 0.508 -0.9398)
			(stroke
				(width 0)
				(type default)
			)
			(fill no)
			(layer "F.Fab")
		)
		(pad "1" smd custom
			(at 0 -0.4445 270)
			(size 0.1397 0.1397)
			(layers "F.Cu" "F.Mask" "F.Paste")
			(net "P1V8_STBY_EN")
			(options
				(clearance outline)
				(anchor circle)
			)
			(primitives
				(gr_poly
					(pts
						(arc
							(start -0.1778 -0.2794)
							(mid -0.249642 -0.249642)
							(end -0.2794 -0.1778)
						)
						(arc
							(start -0.2794 0.1778)
							(mid -0.249642 0.249642)
							(end -0.1778 0.2794)
						)
						(arc
							(start 0.1778 0.2794)
							(mid 0.249642 0.249642)
							(end 0.2794 0.1778)
						)
						(arc
							(start 0.2794 -0.1778)
							(mid 0.249642 -0.249642)
							(end 0.1778 -0.2794)
						)
					)
					(width 0)
					(fill yes)
				)
			)
		)
		(pad "2" smd custom
			(at 0 0.4445 270)
			(size 0.1397 0.1397)
			(layers "F.Cu" "F.Mask" "F.Paste")
			(net "AGND_P1V8_STBY")
			(options
				(clearance outline)
				(anchor circle)
			)
			(primitives
				(gr_poly
					(pts
						(arc
							(start -0.1778 -0.2794)
							(mid -0.249642 -0.249642)
							(end -0.2794 -0.1778)
						)
						(arc
							(start -0.2794 0.1778)
							(mid -0.249642 0.249642)
							(end -0.1778 0.2794)
						)
						(arc
							(start 0.1778 0.2794)
							(mid 0.249642 0.249642)
							(end 0.2794 0.1778)
						)
						(arc
							(start 0.2794 -0.1778)
							(mid 0.249642 -0.249642)
							(end 0.1778 -0.2794)
						)
					)
					(width 0)
					(fill yes)
				)
			)
		)
	)
	(footprint ""
		(layer "F.Cu")
		(at 89.662 -226.822 -90)
		(property "Reference" "SR307"
			(at 0 0 270)
			(layer "F.SilkS")
			(hide yes)
			(effects
				(font
					(size 1.27 1.27)
				)
			)
		)
		(property "Value" "0R2J-2-GP"
			(at 0.064008 -3.993896 270)
			(unlocked yes)
			(layer "F.Fab")
			(hide yes)
			(effects
				(font
					(size 1.016 1.016)
					(thickness 0.1524)
				)
			)
		)
		(property "Device Type" "R402H16"
			(at 0.064008 -5.517896 270)
			(unlocked yes)
			(layer "F.Fab")
			(hide yes)
			(effects
				(font
					(size 1.016 1.016)
					(thickness 0.1524)
				)
			)
		)
		(duplicate_pad_numbers_are_jumpers no)
		(fp_line
			(start -0.508 -0.9398)
			(end -0.508 0.9398)
			(stroke
				(width 0.1524)
				(type default)
			)
			(layer "F.SilkS")
		)
		(fp_line
			(start 0.508 -0.9398)
			(end -0.508 -0.9398)
			(stroke
				(width 0.1524)
				(type default)
			)
			(layer "F.SilkS")
		)
		(fp_rect
			(start -0.508 0.9398)
			(end 0.508 -0.9398)
			(stroke
				(width 0)
				(type default)
			)
			(fill no)
			(layer "F.CrtYd")
		)
		(fp_rect
			(start -0.508 0.9398)
			(end 0.508 -0.9398)
			(stroke
				(width 0)
				(type default)
			)
			(fill no)
			(layer "F.Fab")
		)
		(pad "1" smd custom
			(at 0 -0.4445 270)
			(size 0.1397 0.1397)
			(layers "F.Cu" "F.Mask" "F.Paste")
			(net "I2C_IO_EXP_RESET#_FLT")
			(options
				(clearance outline)
				(anchor circle)
			)
			(primitives
				(gr_poly
					(pts
						(arc
							(start -0.1778 -0.2794)
							(mid -0.249642 -0.249642)
							(end -0.2794 -0.1778)
						)
						(arc
							(start -0.2794 0.1778)
							(mid -0.249642 0.249642)
							(end -0.1778 0.2794)
						)
						(arc
							(start 0.1778 0.2794)
							(mid 0.249642 0.249642)
							(end 0.2794 0.1778)
						)
						(arc
							(start 0.2794 -0.1778)
							(mid 0.249642 -0.249642)
							(end 0.1778 -0.2794)
						)
					)
					(width 0)
					(fill yes)
				)
			)
		)
		(pad "2" smd custom
			(at 0 0.4445 270)
			(size 0.1397 0.1397)
			(layers "F.Cu" "F.Mask" "F.Paste")
			(net "I2C_IO_EXP_RESET#")
			(options
				(clearance outline)
				(anchor circle)
			)
			(primitives
				(gr_poly
					(pts
						(arc
							(start -0.1778 -0.2794)
							(mid -0.249642 -0.249642)
							(end -0.2794 -0.1778)
						)
						(arc
							(start -0.2794 0.1778)
							(mid -0.249642 0.249642)
							(end -0.1778 0.2794)
						)
						(arc
							(start 0.1778 0.2794)
							(mid 0.249642 0.249642)
							(end 0.2794 0.1778)
						)
						(arc
							(start 0.2794 -0.1778)
							(mid 0.249642 -0.249642)
							(end 0.1778 -0.2794)
						)
					)
					(width 0)
					(fill yes)
				)
			)
		)
	)
	(footprint ""
		(layer "F.Cu")
		(at 219.075 -110.363)
		(property "Reference" "R598"
			(at 0 0 0)
			(layer "F.SilkS")
			(hide yes)
			(effects
				(font
					(size 1.27 1.27)
				)
			)
		)
		(property "Value" "4K75R2F-1-GP"
			(at 0.064008 -3.993896 0)
			(unlocked yes)
			(layer "F.Fab")
			(hide yes)
			(effects
				(font
					(size 1.016 1.016)
					(thickness 0.1524)
				)
			)
		)
		(property "Device Type" "R402H16"
			(at 0.064008 -5.517896 0)
			(unlocked yes)
			(layer "F.Fab")
			(hide yes)
			(effects
				(font
					(size 1.016 1.016)
					(thickness 0.1524)
				)
			)
		)
		(duplicate_pad_numbers_are_jumpers no)
		(fp_line
			(start -0.508 -0.9398)
			(end -0.508 0.9398)
			(stroke
				(width 0.1524)
				(type default)
			)
			(layer "F.SilkS")
		)
		(fp_line
			(start 0.508 -0.9398)
			(end -0.508 -0.9398)
			(stroke
				(width 0.1524)
				(type default)
			)
			(layer "F.SilkS")
		)
		(fp_rect
			(start -0.508 0.9398)
			(end 0.508 -0.9398)
			(stroke
				(width 0)
				(type default)
			)
			(fill no)
			(layer "F.CrtYd")
		)
		(fp_rect
			(start -0.508 0.9398)
			(end 0.508 -0.9398)
			(stroke
				(width 0)
				(type default)
			)
			(fill no)
			(layer "F.Fab")
		)
		(pad "1" smd custom
			(at 0 -0.4445)
			(size 0.1397 0.1397)
			(layers "F.Cu" "F.Mask" "F.Paste")
			(net "P3V3_STBY")
			(options
				(clearance outline)
				(anchor circle)
			)
			(primitives
				(gr_poly
					(pts
						(arc
							(start -0.1778 -0.2794)
							(mid -0.249642 -0.249642)
							(end -0.2794 -0.1778)
						)
						(arc
							(start -0.2794 0.1778)
							(mid -0.249642 0.249642)
							(end -0.1778 0.2794)
						)
						(arc
							(start 0.1778 0.2794)
							(mid 0.249642 0.249642)
							(end 0.2794 0.1778)
						)
						(arc
							(start 0.2794 -0.1778)
							(mid 0.249642 -0.249642)
							(end 0.1778 -0.2794)
						)
					)
					(width 0)
					(fill yes)
				)
			)
		)
		(pad "2" smd custom
			(at 0 0.4445)
			(size 0.1397 0.1397)
			(layers "F.Cu" "F.Mask" "F.Paste")
			(net "TPS74801_1V5_C_EN")
			(options
				(clearance outline)
				(anchor circle)
			)
			(primitives
				(gr_poly
					(pts
						(arc
							(start -0.1778 -0.2794)
							(mid -0.249642 -0.249642)
							(end -0.2794 -0.1778)
						)
						(arc
							(start -0.2794 0.1778)
							(mid -0.249642 0.249642)
							(end -0.1778 0.2794)
						)
						(arc
							(start 0.1778 0.2794)
							(mid 0.249642 0.249642)
							(end 0.2794 0.1778)
						)
						(arc
							(start 0.2794 -0.1778)
							(mid 0.249642 -0.249642)
							(end 0.1778 -0.2794)
						)
					)
					(width 0)
					(fill yes)
				)
			)
		)
	)
	(footprint ""
		(layer "F.Cu")
		(at 188.459872 -195.271136 -90)
		(property "Reference" "R154"
			(at 0 0 270)
			(layer "F.SilkS")
			(hide yes)
			(effects
				(font
					(size 1.27 1.27)
				)
			)
		)
		(property "Value" "0R2J-2-GP"
			(at 0.064008 -3.993896 270)
			(unlocked yes)
			(layer "F.Fab")
			(hide yes)
			(effects
				(font
					(size 1.016 1.016)
					(thickness 0.1524)
				)
			)
		)
		(property "Device Type" "R402H16"
			(at 0.064008 -5.517896 270)
			(unlocked yes)
			(layer "F.Fab")
			(hide yes)
			(effects
				(font
					(size 1.016 1.016)
					(thickness 0.1524)
				)
			)
		)
		(duplicate_pad_numbers_are_jumpers no)
		(fp_line
			(start -0.508 -0.9398)
			(end -0.508 0.9398)
			(stroke
				(width 0.1524)
				(type default)
			)
			(layer "F.SilkS")
		)
		(fp_line
			(start 0.508 -0.9398)
			(end -0.508 -0.9398)
			(stroke
				(width 0.1524)
				(type default)
			)
			(layer "F.SilkS")
		)
		(fp_rect
			(start -0.508 0.9398)
			(end 0.508 -0.9398)
			(stroke
				(width 0)
				(type default)
			)
			(fill no)
			(layer "F.CrtYd")
		)
		(fp_rect
			(start -0.508 0.9398)
			(end 0.508 -0.9398)
			(stroke
				(width 0)
				(type default)
			)
			(fill no)
			(layer "F.Fab")
		)
		(pad "1" smd custom
			(at 0 -0.4445 270)
			(size 0.1397 0.1397)
			(layers "F.Cu" "F.Mask" "F.Paste")
			(net "SAS_I2C_C_BUF_SDA_R")
			(options
				(clearance outline)
				(anchor circle)
			)
			(primitives
				(gr_poly
					(pts
						(arc
							(start -0.1778 -0.2794)
							(mid -0.249642 -0.249642)
							(end -0.2794 -0.1778)
						)
						(arc
							(start -0.2794 0.1778)
							(mid -0.249642 0.249642)
							(end -0.1778 0.2794)
						)
						(arc
							(start 0.1778 0.2794)
							(mid 0.249642 0.249642)
							(end 0.2794 0.1778)
						)
						(arc
							(start 0.2794 -0.1778)
							(mid 0.249642 -0.249642)
							(end 0.1778 -0.2794)
						)
					)
					(width 0)
					(fill yes)
				)
			)
		)
		(pad "2" smd custom
			(at 0 0.4445 270)
			(size 0.1397 0.1397)
			(layers "F.Cu" "F.Mask" "F.Paste")
			(net "SAS_I2C_C_BUF_SDA")
			(options
				(clearance outline)
				(anchor circle)
			)
			(primitives
				(gr_poly
					(pts
						(arc
							(start -0.1778 -0.2794)
							(mid -0.249642 -0.249642)
							(end -0.2794 -0.1778)
						)
						(arc
							(start -0.2794 0.1778)
							(mid -0.249642 0.249642)
							(end -0.1778 0.2794)
						)
						(arc
							(start 0.1778 0.2794)
							(mid 0.249642 0.249642)
							(end 0.2794 0.1778)
						)
						(arc
							(start 0.2794 -0.1778)
							(mid 0.249642 -0.249642)
							(end 0.1778 -0.2794)
						)
					)
					(width 0)
					(fill yes)
				)
			)
		)
	)
	(footprint ""
		(layer "F.Cu")
		(at 52.705 -180.086 180)
		(property "Reference" "SR809"
			(at 0 0 180)
			(layer "F.SilkS")
			(hide yes)
			(effects
				(font
					(size 1.27 1.27)
				)
			)
		)
		(property "Value" "4K75R2F-1-GP"
			(at 0.064008 -3.993896 180)
			(unlocked yes)
			(layer "F.Fab")
			(hide yes)
			(effects
				(font
					(size 1.016 1.016)
					(thickness 0.1524)
				)
			)
		)
		(property "Device Type" "R402H16"
			(at 0.064008 -5.517896 180)
			(unlocked yes)
			(layer "F.Fab")
			(hide yes)
			(effects
				(font
					(size 1.016 1.016)
					(thickness 0.1524)
				)
			)
		)
		(duplicate_pad_numbers_are_jumpers no)
		(fp_line
			(start 0.508 -0.9398)
			(end -0.508 -0.9398)
			(stroke
				(width 0.1524)
				(type default)
			)
			(layer "F.SilkS")
		)
		(fp_line
			(start -0.508 -0.9398)
			(end -0.508 0.9398)
			(stroke
				(width 0.1524)
				(type default)
			)
			(layer "F.SilkS")
		)
		(fp_rect
			(start -0.508 0.9398)
			(end 0.508 -0.9398)
			(stroke
				(width 0)
				(type default)
			)
			(fill no)
			(layer "F.CrtYd")
		)
		(fp_rect
			(start -0.508 0.9398)
			(end 0.508 -0.9398)
			(stroke
				(width 0)
				(type default)
			)
			(fill no)
			(layer "F.Fab")
		)
		(pad "1" smd custom
			(at 0 -0.4445 180)
			(size 0.1397 0.1397)
			(layers "F.Cu" "F.Mask" "F.Paste")
			(net "P1V8_E")
			(options
				(clearance outline)
				(anchor circle)
			)
			(primitives
				(gr_poly
					(pts
						(arc
							(start -0.1778 -0.2794)
							(mid -0.249642 -0.249642)
							(end -0.2794 -0.1778)
						)
						(arc
							(start -0.2794 0.1778)
							(mid -0.249642 0.249642)
							(end -0.1778 0.2794)
						)
						(arc
							(start 0.1778 0.2794)
							(mid 0.249642 0.249642)
							(end 0.2794 0.1778)
						)
						(arc
							(start 0.2794 -0.1778)
							(mid 0.249642 -0.249642)
							(end 0.1778 -0.2794)
						)
					)
					(width 0)
					(fill yes)
				)
			)
		)
		(pad "2" smd custom
			(at 0 0.4445 180)
			(size 0.1397 0.1397)
			(layers "F.Cu" "F.Mask" "F.Paste")
			(net "ICE_TRST_N")
			(options
				(clearance outline)
				(anchor circle)
			)
			(primitives
				(gr_poly
					(pts
						(arc
							(start -0.1778 -0.2794)
							(mid -0.249642 -0.249642)
							(end -0.2794 -0.1778)
						)
						(arc
							(start -0.2794 0.1778)
							(mid -0.249642 0.249642)
							(end -0.1778 0.2794)
						)
						(arc
							(start 0.1778 0.2794)
							(mid 0.249642 0.249642)
							(end 0.2794 0.1778)
						)
						(arc
							(start 0.2794 -0.1778)
							(mid 0.249642 -0.249642)
							(end 0.1778 -0.2794)
						)
					)
					(width 0)
					(fill yes)
				)
			)
		)
	)
	(footprint ""
		(layer "F.Cu")
		(at 23.064216 -202.74788 90)
		(property "Reference" "R570"
			(at 0 0 90)
			(layer "F.SilkS")
			(hide yes)
			(effects
				(font
					(size 1.27 1.27)
				)
			)
		)
		(property "Value" "0R2J-2-GP"
			(at 0.064008 -3.993896 90)
			(unlocked yes)
			(layer "F.Fab")
			(hide yes)
			(effects
				(font
					(size 1.016 1.016)
					(thickness 0.1524)
				)
			)
		)
		(property "Device Type" "R402H16"
			(at 0.064008 -5.517896 90)
			(unlocked yes)
			(layer "F.Fab")
			(hide yes)
			(effects
				(font
					(size 1.016 1.016)
					(thickness 0.1524)
				)
			)
		)
		(duplicate_pad_numbers_are_jumpers no)
		(fp_line
			(start 0.508 -0.9398)
			(end -0.508 -0.9398)
			(stroke
				(width 0.1524)
				(type default)
			)
			(layer "F.SilkS")
		)
		(fp_line
			(start -0.508 -0.9398)
			(end -0.508 0.9398)
			(stroke
				(width 0.1524)
				(type default)
			)
			(layer "F.SilkS")
		)
		(fp_rect
			(start -0.508 0.9398)
			(end 0.508 -0.9398)
			(stroke
				(width 0)
				(type default)
			)
			(fill no)
			(layer "F.CrtYd")
		)
		(fp_rect
			(start -0.508 0.9398)
			(end 0.508 -0.9398)
			(stroke
				(width 0)
				(type default)
			)
			(fill no)
			(layer "F.Fab")
		)
		(pad "1" smd custom
			(at 0 -0.4445 90)
			(size 0.1397 0.1397)
			(layers "F.Cu" "F.Mask" "F.Paste")
			(net "ADC_P0V9_E")
			(options
				(clearance outline)
				(anchor circle)
			)
			(primitives
				(gr_poly
					(pts
						(arc
							(start -0.1778 -0.2794)
							(mid -0.249642 -0.249642)
							(end -0.2794 -0.1778)
						)
						(arc
							(start -0.2794 0.1778)
							(mid -0.249642 0.249642)
							(end -0.1778 0.2794)
						)
						(arc
							(start 0.1778 0.2794)
							(mid 0.249642 0.249642)
							(end 0.2794 0.1778)
						)
						(arc
							(start 0.2794 -0.1778)
							(mid 0.249642 -0.249642)
							(end 0.1778 -0.2794)
						)
					)
					(width 0)
					(fill yes)
				)
			)
		)
		(pad "2" smd custom
			(at 0 0.4445 90)
			(size 0.1397 0.1397)
			(layers "F.Cu" "F.Mask" "F.Paste")
			(net "P0V9_E_SENSE")
			(options
				(clearance outline)
				(anchor circle)
			)
			(primitives
				(gr_poly
					(pts
						(arc
							(start -0.1778 -0.2794)
							(mid -0.249642 -0.249642)
							(end -0.2794 -0.1778)
						)
						(arc
							(start -0.2794 0.1778)
							(mid -0.249642 0.249642)
							(end -0.1778 0.2794)
						)
						(arc
							(start 0.1778 0.2794)
							(mid 0.249642 0.249642)
							(end 0.2794 0.1778)
						)
						(arc
							(start 0.2794 -0.1778)
							(mid 0.249642 -0.249642)
							(end 0.1778 -0.2794)
						)
					)
					(width 0)
					(fill yes)
				)
			)
		)
	)
	(footprint ""
		(layer "F.Cu")
		(at 307.848 -173.99)
		(property "Reference" "TP105"
			(at 0 0 0)
			(layer "F.SilkS")
			(hide yes)
			(effects
				(font
					(size 1.27 1.27)
				)
			)
		)
		(property "Value" "TPAD28"
			(at -0.0127 -1.6637 0)
			(unlocked yes)
			(layer "F.Fab")
			(hide yes)
			(effects
				(font
					(size 1.016 1.016)
					(thickness 0.1524)
				)
			)
		)
		(property "Device Type" "TPAD28"
			(at -0.0127 -3.1877 0)
			(unlocked yes)
			(layer "F.Fab")
			(hide yes)
			(effects
				(font
					(size 1.016 1.016)
					(thickness 0.1524)
				)
			)
		)
		(duplicate_pad_numbers_are_jumpers no)
		(fp_poly
			(pts
				(arc
					(start 0.3556 0)
					(mid -0.3556 0)
					(end 0.3556 0)
				)
			)
			(stroke
				(width 0)
				(type default)
			)
			(fill no)
			(layer "F.CrtYd")
		)
		(fp_poly
			(pts
				(arc
					(start 0.6096 0)
					(mid -0.6096 0)
					(end 0.6096 0)
				)
			)
			(stroke
				(width 0)
				(type default)
			)
			(fill no)
			(layer "F.Fab")
		)
		(pad "1" smd circle
			(at 0 0)
			(size 0.7112 0.7112)
			(layers "F.Cu" "F.Mask" "F.Paste")
			(net "TP_BMC_GPIOQ6")
		)
	)
	(footprint ""
		(layer "F.Cu")
		(at 76.327 -22.733 180)
		(property "Reference" "PR192"
			(at 0 0 180)
			(layer "F.SilkS")
			(hide yes)
			(effects
				(font
					(size 1.27 1.27)
				)
			)
		)
		(property "Value" "0R2J-2-GP"
			(at 0.064008 -3.993896 180)
			(unlocked yes)
			(layer "F.Fab")
			(hide yes)
			(effects
				(font
					(size 1.016 1.016)
					(thickness 0.1524)
				)
			)
		)
		(property "Device Type" "R402H16"
			(at 0.064008 -5.517896 180)
			(unlocked yes)
			(layer "F.Fab")
			(hide yes)
			(effects
				(font
					(size 1.016 1.016)
					(thickness 0.1524)
				)
			)
		)
		(duplicate_pad_numbers_are_jumpers no)
		(fp_line
			(start 0.508 -0.9398)
			(end -0.508 -0.9398)
			(stroke
				(width 0.1524)
				(type default)
			)
			(layer "F.SilkS")
		)
		(fp_line
			(start -0.508 -0.9398)
			(end -0.508 0.9398)
			(stroke
				(width 0.1524)
				(type default)
			)
			(layer "F.SilkS")
		)
		(fp_rect
			(start -0.508 0.9398)
			(end 0.508 -0.9398)
			(stroke
				(width 0)
				(type default)
			)
			(fill no)
			(layer "F.CrtYd")
		)
		(fp_rect
			(start -0.508 0.9398)
			(end 0.508 -0.9398)
			(stroke
				(width 0)
				(type default)
			)
			(fill no)
			(layer "F.Fab")
		)
		(pad "1" smd custom
			(at 0 -0.4445 180)
			(size 0.1397 0.1397)
			(layers "F.Cu" "F.Mask" "F.Paste")
			(net "VT235_EN")
			(options
				(clearance outline)
				(anchor circle)
			)
			(primitives
				(gr_poly
					(pts
						(arc
							(start -0.1778 -0.2794)
							(mid -0.249642 -0.249642)
							(end -0.2794 -0.1778)
						)
						(arc
							(start -0.2794 0.1778)
							(mid -0.249642 0.249642)
							(end -0.1778 0.2794)
						)
						(arc
							(start 0.1778 0.2794)
							(mid 0.249642 0.249642)
							(end 0.2794 0.1778)
						)
						(arc
							(start 0.2794 -0.1778)
							(mid 0.249642 -0.249642)
							(end 0.1778 -0.2794)
						)
					)
					(width 0)
					(fill yes)
				)
			)
		)
		(pad "2" smd custom
			(at 0 0.4445 180)
			(size 0.1397 0.1397)
			(layers "F.Cu" "F.Mask" "F.Paste")
			(net "PWRGD_P1V5_C_PG")
			(options
				(clearance outline)
				(anchor circle)
			)
			(primitives
				(gr_poly
					(pts
						(arc
							(start -0.1778 -0.2794)
							(mid -0.249642 -0.249642)
							(end -0.2794 -0.1778)
						)
						(arc
							(start -0.2794 0.1778)
							(mid -0.249642 0.249642)
							(end -0.1778 0.2794)
						)
						(arc
							(start 0.1778 0.2794)
							(mid 0.249642 0.249642)
							(end 0.2794 0.1778)
						)
						(arc
							(start 0.2794 -0.1778)
							(mid 0.249642 -0.249642)
							(end 0.1778 -0.2794)
						)
					)
					(width 0)
					(fill yes)
				)
			)
		)
	)
	(footprint ""
		(layer "F.Cu")
		(at 86.233 -11.811)
		(property "Reference" "PL11"
			(at 0 0 0)
			(layer "F.SilkS")
			(hide yes)
			(effects
				(font
					(size 1.27 1.27)
				)
			)
		)
		(property "Value" "IND-D47UH-22-GP"
			(at -5.08 -0.4572 0)
			(unlocked yes)
			(layer "F.Fab")
			(hide yes)
			(effects
				(font
					(size 1.016 1.016)
					(thickness 0.1524)
				)
			)
		)
		(property "Device Type" "L736630H119"
			(at -5.08 -1.9812 0)
			(unlocked yes)
			(layer "F.Fab")
			(hide yes)
			(effects
				(font
					(size 1.016 1.016)
					(thickness 0.1524)
				)
			)
		)
		(duplicate_pad_numbers_are_jumpers no)
		(fp_line
			(start -3.556 -4.4196)
			(end -3.556 4.4196)
			(stroke
				(width 0.1524)
				(type default)
			)
			(layer "F.SilkS")
		)
		(fp_line
			(start -3.556 4.4196)
			(end 3.556 4.4196)
			(stroke
				(width 0.1524)
				(type default)
			)
			(layer "F.SilkS")
		)
		(fp_line
			(start 3.556 -4.4196)
			(end -3.556 -4.4196)
			(stroke
				(width 0.1524)
				(type default)
			)
			(layer "F.SilkS")
		)
		(fp_line
			(start 3.556 4.4196)
			(end 3.556 -4.4196)
			(stroke
				(width 0.1524)
				(type default)
			)
			(layer "F.SilkS")
		)
		(fp_rect
			(start -3.81 4.4958)
			(end 3.81 -4.4958)
			(stroke
				(width 0)
				(type default)
			)
			(fill no)
			(layer "F.CrtYd")
		)
		(fp_rect
			(start -3.81 4.4958)
			(end 3.81 -4.4958)
			(stroke
				(width 0)
				(type default)
			)
			(fill no)
			(layer "F.Fab")
		)
		(pad "1" smd rect
			(at 0 -2.8194)
			(size 3.2512 2.7432)
			(layers "F.Cu" "F.Mask" "F.Paste")
			(net "VT235_VX")
		)
		(pad "2" smd rect
			(at 0 2.8194)
			(size 3.2512 2.7432)
			(layers "F.Cu" "F.Mask" "F.Paste")
			(net "P0V955_C")
		)
	)
	(footprint ""
		(layer "F.Cu")
		(at 274.193 -171.577 90)
		(property "Reference" "R238"
			(at 0 0 90)
			(layer "F.SilkS")
			(hide yes)
			(effects
				(font
					(size 1.27 1.27)
				)
			)
		)
		(property "Value" "0R2J-2-GP"
			(at 0.064008 -3.993896 90)
			(unlocked yes)
			(layer "F.Fab")
			(hide yes)
			(effects
				(font
					(size 1.016 1.016)
					(thickness 0.1524)
				)
			)
		)
		(property "Device Type" "R402H16"
			(at 0.064008 -5.517896 90)
			(unlocked yes)
			(layer "F.Fab")
			(hide yes)
			(effects
				(font
					(size 1.016 1.016)
					(thickness 0.1524)
				)
			)
		)
		(duplicate_pad_numbers_are_jumpers no)
		(fp_line
			(start 0.508 -0.9398)
			(end -0.508 -0.9398)
			(stroke
				(width 0.1524)
				(type default)
			)
			(layer "F.SilkS")
		)
		(fp_line
			(start -0.508 -0.9398)
			(end -0.508 0.9398)
			(stroke
				(width 0.1524)
				(type default)
			)
			(layer "F.SilkS")
		)
		(fp_rect
			(start -0.508 0.9398)
			(end 0.508 -0.9398)
			(stroke
				(width 0)
				(type default)
			)
			(fill no)
			(layer "F.CrtYd")
		)
		(fp_rect
			(start -0.508 0.9398)
			(end 0.508 -0.9398)
			(stroke
				(width 0)
				(type default)
			)
			(fill no)
			(layer "F.Fab")
		)
		(pad "1" smd custom
			(at 0 -0.4445 90)
			(size 0.1397 0.1397)
			(layers "F.Cu" "F.Mask" "F.Paste")
			(net "BMC_MBC_I2C_E_SCL")
			(options
				(clearance outline)
				(anchor circle)
			)
			(primitives
				(gr_poly
					(pts
						(arc
							(start -0.1778 -0.2794)
							(mid -0.249642 -0.249642)
							(end -0.2794 -0.1778)
						)
						(arc
							(start -0.2794 0.1778)
							(mid -0.249642 0.249642)
							(end -0.1778 0.2794)
						)
						(arc
							(start 0.1778 0.2794)
							(mid 0.249642 0.249642)
							(end 0.2794 0.1778)
						)
						(arc
							(start 0.2794 -0.1778)
							(mid 0.249642 -0.249642)
							(end 0.1778 -0.2794)
						)
					)
					(width 0)
					(fill yes)
				)
			)
		)
		(pad "2" smd custom
			(at 0 0.4445 90)
			(size 0.1397 0.1397)
			(layers "F.Cu" "F.Mask" "F.Paste")
			(net "BMC0_SMB1_CLK")
			(options
				(clearance outline)
				(anchor circle)
			)
			(primitives
				(gr_poly
					(pts
						(arc
							(start -0.1778 -0.2794)
							(mid -0.249642 -0.249642)
							(end -0.2794 -0.1778)
						)
						(arc
							(start -0.2794 0.1778)
							(mid -0.249642 0.249642)
							(end -0.1778 0.2794)
						)
						(arc
							(start 0.1778 0.2794)
							(mid 0.249642 0.249642)
							(end 0.2794 0.1778)
						)
						(arc
							(start 0.2794 -0.1778)
							(mid 0.249642 -0.249642)
							(end 0.1778 -0.2794)
						)
					)
					(width 0)
					(fill yes)
				)
			)
		)
	)
	(footprint ""
		(layer "F.Cu")
		(at 143.65097 -83.439 90)
		(property "Reference" "C327"
			(at 0 0 90)
			(layer "F.SilkS")
			(hide yes)
			(effects
				(font
					(size 1.27 1.27)
				)
			)
		)
		(property "Value" "SCD1U16V2KX-3GP"
			(at 1.1811 -2.7051 90)
			(unlocked yes)
			(layer "F.Fab")
			(hide yes)
			(effects
				(font
					(size 1.016 1.016)
					(thickness 0.1524)
				)
			)
		)
		(property "Device Type" "C402H22"
			(at 1.1811 -4.2291 90)
			(unlocked yes)
			(layer "F.Fab")
			(hide yes)
			(effects
				(font
					(size 1.016 1.016)
					(thickness 0.1524)
				)
			)
		)
		(duplicate_pad_numbers_are_jumpers no)
		(fp_rect
			(start -0.4318 0.9525)
			(end 0.4318 -0.9525)
			(stroke
				(width 0)
				(type default)
			)
			(fill no)
			(layer "F.CrtYd")
		)
		(fp_rect
			(start -0.4318 0.9525)
			(end 0.4318 -0.9525)
			(stroke
				(width 0)
				(type default)
			)
			(fill no)
			(layer "F.Fab")
		)
		(pad "1" smd custom
			(at 0 -0.4445 90)
			(size 0.1524 0.1524)
			(layers "F.Cu" "F.Mask" "F.Paste")
			(net "P3V3_STBY")
			(options
				(clearance outline)
				(anchor circle)
			)
			(primitives
				(gr_poly
					(pts
						(arc
							(start 0.3048 -0.2032)
							(mid 0.275042 -0.275042)
							(end 0.2032 -0.3048)
						)
						(arc
							(start -0.2032 -0.3048)
							(mid -0.275042 -0.275042)
							(end -0.3048 -0.2032)
						)
						(arc
							(start -0.3048 0.2032)
							(mid -0.275042 0.275042)
							(end -0.2032 0.3048)
						)
						(arc
							(start 0.2032 0.3048)
							(mid 0.275042 0.275042)
							(end 0.3048 0.2032)
						)
					)
					(width 0)
					(fill yes)
				)
			)
		)
		(pad "2" smd custom
			(at 0 0.4445 90)
			(size 0.1524 0.1524)
			(layers "F.Cu" "F.Mask" "F.Paste")
			(net "GND")
			(options
				(clearance outline)
				(anchor circle)
			)
			(primitives
				(gr_poly
					(pts
						(arc
							(start 0.3048 -0.2032)
							(mid 0.275042 -0.275042)
							(end 0.2032 -0.3048)
						)
						(arc
							(start -0.2032 -0.3048)
							(mid -0.275042 -0.275042)
							(end -0.3048 -0.2032)
						)
						(arc
							(start -0.3048 0.2032)
							(mid -0.275042 0.275042)
							(end -0.2032 0.3048)
						)
						(arc
							(start 0.2032 0.3048)
							(mid 0.275042 0.275042)
							(end 0.3048 0.2032)
						)
					)
					(width 0)
					(fill yes)
				)
			)
		)
	)
	(footprint ""
		(layer "F.Cu")
		(at 266.065 -172.974 90)
		(property "Reference" "R526"
			(at 0 0 90)
			(layer "F.SilkS")
			(hide yes)
			(effects
				(font
					(size 1.27 1.27)
				)
			)
		)
		(property "Value" "0R2J-2-GP"
			(at 0.064008 -3.993896 90)
			(unlocked yes)
			(layer "F.Fab")
			(hide yes)
			(effects
				(font
					(size 1.016 1.016)
					(thickness 0.1524)
				)
			)
		)
		(property "Device Type" "R402H16"
			(at 0.064008 -5.517896 90)
			(unlocked yes)
			(layer "F.Fab")
			(hide yes)
			(effects
				(font
					(size 1.016 1.016)
					(thickness 0.1524)
				)
			)
		)
		(duplicate_pad_numbers_are_jumpers no)
		(fp_line
			(start 0.508 -0.9398)
			(end -0.508 -0.9398)
			(stroke
				(width 0.1524)
				(type default)
			)
			(layer "F.SilkS")
		)
		(fp_line
			(start -0.508 -0.9398)
			(end -0.508 0.9398)
			(stroke
				(width 0.1524)
				(type default)
			)
			(layer "F.SilkS")
		)
		(fp_rect
			(start -0.508 0.9398)
			(end 0.508 -0.9398)
			(stroke
				(width 0)
				(type default)
			)
			(fill no)
			(layer "F.CrtYd")
		)
		(fp_rect
			(start -0.508 0.9398)
			(end 0.508 -0.9398)
			(stroke
				(width 0)
				(type default)
			)
			(fill no)
			(layer "F.Fab")
		)
		(pad "1" smd custom
			(at 0 -0.4445 90)
			(size 0.1397 0.1397)
			(layers "F.Cu" "F.Mask" "F.Paste")
			(net "NIC_SMBUS_ALERT_N")
			(options
				(clearance outline)
				(anchor circle)
			)
			(primitives
				(gr_poly
					(pts
						(arc
							(start -0.1778 -0.2794)
							(mid -0.249642 -0.249642)
							(end -0.2794 -0.1778)
						)
						(arc
							(start -0.2794 0.1778)
							(mid -0.249642 0.249642)
							(end -0.1778 0.2794)
						)
						(arc
							(start 0.1778 0.2794)
							(mid 0.249642 0.249642)
							(end 0.2794 0.1778)
						)
						(arc
							(start 0.2794 -0.1778)
							(mid 0.249642 -0.249642)
							(end 0.1778 -0.2794)
						)
					)
					(width 0)
					(fill yes)
				)
			)
		)
		(pad "2" smd custom
			(at 0 0.4445 90)
			(size 0.1397 0.1397)
			(layers "F.Cu" "F.Mask" "F.Paste")
			(net "BMC_SALT4")
			(options
				(clearance outline)
				(anchor circle)
			)
			(primitives
				(gr_poly
					(pts
						(arc
							(start -0.1778 -0.2794)
							(mid -0.249642 -0.249642)
							(end -0.2794 -0.1778)
						)
						(arc
							(start -0.2794 0.1778)
							(mid -0.249642 0.249642)
							(end -0.1778 0.2794)
						)
						(arc
							(start 0.1778 0.2794)
							(mid 0.249642 0.249642)
							(end 0.2794 0.1778)
						)
						(arc
							(start 0.2794 -0.1778)
							(mid 0.249642 -0.249642)
							(end 0.1778 -0.2794)
						)
					)
					(width 0)
					(fill yes)
				)
			)
		)
	)
	(footprint ""
		(layer "F.Cu")
		(at 43.8912 -114.7572 180)
		(property "Reference" "SR850"
			(at 0 0 180)
			(layer "F.SilkS")
			(hide yes)
			(effects
				(font
					(size 1.27 1.27)
				)
			)
		)
		(property "Value" "0R2J-2-GP"
			(at 0.064008 -3.993896 180)
			(unlocked yes)
			(layer "F.Fab")
			(hide yes)
			(effects
				(font
					(size 1.016 1.016)
					(thickness 0.1524)
				)
			)
		)
		(property "Device Type" "R402H16"
			(at 0.064008 -5.517896 180)
			(unlocked yes)
			(layer "F.Fab")
			(hide yes)
			(effects
				(font
					(size 1.016 1.016)
					(thickness 0.1524)
				)
			)
		)
		(duplicate_pad_numbers_are_jumpers no)
		(fp_line
			(start 0.508 -0.9398)
			(end -0.508 -0.9398)
			(stroke
				(width 0.1524)
				(type default)
			)
			(layer "F.SilkS")
		)
		(fp_line
			(start -0.508 -0.9398)
			(end -0.508 0.9398)
			(stroke
				(width 0.1524)
				(type default)
			)
			(layer "F.SilkS")
		)
		(fp_rect
			(start -0.508 0.9398)
			(end 0.508 -0.9398)
			(stroke
				(width 0)
				(type default)
			)
			(fill no)
			(layer "F.CrtYd")
		)
		(fp_rect
			(start -0.508 0.9398)
			(end 0.508 -0.9398)
			(stroke
				(width 0)
				(type default)
			)
			(fill no)
			(layer "F.Fab")
		)
		(pad "1" smd custom
			(at 0 -0.4445 180)
			(size 0.1397 0.1397)
			(layers "F.Cu" "F.Mask" "F.Paste")
			(net "SAS_SDBRX_R")
			(options
				(clearance outline)
				(anchor circle)
			)
			(primitives
				(gr_poly
					(pts
						(arc
							(start -0.1778 -0.2794)
							(mid -0.249642 -0.249642)
							(end -0.2794 -0.1778)
						)
						(arc
							(start -0.2794 0.1778)
							(mid -0.249642 0.249642)
							(end -0.1778 0.2794)
						)
						(arc
							(start 0.1778 0.2794)
							(mid 0.249642 0.249642)
							(end 0.2794 0.1778)
						)
						(arc
							(start 0.2794 -0.1778)
							(mid 0.249642 -0.249642)
							(end 0.1778 -0.2794)
						)
					)
					(width 0)
					(fill yes)
				)
			)
		)
		(pad "2" smd custom
			(at 0 0.4445 180)
			(size 0.1397 0.1397)
			(layers "F.Cu" "F.Mask" "F.Paste")
			(net "SAS_SDBRX")
			(options
				(clearance outline)
				(anchor circle)
			)
			(primitives
				(gr_poly
					(pts
						(arc
							(start -0.1778 -0.2794)
							(mid -0.249642 -0.249642)
							(end -0.2794 -0.1778)
						)
						(arc
							(start -0.2794 0.1778)
							(mid -0.249642 0.249642)
							(end -0.1778 0.2794)
						)
						(arc
							(start 0.1778 0.2794)
							(mid 0.249642 0.249642)
							(end 0.2794 0.1778)
						)
						(arc
							(start 0.2794 -0.1778)
							(mid 0.249642 -0.249642)
							(end 0.1778 -0.2794)
						)
					)
					(width 0)
					(fill yes)
				)
			)
		)
	)
	(footprint ""
		(layer "F.Cu")
		(at 266.065 -212.598 180)
		(property "Reference" "PR85"
			(at 0 0 180)
			(layer "F.SilkS")
			(hide yes)
			(effects
				(font
					(size 1.27 1.27)
				)
			)
		)
		(property "Value" "0R6J-3-GP"
			(at -0.0508 -4.8514 180)
			(unlocked yes)
			(layer "F.Fab")
			(hide yes)
			(effects
				(font
					(size 1.016 1.016)
					(thickness 0.1524)
				)
			)
		)
		(property "Device Type" "R1206H28"
			(at 0 -6.3754 180)
			(unlocked yes)
			(layer "F.Fab")
			(hide yes)
			(effects
				(font
					(size 1.016 1.016)
					(thickness 0.1524)
				)
			)
		)
		(duplicate_pad_numbers_are_jumpers no)
		(fp_line
			(start 1.016 2.2352)
			(end -1.016 2.2352)
			(stroke
				(width 0.1524)
				(type default)
			)
			(layer "F.SilkS")
		)
		(fp_line
			(start 1.016 -2.2352)
			(end 1.016 2.2352)
			(stroke
				(width 0.1524)
				(type default)
			)
			(layer "F.SilkS")
		)
		(fp_line
			(start -1.016 2.2352)
			(end -1.016 -2.2352)
			(stroke
				(width 0.1524)
				(type default)
			)
			(layer "F.SilkS")
		)
		(fp_line
			(start -1.016 -2.2352)
			(end 1.016 -2.2352)
			(stroke
				(width 0.1524)
				(type default)
			)
			(layer "F.SilkS")
		)
		(fp_rect
			(start -1.0922 2.3114)
			(end 1.0922 -2.3114)
			(stroke
				(width 0)
				(type default)
			)
			(fill no)
			(layer "F.CrtYd")
		)
		(fp_poly
			(pts
				(xy -1.0922 -2.3114) (xy 1.0922 -2.3114) (xy 1.0922 2.3114) (xy -1.0922 2.3114)
			)
			(stroke
				(width 0)
				(type default)
			)
			(fill no)
			(layer "F.Fab")
		)
		(pad "1" smd rect
			(at 0 -1.397 180)
			(size 1.651 1.27)
			(layers "F.Cu" "F.Mask" "F.Paste")
			(net "P1V26_STBY")
		)
		(pad "2" smd rect
			(at 0 1.397 180)
			(size 1.651 1.27)
			(layers "F.Cu" "F.Mask" "F.Paste")
			(net "TPS74801_1V26_STBY_OUT")
		)
	)
	(footprint ""
		(layer "F.Cu")
		(at 281.423872 -64.461136)
		(property "Reference" "R527"
			(at 0 0 0)
			(layer "F.SilkS")
			(hide yes)
			(effects
				(font
					(size 1.27 1.27)
				)
			)
		)
		(property "Value" "1K33R3F-GP"
			(at -0.0254 -2.5146 0)
			(unlocked yes)
			(layer "F.Fab")
			(hide yes)
			(effects
				(font
					(size 1.016 1.016)
					(thickness 0.1524)
				)
			)
		)
		(property "Device Type" "R603H22"
			(at -0.0254 -4.0386 0)
			(unlocked yes)
			(layer "F.Fab")
			(hide yes)
			(effects
				(font
					(size 1.016 1.016)
					(thickness 0.1524)
				)
			)
		)
		(duplicate_pad_numbers_are_jumpers no)
		(fp_line
			(start -0.4826 0)
			(end -0.2032 0)
			(stroke
				(width 0.2032)
				(type default)
			)
			(layer "F.SilkS")
		)
		(fp_line
			(start 0.2032 0)
			(end 0.4826 0)
			(stroke
				(width 0.2032)
				(type default)
			)
			(layer "F.SilkS")
		)
		(fp_rect
			(start -0.5842 1.3335)
			(end 0.5842 -1.3335)
			(stroke
				(width 0)
				(type default)
			)
			(fill no)
			(layer "F.CrtYd")
		)
		(fp_rect
			(start -0.5842 1.3335)
			(end 0.5842 -1.3335)
			(stroke
				(width 0)
				(type default)
			)
			(fill no)
			(layer "F.Fab")
		)
		(pad "1" smd custom
			(at 0 -0.762)
			(size 0.2159 0.2159)
			(layers "F.Cu" "F.Mask" "F.Paste")
			(net "PRSNT_EN_HPIC")
			(options
				(clearance outline)
				(anchor circle)
			)
			(primitives
				(gr_poly
					(pts
						(arc
							(start -0.3302 -0.4318)
							(mid -0.402042 -0.402042)
							(end -0.4318 -0.3302)
						)
						(arc
							(start -0.4318 0.3302)
							(mid -0.402042 0.402042)
							(end -0.3302 0.4318)
						)
						(arc
							(start 0.3302 0.4318)
							(mid 0.402042 0.402042)
							(end 0.4318 0.3302)
						)
						(arc
							(start 0.4318 -0.3302)
							(mid 0.402042 -0.402042)
							(end 0.3302 -0.4318)
						)
					)
					(width 0)
					(fill yes)
				)
			)
		)
		(pad "2" smd custom
			(at 0 0.762)
			(size 0.2159 0.2159)
			(layers "F.Cu" "F.Mask" "F.Paste")
			(net "GND")
			(options
				(clearance outline)
				(anchor circle)
			)
			(primitives
				(gr_poly
					(pts
						(arc
							(start -0.3302 -0.4318)
							(mid -0.402042 -0.402042)
							(end -0.4318 -0.3302)
						)
						(arc
							(start -0.4318 0.3302)
							(mid -0.402042 0.402042)
							(end -0.3302 0.4318)
						)
						(arc
							(start 0.3302 0.4318)
							(mid 0.402042 0.402042)
							(end 0.4318 0.3302)
						)
						(arc
							(start 0.4318 -0.3302)
							(mid 0.402042 -0.402042)
							(end 0.3302 -0.4318)
						)
					)
					(width 0)
					(fill yes)
				)
			)
		)
	)
	(footprint ""
		(layer "F.Cu")
		(at 302.514 -102.108)
		(property "Reference" "R161"
			(at 0 0 0)
			(layer "F.SilkS")
			(hide yes)
			(effects
				(font
					(size 1.27 1.27)
				)
			)
		)
		(property "Value" "4K7R2F-GP"
			(at 0.064008 -3.993896 0)
			(unlocked yes)
			(layer "F.Fab")
			(hide yes)
			(effects
				(font
					(size 1.016 1.016)
					(thickness 0.1524)
				)
			)
		)
		(property "Device Type" "R402H16"
			(at 0.064008 -5.517896 0)
			(unlocked yes)
			(layer "F.Fab")
			(hide yes)
			(effects
				(font
					(size 1.016 1.016)
					(thickness 0.1524)
				)
			)
		)
		(duplicate_pad_numbers_are_jumpers no)
		(fp_line
			(start -0.508 -0.9398)
			(end -0.508 0.9398)
			(stroke
				(width 0.1524)
				(type default)
			)
			(layer "F.SilkS")
		)
		(fp_line
			(start 0.508 -0.9398)
			(end -0.508 -0.9398)
			(stroke
				(width 0.1524)
				(type default)
			)
			(layer "F.SilkS")
		)
		(fp_rect
			(start -0.508 0.9398)
			(end 0.508 -0.9398)
			(stroke
				(width 0)
				(type default)
			)
			(fill no)
			(layer "F.CrtYd")
		)
		(fp_rect
			(start -0.508 0.9398)
			(end 0.508 -0.9398)
			(stroke
				(width 0)
				(type default)
			)
			(fill no)
			(layer "F.Fab")
		)
		(pad "1" smd custom
			(at 0 -0.4445)
			(size 0.1397 0.1397)
			(layers "F.Cu" "F.Mask" "F.Paste")
			(net "P3V3_STBY")
			(options
				(clearance outline)
				(anchor circle)
			)
			(primitives
				(gr_poly
					(pts
						(arc
							(start -0.1778 -0.2794)
							(mid -0.249642 -0.249642)
							(end -0.2794 -0.1778)
						)
						(arc
							(start -0.2794 0.1778)
							(mid -0.249642 0.249642)
							(end -0.1778 0.2794)
						)
						(arc
							(start 0.1778 0.2794)
							(mid 0.249642 0.249642)
							(end 0.2794 0.1778)
						)
						(arc
							(start 0.2794 -0.1778)
							(mid 0.249642 -0.249642)
							(end 0.1778 -0.2794)
						)
					)
					(width 0)
					(fill yes)
				)
			)
		)
		(pad "2" smd custom
			(at 0 0.4445)
			(size 0.1397 0.1397)
			(layers "F.Cu" "F.Mask" "F.Paste")
			(net "TEMP_2_A1")
			(options
				(clearance outline)
				(anchor circle)
			)
			(primitives
				(gr_poly
					(pts
						(arc
							(start -0.1778 -0.2794)
							(mid -0.249642 -0.249642)
							(end -0.2794 -0.1778)
						)
						(arc
							(start -0.2794 0.1778)
							(mid -0.249642 0.249642)
							(end -0.1778 0.2794)
						)
						(arc
							(start 0.1778 0.2794)
							(mid 0.249642 0.249642)
							(end 0.2794 0.1778)
						)
						(arc
							(start 0.2794 -0.1778)
							(mid 0.249642 -0.249642)
							(end 0.1778 -0.2794)
						)
					)
					(width 0)
					(fill yes)
				)
			)
		)
	)
	(footprint ""
		(layer "F.Cu")
		(at 253.492 -122.555)
		(property "Reference" "R7905"
			(at 0 0 0)
			(layer "F.SilkS")
			(hide yes)
			(effects
				(font
					(size 1.27 1.27)
				)
			)
		)
		(property "Value" "0R2J-2-GP"
			(at 0.064008 -3.993896 0)
			(unlocked yes)
			(layer "F.Fab")
			(hide yes)
			(effects
				(font
					(size 1.016 1.016)
					(thickness 0.1524)
				)
			)
		)
		(property "Device Type" "R402H16"
			(at 0.064008 -5.517896 0)
			(unlocked yes)
			(layer "F.Fab")
			(hide yes)
			(effects
				(font
					(size 1.016 1.016)
					(thickness 0.1524)
				)
			)
		)
		(duplicate_pad_numbers_are_jumpers no)
		(fp_line
			(start -0.508 -0.9398)
			(end -0.508 0.9398)
			(stroke
				(width 0.1524)
				(type default)
			)
			(layer "F.SilkS")
		)
		(fp_line
			(start 0.508 -0.9398)
			(end -0.508 -0.9398)
			(stroke
				(width 0.1524)
				(type default)
			)
			(layer "F.SilkS")
		)
		(fp_rect
			(start -0.508 0.9398)
			(end 0.508 -0.9398)
			(stroke
				(width 0)
				(type default)
			)
			(fill no)
			(layer "F.CrtYd")
		)
		(fp_rect
			(start -0.508 0.9398)
			(end 0.508 -0.9398)
			(stroke
				(width 0)
				(type default)
			)
			(fill no)
			(layer "F.Fab")
		)
		(pad "1" smd custom
			(at 0 -0.4445)
			(size 0.1397 0.1397)
			(layers "F.Cu" "F.Mask" "F.Paste")
			(net "CPU_U193_PIN3_RX")
			(options
				(clearance outline)
				(anchor circle)
			)
			(primitives
				(gr_poly
					(pts
						(arc
							(start -0.1778 -0.2794)
							(mid -0.249642 -0.249642)
							(end -0.2794 -0.1778)
						)
						(arc
							(start -0.2794 0.1778)
							(mid -0.249642 0.249642)
							(end -0.1778 0.2794)
						)
						(arc
							(start 0.1778 0.2794)
							(mid 0.249642 0.249642)
							(end 0.2794 0.1778)
						)
						(arc
							(start 0.2794 -0.1778)
							(mid 0.249642 -0.249642)
							(end 0.1778 -0.2794)
						)
					)
					(width 0)
					(fill yes)
				)
			)
		)
		(pad "2" smd custom
			(at 0 0.4445)
			(size 0.1397 0.1397)
			(layers "F.Cu" "F.Mask" "F.Paste")
			(net "CPU_U193_PIN3_RX_R")
			(options
				(clearance outline)
				(anchor circle)
			)
			(primitives
				(gr_poly
					(pts
						(arc
							(start -0.1778 -0.2794)
							(mid -0.249642 -0.249642)
							(end -0.2794 -0.1778)
						)
						(arc
							(start -0.2794 0.1778)
							(mid -0.249642 0.249642)
							(end -0.1778 0.2794)
						)
						(arc
							(start 0.1778 0.2794)
							(mid 0.249642 0.249642)
							(end 0.2794 0.1778)
						)
						(arc
							(start 0.2794 -0.1778)
							(mid 0.249642 -0.249642)
							(end 0.1778 -0.2794)
						)
					)
					(width 0)
					(fill yes)
				)
			)
		)
	)
	(footprint ""
		(layer "F.Cu")
		(at 208.407 -94.996 -90)
		(property "Reference" "PC145"
			(at 0 0 270)
			(layer "F.SilkS")
			(hide yes)
			(effects
				(font
					(size 1.27 1.27)
				)
			)
		)
		(property "Value" "SC10U6D3V5KX-1GP"
			(at -0.0762 -6.1214 270)
			(unlocked yes)
			(layer "F.Fab")
			(hide yes)
			(effects
				(font
					(size 1.016 1.016)
					(thickness 0.1524)
				)
			)
		)
		(property "Device Type" "C805H54"
			(at -0.0762 -8.1534 270)
			(unlocked yes)
			(layer "F.Fab")
			(hide yes)
			(effects
				(font
					(size 1.016 1.016)
					(thickness 0.1524)
				)
			)
		)
		(duplicate_pad_numbers_are_jumpers no)
		(fp_line
			(start 0.635 0)
			(end -0.635 0)
			(stroke
				(width 0.508)
				(type default)
			)
			(layer "F.SilkS")
		)
		(fp_rect
			(start -0.9652 1.778)
			(end 0.9652 -1.778)
			(stroke
				(width 0)
				(type default)
			)
			(fill no)
			(layer "F.CrtYd")
		)
		(fp_poly
			(pts
				(xy -0.9652 -1.778) (xy 0.9652 -1.778) (xy 0.9652 1.778) (xy -0.9652 1.778)
			)
			(stroke
				(width 0)
				(type default)
			)
			(fill no)
			(layer "F.Fab")
		)
		(pad "1" smd rect
			(at 0 -0.9652 270)
			(size 1.397 1.143)
			(layers "F.Cu" "F.Mask" "F.Paste")
			(net "P1V5_C")
		)
		(pad "2" smd rect
			(at 0 0.9652 270)
			(size 1.397 1.143)
			(layers "F.Cu" "F.Mask" "F.Paste")
			(net "GND")
		)
	)
	(footprint ""
		(layer "F.Cu")
		(at 60.706 -108.458 90)
		(property "Reference" "SR826"
			(at 0 0 90)
			(layer "F.SilkS")
			(hide yes)
			(effects
				(font
					(size 1.27 1.27)
				)
			)
		)
		(property "Value" "4K75R2F-1-GP"
			(at 0.064008 -3.993896 90)
			(unlocked yes)
			(layer "F.Fab")
			(hide yes)
			(effects
				(font
					(size 1.016 1.016)
					(thickness 0.1524)
				)
			)
		)
		(property "Device Type" "R402H16"
			(at 0.064008 -5.517896 90)
			(unlocked yes)
			(layer "F.Fab")
			(hide yes)
			(effects
				(font
					(size 1.016 1.016)
					(thickness 0.1524)
				)
			)
		)
		(duplicate_pad_numbers_are_jumpers no)
		(fp_line
			(start 0.508 -0.9398)
			(end -0.508 -0.9398)
			(stroke
				(width 0.1524)
				(type default)
			)
			(layer "F.SilkS")
		)
		(fp_line
			(start -0.508 -0.9398)
			(end -0.508 0.9398)
			(stroke
				(width 0.1524)
				(type default)
			)
			(layer "F.SilkS")
		)
		(fp_rect
			(start -0.508 0.9398)
			(end 0.508 -0.9398)
			(stroke
				(width 0)
				(type default)
			)
			(fill no)
			(layer "F.CrtYd")
		)
		(fp_rect
			(start -0.508 0.9398)
			(end 0.508 -0.9398)
			(stroke
				(width 0)
				(type default)
			)
			(fill no)
			(layer "F.Fab")
		)
		(pad "1" smd custom
			(at 0 -0.4445 90)
			(size 0.1397 0.1397)
			(layers "F.Cu" "F.Mask" "F.Paste")
			(net "P1V8_E")
			(options
				(clearance outline)
				(anchor circle)
			)
			(primitives
				(gr_poly
					(pts
						(arc
							(start -0.1778 -0.2794)
							(mid -0.249642 -0.249642)
							(end -0.2794 -0.1778)
						)
						(arc
							(start -0.2794 0.1778)
							(mid -0.249642 0.249642)
							(end -0.1778 0.2794)
						)
						(arc
							(start 0.1778 0.2794)
							(mid 0.249642 0.249642)
							(end 0.2794 0.1778)
						)
						(arc
							(start 0.2794 -0.1778)
							(mid 0.249642 -0.249642)
							(end 0.1778 -0.2794)
						)
					)
					(width 0)
					(fill yes)
				)
			)
		)
		(pad "2" smd custom
			(at 0 0.4445 90)
			(size 0.1397 0.1397)
			(layers "F.Cu" "F.Mask" "F.Paste")
			(net "EXP_FW_DET_BOARD_VER_0")
			(options
				(clearance outline)
				(anchor circle)
			)
			(primitives
				(gr_poly
					(pts
						(arc
							(start -0.1778 -0.2794)
							(mid -0.249642 -0.249642)
							(end -0.2794 -0.1778)
						)
						(arc
							(start -0.2794 0.1778)
							(mid -0.249642 0.249642)
							(end -0.1778 0.2794)
						)
						(arc
							(start 0.1778 0.2794)
							(mid 0.249642 0.249642)
							(end 0.2794 0.1778)
						)
						(arc
							(start 0.2794 -0.1778)
							(mid 0.249642 -0.249642)
							(end 0.1778 -0.2794)
						)
					)
					(width 0)
					(fill yes)
				)
			)
		)
	)
	(footprint ""
		(layer "F.Cu")
		(at 95.89897 -79.375 -90)
		(property "Reference" "SR815"
			(at 0 0 270)
			(layer "F.SilkS")
			(hide yes)
			(effects
				(font
					(size 1.27 1.27)
				)
			)
		)
		(property "Value" "1KR2F-3-GP"
			(at 0.064008 -3.993896 270)
			(unlocked yes)
			(layer "F.Fab")
			(hide yes)
			(effects
				(font
					(size 1.016 1.016)
					(thickness 0.1524)
				)
			)
		)
		(property "Device Type" "R402H16"
			(at 0.064008 -5.517896 270)
			(unlocked yes)
			(layer "F.Fab")
			(hide yes)
			(effects
				(font
					(size 1.016 1.016)
					(thickness 0.1524)
				)
			)
		)
		(duplicate_pad_numbers_are_jumpers no)
		(fp_line
			(start -0.508 -0.9398)
			(end -0.508 0.9398)
			(stroke
				(width 0.1524)
				(type default)
			)
			(layer "F.SilkS")
		)
		(fp_line
			(start 0.508 -0.9398)
			(end -0.508 -0.9398)
			(stroke
				(width 0.1524)
				(type default)
			)
			(layer "F.SilkS")
		)
		(fp_rect
			(start -0.508 0.9398)
			(end 0.508 -0.9398)
			(stroke
				(width 0)
				(type default)
			)
			(fill no)
			(layer "F.CrtYd")
		)
		(fp_rect
			(start -0.508 0.9398)
			(end 0.508 -0.9398)
			(stroke
				(width 0)
				(type default)
			)
			(fill no)
			(layer "F.Fab")
		)
		(pad "1" smd custom
			(at 0 -0.4445 270)
			(size 0.1397 0.1397)
			(layers "F.Cu" "F.Mask" "F.Paste")
			(net "TMUX_EN")
			(options
				(clearance outline)
				(anchor circle)
			)
			(primitives
				(gr_poly
					(pts
						(arc
							(start -0.1778 -0.2794)
							(mid -0.249642 -0.249642)
							(end -0.2794 -0.1778)
						)
						(arc
							(start -0.2794 0.1778)
							(mid -0.249642 0.249642)
							(end -0.1778 0.2794)
						)
						(arc
							(start 0.1778 0.2794)
							(mid 0.249642 0.249642)
							(end 0.2794 0.1778)
						)
						(arc
							(start 0.2794 -0.1778)
							(mid 0.249642 -0.249642)
							(end 0.1778 -0.2794)
						)
					)
					(width 0)
					(fill yes)
				)
			)
		)
		(pad "2" smd custom
			(at 0 0.4445 270)
			(size 0.1397 0.1397)
			(layers "F.Cu" "F.Mask" "F.Paste")
			(net "P1V8_E")
			(options
				(clearance outline)
				(anchor circle)
			)
			(primitives
				(gr_poly
					(pts
						(arc
							(start -0.1778 -0.2794)
							(mid -0.249642 -0.249642)
							(end -0.2794 -0.1778)
						)
						(arc
							(start -0.2794 0.1778)
							(mid -0.249642 0.249642)
							(end -0.1778 0.2794)
						)
						(arc
							(start 0.1778 0.2794)
							(mid 0.249642 0.249642)
							(end 0.2794 0.1778)
						)
						(arc
							(start 0.2794 -0.1778)
							(mid 0.249642 -0.249642)
							(end 0.1778 -0.2794)
						)
					)
					(width 0)
					(fill yes)
				)
			)
		)
	)
	(footprint ""
		(layer "F.Cu")
		(at 99.568 -10.795 180)
		(property "Reference" "SR715"
			(at 0 0 180)
			(layer "F.SilkS")
			(hide yes)
			(effects
				(font
					(size 1.27 1.27)
				)
			)
		)
		(property "Value" "D51R3F-2-GP"
			(at -0.0254 -2.5146 180)
			(unlocked yes)
			(layer "F.Fab")
			(hide yes)
			(effects
				(font
					(size 1.016 1.016)
					(thickness 0.1524)
				)
			)
		)
		(property "Device Type" "R603H22"
			(at -0.0254 -4.0386 180)
			(unlocked yes)
			(layer "F.Fab")
			(hide yes)
			(effects
				(font
					(size 1.016 1.016)
					(thickness 0.1524)
				)
			)
		)
		(duplicate_pad_numbers_are_jumpers no)
		(fp_line
			(start 0.2032 0)
			(end 0.4826 0)
			(stroke
				(width 0.2032)
				(type default)
			)
			(layer "F.SilkS")
		)
		(fp_line
			(start -0.4826 0)
			(end -0.2032 0)
			(stroke
				(width 0.2032)
				(type default)
			)
			(layer "F.SilkS")
		)
		(fp_rect
			(start -0.5842 1.3335)
			(end 0.5842 -1.3335)
			(stroke
				(width 0)
				(type default)
			)
			(fill no)
			(layer "F.CrtYd")
		)
		(fp_rect
			(start -0.5842 1.3335)
			(end 0.5842 -1.3335)
			(stroke
				(width 0)
				(type default)
			)
			(fill no)
			(layer "F.Fab")
		)
		(pad "1" smd custom
			(at 0 -0.762 180)
			(size 0.2159 0.2159)
			(layers "F.Cu" "F.Mask" "F.Paste")
			(net "P0V955_C")
			(options
				(clearance outline)
				(anchor circle)
			)
			(primitives
				(gr_poly
					(pts
						(arc
							(start -0.3302 -0.4318)
							(mid -0.402042 -0.402042)
							(end -0.4318 -0.3302)
						)
						(arc
							(start -0.4318 0.3302)
							(mid -0.402042 0.402042)
							(end -0.3302 0.4318)
						)
						(arc
							(start 0.3302 0.4318)
							(mid 0.402042 0.402042)
							(end 0.4318 0.3302)
						)
						(arc
							(start 0.4318 -0.3302)
							(mid 0.402042 -0.402042)
							(end 0.3302 -0.4318)
						)
					)
					(width 0)
					(fill yes)
				)
			)
		)
		(pad "2" smd custom
			(at 0 0.762 180)
			(size 0.2159 0.2159)
			(layers "F.Cu" "F.Mask" "F.Paste")
			(net "PCE_AVDD")
			(options
				(clearance outline)
				(anchor circle)
			)
			(primitives
				(gr_poly
					(pts
						(arc
							(start -0.3302 -0.4318)
							(mid -0.402042 -0.402042)
							(end -0.4318 -0.3302)
						)
						(arc
							(start -0.4318 0.3302)
							(mid -0.402042 0.402042)
							(end -0.3302 0.4318)
						)
						(arc
							(start 0.3302 0.4318)
							(mid 0.402042 0.402042)
							(end 0.4318 0.3302)
						)
						(arc
							(start 0.4318 -0.3302)
							(mid 0.402042 -0.402042)
							(end 0.3302 -0.4318)
						)
					)
					(width 0)
					(fill yes)
				)
			)
		)
	)
	(footprint ""
		(layer "F.Cu")
		(at 35.383216 -205.28788 90)
		(property "Reference" "R5310"
			(at 0 0 90)
			(layer "F.SilkS")
			(hide yes)
			(effects
				(font
					(size 1.27 1.27)
				)
			)
		)
		(property "Value" "0R2J-2-GP"
			(at 0.064008 -3.993896 90)
			(unlocked yes)
			(layer "F.Fab")
			(hide yes)
			(effects
				(font
					(size 1.016 1.016)
					(thickness 0.1524)
				)
			)
		)
		(property "Device Type" "R402H16"
			(at 0.064008 -5.517896 90)
			(unlocked yes)
			(layer "F.Fab")
			(hide yes)
			(effects
				(font
					(size 1.016 1.016)
					(thickness 0.1524)
				)
			)
		)
		(duplicate_pad_numbers_are_jumpers no)
		(fp_line
			(start 0.508 -0.9398)
			(end -0.508 -0.9398)
			(stroke
				(width 0.1524)
				(type default)
			)
			(layer "F.SilkS")
		)
		(fp_line
			(start -0.508 -0.9398)
			(end -0.508 0.9398)
			(stroke
				(width 0.1524)
				(type default)
			)
			(layer "F.SilkS")
		)
		(fp_rect
			(start -0.508 0.9398)
			(end 0.508 -0.9398)
			(stroke
				(width 0)
				(type default)
			)
			(fill no)
			(layer "F.CrtYd")
		)
		(fp_rect
			(start -0.508 0.9398)
			(end 0.508 -0.9398)
			(stroke
				(width 0)
				(type default)
			)
			(fill no)
			(layer "F.Fab")
		)
		(pad "1" smd custom
			(at 0 -0.4445 90)
			(size 0.1397 0.1397)
			(layers "F.Cu" "F.Mask" "F.Paste")
			(net "VOL_SEN_SCL_U17")
			(options
				(clearance outline)
				(anchor circle)
			)
			(primitives
				(gr_poly
					(pts
						(arc
							(start -0.1778 -0.2794)
							(mid -0.249642 -0.249642)
							(end -0.2794 -0.1778)
						)
						(arc
							(start -0.2794 0.1778)
							(mid -0.249642 0.249642)
							(end -0.1778 0.2794)
						)
						(arc
							(start 0.1778 0.2794)
							(mid 0.249642 0.249642)
							(end 0.2794 0.1778)
						)
						(arc
							(start 0.2794 -0.1778)
							(mid 0.249642 -0.249642)
							(end 0.1778 -0.2794)
						)
					)
					(width 0)
					(fill yes)
				)
			)
		)
		(pad "2" smd custom
			(at 0 0.4445 90)
			(size 0.1397 0.1397)
			(layers "F.Cu" "F.Mask" "F.Paste")
			(net "BMC_I2C_SCL_10")
			(options
				(clearance outline)
				(anchor circle)
			)
			(primitives
				(gr_poly
					(pts
						(arc
							(start -0.1778 -0.2794)
							(mid -0.249642 -0.249642)
							(end -0.2794 -0.1778)
						)
						(arc
							(start -0.2794 0.1778)
							(mid -0.249642 0.249642)
							(end -0.1778 0.2794)
						)
						(arc
							(start 0.1778 0.2794)
							(mid 0.249642 0.249642)
							(end 0.2794 0.1778)
						)
						(arc
							(start 0.2794 -0.1778)
							(mid 0.249642 -0.249642)
							(end 0.1778 -0.2794)
						)
					)
					(width 0)
					(fill yes)
				)
			)
		)
	)
	(footprint ""
		(layer "F.Cu")
		(at 315.468 -118.618)
		(property "Reference" "PR31"
			(at 0 0 0)
			(layer "F.SilkS")
			(hide yes)
			(effects
				(font
					(size 1.27 1.27)
				)
			)
		)
		(property "Value" "73K2R2F-GP"
			(at 0.064008 -3.993896 0)
			(unlocked yes)
			(layer "F.Fab")
			(hide yes)
			(effects
				(font
					(size 1.016 1.016)
					(thickness 0.1524)
				)
			)
		)
		(property "Device Type" "R402H16"
			(at 0.064008 -5.517896 0)
			(unlocked yes)
			(layer "F.Fab")
			(hide yes)
			(effects
				(font
					(size 1.016 1.016)
					(thickness 0.1524)
				)
			)
		)
		(duplicate_pad_numbers_are_jumpers no)
		(fp_line
			(start -0.508 -0.9398)
			(end -0.508 0.9398)
			(stroke
				(width 0.1524)
				(type default)
			)
			(layer "F.SilkS")
		)
		(fp_line
			(start 0.508 -0.9398)
			(end -0.508 -0.9398)
			(stroke
				(width 0.1524)
				(type default)
			)
			(layer "F.SilkS")
		)
		(fp_rect
			(start -0.508 0.9398)
			(end 0.508 -0.9398)
			(stroke
				(width 0)
				(type default)
			)
			(fill no)
			(layer "F.CrtYd")
		)
		(fp_rect
			(start -0.508 0.9398)
			(end 0.508 -0.9398)
			(stroke
				(width 0)
				(type default)
			)
			(fill no)
			(layer "F.Fab")
		)
		(pad "1" smd custom
			(at 0 -0.4445)
			(size 0.1397 0.1397)
			(layers "F.Cu" "F.Mask" "F.Paste")
			(net "AGND_P3V3_STBY")
			(options
				(clearance outline)
				(anchor circle)
			)
			(primitives
				(gr_poly
					(pts
						(arc
							(start -0.1778 -0.2794)
							(mid -0.249642 -0.249642)
							(end -0.2794 -0.1778)
						)
						(arc
							(start -0.2794 0.1778)
							(mid -0.249642 0.249642)
							(end -0.1778 0.2794)
						)
						(arc
							(start 0.1778 0.2794)
							(mid 0.249642 0.249642)
							(end 0.2794 0.1778)
						)
						(arc
							(start 0.2794 -0.1778)
							(mid 0.249642 -0.249642)
							(end 0.1778 -0.2794)
						)
					)
					(width 0)
					(fill yes)
				)
			)
		)
		(pad "2" smd custom
			(at 0 0.4445)
			(size 0.1397 0.1397)
			(layers "F.Cu" "F.Mask" "F.Paste")
			(net "P3V3_STBY_TRIP")
			(options
				(clearance outline)
				(anchor circle)
			)
			(primitives
				(gr_poly
					(pts
						(arc
							(start -0.1778 -0.2794)
							(mid -0.249642 -0.249642)
							(end -0.2794 -0.1778)
						)
						(arc
							(start -0.2794 0.1778)
							(mid -0.249642 0.249642)
							(end -0.1778 0.2794)
						)
						(arc
							(start 0.1778 0.2794)
							(mid 0.249642 0.249642)
							(end 0.2794 0.1778)
						)
						(arc
							(start 0.2794 -0.1778)
							(mid 0.249642 -0.249642)
							(end 0.1778 -0.2794)
						)
					)
					(width 0)
					(fill yes)
				)
			)
		)
	)
	(footprint ""
		(layer "F.Cu")
		(at 86.614 -27.18816 180)
		(property "Reference" "SR581"
			(at 0 0 180)
			(layer "F.SilkS")
			(hide yes)
			(effects
				(font
					(size 1.27 1.27)
				)
			)
		)
		(property "Value" "0R2J-2-GP"
			(at 0.064008 -3.993896 180)
			(unlocked yes)
			(layer "F.Fab")
			(hide yes)
			(effects
				(font
					(size 1.016 1.016)
					(thickness 0.1524)
				)
			)
		)
		(property "Device Type" "R402H16"
			(at 0.064008 -5.517896 180)
			(unlocked yes)
			(layer "F.Fab")
			(hide yes)
			(effects
				(font
					(size 1.016 1.016)
					(thickness 0.1524)
				)
			)
		)
		(duplicate_pad_numbers_are_jumpers no)
		(fp_line
			(start 0.508 -0.9398)
			(end -0.508 -0.9398)
			(stroke
				(width 0.1524)
				(type default)
			)
			(layer "F.SilkS")
		)
		(fp_line
			(start -0.508 -0.9398)
			(end -0.508 0.9398)
			(stroke
				(width 0.1524)
				(type default)
			)
			(layer "F.SilkS")
		)
		(fp_rect
			(start -0.508 0.9398)
			(end 0.508 -0.9398)
			(stroke
				(width 0)
				(type default)
			)
			(fill no)
			(layer "F.CrtYd")
		)
		(fp_rect
			(start -0.508 0.9398)
			(end 0.508 -0.9398)
			(stroke
				(width 0)
				(type default)
			)
			(fill no)
			(layer "F.Fab")
		)
		(pad "1" smd custom
			(at 0 -0.4445 180)
			(size 0.1397 0.1397)
			(layers "F.Cu" "F.Mask" "F.Paste")
			(net "CLK_100M_PCIE_SAS_C_P")
			(options
				(clearance outline)
				(anchor circle)
			)
			(primitives
				(gr_poly
					(pts
						(arc
							(start -0.1778 -0.2794)
							(mid -0.249642 -0.249642)
							(end -0.2794 -0.1778)
						)
						(arc
							(start -0.2794 0.1778)
							(mid -0.249642 0.249642)
							(end -0.1778 0.2794)
						)
						(arc
							(start 0.1778 0.2794)
							(mid 0.249642 0.249642)
							(end 0.2794 0.1778)
						)
						(arc
							(start 0.2794 -0.1778)
							(mid 0.249642 -0.249642)
							(end 0.1778 -0.2794)
						)
					)
					(width 0)
					(fill yes)
				)
			)
		)
		(pad "2" smd custom
			(at 0 0.4445 180)
			(size 0.1397 0.1397)
			(layers "F.Cu" "F.Mask" "F.Paste")
			(net "CLK_100M_PCIE_P")
			(options
				(clearance outline)
				(anchor circle)
			)
			(primitives
				(gr_poly
					(pts
						(arc
							(start -0.1778 -0.2794)
							(mid -0.249642 -0.249642)
							(end -0.2794 -0.1778)
						)
						(arc
							(start -0.2794 0.1778)
							(mid -0.249642 0.249642)
							(end -0.1778 0.2794)
						)
						(arc
							(start 0.1778 0.2794)
							(mid 0.249642 0.249642)
							(end 0.2794 0.1778)
						)
						(arc
							(start 0.2794 -0.1778)
							(mid 0.249642 -0.249642)
							(end 0.1778 -0.2794)
						)
					)
					(width 0)
					(fill yes)
				)
			)
		)
	)
	(footprint ""
		(layer "F.Cu")
		(at 53.975 -204.343 180)
		(property "Reference" "R690"
			(at 0 0 180)
			(layer "F.SilkS")
			(hide yes)
			(effects
				(font
					(size 1.27 1.27)
				)
			)
		)
		(property "Value" "10KR3F-L-GP"
			(at -0.0254 -2.5146 180)
			(unlocked yes)
			(layer "F.Fab")
			(hide yes)
			(effects
				(font
					(size 1.016 1.016)
					(thickness 0.1524)
				)
			)
		)
		(property "Device Type" "R603H22"
			(at -0.0254 -4.0386 180)
			(unlocked yes)
			(layer "F.Fab")
			(hide yes)
			(effects
				(font
					(size 1.016 1.016)
					(thickness 0.1524)
				)
			)
		)
		(duplicate_pad_numbers_are_jumpers no)
		(fp_line
			(start 0.2032 0)
			(end 0.4826 0)
			(stroke
				(width 0.2032)
				(type default)
			)
			(layer "F.SilkS")
		)
		(fp_line
			(start -0.4826 0)
			(end -0.2032 0)
			(stroke
				(width 0.2032)
				(type default)
			)
			(layer "F.SilkS")
		)
		(fp_rect
			(start -0.5842 1.3335)
			(end 0.5842 -1.3335)
			(stroke
				(width 0)
				(type default)
			)
			(fill no)
			(layer "F.CrtYd")
		)
		(fp_rect
			(start -0.5842 1.3335)
			(end 0.5842 -1.3335)
			(stroke
				(width 0)
				(type default)
			)
			(fill no)
			(layer "F.Fab")
		)
		(pad "1" smd custom
			(at 0 -0.762 180)
			(size 0.2159 0.2159)
			(layers "F.Cu" "F.Mask" "F.Paste")
			(net "P12V_PCIE")
			(options
				(clearance outline)
				(anchor circle)
			)
			(primitives
				(gr_poly
					(pts
						(arc
							(start -0.3302 -0.4318)
							(mid -0.402042 -0.402042)
							(end -0.4318 -0.3302)
						)
						(arc
							(start -0.4318 0.3302)
							(mid -0.402042 0.402042)
							(end -0.3302 0.4318)
						)
						(arc
							(start 0.3302 0.4318)
							(mid 0.402042 0.402042)
							(end 0.4318 0.3302)
						)
						(arc
							(start 0.4318 -0.3302)
							(mid 0.402042 -0.402042)
							(end 0.3302 -0.4318)
						)
					)
					(width 0)
					(fill yes)
				)
			)
		)
		(pad "2" smd custom
			(at 0 0.762 180)
			(size 0.2159 0.2159)
			(layers "F.Cu" "F.Mask" "F.Paste")
			(net "MATED_P12V_EN")
			(options
				(clearance outline)
				(anchor circle)
			)
			(primitives
				(gr_poly
					(pts
						(arc
							(start -0.3302 -0.4318)
							(mid -0.402042 -0.402042)
							(end -0.4318 -0.3302)
						)
						(arc
							(start -0.4318 0.3302)
							(mid -0.402042 0.402042)
							(end -0.3302 0.4318)
						)
						(arc
							(start 0.3302 0.4318)
							(mid 0.402042 0.402042)
							(end 0.4318 0.3302)
						)
						(arc
							(start 0.4318 -0.3302)
							(mid 0.402042 -0.402042)
							(end 0.3302 -0.4318)
						)
					)
					(width 0)
					(fill yes)
				)
			)
		)
	)
	(footprint ""
		(layer "F.Cu")
		(at 95.89897 -86.233 90)
		(property "Reference" "SR772"
			(at 0 0 90)
			(layer "F.SilkS")
			(hide yes)
			(effects
				(font
					(size 1.27 1.27)
				)
			)
		)
		(property "Value" "4K75R2F-1-GP"
			(at 0.064008 -3.993896 90)
			(unlocked yes)
			(layer "F.Fab")
			(hide yes)
			(effects
				(font
					(size 1.016 1.016)
					(thickness 0.1524)
				)
			)
		)
		(property "Device Type" "R402H16"
			(at 0.064008 -5.517896 90)
			(unlocked yes)
			(layer "F.Fab")
			(hide yes)
			(effects
				(font
					(size 1.016 1.016)
					(thickness 0.1524)
				)
			)
		)
		(duplicate_pad_numbers_are_jumpers no)
		(fp_line
			(start 0.508 -0.9398)
			(end -0.508 -0.9398)
			(stroke
				(width 0.1524)
				(type default)
			)
			(layer "F.SilkS")
		)
		(fp_line
			(start -0.508 -0.9398)
			(end -0.508 0.9398)
			(stroke
				(width 0.1524)
				(type default)
			)
			(layer "F.SilkS")
		)
		(fp_rect
			(start -0.508 0.9398)
			(end 0.508 -0.9398)
			(stroke
				(width 0)
				(type default)
			)
			(fill no)
			(layer "F.CrtYd")
		)
		(fp_rect
			(start -0.508 0.9398)
			(end 0.508 -0.9398)
			(stroke
				(width 0)
				(type default)
			)
			(fill no)
			(layer "F.Fab")
		)
		(pad "1" smd custom
			(at 0 -0.4445 90)
			(size 0.1397 0.1397)
			(layers "F.Cu" "F.Mask" "F.Paste")
			(net "P1V8_E")
			(options
				(clearance outline)
				(anchor circle)
			)
			(primitives
				(gr_poly
					(pts
						(arc
							(start -0.1778 -0.2794)
							(mid -0.249642 -0.249642)
							(end -0.2794 -0.1778)
						)
						(arc
							(start -0.2794 0.1778)
							(mid -0.249642 0.249642)
							(end -0.1778 0.2794)
						)
						(arc
							(start 0.1778 0.2794)
							(mid 0.249642 0.249642)
							(end 0.2794 0.1778)
						)
						(arc
							(start 0.2794 -0.1778)
							(mid 0.249642 -0.249642)
							(end 0.1778 -0.2794)
						)
					)
					(width 0)
					(fill yes)
				)
			)
		)
		(pad "2" smd custom
			(at 0 0.4445 90)
			(size 0.1397 0.1397)
			(layers "F.Cu" "F.Mask" "F.Paste")
			(net "SXP_ACTIVE_1")
			(options
				(clearance outline)
				(anchor circle)
			)
			(primitives
				(gr_poly
					(pts
						(arc
							(start -0.1778 -0.2794)
							(mid -0.249642 -0.249642)
							(end -0.2794 -0.1778)
						)
						(arc
							(start -0.2794 0.1778)
							(mid -0.249642 0.249642)
							(end -0.1778 0.2794)
						)
						(arc
							(start 0.1778 0.2794)
							(mid 0.249642 0.249642)
							(end 0.2794 0.1778)
						)
						(arc
							(start 0.2794 -0.1778)
							(mid 0.249642 -0.249642)
							(end 0.1778 -0.2794)
						)
					)
					(width 0)
					(fill yes)
				)
			)
		)
	)
	(footprint ""
		(layer "F.Cu")
		(at 174.743872 -196.591936 180)
		(property "Reference" "C246"
			(at 0 0 180)
			(layer "F.SilkS")
			(hide yes)
			(effects
				(font
					(size 1.27 1.27)
				)
			)
		)
		(property "Value" "SC220P50V3JN-GP"
			(at 0 -2.8194 180)
			(unlocked yes)
			(layer "F.Fab")
			(hide yes)
			(effects
				(font
					(size 1.016 1.016)
					(thickness 0.1524)
				)
			)
		)
		(property "Device Type" "C603H36"
			(at 0 -4.3434 180)
			(unlocked yes)
			(layer "F.Fab")
			(hide yes)
			(effects
				(font
					(size 1.016 1.016)
					(thickness 0.1524)
				)
			)
		)
		(duplicate_pad_numbers_are_jumpers no)
		(fp_line
			(start 0.508 0)
			(end -0.508 0)
			(stroke
				(width 0.2032)
				(type default)
			)
			(layer "F.SilkS")
		)
		(fp_rect
			(start -0.5842 1.3335)
			(end 0.5842 -1.3335)
			(stroke
				(width 0)
				(type default)
			)
			(fill no)
			(layer "F.CrtYd")
		)
		(fp_rect
			(start -0.5842 1.3335)
			(end 0.5842 -1.3335)
			(stroke
				(width 0)
				(type default)
			)
			(fill no)
			(layer "F.Fab")
		)
		(pad "1" smd custom
			(at 0 -0.762 180)
			(size 0.2159 0.2159)
			(layers "F.Cu" "F.Mask" "F.Paste")
			(net "BMC_I2C_C_SCL")
			(options
				(clearance outline)
				(anchor circle)
			)
			(primitives
				(gr_poly
					(pts
						(arc
							(start -0.3302 -0.4318)
							(mid -0.402042 -0.402042)
							(end -0.4318 -0.3302)
						)
						(arc
							(start -0.4318 0.3302)
							(mid -0.402042 0.402042)
							(end -0.3302 0.4318)
						)
						(arc
							(start 0.3302 0.4318)
							(mid 0.402042 0.402042)
							(end 0.4318 0.3302)
						)
						(arc
							(start 0.4318 -0.3302)
							(mid 0.402042 -0.402042)
							(end 0.3302 -0.4318)
						)
					)
					(width 0)
					(fill yes)
				)
			)
		)
		(pad "2" smd custom
			(at 0 0.762 180)
			(size 0.2159 0.2159)
			(layers "F.Cu" "F.Mask" "F.Paste")
			(net "GND")
			(options
				(clearance outline)
				(anchor circle)
			)
			(primitives
				(gr_poly
					(pts
						(arc
							(start -0.3302 -0.4318)
							(mid -0.402042 -0.402042)
							(end -0.4318 -0.3302)
						)
						(arc
							(start -0.4318 0.3302)
							(mid -0.402042 0.402042)
							(end -0.3302 0.4318)
						)
						(arc
							(start 0.3302 0.4318)
							(mid 0.402042 0.402042)
							(end 0.4318 0.3302)
						)
						(arc
							(start 0.4318 -0.3302)
							(mid 0.402042 -0.402042)
							(end 0.3302 -0.4318)
						)
					)
					(width 0)
					(fill yes)
				)
			)
		)
	)
	(footprint ""
		(layer "F.Cu")
		(at 278.384 -207.772 180)
		(property "Reference" "C330"
			(at 0 0 180)
			(layer "F.SilkS")
			(hide yes)
			(effects
				(font
					(size 1.27 1.27)
				)
			)
		)
		(property "Value" "SCD1U25V2KX-2-GP"
			(at 1.1811 -2.7051 180)
			(unlocked yes)
			(layer "F.Fab")
			(hide yes)
			(effects
				(font
					(size 1.016 1.016)
					(thickness 0.1524)
				)
			)
		)
		(property "Device Type" "C402H22"
			(at 1.1811 -4.2291 180)
			(unlocked yes)
			(layer "F.Fab")
			(hide yes)
			(effects
				(font
					(size 1.016 1.016)
					(thickness 0.1524)
				)
			)
		)
		(duplicate_pad_numbers_are_jumpers no)
		(fp_rect
			(start -0.4318 0.9525)
			(end 0.4318 -0.9525)
			(stroke
				(width 0)
				(type default)
			)
			(fill no)
			(layer "F.CrtYd")
		)
		(fp_rect
			(start -0.4318 0.9525)
			(end 0.4318 -0.9525)
			(stroke
				(width 0)
				(type default)
			)
			(fill no)
			(layer "F.Fab")
		)
		(pad "1" smd custom
			(at 0 -0.4445 180)
			(size 0.1524 0.1524)
			(layers "F.Cu" "F.Mask" "F.Paste")
			(net "P3V3_STBY")
			(options
				(clearance outline)
				(anchor circle)
			)
			(primitives
				(gr_poly
					(pts
						(arc
							(start 0.3048 -0.2032)
							(mid 0.275042 -0.275042)
							(end 0.2032 -0.3048)
						)
						(arc
							(start -0.2032 -0.3048)
							(mid -0.275042 -0.275042)
							(end -0.3048 -0.2032)
						)
						(arc
							(start -0.3048 0.2032)
							(mid -0.275042 0.275042)
							(end -0.2032 0.3048)
						)
						(arc
							(start 0.2032 0.3048)
							(mid 0.275042 0.275042)
							(end 0.3048 0.2032)
						)
					)
					(width 0)
					(fill yes)
				)
			)
		)
		(pad "2" smd custom
			(at 0 0.4445 180)
			(size 0.1524 0.1524)
			(layers "F.Cu" "F.Mask" "F.Paste")
			(net "GND")
			(options
				(clearance outline)
				(anchor circle)
			)
			(primitives
				(gr_poly
					(pts
						(arc
							(start 0.3048 -0.2032)
							(mid 0.275042 -0.275042)
							(end 0.2032 -0.3048)
						)
						(arc
							(start -0.2032 -0.3048)
							(mid -0.275042 -0.275042)
							(end -0.3048 -0.2032)
						)
						(arc
							(start -0.3048 0.2032)
							(mid -0.275042 0.275042)
							(end -0.2032 0.3048)
						)
						(arc
							(start 0.2032 0.3048)
							(mid 0.275042 0.275042)
							(end 0.3048 0.2032)
						)
					)
					(width 0)
					(fill yes)
				)
			)
		)
	)
	(footprint ""
		(layer "F.Cu")
		(at 279.273 -65.532 180)
		(property "Reference" "C265"
			(at 0 0 180)
			(layer "F.SilkS")
			(hide yes)
			(effects
				(font
					(size 1.27 1.27)
				)
			)
		)
		(property "Value" "SCD047U16V2KX-1-GP"
			(at 1.1811 -2.7051 180)
			(unlocked yes)
			(layer "F.Fab")
			(hide yes)
			(effects
				(font
					(size 1.016 1.016)
					(thickness 0.1524)
				)
			)
		)
		(property "Device Type" "C402H22"
			(at 1.1811 -4.2291 180)
			(unlocked yes)
			(layer "F.Fab")
			(hide yes)
			(effects
				(font
					(size 1.016 1.016)
					(thickness 0.1524)
				)
			)
		)
		(duplicate_pad_numbers_are_jumpers no)
		(fp_rect
			(start -0.4318 0.9525)
			(end 0.4318 -0.9525)
			(stroke
				(width 0)
				(type default)
			)
			(fill no)
			(layer "F.CrtYd")
		)
		(fp_rect
			(start -0.4318 0.9525)
			(end 0.4318 -0.9525)
			(stroke
				(width 0)
				(type default)
			)
			(fill no)
			(layer "F.Fab")
		)
		(pad "1" smd custom
			(at 0 -0.4445 180)
			(size 0.1524 0.1524)
			(layers "F.Cu" "F.Mask" "F.Paste")
			(net "VR_HSC_TIMER_MSB")
			(options
				(clearance outline)
				(anchor circle)
			)
			(primitives
				(gr_poly
					(pts
						(arc
							(start 0.3048 -0.2032)
							(mid 0.275042 -0.275042)
							(end 0.2032 -0.3048)
						)
						(arc
							(start -0.2032 -0.3048)
							(mid -0.275042 -0.275042)
							(end -0.3048 -0.2032)
						)
						(arc
							(start -0.3048 0.2032)
							(mid -0.275042 0.275042)
							(end -0.2032 0.3048)
						)
						(arc
							(start 0.2032 0.3048)
							(mid 0.275042 0.275042)
							(end 0.3048 0.2032)
						)
					)
					(width 0)
					(fill yes)
				)
			)
		)
		(pad "2" smd custom
			(at 0 0.4445 180)
			(size 0.1524 0.1524)
			(layers "F.Cu" "F.Mask" "F.Paste")
			(net "GND")
			(options
				(clearance outline)
				(anchor circle)
			)
			(primitives
				(gr_poly
					(pts
						(arc
							(start 0.3048 -0.2032)
							(mid 0.275042 -0.275042)
							(end 0.2032 -0.3048)
						)
						(arc
							(start -0.2032 -0.3048)
							(mid -0.275042 -0.275042)
							(end -0.3048 -0.2032)
						)
						(arc
							(start -0.3048 0.2032)
							(mid -0.275042 0.275042)
							(end -0.2032 0.3048)
						)
						(arc
							(start 0.2032 0.3048)
							(mid 0.275042 0.275042)
							(end 0.3048 0.2032)
						)
					)
					(width 0)
					(fill yes)
				)
			)
		)
	)
	(footprint ""
		(layer "F.Cu")
		(at 34.036 -172.847 180)
		(property "Reference" "SR1280"
			(at 0 0 180)
			(layer "F.SilkS")
			(hide yes)
			(effects
				(font
					(size 1.27 1.27)
				)
			)
		)
		(property "Value" "10KR2F-2-GP"
			(at 0.064008 -3.993896 180)
			(unlocked yes)
			(layer "F.Fab")
			(hide yes)
			(effects
				(font
					(size 1.016 1.016)
					(thickness 0.1524)
				)
			)
		)
		(property "Device Type" "R402H16"
			(at 0.064008 -5.517896 180)
			(unlocked yes)
			(layer "F.Fab")
			(hide yes)
			(effects
				(font
					(size 1.016 1.016)
					(thickness 0.1524)
				)
			)
		)
		(duplicate_pad_numbers_are_jumpers no)
		(fp_line
			(start 0.508 -0.9398)
			(end -0.508 -0.9398)
			(stroke
				(width 0.1524)
				(type default)
			)
			(layer "F.SilkS")
		)
		(fp_line
			(start -0.508 -0.9398)
			(end -0.508 0.9398)
			(stroke
				(width 0.1524)
				(type default)
			)
			(layer "F.SilkS")
		)
		(fp_rect
			(start -0.508 0.9398)
			(end 0.508 -0.9398)
			(stroke
				(width 0)
				(type default)
			)
			(fill no)
			(layer "F.CrtYd")
		)
		(fp_rect
			(start -0.508 0.9398)
			(end 0.508 -0.9398)
			(stroke
				(width 0)
				(type default)
			)
			(fill no)
			(layer "F.Fab")
		)
		(pad "1" smd custom
			(at 0 -0.4445 180)
			(size 0.1397 0.1397)
			(layers "F.Cu" "F.Mask" "F.Paste")
			(net "P3V3_STBY_R8")
			(options
				(clearance outline)
				(anchor circle)
			)
			(primitives
				(gr_poly
					(pts
						(arc
							(start -0.1778 -0.2794)
							(mid -0.249642 -0.249642)
							(end -0.2794 -0.1778)
						)
						(arc
							(start -0.2794 0.1778)
							(mid -0.249642 0.249642)
							(end -0.1778 0.2794)
						)
						(arc
							(start 0.1778 0.2794)
							(mid 0.249642 0.249642)
							(end 0.2794 0.1778)
						)
						(arc
							(start 0.2794 -0.1778)
							(mid 0.249642 -0.249642)
							(end 0.1778 -0.2794)
						)
					)
					(width 0)
					(fill yes)
				)
			)
		)
		(pad "2" smd custom
			(at 0 0.4445 180)
			(size 0.1397 0.1397)
			(layers "F.Cu" "F.Mask" "F.Paste")
			(net "P3V3_STBY_G8")
			(options
				(clearance outline)
				(anchor circle)
			)
			(primitives
				(gr_poly
					(pts
						(arc
							(start -0.1778 -0.2794)
							(mid -0.249642 -0.249642)
							(end -0.2794 -0.1778)
						)
						(arc
							(start -0.2794 0.1778)
							(mid -0.249642 0.249642)
							(end -0.1778 0.2794)
						)
						(arc
							(start 0.1778 0.2794)
							(mid 0.249642 0.249642)
							(end 0.2794 0.1778)
						)
						(arc
							(start 0.2794 -0.1778)
							(mid 0.249642 -0.249642)
							(end 0.1778 -0.2794)
						)
					)
					(width 0)
					(fill yes)
				)
			)
		)
	)
	(footprint ""
		(layer "F.Cu")
		(at 168.646348 -122.545856 180)
		(property "Reference" "PR164"
			(at 0 0 180)
			(layer "F.SilkS")
			(hide yes)
			(effects
				(font
					(size 1.27 1.27)
				)
			)
		)
		(property "Value" "113KR2F-1-GP"
			(at 0.064008 -3.993896 180)
			(unlocked yes)
			(layer "F.Fab")
			(hide yes)
			(effects
				(font
					(size 1.016 1.016)
					(thickness 0.1524)
				)
			)
		)
		(property "Device Type" "R402H16"
			(at 0.064008 -5.517896 180)
			(unlocked yes)
			(layer "F.Fab")
			(hide yes)
			(effects
				(font
					(size 1.016 1.016)
					(thickness 0.1524)
				)
			)
		)
		(duplicate_pad_numbers_are_jumpers no)
		(fp_line
			(start 0.508 -0.9398)
			(end -0.508 -0.9398)
			(stroke
				(width 0.1524)
				(type default)
			)
			(layer "F.SilkS")
		)
		(fp_line
			(start -0.508 -0.9398)
			(end -0.508 0.9398)
			(stroke
				(width 0.1524)
				(type default)
			)
			(layer "F.SilkS")
		)
		(fp_rect
			(start -0.508 0.9398)
			(end 0.508 -0.9398)
			(stroke
				(width 0)
				(type default)
			)
			(fill no)
			(layer "F.CrtYd")
		)
		(fp_rect
			(start -0.508 0.9398)
			(end 0.508 -0.9398)
			(stroke
				(width 0)
				(type default)
			)
			(fill no)
			(layer "F.Fab")
		)
		(pad "1" smd custom
			(at 0 -0.4445 180)
			(size 0.1397 0.1397)
			(layers "F.Cu" "F.Mask" "F.Paste")
			(net "P0V9_E_TRIP")
			(options
				(clearance outline)
				(anchor circle)
			)
			(primitives
				(gr_poly
					(pts
						(arc
							(start -0.1778 -0.2794)
							(mid -0.249642 -0.249642)
							(end -0.2794 -0.1778)
						)
						(arc
							(start -0.2794 0.1778)
							(mid -0.249642 0.249642)
							(end -0.1778 0.2794)
						)
						(arc
							(start 0.1778 0.2794)
							(mid 0.249642 0.249642)
							(end 0.2794 0.1778)
						)
						(arc
							(start 0.2794 -0.1778)
							(mid 0.249642 -0.249642)
							(end 0.1778 -0.2794)
						)
					)
					(width 0)
					(fill yes)
				)
			)
		)
		(pad "2" smd custom
			(at 0 0.4445 180)
			(size 0.1397 0.1397)
			(layers "F.Cu" "F.Mask" "F.Paste")
			(net "AGND_P0V9_E")
			(options
				(clearance outline)
				(anchor circle)
			)
			(primitives
				(gr_poly
					(pts
						(arc
							(start -0.1778 -0.2794)
							(mid -0.249642 -0.249642)
							(end -0.2794 -0.1778)
						)
						(arc
							(start -0.2794 0.1778)
							(mid -0.249642 0.249642)
							(end -0.1778 0.2794)
						)
						(arc
							(start 0.1778 0.2794)
							(mid 0.249642 0.249642)
							(end 0.2794 0.1778)
						)
						(arc
							(start 0.2794 -0.1778)
							(mid 0.249642 -0.249642)
							(end 0.1778 -0.2794)
						)
					)
					(width 0)
					(fill yes)
				)
			)
		)
	)
	(footprint ""
		(layer "F.Cu")
		(at 88.27897 -112.014 180)
		(property "Reference" "SC1237"
			(at 0 0 180)
			(layer "F.SilkS")
			(hide yes)
			(effects
				(font
					(size 1.27 1.27)
				)
			)
		)
		(property "Value" "SCD1U6D3V1KX-GP"
			(at -2.8321 -1.7399 180)
			(unlocked yes)
			(layer "F.Fab")
			(hide yes)
			(effects
				(font
					(size 1.016 1.016)
					(thickness 0.1524)
				)
			)
		)
		(property "Device Type" "C0201H13"
			(at -2.8321 -3.2639 180)
			(unlocked yes)
			(layer "F.Fab")
			(hide yes)
			(effects
				(font
					(size 1.016 1.016)
					(thickness 0.1524)
				)
			)
		)
		(duplicate_pad_numbers_are_jumpers no)
		(fp_rect
			(start -0.2794 0.6477)
			(end 0.2794 -0.6477)
			(stroke
				(width 0)
				(type default)
			)
			(fill no)
			(layer "F.CrtYd")
		)
		(fp_rect
			(start -0.2794 0.6477)
			(end 0.2794 -0.6477)
			(stroke
				(width 0)
				(type default)
			)
			(fill no)
			(layer "F.Fab")
		)
		(pad "1" smd custom
			(at 0 -0.2794 180)
			(size 0.0762 0.0762)
			(layers "F.Cu" "F.Mask" "F.Paste")
			(net "P1V8_E")
			(options
				(clearance outline)
				(anchor circle)
			)
			(primitives
				(gr_poly
					(pts
						(arc
							(start 0.1524 -0.127)
							(mid 0.137521 -0.162921)
							(end 0.1016 -0.1778)
						)
						(arc
							(start -0.1016 -0.1778)
							(mid -0.137521 -0.162921)
							(end -0.1524 -0.127)
						)
						(arc
							(start -0.1524 0.127)
							(mid -0.137521 0.162921)
							(end -0.1016 0.1778)
						)
						(arc
							(start 0.1016 0.1778)
							(mid 0.137521 0.162921)
							(end 0.1524 0.127)
						)
					)
					(width 0)
					(fill yes)
				)
			)
		)
		(pad "2" smd custom
			(at 0 0.2794 180)
			(size 0.0762 0.0762)
			(layers "F.Cu" "F.Mask" "F.Paste")
			(net "GND")
			(options
				(clearance outline)
				(anchor circle)
			)
			(primitives
				(gr_poly
					(pts
						(arc
							(start 0.1524 -0.127)
							(mid 0.137521 -0.162921)
							(end 0.1016 -0.1778)
						)
						(arc
							(start -0.1016 -0.1778)
							(mid -0.137521 -0.162921)
							(end -0.1524 -0.127)
						)
						(arc
							(start -0.1524 0.127)
							(mid -0.137521 0.162921)
							(end -0.1016 0.1778)
						)
						(arc
							(start 0.1016 0.1778)
							(mid 0.137521 0.162921)
							(end 0.1524 0.127)
						)
					)
					(width 0)
					(fill yes)
				)
			)
		)
	)
	(footprint ""
		(layer "F.Cu")
		(at 152.019 -53.213 -90)
		(property "Reference" "SR690"
			(at 0 0 270)
			(layer "F.SilkS")
			(hide yes)
			(effects
				(font
					(size 1.27 1.27)
				)
			)
		)
		(property "Value" "10KR2F-2-GP"
			(at 0.064008 -3.993896 270)
			(unlocked yes)
			(layer "F.Fab")
			(hide yes)
			(effects
				(font
					(size 1.016 1.016)
					(thickness 0.1524)
				)
			)
		)
		(property "Device Type" "R402H16"
			(at 0.064008 -5.517896 270)
			(unlocked yes)
			(layer "F.Fab")
			(hide yes)
			(effects
				(font
					(size 1.016 1.016)
					(thickness 0.1524)
				)
			)
		)
		(duplicate_pad_numbers_are_jumpers no)
		(fp_line
			(start -0.508 -0.9398)
			(end -0.508 0.9398)
			(stroke
				(width 0.1524)
				(type default)
			)
			(layer "F.SilkS")
		)
		(fp_line
			(start 0.508 -0.9398)
			(end -0.508 -0.9398)
			(stroke
				(width 0.1524)
				(type default)
			)
			(layer "F.SilkS")
		)
		(fp_rect
			(start -0.508 0.9398)
			(end 0.508 -0.9398)
			(stroke
				(width 0)
				(type default)
			)
			(fill no)
			(layer "F.CrtYd")
		)
		(fp_rect
			(start -0.508 0.9398)
			(end 0.508 -0.9398)
			(stroke
				(width 0)
				(type default)
			)
			(fill no)
			(layer "F.Fab")
		)
		(pad "1" smd custom
			(at 0 -0.4445 270)
			(size 0.1397 0.1397)
			(layers "F.Cu" "F.Mask" "F.Paste")
			(net "P1V8_C")
			(options
				(clearance outline)
				(anchor circle)
			)
			(primitives
				(gr_poly
					(pts
						(arc
							(start -0.1778 -0.2794)
							(mid -0.249642 -0.249642)
							(end -0.2794 -0.1778)
						)
						(arc
							(start -0.2794 0.1778)
							(mid -0.249642 0.249642)
							(end -0.1778 0.2794)
						)
						(arc
							(start 0.1778 0.2794)
							(mid 0.249642 0.249642)
							(end 0.2794 0.1778)
						)
						(arc
							(start 0.2794 -0.1778)
							(mid 0.249642 -0.249642)
							(end 0.1778 -0.2794)
						)
					)
					(width 0)
					(fill yes)
				)
			)
		)
		(pad "2" smd custom
			(at 0 0.4445 270)
			(size 0.1397 0.1397)
			(layers "F.Cu" "F.Mask" "F.Paste")
			(net "XM_ADDR_4")
			(options
				(clearance outline)
				(anchor circle)
			)
			(primitives
				(gr_poly
					(pts
						(arc
							(start -0.1778 -0.2794)
							(mid -0.249642 -0.249642)
							(end -0.2794 -0.1778)
						)
						(arc
							(start -0.2794 0.1778)
							(mid -0.249642 0.249642)
							(end -0.1778 0.2794)
						)
						(arc
							(start 0.1778 0.2794)
							(mid 0.249642 0.249642)
							(end 0.2794 0.1778)
						)
						(arc
							(start 0.2794 -0.1778)
							(mid 0.249642 -0.249642)
							(end 0.1778 -0.2794)
						)
					)
					(width 0)
					(fill yes)
				)
			)
		)
	)
	(footprint ""
		(layer "F.Cu")
		(at 342.265 -106.68 90)
		(property "Reference" "PC10"
			(at 0 0 90)
			(layer "F.SilkS")
			(hide yes)
			(effects
				(font
					(size 1.27 1.27)
				)
			)
		)
		(property "Value" "SCD1U50V3KX-GP"
			(at 0 -2.8194 90)
			(unlocked yes)
			(layer "F.Fab")
			(hide yes)
			(effects
				(font
					(size 1.016 1.016)
					(thickness 0.1524)
				)
			)
		)
		(property "Device Type" "C603H36"
			(at 0 -4.3434 90)
			(unlocked yes)
			(layer "F.Fab")
			(hide yes)
			(effects
				(font
					(size 1.016 1.016)
					(thickness 0.1524)
				)
			)
		)
		(duplicate_pad_numbers_are_jumpers no)
		(fp_line
			(start 0.508 0)
			(end -0.508 0)
			(stroke
				(width 0.2032)
				(type default)
			)
			(layer "F.SilkS")
		)
		(fp_rect
			(start -0.5842 1.3335)
			(end 0.5842 -1.3335)
			(stroke
				(width 0)
				(type default)
			)
			(fill no)
			(layer "F.CrtYd")
		)
		(fp_rect
			(start -0.5842 1.3335)
			(end 0.5842 -1.3335)
			(stroke
				(width 0)
				(type default)
			)
			(fill no)
			(layer "F.Fab")
		)
		(pad "1" smd custom
			(at 0 -0.762 90)
			(size 0.2159 0.2159)
			(layers "F.Cu" "F.Mask" "F.Paste")
			(net "P5V_STBY_SW")
			(options
				(clearance outline)
				(anchor circle)
			)
			(primitives
				(gr_poly
					(pts
						(arc
							(start -0.3302 -0.4318)
							(mid -0.402042 -0.402042)
							(end -0.4318 -0.3302)
						)
						(arc
							(start -0.4318 0.3302)
							(mid -0.402042 0.402042)
							(end -0.3302 0.4318)
						)
						(arc
							(start 0.3302 0.4318)
							(mid 0.402042 0.402042)
							(end 0.4318 0.3302)
						)
						(arc
							(start 0.4318 -0.3302)
							(mid 0.402042 -0.402042)
							(end 0.3302 -0.4318)
						)
					)
					(width 0)
					(fill yes)
				)
			)
		)
		(pad "2" smd custom
			(at 0 0.762 90)
			(size 0.2159 0.2159)
			(layers "F.Cu" "F.Mask" "F.Paste")
			(net "P5V_STBY_VBST_RR")
			(options
				(clearance outline)
				(anchor circle)
			)
			(primitives
				(gr_poly
					(pts
						(arc
							(start -0.3302 -0.4318)
							(mid -0.402042 -0.402042)
							(end -0.4318 -0.3302)
						)
						(arc
							(start -0.4318 0.3302)
							(mid -0.402042 0.402042)
							(end -0.3302 0.4318)
						)
						(arc
							(start 0.3302 0.4318)
							(mid 0.402042 0.402042)
							(end 0.4318 0.3302)
						)
						(arc
							(start 0.4318 -0.3302)
							(mid 0.402042 -0.402042)
							(end 0.3302 -0.4318)
						)
					)
					(width 0)
					(fill yes)
				)
			)
		)
	)
	(footprint ""
		(layer "F.Cu")
		(at 304.717958 -58.928 180)
		(property "Reference" "C288"
			(at 0 0 180)
			(layer "F.SilkS")
			(hide yes)
			(effects
				(font
					(size 1.27 1.27)
				)
			)
		)
		(property "Value" "SCD1U25V2KX-2-GP"
			(at 1.1811 -2.7051 180)
			(unlocked yes)
			(layer "F.Fab")
			(hide yes)
			(effects
				(font
					(size 1.016 1.016)
					(thickness 0.1524)
				)
			)
		)
		(property "Device Type" "C402H22"
			(at 1.1811 -4.2291 180)
			(unlocked yes)
			(layer "F.Fab")
			(hide yes)
			(effects
				(font
					(size 1.016 1.016)
					(thickness 0.1524)
				)
			)
		)
		(duplicate_pad_numbers_are_jumpers no)
		(fp_rect
			(start -0.4318 0.9525)
			(end 0.4318 -0.9525)
			(stroke
				(width 0)
				(type default)
			)
			(fill no)
			(layer "F.CrtYd")
		)
		(fp_rect
			(start -0.4318 0.9525)
			(end 0.4318 -0.9525)
			(stroke
				(width 0)
				(type default)
			)
			(fill no)
			(layer "F.Fab")
		)
		(pad "1" smd custom
			(at 0 -0.4445 180)
			(size 0.1524 0.1524)
			(layers "F.Cu" "F.Mask" "F.Paste")
			(net "P3V3")
			(options
				(clearance outline)
				(anchor circle)
			)
			(primitives
				(gr_poly
					(pts
						(arc
							(start 0.3048 -0.2032)
							(mid 0.275042 -0.275042)
							(end 0.2032 -0.3048)
						)
						(arc
							(start -0.2032 -0.3048)
							(mid -0.275042 -0.275042)
							(end -0.3048 -0.2032)
						)
						(arc
							(start -0.3048 0.2032)
							(mid -0.275042 0.275042)
							(end -0.2032 0.3048)
						)
						(arc
							(start 0.2032 0.3048)
							(mid 0.275042 0.275042)
							(end 0.3048 0.2032)
						)
					)
					(width 0)
					(fill yes)
				)
			)
		)
		(pad "2" smd custom
			(at 0 0.4445 180)
			(size 0.1524 0.1524)
			(layers "F.Cu" "F.Mask" "F.Paste")
			(net "GND")
			(options
				(clearance outline)
				(anchor circle)
			)
			(primitives
				(gr_poly
					(pts
						(arc
							(start 0.3048 -0.2032)
							(mid 0.275042 -0.275042)
							(end 0.2032 -0.3048)
						)
						(arc
							(start -0.2032 -0.3048)
							(mid -0.275042 -0.275042)
							(end -0.3048 -0.2032)
						)
						(arc
							(start -0.3048 0.2032)
							(mid -0.275042 0.275042)
							(end -0.2032 0.3048)
						)
						(arc
							(start 0.2032 0.3048)
							(mid 0.275042 0.275042)
							(end 0.3048 0.2032)
						)
					)
					(width 0)
					(fill yes)
				)
			)
		)
	)
	(footprint ""
		(layer "F.Cu")
		(at 184.903872 -193.289936)
		(property "Reference" "C248"
			(at 0 0 0)
			(layer "F.SilkS")
			(hide yes)
			(effects
				(font
					(size 1.27 1.27)
				)
			)
		)
		(property "Value" "SC220P50V3JN-GP"
			(at 0 -2.8194 0)
			(unlocked yes)
			(layer "F.Fab")
			(hide yes)
			(effects
				(font
					(size 1.016 1.016)
					(thickness 0.1524)
				)
			)
		)
		(property "Device Type" "C603H36"
			(at 0 -4.3434 0)
			(unlocked yes)
			(layer "F.Fab")
			(hide yes)
			(effects
				(font
					(size 1.016 1.016)
					(thickness 0.1524)
				)
			)
		)
		(duplicate_pad_numbers_are_jumpers no)
		(fp_line
			(start 0.508 0)
			(end -0.508 0)
			(stroke
				(width 0.2032)
				(type default)
			)
			(layer "F.SilkS")
		)
		(fp_rect
			(start -0.5842 1.3335)
			(end 0.5842 -1.3335)
			(stroke
				(width 0)
				(type default)
			)
			(fill no)
			(layer "F.CrtYd")
		)
		(fp_rect
			(start -0.5842 1.3335)
			(end 0.5842 -1.3335)
			(stroke
				(width 0)
				(type default)
			)
			(fill no)
			(layer "F.Fab")
		)
		(pad "1" smd custom
			(at 0 -0.762)
			(size 0.2159 0.2159)
			(layers "F.Cu" "F.Mask" "F.Paste")
			(net "SAS_I2C_C_BUF_SDA")
			(options
				(clearance outline)
				(anchor circle)
			)
			(primitives
				(gr_poly
					(pts
						(arc
							(start -0.3302 -0.4318)
							(mid -0.402042 -0.402042)
							(end -0.4318 -0.3302)
						)
						(arc
							(start -0.4318 0.3302)
							(mid -0.402042 0.402042)
							(end -0.3302 0.4318)
						)
						(arc
							(start 0.3302 0.4318)
							(mid 0.402042 0.402042)
							(end 0.4318 0.3302)
						)
						(arc
							(start 0.4318 -0.3302)
							(mid 0.402042 -0.402042)
							(end 0.3302 -0.4318)
						)
					)
					(width 0)
					(fill yes)
				)
			)
		)
		(pad "2" smd custom
			(at 0 0.762)
			(size 0.2159 0.2159)
			(layers "F.Cu" "F.Mask" "F.Paste")
			(net "GND")
			(options
				(clearance outline)
				(anchor circle)
			)
			(primitives
				(gr_poly
					(pts
						(arc
							(start -0.3302 -0.4318)
							(mid -0.402042 -0.402042)
							(end -0.4318 -0.3302)
						)
						(arc
							(start -0.4318 0.3302)
							(mid -0.402042 0.402042)
							(end -0.3302 0.4318)
						)
						(arc
							(start 0.3302 0.4318)
							(mid 0.402042 0.402042)
							(end 0.4318 0.3302)
						)
						(arc
							(start 0.4318 -0.3302)
							(mid 0.402042 -0.402042)
							(end 0.3302 -0.4318)
						)
					)
					(width 0)
					(fill yes)
				)
			)
		)
	)
	(footprint ""
		(layer "F.Cu")
		(at 333.375 -211.455 180)
		(property "Reference" "R208"
			(at 0 0 180)
			(layer "F.SilkS")
			(hide yes)
			(effects
				(font
					(size 1.27 1.27)
				)
			)
		)
		(property "Value" "0R2J-2-GP"
			(at 0.064008 -3.993896 180)
			(unlocked yes)
			(layer "F.Fab")
			(hide yes)
			(effects
				(font
					(size 1.016 1.016)
					(thickness 0.1524)
				)
			)
		)
		(property "Device Type" "R402H16"
			(at 0.064008 -5.517896 180)
			(unlocked yes)
			(layer "F.Fab")
			(hide yes)
			(effects
				(font
					(size 1.016 1.016)
					(thickness 0.1524)
				)
			)
		)
		(duplicate_pad_numbers_are_jumpers no)
		(fp_line
			(start 0.508 -0.9398)
			(end -0.508 -0.9398)
			(stroke
				(width 0.1524)
				(type default)
			)
			(layer "F.SilkS")
		)
		(fp_line
			(start -0.508 -0.9398)
			(end -0.508 0.9398)
			(stroke
				(width 0.1524)
				(type default)
			)
			(layer "F.SilkS")
		)
		(fp_rect
			(start -0.508 0.9398)
			(end 0.508 -0.9398)
			(stroke
				(width 0)
				(type default)
			)
			(fill no)
			(layer "F.CrtYd")
		)
		(fp_rect
			(start -0.508 0.9398)
			(end 0.508 -0.9398)
			(stroke
				(width 0)
				(type default)
			)
			(fill no)
			(layer "F.Fab")
		)
		(pad "1" smd custom
			(at 0 -0.4445 180)
			(size 0.1397 0.1397)
			(layers "F.Cu" "F.Mask" "F.Paste")
			(net "EEPROM_SCL")
			(options
				(clearance outline)
				(anchor circle)
			)
			(primitives
				(gr_poly
					(pts
						(arc
							(start -0.1778 -0.2794)
							(mid -0.249642 -0.249642)
							(end -0.2794 -0.1778)
						)
						(arc
							(start -0.2794 0.1778)
							(mid -0.249642 0.249642)
							(end -0.1778 0.2794)
						)
						(arc
							(start 0.1778 0.2794)
							(mid 0.249642 0.249642)
							(end 0.2794 0.1778)
						)
						(arc
							(start 0.2794 -0.1778)
							(mid 0.249642 -0.249642)
							(end 0.1778 -0.2794)
						)
					)
					(width 0)
					(fill yes)
				)
			)
		)
		(pad "2" smd custom
			(at 0 0.4445 180)
			(size 0.1397 0.1397)
			(layers "F.Cu" "F.Mask" "F.Paste")
			(net "BMC_I2C_A_SCL")
			(options
				(clearance outline)
				(anchor circle)
			)
			(primitives
				(gr_poly
					(pts
						(arc
							(start -0.1778 -0.2794)
							(mid -0.249642 -0.249642)
							(end -0.2794 -0.1778)
						)
						(arc
							(start -0.2794 0.1778)
							(mid -0.249642 0.249642)
							(end -0.1778 0.2794)
						)
						(arc
							(start 0.1778 0.2794)
							(mid 0.249642 0.249642)
							(end 0.2794 0.1778)
						)
						(arc
							(start 0.2794 -0.1778)
							(mid 0.249642 -0.249642)
							(end 0.1778 -0.2794)
						)
					)
					(width 0)
					(fill yes)
				)
			)
		)
	)
	(footprint ""
		(layer "F.Cu")
		(at 184.404 -226.822)
		(property "Reference" "R1581"
			(at 0 0 0)
			(layer "F.SilkS")
			(hide yes)
			(effects
				(font
					(size 1.27 1.27)
				)
			)
		)
		(property "Value" "33R2F-3-GP"
			(at 0.064008 -3.993896 0)
			(unlocked yes)
			(layer "F.Fab")
			(hide yes)
			(effects
				(font
					(size 1.016 1.016)
					(thickness 0.1524)
				)
			)
		)
		(property "Device Type" "R402H16"
			(at 0.064008 -5.517896 0)
			(unlocked yes)
			(layer "F.Fab")
			(hide yes)
			(effects
				(font
					(size 1.016 1.016)
					(thickness 0.1524)
				)
			)
		)
		(duplicate_pad_numbers_are_jumpers no)
		(fp_line
			(start -0.508 -0.9398)
			(end -0.508 0.9398)
			(stroke
				(width 0.1524)
				(type default)
			)
			(layer "F.SilkS")
		)
		(fp_line
			(start 0.508 -0.9398)
			(end -0.508 -0.9398)
			(stroke
				(width 0.1524)
				(type default)
			)
			(layer "F.SilkS")
		)
		(fp_rect
			(start -0.508 0.9398)
			(end 0.508 -0.9398)
			(stroke
				(width 0)
				(type default)
			)
			(fill no)
			(layer "F.CrtYd")
		)
		(fp_rect
			(start -0.508 0.9398)
			(end 0.508 -0.9398)
			(stroke
				(width 0)
				(type default)
			)
			(fill no)
			(layer "F.Fab")
		)
		(pad "1" smd custom
			(at 0 -0.4445)
			(size 0.1397 0.1397)
			(layers "F.Cu" "F.Mask" "F.Paste")
			(net "FP_PWRBTN")
			(options
				(clearance outline)
				(anchor circle)
			)
			(primitives
				(gr_poly
					(pts
						(arc
							(start -0.1778 -0.2794)
							(mid -0.249642 -0.249642)
							(end -0.2794 -0.1778)
						)
						(arc
							(start -0.2794 0.1778)
							(mid -0.249642 0.249642)
							(end -0.1778 0.2794)
						)
						(arc
							(start 0.1778 0.2794)
							(mid 0.249642 0.249642)
							(end 0.2794 0.1778)
						)
						(arc
							(start 0.2794 -0.1778)
							(mid 0.249642 -0.249642)
							(end 0.1778 -0.2794)
						)
					)
					(width 0)
					(fill yes)
				)
			)
		)
		(pad "2" smd custom
			(at 0 0.4445)
			(size 0.1397 0.1397)
			(layers "F.Cu" "F.Mask" "F.Paste")
			(net "FP_PWRBTN_R")
			(options
				(clearance outline)
				(anchor circle)
			)
			(primitives
				(gr_poly
					(pts
						(arc
							(start -0.1778 -0.2794)
							(mid -0.249642 -0.249642)
							(end -0.2794 -0.1778)
						)
						(arc
							(start -0.2794 0.1778)
							(mid -0.249642 0.249642)
							(end -0.1778 0.2794)
						)
						(arc
							(start 0.1778 0.2794)
							(mid 0.249642 0.249642)
							(end 0.2794 0.1778)
						)
						(arc
							(start 0.2794 -0.1778)
							(mid 0.249642 -0.249642)
							(end 0.1778 -0.2794)
						)
					)
					(width 0)
					(fill yes)
				)
			)
		)
	)
	(footprint ""
		(layer "F.Cu")
		(at 274.32 -41.148)
		(property "Reference" "PC42"
			(at 0 0 0)
			(layer "F.SilkS")
			(hide yes)
			(effects
				(font
					(size 1.27 1.27)
				)
			)
		)
		(property "Value" "SC22U25V5MX-GP"
			(at -0.0762 -6.1214 0)
			(unlocked yes)
			(layer "F.Fab")
			(hide yes)
			(effects
				(font
					(size 1.016 1.016)
					(thickness 0.1524)
				)
			)
		)
		(property "Device Type" "C805H58"
			(at -0.0762 -8.1534 0)
			(unlocked yes)
			(layer "F.Fab")
			(hide yes)
			(effects
				(font
					(size 1.016 1.016)
					(thickness 0.1524)
				)
			)
		)
		(duplicate_pad_numbers_are_jumpers no)
		(fp_line
			(start 0.635 0)
			(end -0.635 0)
			(stroke
				(width 0.508)
				(type default)
			)
			(layer "F.SilkS")
		)
		(fp_rect
			(start -0.9652 1.778)
			(end 0.9652 -1.778)
			(stroke
				(width 0)
				(type default)
			)
			(fill no)
			(layer "F.CrtYd")
		)
		(fp_poly
			(pts
				(xy -0.9652 -1.778) (xy 0.9652 -1.778) (xy 0.9652 1.778) (xy -0.9652 1.778)
			)
			(stroke
				(width 0)
				(type default)
			)
			(fill no)
			(layer "F.Fab")
		)
		(pad "1" smd rect
			(at 0 -0.9652)
			(size 1.397 1.143)
			(layers "F.Cu" "F.Mask" "F.Paste")
			(net "P1V8_STBY_VIN")
		)
		(pad "2" smd rect
			(at 0 0.9652)
			(size 1.397 1.143)
			(layers "F.Cu" "F.Mask" "F.Paste")
			(net "GND")
		)
	)
	(footprint ""
		(layer "F.Cu")
		(at 320.04 -141.986 90)
		(property "Reference" "D13"
			(at 0 0 90)
			(layer "F.SilkS")
			(hide yes)
			(effects
				(font
					(size 1.27 1.27)
				)
			)
		)
		(property "Value" "BAT54C-7-F-3-GP"
			(at 0 -5.0292 90)
			(unlocked yes)
			(layer "F.Fab")
			(hide yes)
			(effects
				(font
					(size 1.016 1.016)
					(thickness 0.1524)
				)
			)
		)
		(property "Device Type" "SOT23-2D4-312H48"
			(at 0 -6.5532 90)
			(unlocked yes)
			(layer "F.Fab")
			(hide yes)
			(effects
				(font
					(size 1.016 1.016)
					(thickness 0.1524)
				)
			)
		)
		(duplicate_pad_numbers_are_jumpers no)
		(fp_line
			(start 0.635 -1.778)
			(end 0.635 -0.9017)
			(stroke
				(width 0.1524)
				(type default)
			)
			(layer "F.SilkS")
		)
		(fp_line
			(start -0.635 -1.778)
			(end 0.635 -1.778)
			(stroke
				(width 0.1524)
				(type default)
			)
			(layer "F.SilkS")
		)
		(fp_line
			(start 1.7018 -0.9017)
			(end 1.7018 1.778)
			(stroke
				(width 0.1524)
				(type default)
			)
			(layer "F.SilkS")
		)
		(fp_line
			(start 0.635 -0.9017)
			(end 1.7018 -0.9017)
			(stroke
				(width 0.1524)
				(type default)
			)
			(layer "F.SilkS")
		)
		(fp_line
			(start -0.635 -0.9017)
			(end -0.635 -1.778)
			(stroke
				(width 0.1524)
				(type default)
			)
			(layer "F.SilkS")
		)
		(fp_line
			(start -1.7018 -0.9017)
			(end -0.635 -0.9017)
			(stroke
				(width 0.1524)
				(type default)
			)
			(layer "F.SilkS")
		)
		(fp_line
			(start 1.7018 1.778)
			(end -1.7018 1.778)
			(stroke
				(width 0.1524)
				(type default)
			)
			(layer "F.SilkS")
		)
		(fp_line
			(start -1.7018 1.778)
			(end -1.7018 -0.9017)
			(stroke
				(width 0.1524)
				(type default)
			)
			(layer "F.SilkS")
		)
		(fp_poly
			(pts
				(xy 0.2159 -1.1938) (xy -0.2159 -1.1938) (xy -0.2159 -0.6477) (xy -1.4478 -0.6477) (xy -1.4478 1.1938)
				(xy 1.4478 1.1938) (xy 1.4478 -0.6477) (xy 0.2159 -0.6477)
			)
			(stroke
				(width 0)
				(type default)
			)
			(fill no)
			(layer "F.CrtYd")
		)
		(fp_poly
			(pts
				(xy 1.9558 2.032) (xy 1.9558 -0.1905) (xy 1.4478 -0.1905) (xy 1.4478 1.1938) (xy -1.4478 1.1938)
				(xy -1.4478 -0.6477) (xy -0.2159 -0.6477) (xy -0.2159 -1.1938) (xy 0.2159 -1.1938) (xy 0.2159 -0.6477)
				(xy 1.4478 -0.6477) (xy 1.4478 -0.2032) (xy 1.9558 -0.2032) (xy 1.9558 -1.1557) (xy 0.889 -1.1557)
				(xy 0.889 -2.032) (xy -0.889 -2.032) (xy -0.889 -1.1557) (xy -1.9558 -1.1557) (xy -1.9558 2.032)
			)
			(stroke
				(width 0)
				(type default)
			)
			(fill no)
			(layer "F.CrtYd")
		)
		(fp_poly
			(pts
				(xy -1.9558 2.032) (xy -1.9558 -1.1557) (xy -0.889 -1.1557) (xy -0.889 -2.032) (xy 0.889 -2.032)
				(xy 0.889 -1.1557) (xy 1.9558 -1.1557) (xy 1.9558 2.032)
			)
			(stroke
				(width 0)
				(type default)
			)
			(fill no)
			(layer "F.Fab")
		)
		(pad "1" smd custom
			(at -0.98425 0.9525 90)
			(size 0.1905 0.1905)
			(layers "F.Cu" "F.Mask" "F.Paste")
			(net "P3V3_STBY")
			(options
				(clearance outline)
				(anchor circle)
			)
			(primitives
				(gr_poly
					(pts
						(arc
							(start -0.1778 0.5715)
							(mid -0.321484 0.511984)
							(end -0.381 0.3683)
						)
						(arc
							(start -0.381 -0.3683)
							(mid -0.321484 -0.511984)
							(end -0.1778 -0.5715)
						)
						(arc
							(start 0.1778 -0.5715)
							(mid 0.321484 -0.511984)
							(end 0.381 -0.3683)
						)
						(arc
							(start 0.381 0.3683)
							(mid 0.321484 0.511984)
							(end 0.1778 0.5715)
						)
					)
					(width 0)
					(fill yes)
				)
			)
		)
		(pad "2" smd custom
			(at 0.98425 0.9525 90)
			(size 0.1905 0.1905)
			(layers "F.Cu" "F.Mask" "F.Paste")
			(net "P3V0_BAT_R")
			(options
				(clearance outline)
				(anchor circle)
			)
			(primitives
				(gr_poly
					(pts
						(arc
							(start -0.1778 0.5715)
							(mid -0.321484 0.511984)
							(end -0.381 0.3683)
						)
						(arc
							(start -0.381 -0.3683)
							(mid -0.321484 -0.511984)
							(end -0.1778 -0.5715)
						)
						(arc
							(start 0.1778 -0.5715)
							(mid 0.321484 -0.511984)
							(end 0.381 -0.3683)
						)
						(arc
							(start 0.381 0.3683)
							(mid 0.321484 0.511984)
							(end 0.1778 0.5715)
						)
					)
					(width 0)
					(fill yes)
				)
			)
		)
		(pad "3" smd custom
			(at 0 -0.9525 90)
			(size 0.1905 0.1905)
			(layers "F.Cu" "F.Mask" "F.Paste")
			(net "P3V3_RTC")
			(options
				(clearance outline)
				(anchor circle)
			)
			(primitives
				(gr_poly
					(pts
						(arc
							(start -0.1778 0.5715)
							(mid -0.321484 0.511984)
							(end -0.381 0.3683)
						)
						(arc
							(start -0.381 -0.3683)
							(mid -0.321484 -0.511984)
							(end -0.1778 -0.5715)
						)
						(arc
							(start 0.1778 -0.5715)
							(mid 0.321484 -0.511984)
							(end 0.381 -0.3683)
						)
						(arc
							(start 0.381 0.3683)
							(mid 0.321484 0.511984)
							(end 0.1778 0.5715)
						)
					)
					(width 0)
					(fill yes)
				)
			)
		)
	)
	(footprint ""
		(layer "F.Cu")
		(at 81.285842 -121.864882 -90)
		(property "Reference" "SR740"
			(at 0 0 270)
			(layer "F.SilkS")
			(hide yes)
			(effects
				(font
					(size 1.27 1.27)
				)
			)
		)
		(property "Value" "2K2R2F-GP"
			(at 0.064008 -3.993896 270)
			(unlocked yes)
			(layer "F.Fab")
			(hide yes)
			(effects
				(font
					(size 1.016 1.016)
					(thickness 0.1524)
				)
			)
		)
		(property "Device Type" "R402H16"
			(at 0.064008 -5.517896 270)
			(unlocked yes)
			(layer "F.Fab")
			(hide yes)
			(effects
				(font
					(size 1.016 1.016)
					(thickness 0.1524)
				)
			)
		)
		(duplicate_pad_numbers_are_jumpers no)
		(fp_line
			(start -0.508 -0.9398)
			(end -0.508 0.9398)
			(stroke
				(width 0.1524)
				(type default)
			)
			(layer "F.SilkS")
		)
		(fp_line
			(start 0.508 -0.9398)
			(end -0.508 -0.9398)
			(stroke
				(width 0.1524)
				(type default)
			)
			(layer "F.SilkS")
		)
		(fp_rect
			(start -0.508 0.9398)
			(end 0.508 -0.9398)
			(stroke
				(width 0)
				(type default)
			)
			(fill no)
			(layer "F.CrtYd")
		)
		(fp_rect
			(start -0.508 0.9398)
			(end 0.508 -0.9398)
			(stroke
				(width 0)
				(type default)
			)
			(fill no)
			(layer "F.Fab")
		)
		(pad "1" smd custom
			(at 0 -0.4445 270)
			(size 0.1397 0.1397)
			(layers "F.Cu" "F.Mask" "F.Paste")
			(net "EXP_SCL_0")
			(options
				(clearance outline)
				(anchor circle)
			)
			(primitives
				(gr_poly
					(pts
						(arc
							(start -0.1778 -0.2794)
							(mid -0.249642 -0.249642)
							(end -0.2794 -0.1778)
						)
						(arc
							(start -0.2794 0.1778)
							(mid -0.249642 0.249642)
							(end -0.1778 0.2794)
						)
						(arc
							(start 0.1778 0.2794)
							(mid 0.249642 0.249642)
							(end 0.2794 0.1778)
						)
						(arc
							(start 0.2794 -0.1778)
							(mid 0.249642 -0.249642)
							(end 0.1778 -0.2794)
						)
					)
					(width 0)
					(fill yes)
				)
			)
		)
		(pad "2" smd custom
			(at 0 0.4445 270)
			(size 0.1397 0.1397)
			(layers "F.Cu" "F.Mask" "F.Paste")
			(net "P1V8_E")
			(options
				(clearance outline)
				(anchor circle)
			)
			(primitives
				(gr_poly
					(pts
						(arc
							(start -0.1778 -0.2794)
							(mid -0.249642 -0.249642)
							(end -0.2794 -0.1778)
						)
						(arc
							(start -0.2794 0.1778)
							(mid -0.249642 0.249642)
							(end -0.1778 0.2794)
						)
						(arc
							(start 0.1778 0.2794)
							(mid 0.249642 0.249642)
							(end 0.2794 0.1778)
						)
						(arc
							(start 0.2794 -0.1778)
							(mid 0.249642 -0.249642)
							(end 0.1778 -0.2794)
						)
					)
					(width 0)
					(fill yes)
				)
			)
		)
	)
	(footprint ""
		(layer "F.Cu")
		(at 180.35397 -67.183 180)
		(property "Reference" "C275"
			(at 0 0 180)
			(layer "F.SilkS")
			(hide yes)
			(effects
				(font
					(size 1.27 1.27)
				)
			)
		)
		(property "Value" "SCD1U25V2KX-2-GP"
			(at 1.1811 -2.7051 180)
			(unlocked yes)
			(layer "F.Fab")
			(hide yes)
			(effects
				(font
					(size 1.016 1.016)
					(thickness 0.1524)
				)
			)
		)
		(property "Device Type" "C402H22"
			(at 1.1811 -4.2291 180)
			(unlocked yes)
			(layer "F.Fab")
			(hide yes)
			(effects
				(font
					(size 1.016 1.016)
					(thickness 0.1524)
				)
			)
		)
		(duplicate_pad_numbers_are_jumpers no)
		(fp_rect
			(start -0.4318 0.9525)
			(end 0.4318 -0.9525)
			(stroke
				(width 0)
				(type default)
			)
			(fill no)
			(layer "F.CrtYd")
		)
		(fp_rect
			(start -0.4318 0.9525)
			(end 0.4318 -0.9525)
			(stroke
				(width 0)
				(type default)
			)
			(fill no)
			(layer "F.Fab")
		)
		(pad "1" smd custom
			(at 0 -0.4445 180)
			(size 0.1524 0.1524)
			(layers "F.Cu" "F.Mask" "F.Paste")
			(net "GND")
			(options
				(clearance outline)
				(anchor circle)
			)
			(primitives
				(gr_poly
					(pts
						(arc
							(start 0.3048 -0.2032)
							(mid 0.275042 -0.275042)
							(end 0.2032 -0.3048)
						)
						(arc
							(start -0.2032 -0.3048)
							(mid -0.275042 -0.275042)
							(end -0.3048 -0.2032)
						)
						(arc
							(start -0.3048 0.2032)
							(mid -0.275042 0.275042)
							(end -0.2032 0.3048)
						)
						(arc
							(start 0.2032 0.3048)
							(mid 0.275042 0.275042)
							(end 0.3048 0.2032)
						)
					)
					(width 0)
					(fill yes)
				)
			)
		)
		(pad "2" smd custom
			(at 0 0.4445 180)
			(size 0.1524 0.1524)
			(layers "F.Cu" "F.Mask" "F.Paste")
			(net "TP_MSB_B31_CPU_SATA_TX_P")
			(options
				(clearance outline)
				(anchor circle)
			)
			(primitives
				(gr_poly
					(pts
						(arc
							(start 0.3048 -0.2032)
							(mid 0.275042 -0.275042)
							(end 0.2032 -0.3048)
						)
						(arc
							(start -0.2032 -0.3048)
							(mid -0.275042 -0.275042)
							(end -0.3048 -0.2032)
						)
						(arc
							(start -0.3048 0.2032)
							(mid -0.275042 0.275042)
							(end -0.2032 0.3048)
						)
						(arc
							(start 0.2032 0.3048)
							(mid 0.275042 0.275042)
							(end 0.3048 0.2032)
						)
					)
					(width 0)
					(fill yes)
				)
			)
		)
	)
	(footprint ""
		(layer "F.Cu")
		(at 152.019 -57.785 -90)
		(property "Reference" "SR708"
			(at 0 0 270)
			(layer "F.SilkS")
			(hide yes)
			(effects
				(font
					(size 1.27 1.27)
				)
			)
		)
		(property "Value" "10KR2F-2-GP"
			(at 0.064008 -3.993896 270)
			(unlocked yes)
			(layer "F.Fab")
			(hide yes)
			(effects
				(font
					(size 1.016 1.016)
					(thickness 0.1524)
				)
			)
		)
		(property "Device Type" "R402H16"
			(at 0.064008 -5.517896 270)
			(unlocked yes)
			(layer "F.Fab")
			(hide yes)
			(effects
				(font
					(size 1.016 1.016)
					(thickness 0.1524)
				)
			)
		)
		(duplicate_pad_numbers_are_jumpers no)
		(fp_line
			(start -0.508 -0.9398)
			(end -0.508 0.9398)
			(stroke
				(width 0.1524)
				(type default)
			)
			(layer "F.SilkS")
		)
		(fp_line
			(start 0.508 -0.9398)
			(end -0.508 -0.9398)
			(stroke
				(width 0.1524)
				(type default)
			)
			(layer "F.SilkS")
		)
		(fp_rect
			(start -0.508 0.9398)
			(end 0.508 -0.9398)
			(stroke
				(width 0)
				(type default)
			)
			(fill no)
			(layer "F.CrtYd")
		)
		(fp_rect
			(start -0.508 0.9398)
			(end 0.508 -0.9398)
			(stroke
				(width 0)
				(type default)
			)
			(fill no)
			(layer "F.Fab")
		)
		(pad "1" smd custom
			(at 0 -0.4445 270)
			(size 0.1397 0.1397)
			(layers "F.Cu" "F.Mask" "F.Paste")
			(net "P1V8_C")
			(options
				(clearance outline)
				(anchor circle)
			)
			(primitives
				(gr_poly
					(pts
						(arc
							(start -0.1778 -0.2794)
							(mid -0.249642 -0.249642)
							(end -0.2794 -0.1778)
						)
						(arc
							(start -0.2794 0.1778)
							(mid -0.249642 0.249642)
							(end -0.1778 0.2794)
						)
						(arc
							(start 0.1778 0.2794)
							(mid 0.249642 0.249642)
							(end 0.2794 0.1778)
						)
						(arc
							(start 0.2794 -0.1778)
							(mid 0.249642 -0.249642)
							(end 0.1778 -0.2794)
						)
					)
					(width 0)
					(fill yes)
				)
			)
		)
		(pad "2" smd custom
			(at 0 0.4445 270)
			(size 0.1397 0.1397)
			(layers "F.Cu" "F.Mask" "F.Paste")
			(net "XM_NOR_CS_N")
			(options
				(clearance outline)
				(anchor circle)
			)
			(primitives
				(gr_poly
					(pts
						(arc
							(start -0.1778 -0.2794)
							(mid -0.249642 -0.249642)
							(end -0.2794 -0.1778)
						)
						(arc
							(start -0.2794 0.1778)
							(mid -0.249642 0.249642)
							(end -0.1778 0.2794)
						)
						(arc
							(start 0.1778 0.2794)
							(mid 0.249642 0.249642)
							(end 0.2794 0.1778)
						)
						(arc
							(start 0.2794 -0.1778)
							(mid 0.249642 -0.249642)
							(end 0.1778 -0.2794)
						)
					)
					(width 0)
					(fill yes)
				)
			)
		)
	)
	(footprint ""
		(layer "F.Cu")
		(at 63.119 -213.741 90)
		(property "Reference" "CA1"
			(at 0 0 90)
			(layer "F.SilkS")
			(hide yes)
			(effects
				(font
					(size 1.27 1.27)
				)
			)
		)
		(property "Value" "SC2D2U25V5KX-2-GP"
			(at -0.0762 -6.1214 90)
			(unlocked yes)
			(layer "F.Fab")
			(hide yes)
			(effects
				(font
					(size 1.016 1.016)
					(thickness 0.1524)
				)
			)
		)
		(property "Device Type" "C805H54"
			(at -0.0762 -8.1534 90)
			(unlocked yes)
			(layer "F.Fab")
			(hide yes)
			(effects
				(font
					(size 1.016 1.016)
					(thickness 0.1524)
				)
			)
		)
		(duplicate_pad_numbers_are_jumpers no)
		(fp_line
			(start 0.635 0)
			(end -0.635 0)
			(stroke
				(width 0.508)
				(type default)
			)
			(layer "F.SilkS")
		)
		(fp_rect
			(start -0.9652 1.778)
			(end 0.9652 -1.778)
			(stroke
				(width 0)
				(type default)
			)
			(fill no)
			(layer "F.CrtYd")
		)
		(fp_poly
			(pts
				(xy -0.9652 -1.778) (xy 0.9652 -1.778) (xy 0.9652 1.778) (xy -0.9652 1.778)
			)
			(stroke
				(width 0)
				(type default)
			)
			(fill no)
			(layer "F.Fab")
		)
		(pad "1" smd rect
			(at 0 -0.9652 90)
			(size 1.397 1.143)
			(layers "F.Cu" "F.Mask" "F.Paste")
			(net "MB0_P12V_PWRGOOD")
		)
		(pad "2" smd rect
			(at 0 0.9652 90)
			(size 1.397 1.143)
			(layers "F.Cu" "F.Mask" "F.Paste")
			(net "AGND_CURRENT_MON")
		)
	)
	(footprint ""
		(layer "F.Cu")
		(at 345.088718 -143.233648)
		(property "Reference" "C159"
			(at 0 0 0)
			(layer "F.SilkS")
			(hide yes)
			(effects
				(font
					(size 1.27 1.27)
				)
			)
		)
		(property "Value" "SC1U10V2KX-4-GP"
			(at 1.1811 -2.7051 0)
			(unlocked yes)
			(layer "F.Fab")
			(hide yes)
			(effects
				(font
					(size 1.016 1.016)
					(thickness 0.1524)
				)
			)
		)
		(property "Device Type" "C402H22"
			(at 1.1811 -4.2291 0)
			(unlocked yes)
			(layer "F.Fab")
			(hide yes)
			(effects
				(font
					(size 1.016 1.016)
					(thickness 0.1524)
				)
			)
		)
		(duplicate_pad_numbers_are_jumpers no)
		(fp_rect
			(start -0.4318 0.9525)
			(end 0.4318 -0.9525)
			(stroke
				(width 0)
				(type default)
			)
			(fill no)
			(layer "F.CrtYd")
		)
		(fp_rect
			(start -0.4318 0.9525)
			(end 0.4318 -0.9525)
			(stroke
				(width 0)
				(type default)
			)
			(fill no)
			(layer "F.Fab")
		)
		(pad "1" smd custom
			(at 0 -0.4445)
			(size 0.1524 0.1524)
			(layers "F.Cu" "F.Mask" "F.Paste")
			(net "PLLFILT")
			(options
				(clearance outline)
				(anchor circle)
			)
			(primitives
				(gr_poly
					(pts
						(arc
							(start 0.3048 -0.2032)
							(mid 0.275042 -0.275042)
							(end 0.2032 -0.3048)
						)
						(arc
							(start -0.2032 -0.3048)
							(mid -0.275042 -0.275042)
							(end -0.3048 -0.2032)
						)
						(arc
							(start -0.3048 0.2032)
							(mid -0.275042 0.275042)
							(end -0.2032 0.3048)
						)
						(arc
							(start 0.2032 0.3048)
							(mid 0.275042 0.275042)
							(end 0.3048 0.2032)
						)
					)
					(width 0)
					(fill yes)
				)
			)
		)
		(pad "2" smd custom
			(at 0 0.4445)
			(size 0.1524 0.1524)
			(layers "F.Cu" "F.Mask" "F.Paste")
			(net "GND")
			(options
				(clearance outline)
				(anchor circle)
			)
			(primitives
				(gr_poly
					(pts
						(arc
							(start 0.3048 -0.2032)
							(mid 0.275042 -0.275042)
							(end 0.2032 -0.3048)
						)
						(arc
							(start -0.2032 -0.3048)
							(mid -0.275042 -0.275042)
							(end -0.3048 -0.2032)
						)
						(arc
							(start -0.3048 0.2032)
							(mid -0.275042 0.275042)
							(end -0.2032 0.3048)
						)
						(arc
							(start 0.2032 0.3048)
							(mid 0.275042 0.275042)
							(end 0.3048 0.2032)
						)
					)
					(width 0)
					(fill yes)
				)
			)
		)
	)
	(footprint ""
		(layer "F.Cu")
		(at 79.888842 -133.269482 90)
		(property "Reference" "SC1101"
			(at 0 0 90)
			(layer "F.SilkS")
			(hide yes)
			(effects
				(font
					(size 1.27 1.27)
				)
			)
		)
		(property "Value" "SCD1U16V2KX-3GP"
			(at 1.1811 -2.7051 90)
			(unlocked yes)
			(layer "F.Fab")
			(hide yes)
			(effects
				(font
					(size 1.016 1.016)
					(thickness 0.1524)
				)
			)
		)
		(property "Device Type" "C402H22"
			(at 1.1811 -4.2291 90)
			(unlocked yes)
			(layer "F.Fab")
			(hide yes)
			(effects
				(font
					(size 1.016 1.016)
					(thickness 0.1524)
				)
			)
		)
		(duplicate_pad_numbers_are_jumpers no)
		(fp_rect
			(start -0.4318 0.9525)
			(end 0.4318 -0.9525)
			(stroke
				(width 0)
				(type default)
			)
			(fill no)
			(layer "F.CrtYd")
		)
		(fp_rect
			(start -0.4318 0.9525)
			(end 0.4318 -0.9525)
			(stroke
				(width 0)
				(type default)
			)
			(fill no)
			(layer "F.Fab")
		)
		(pad "1" smd custom
			(at 0 -0.4445 90)
			(size 0.1524 0.1524)
			(layers "F.Cu" "F.Mask" "F.Paste")
			(net "P3V3_STBY")
			(options
				(clearance outline)
				(anchor circle)
			)
			(primitives
				(gr_poly
					(pts
						(arc
							(start 0.3048 -0.2032)
							(mid 0.275042 -0.275042)
							(end 0.2032 -0.3048)
						)
						(arc
							(start -0.2032 -0.3048)
							(mid -0.275042 -0.275042)
							(end -0.3048 -0.2032)
						)
						(arc
							(start -0.3048 0.2032)
							(mid -0.275042 0.275042)
							(end -0.2032 0.3048)
						)
						(arc
							(start 0.2032 0.3048)
							(mid 0.275042 0.275042)
							(end 0.3048 0.2032)
						)
					)
					(width 0)
					(fill yes)
				)
			)
		)
		(pad "2" smd custom
			(at 0 0.4445 90)
			(size 0.1524 0.1524)
			(layers "F.Cu" "F.Mask" "F.Paste")
			(net "GND")
			(options
				(clearance outline)
				(anchor circle)
			)
			(primitives
				(gr_poly
					(pts
						(arc
							(start 0.3048 -0.2032)
							(mid 0.275042 -0.275042)
							(end 0.2032 -0.3048)
						)
						(arc
							(start -0.2032 -0.3048)
							(mid -0.275042 -0.275042)
							(end -0.3048 -0.2032)
						)
						(arc
							(start -0.3048 0.2032)
							(mid -0.275042 0.275042)
							(end -0.2032 0.3048)
						)
						(arc
							(start 0.2032 0.3048)
							(mid 0.275042 0.275042)
							(end 0.3048 0.2032)
						)
					)
					(width 0)
					(fill yes)
				)
			)
		)
	)
	(footprint ""
		(layer "F.Cu")
		(at 289.687 -70.739 90)
		(property "Reference" "PR6889"
			(at 0 0 90)
			(layer "F.SilkS")
			(hide yes)
			(effects
				(font
					(size 1.27 1.27)
				)
			)
		)
		(property "Value" "2K05R2F-GP"
			(at 0.064008 -3.993896 90)
			(unlocked yes)
			(layer "F.Fab")
			(hide yes)
			(effects
				(font
					(size 1.016 1.016)
					(thickness 0.1524)
				)
			)
		)
		(property "Device Type" "R402H16"
			(at 0.064008 -5.517896 90)
			(unlocked yes)
			(layer "F.Fab")
			(hide yes)
			(effects
				(font
					(size 1.016 1.016)
					(thickness 0.1524)
				)
			)
		)
		(duplicate_pad_numbers_are_jumpers no)
		(fp_line
			(start 0.508 -0.9398)
			(end -0.508 -0.9398)
			(stroke
				(width 0.1524)
				(type default)
			)
			(layer "F.SilkS")
		)
		(fp_line
			(start -0.508 -0.9398)
			(end -0.508 0.9398)
			(stroke
				(width 0.1524)
				(type default)
			)
			(layer "F.SilkS")
		)
		(fp_rect
			(start -0.508 0.9398)
			(end 0.508 -0.9398)
			(stroke
				(width 0)
				(type default)
			)
			(fill no)
			(layer "F.CrtYd")
		)
		(fp_rect
			(start -0.508 0.9398)
			(end 0.508 -0.9398)
			(stroke
				(width 0)
				(type default)
			)
			(fill no)
			(layer "F.Fab")
		)
		(pad "1" smd custom
			(at 0 -0.4445 90)
			(size 0.1397 0.1397)
			(layers "F.Cu" "F.Mask" "F.Paste")
			(net "HS_ADR")
			(options
				(clearance outline)
				(anchor circle)
			)
			(primitives
				(gr_poly
					(pts
						(arc
							(start -0.1778 -0.2794)
							(mid -0.249642 -0.249642)
							(end -0.2794 -0.1778)
						)
						(arc
							(start -0.2794 0.1778)
							(mid -0.249642 0.249642)
							(end -0.1778 0.2794)
						)
						(arc
							(start 0.1778 0.2794)
							(mid 0.249642 0.249642)
							(end 0.2794 0.1778)
						)
						(arc
							(start 0.2794 -0.1778)
							(mid 0.249642 -0.249642)
							(end 0.1778 -0.2794)
						)
					)
					(width 0)
					(fill yes)
				)
			)
		)
		(pad "2" smd custom
			(at 0 0.4445 90)
			(size 0.1397 0.1397)
			(layers "F.Cu" "F.Mask" "F.Paste")
			(net "GND")
			(options
				(clearance outline)
				(anchor circle)
			)
			(primitives
				(gr_poly
					(pts
						(arc
							(start -0.1778 -0.2794)
							(mid -0.249642 -0.249642)
							(end -0.2794 -0.1778)
						)
						(arc
							(start -0.2794 0.1778)
							(mid -0.249642 0.249642)
							(end -0.1778 0.2794)
						)
						(arc
							(start 0.1778 0.2794)
							(mid 0.249642 0.249642)
							(end 0.2794 0.1778)
						)
						(arc
							(start 0.2794 -0.1778)
							(mid 0.249642 -0.249642)
							(end 0.1778 -0.2794)
						)
					)
					(width 0)
					(fill yes)
				)
			)
		)
	)
	(footprint ""
		(layer "F.Cu")
		(at 68.834 -47.879 -90)
		(property "Reference" "SC935"
			(at 0 0 270)
			(layer "F.SilkS")
			(hide yes)
			(effects
				(font
					(size 1.27 1.27)
				)
			)
		)
		(property "Value" "SC22U6D3V5MX-2GP"
			(at -0.0762 -6.1214 270)
			(unlocked yes)
			(layer "F.Fab")
			(hide yes)
			(effects
				(font
					(size 1.016 1.016)
					(thickness 0.1524)
				)
			)
		)
		(property "Device Type" "C805H58"
			(at -0.0762 -8.1534 270)
			(unlocked yes)
			(layer "F.Fab")
			(hide yes)
			(effects
				(font
					(size 1.016 1.016)
					(thickness 0.1524)
				)
			)
		)
		(duplicate_pad_numbers_are_jumpers no)
		(fp_line
			(start 0.635 0)
			(end -0.635 0)
			(stroke
				(width 0.508)
				(type default)
			)
			(layer "F.SilkS")
		)
		(fp_rect
			(start -0.9652 1.778)
			(end 0.9652 -1.778)
			(stroke
				(width 0)
				(type default)
			)
			(fill no)
			(layer "F.CrtYd")
		)
		(fp_poly
			(pts
				(xy -0.9652 -1.778) (xy 0.9652 -1.778) (xy 0.9652 1.778) (xy -0.9652 1.778)
			)
			(stroke
				(width 0)
				(type default)
			)
			(fill no)
			(layer "F.Fab")
		)
		(pad "1" smd rect
			(at 0 -0.9652 270)
			(size 1.397 1.143)
			(layers "F.Cu" "F.Mask" "F.Paste")
			(net "SAS0_VDDH")
		)
		(pad "2" smd rect
			(at 0 0.9652 270)
			(size 1.397 1.143)
			(layers "F.Cu" "F.Mask" "F.Paste")
			(net "GND")
		)
	)
	(footprint ""
		(layer "F.Cu")
		(at 330.708 -118.491)
		(property "Reference" "PL2"
			(at 0 0 0)
			(layer "F.SilkS")
			(hide yes)
			(effects
				(font
					(size 1.27 1.27)
				)
			)
		)
		(property "Value" "BLM21PG220SN1DGP"
			(at 0.0254 -5.6896 0)
			(unlocked yes)
			(layer "F.Fab")
			(hide yes)
			(effects
				(font
					(size 1.016 1.016)
					(thickness 0.1524)
				)
			)
		)
		(property "Device Type" "L20125H42"
			(at 0.0254 -7.5946 0)
			(unlocked yes)
			(layer "F.Fab")
			(hide yes)
			(effects
				(font
					(size 1.016 1.016)
					(thickness 0.1524)
				)
			)
		)
		(duplicate_pad_numbers_are_jumpers no)
		(fp_line
			(start -0.9144 -1.7018)
			(end -0.9144 1.7018)
			(stroke
				(width 0.1524)
				(type default)
			)
			(layer "F.SilkS")
		)
		(fp_line
			(start -0.9144 1.7018)
			(end 0.9144 1.7018)
			(stroke
				(width 0.1524)
				(type default)
			)
			(layer "F.SilkS")
		)
		(fp_line
			(start 0.9144 -1.7018)
			(end -0.9144 -1.7018)
			(stroke
				(width 0.1524)
				(type default)
			)
			(layer "F.SilkS")
		)
		(fp_line
			(start 0.9144 1.7018)
			(end 0.9144 -1.7018)
			(stroke
				(width 0.1524)
				(type default)
			)
			(layer "F.SilkS")
		)
		(fp_rect
			(start -1.0033 1.778)
			(end 1.0033 -1.778)
			(stroke
				(width 0)
				(type default)
			)
			(fill no)
			(layer "F.CrtYd")
		)
		(fp_poly
			(pts
				(xy -1.0033 -1.778) (xy 1.0033 -1.778) (xy 1.0033 1.778) (xy -1.0033 1.778)
			)
			(stroke
				(width 0)
				(type default)
			)
			(fill no)
			(layer "F.Fab")
		)
		(pad "1" smd rect
			(at 0 -0.9652)
			(size 1.397 1.143)
			(layers "F.Cu" "F.Mask" "F.Paste")
			(net "P12V")
		)
		(pad "2" smd rect
			(at 0 0.9652)
			(size 1.397 1.143)
			(layers "F.Cu" "F.Mask" "F.Paste")
			(net "P3V3_STBY_VIN")
		)
	)
	(footprint ""
		(layer "F.Cu")
		(at 105.7148 -62.3062)
		(property "Reference" "STP59"
			(at 0 0 0)
			(layer "F.SilkS")
			(hide yes)
			(effects
				(font
					(size 1.27 1.27)
				)
			)
		)
		(property "Value" "TPAD28"
			(at 0.0127 -1.8034 0)
			(unlocked yes)
			(layer "F.Fab")
			(hide yes)
			(effects
				(font
					(size 1.016 1.016)
					(thickness 0.1524)
				)
			)
		)
		(property "Device Type" "TPAD28"
			(at 0.0127 -3.3274 0)
			(unlocked yes)
			(layer "F.Fab")
			(hide yes)
			(effects
				(font
					(size 1.016 1.016)
					(thickness 0.1524)
				)
			)
		)
		(duplicate_pad_numbers_are_jumpers no)
		(fp_poly
			(pts
				(arc
					(start 0.3556 0)
					(mid -0.3556 0)
					(end 0.3556 0)
				)
			)
			(stroke
				(width 0)
				(type default)
			)
			(fill no)
			(layer "F.CrtYd")
		)
		(fp_poly
			(pts
				(arc
					(start 0.6096 0)
					(mid -0.6096 0)
					(end 0.6096 0)
				)
			)
			(stroke
				(width 0)
				(type default)
			)
			(fill no)
			(layer "F.Fab")
		)
		(pad "1" smd circle
			(at 0 0)
			(size 0.7112 0.7112)
			(layers "F.Cu" "F.Mask" "F.Paste")
			(net "IOC_TRST_N")
		)
	)
	(footprint ""
		(layer "F.Cu")
		(at 274.193 -166.624 90)
		(property "Reference" "R539"
			(at 0 0 90)
			(layer "F.SilkS")
			(hide yes)
			(effects
				(font
					(size 1.27 1.27)
				)
			)
		)
		(property "Value" "0R2J-2-GP"
			(at 0.064008 -3.993896 90)
			(unlocked yes)
			(layer "F.Fab")
			(hide yes)
			(effects
				(font
					(size 1.016 1.016)
					(thickness 0.1524)
				)
			)
		)
		(property "Device Type" "R402H16"
			(at 0.064008 -5.517896 90)
			(unlocked yes)
			(layer "F.Fab")
			(hide yes)
			(effects
				(font
					(size 1.016 1.016)
					(thickness 0.1524)
				)
			)
		)
		(duplicate_pad_numbers_are_jumpers no)
		(fp_line
			(start 0.508 -0.9398)
			(end -0.508 -0.9398)
			(stroke
				(width 0.1524)
				(type default)
			)
			(layer "F.SilkS")
		)
		(fp_line
			(start -0.508 -0.9398)
			(end -0.508 0.9398)
			(stroke
				(width 0.1524)
				(type default)
			)
			(layer "F.SilkS")
		)
		(fp_rect
			(start -0.508 0.9398)
			(end 0.508 -0.9398)
			(stroke
				(width 0)
				(type default)
			)
			(fill no)
			(layer "F.CrtYd")
		)
		(fp_rect
			(start -0.508 0.9398)
			(end 0.508 -0.9398)
			(stroke
				(width 0)
				(type default)
			)
			(fill no)
			(layer "F.Fab")
		)
		(pad "1" smd custom
			(at 0 -0.4445 90)
			(size 0.1397 0.1397)
			(layers "F.Cu" "F.Mask" "F.Paste")
			(net "PG_STAT_P0V955_C")
			(options
				(clearance outline)
				(anchor circle)
			)
			(primitives
				(gr_poly
					(pts
						(arc
							(start -0.1778 -0.2794)
							(mid -0.249642 -0.249642)
							(end -0.2794 -0.1778)
						)
						(arc
							(start -0.2794 0.1778)
							(mid -0.249642 0.249642)
							(end -0.1778 0.2794)
						)
						(arc
							(start 0.1778 0.2794)
							(mid 0.249642 0.249642)
							(end 0.2794 0.1778)
						)
						(arc
							(start 0.2794 -0.1778)
							(mid 0.249642 -0.249642)
							(end 0.1778 -0.2794)
						)
					)
					(width 0)
					(fill yes)
				)
			)
		)
		(pad "2" smd custom
			(at 0 0.4445 90)
			(size 0.1397 0.1397)
			(layers "F.Cu" "F.Mask" "F.Paste")
			(net "PWGD_P0V955_C_PG_R")
			(options
				(clearance outline)
				(anchor circle)
			)
			(primitives
				(gr_poly
					(pts
						(arc
							(start -0.1778 -0.2794)
							(mid -0.249642 -0.249642)
							(end -0.2794 -0.1778)
						)
						(arc
							(start -0.2794 0.1778)
							(mid -0.249642 0.249642)
							(end -0.1778 0.2794)
						)
						(arc
							(start 0.1778 0.2794)
							(mid 0.249642 0.249642)
							(end 0.2794 0.1778)
						)
						(arc
							(start 0.2794 -0.1778)
							(mid 0.249642 -0.249642)
							(end 0.1778 -0.2794)
						)
					)
					(width 0)
					(fill yes)
				)
			)
		)
	)
	(footprint ""
		(layer "F.Cu")
		(at 201.549 -185.547)
		(property "Reference" "C304"
			(at 0 0 0)
			(layer "F.SilkS")
			(hide yes)
			(effects
				(font
					(size 1.27 1.27)
				)
			)
		)
		(property "Value" "SC1U10V3KX-4GP-U"
			(at 0 -2.8194 0)
			(unlocked yes)
			(layer "F.Fab")
			(hide yes)
			(effects
				(font
					(size 1.016 1.016)
					(thickness 0.1524)
				)
			)
		)
		(property "Device Type" "C603H36"
			(at 0 -4.3434 0)
			(unlocked yes)
			(layer "F.Fab")
			(hide yes)
			(effects
				(font
					(size 1.016 1.016)
					(thickness 0.1524)
				)
			)
		)
		(duplicate_pad_numbers_are_jumpers no)
		(fp_line
			(start 0.508 0)
			(end -0.508 0)
			(stroke
				(width 0.2032)
				(type default)
			)
			(layer "F.SilkS")
		)
		(fp_rect
			(start -0.5842 1.3335)
			(end 0.5842 -1.3335)
			(stroke
				(width 0)
				(type default)
			)
			(fill no)
			(layer "F.CrtYd")
		)
		(fp_rect
			(start -0.5842 1.3335)
			(end 0.5842 -1.3335)
			(stroke
				(width 0)
				(type default)
			)
			(fill no)
			(layer "F.Fab")
		)
		(pad "1" smd custom
			(at 0 -0.762)
			(size 0.2159 0.2159)
			(layers "F.Cu" "F.Mask" "F.Paste")
			(net "HB_A_IN")
			(options
				(clearance outline)
				(anchor circle)
			)
			(primitives
				(gr_poly
					(pts
						(arc
							(start -0.3302 -0.4318)
							(mid -0.402042 -0.402042)
							(end -0.4318 -0.3302)
						)
						(arc
							(start -0.4318 0.3302)
							(mid -0.402042 0.402042)
							(end -0.3302 0.4318)
						)
						(arc
							(start 0.3302 0.4318)
							(mid 0.402042 0.402042)
							(end 0.4318 0.3302)
						)
						(arc
							(start 0.4318 -0.3302)
							(mid 0.402042 -0.402042)
							(end 0.3302 -0.4318)
						)
					)
					(width 0)
					(fill yes)
				)
			)
		)
		(pad "2" smd custom
			(at 0 0.762)
			(size 0.2159 0.2159)
			(layers "F.Cu" "F.Mask" "F.Paste")
			(net "GND")
			(options
				(clearance outline)
				(anchor circle)
			)
			(primitives
				(gr_poly
					(pts
						(arc
							(start -0.3302 -0.4318)
							(mid -0.402042 -0.402042)
							(end -0.4318 -0.3302)
						)
						(arc
							(start -0.4318 0.3302)
							(mid -0.402042 0.402042)
							(end -0.3302 0.4318)
						)
						(arc
							(start 0.3302 0.4318)
							(mid 0.402042 0.402042)
							(end 0.4318 0.3302)
						)
						(arc
							(start 0.4318 -0.3302)
							(mid 0.402042 -0.402042)
							(end 0.3302 -0.4318)
						)
					)
					(width 0)
					(fill yes)
				)
			)
		)
	)
	(footprint ""
		(layer "F.Cu")
		(at 339.716872 -171.395136 180)
		(property "Reference" "R277"
			(at 0 0 180)
			(layer "F.SilkS")
			(hide yes)
			(effects
				(font
					(size 1.27 1.27)
				)
			)
		)
		(property "Value" "0R2J-2-GP"
			(at 0.064008 -3.993896 180)
			(unlocked yes)
			(layer "F.Fab")
			(hide yes)
			(effects
				(font
					(size 1.016 1.016)
					(thickness 0.1524)
				)
			)
		)
		(property "Device Type" "R402H16"
			(at 0.064008 -5.517896 180)
			(unlocked yes)
			(layer "F.Fab")
			(hide yes)
			(effects
				(font
					(size 1.016 1.016)
					(thickness 0.1524)
				)
			)
		)
		(duplicate_pad_numbers_are_jumpers no)
		(fp_line
			(start 0.508 -0.9398)
			(end -0.508 -0.9398)
			(stroke
				(width 0.1524)
				(type default)
			)
			(layer "F.SilkS")
		)
		(fp_line
			(start -0.508 -0.9398)
			(end -0.508 0.9398)
			(stroke
				(width 0.1524)
				(type default)
			)
			(layer "F.SilkS")
		)
		(fp_rect
			(start -0.508 0.9398)
			(end 0.508 -0.9398)
			(stroke
				(width 0)
				(type default)
			)
			(fill no)
			(layer "F.CrtYd")
		)
		(fp_rect
			(start -0.508 0.9398)
			(end 0.508 -0.9398)
			(stroke
				(width 0)
				(type default)
			)
			(fill no)
			(layer "F.Fab")
		)
		(pad "1" smd custom
			(at 0 -0.4445 180)
			(size 0.1397 0.1397)
			(layers "F.Cu" "F.Mask" "F.Paste")
			(net "BMC_UART_SWITCH_R")
			(options
				(clearance outline)
				(anchor circle)
			)
			(primitives
				(gr_poly
					(pts
						(arc
							(start -0.1778 -0.2794)
							(mid -0.249642 -0.249642)
							(end -0.2794 -0.1778)
						)
						(arc
							(start -0.2794 0.1778)
							(mid -0.249642 0.249642)
							(end -0.1778 0.2794)
						)
						(arc
							(start 0.1778 0.2794)
							(mid 0.249642 0.249642)
							(end 0.2794 0.1778)
						)
						(arc
							(start 0.2794 -0.1778)
							(mid 0.249642 -0.249642)
							(end 0.1778 -0.2794)
						)
					)
					(width 0)
					(fill yes)
				)
			)
		)
		(pad "2" smd custom
			(at 0 0.4445 180)
			(size 0.1397 0.1397)
			(layers "F.Cu" "F.Mask" "F.Paste")
			(net "BMC_UART_SWITCH_2")
			(options
				(clearance outline)
				(anchor circle)
			)
			(primitives
				(gr_poly
					(pts
						(arc
							(start -0.1778 -0.2794)
							(mid -0.249642 -0.249642)
							(end -0.2794 -0.1778)
						)
						(arc
							(start -0.2794 0.1778)
							(mid -0.249642 0.249642)
							(end -0.1778 0.2794)
						)
						(arc
							(start 0.1778 0.2794)
							(mid 0.249642 0.249642)
							(end 0.2794 0.1778)
						)
						(arc
							(start 0.2794 -0.1778)
							(mid 0.249642 -0.249642)
							(end 0.1778 -0.2794)
						)
					)
					(width 0)
					(fill yes)
				)
			)
		)
	)
	(footprint ""
		(layer "F.Cu")
		(at 119.64797 -76.581 -90)
		(property "Reference" "SC1125"
			(at 0 0 270)
			(layer "F.SilkS")
			(hide yes)
			(effects
				(font
					(size 1.27 1.27)
				)
			)
		)
		(property "Value" "SC12P50V2JN-3GP"
			(at 1.1811 -2.7051 270)
			(unlocked yes)
			(layer "F.Fab")
			(hide yes)
			(effects
				(font
					(size 1.016 1.016)
					(thickness 0.1524)
				)
			)
		)
		(property "Device Type" "C402H24"
			(at 1.1811 -4.2291 270)
			(unlocked yes)
			(layer "F.Fab")
			(hide yes)
			(effects
				(font
					(size 1.016 1.016)
					(thickness 0.1524)
				)
			)
		)
		(duplicate_pad_numbers_are_jumpers no)
		(fp_rect
			(start -0.4318 0.9525)
			(end 0.4318 -0.9525)
			(stroke
				(width 0)
				(type default)
			)
			(fill no)
			(layer "F.CrtYd")
		)
		(fp_rect
			(start -0.4318 0.9525)
			(end 0.4318 -0.9525)
			(stroke
				(width 0)
				(type default)
			)
			(fill no)
			(layer "F.Fab")
		)
		(pad "1" smd custom
			(at 0 -0.4445 270)
			(size 0.1524 0.1524)
			(layers "F.Cu" "F.Mask" "F.Paste")
			(net "EXP_REF_CLK_N_R")
			(options
				(clearance outline)
				(anchor circle)
			)
			(primitives
				(gr_poly
					(pts
						(arc
							(start 0.3048 -0.2032)
							(mid 0.275042 -0.275042)
							(end 0.2032 -0.3048)
						)
						(arc
							(start -0.2032 -0.3048)
							(mid -0.275042 -0.275042)
							(end -0.3048 -0.2032)
						)
						(arc
							(start -0.3048 0.2032)
							(mid -0.275042 0.275042)
							(end -0.2032 0.3048)
						)
						(arc
							(start 0.2032 0.3048)
							(mid 0.275042 0.275042)
							(end 0.3048 0.2032)
						)
					)
					(width 0)
					(fill yes)
				)
			)
		)
		(pad "2" smd custom
			(at 0 0.4445 270)
			(size 0.1524 0.1524)
			(layers "F.Cu" "F.Mask" "F.Paste")
			(net "GND")
			(options
				(clearance outline)
				(anchor circle)
			)
			(primitives
				(gr_poly
					(pts
						(arc
							(start 0.3048 -0.2032)
							(mid 0.275042 -0.275042)
							(end 0.2032 -0.3048)
						)
						(arc
							(start -0.2032 -0.3048)
							(mid -0.275042 -0.275042)
							(end -0.3048 -0.2032)
						)
						(arc
							(start -0.3048 0.2032)
							(mid -0.275042 0.275042)
							(end -0.2032 0.3048)
						)
						(arc
							(start 0.2032 0.3048)
							(mid 0.275042 0.275042)
							(end 0.3048 0.2032)
						)
					)
					(width 0)
					(fill yes)
				)
			)
		)
	)
	(footprint ""
		(layer "F.Cu")
		(at 44.638722 -136.498584 -90)
		(property "Reference" "SC1122"
			(at 0 0 270)
			(layer "F.SilkS")
			(hide yes)
			(effects
				(font
					(size 1.27 1.27)
				)
			)
		)
		(property "Value" "SCD1U16V2KX-3GP"
			(at 1.1811 -2.7051 270)
			(unlocked yes)
			(layer "F.Fab")
			(hide yes)
			(effects
				(font
					(size 1.016 1.016)
					(thickness 0.1524)
				)
			)
		)
		(property "Device Type" "C402H22"
			(at 1.1811 -4.2291 270)
			(unlocked yes)
			(layer "F.Fab")
			(hide yes)
			(effects
				(font
					(size 1.016 1.016)
					(thickness 0.1524)
				)
			)
		)
		(duplicate_pad_numbers_are_jumpers no)
		(fp_rect
			(start -0.4318 0.9525)
			(end 0.4318 -0.9525)
			(stroke
				(width 0)
				(type default)
			)
			(fill no)
			(layer "F.CrtYd")
		)
		(fp_rect
			(start -0.4318 0.9525)
			(end 0.4318 -0.9525)
			(stroke
				(width 0)
				(type default)
			)
			(fill no)
			(layer "F.Fab")
		)
		(pad "1" smd custom
			(at 0 -0.4445 270)
			(size 0.1524 0.1524)
			(layers "F.Cu" "F.Mask" "F.Paste")
			(net "P1V8_STBY")
			(options
				(clearance outline)
				(anchor circle)
			)
			(primitives
				(gr_poly
					(pts
						(arc
							(start 0.3048 -0.2032)
							(mid 0.275042 -0.275042)
							(end 0.2032 -0.3048)
						)
						(arc
							(start -0.2032 -0.3048)
							(mid -0.275042 -0.275042)
							(end -0.3048 -0.2032)
						)
						(arc
							(start -0.3048 0.2032)
							(mid -0.275042 0.275042)
							(end -0.2032 0.3048)
						)
						(arc
							(start 0.2032 0.3048)
							(mid 0.275042 0.275042)
							(end 0.3048 0.2032)
						)
					)
					(width 0)
					(fill yes)
				)
			)
		)
		(pad "2" smd custom
			(at 0 0.4445 270)
			(size 0.1524 0.1524)
			(layers "F.Cu" "F.Mask" "F.Paste")
			(net "GND")
			(options
				(clearance outline)
				(anchor circle)
			)
			(primitives
				(gr_poly
					(pts
						(arc
							(start 0.3048 -0.2032)
							(mid 0.275042 -0.275042)
							(end 0.2032 -0.3048)
						)
						(arc
							(start -0.2032 -0.3048)
							(mid -0.275042 -0.275042)
							(end -0.3048 -0.2032)
						)
						(arc
							(start -0.3048 0.2032)
							(mid -0.275042 0.275042)
							(end -0.2032 0.3048)
						)
						(arc
							(start 0.2032 0.3048)
							(mid 0.275042 0.275042)
							(end 0.3048 0.2032)
						)
					)
					(width 0)
					(fill yes)
				)
			)
		)
	)
	(footprint ""
		(layer "F.Cu")
		(at 18.873216 -213.79688 180)
		(property "Reference" "SR305"
			(at 0 0 180)
			(layer "F.SilkS")
			(hide yes)
			(effects
				(font
					(size 1.27 1.27)
				)
			)
		)
		(property "Value" "0R2J-2-GP"
			(at 0.064008 -3.993896 180)
			(unlocked yes)
			(layer "F.Fab")
			(hide yes)
			(effects
				(font
					(size 1.016 1.016)
					(thickness 0.1524)
				)
			)
		)
		(property "Device Type" "R402H16"
			(at 0.064008 -5.517896 180)
			(unlocked yes)
			(layer "F.Fab")
			(hide yes)
			(effects
				(font
					(size 1.016 1.016)
					(thickness 0.1524)
				)
			)
		)
		(duplicate_pad_numbers_are_jumpers no)
		(fp_line
			(start 0.508 -0.9398)
			(end -0.508 -0.9398)
			(stroke
				(width 0.1524)
				(type default)
			)
			(layer "F.SilkS")
		)
		(fp_line
			(start -0.508 -0.9398)
			(end -0.508 0.9398)
			(stroke
				(width 0.1524)
				(type default)
			)
			(layer "F.SilkS")
		)
		(fp_rect
			(start -0.508 0.9398)
			(end 0.508 -0.9398)
			(stroke
				(width 0)
				(type default)
			)
			(fill no)
			(layer "F.CrtYd")
		)
		(fp_rect
			(start -0.508 0.9398)
			(end 0.508 -0.9398)
			(stroke
				(width 0)
				(type default)
			)
			(fill no)
			(layer "F.Fab")
		)
		(pad "1" smd custom
			(at 0 -0.4445 180)
			(size 0.1397 0.1397)
			(layers "F.Cu" "F.Mask" "F.Paste")
			(net "I2C_IO_EXP_RESET#")
			(options
				(clearance outline)
				(anchor circle)
			)
			(primitives
				(gr_poly
					(pts
						(arc
							(start -0.1778 -0.2794)
							(mid -0.249642 -0.249642)
							(end -0.2794 -0.1778)
						)
						(arc
							(start -0.2794 0.1778)
							(mid -0.249642 0.249642)
							(end -0.1778 0.2794)
						)
						(arc
							(start 0.1778 0.2794)
							(mid 0.249642 0.249642)
							(end 0.2794 0.1778)
						)
						(arc
							(start 0.2794 -0.1778)
							(mid 0.249642 -0.249642)
							(end 0.1778 -0.2794)
						)
					)
					(width 0)
					(fill yes)
				)
			)
		)
		(pad "2" smd custom
			(at 0 0.4445 180)
			(size 0.1397 0.1397)
			(layers "F.Cu" "F.Mask" "F.Paste")
			(net "I2C_IO_EXP_RESET#_PWR")
			(options
				(clearance outline)
				(anchor circle)
			)
			(primitives
				(gr_poly
					(pts
						(arc
							(start -0.1778 -0.2794)
							(mid -0.249642 -0.249642)
							(end -0.2794 -0.1778)
						)
						(arc
							(start -0.2794 0.1778)
							(mid -0.249642 0.249642)
							(end -0.1778 0.2794)
						)
						(arc
							(start 0.1778 0.2794)
							(mid 0.249642 0.249642)
							(end 0.2794 0.1778)
						)
						(arc
							(start 0.2794 -0.1778)
							(mid 0.249642 -0.249642)
							(end 0.1778 -0.2794)
						)
					)
					(width 0)
					(fill yes)
				)
			)
		)
	)
	(footprint ""
		(layer "F.Cu")
		(at 333.883 -10.541)
		(property "Reference" "R86"
			(at 0 0 0)
			(layer "F.SilkS")
			(hide yes)
			(effects
				(font
					(size 1.27 1.27)
				)
			)
		)
		(property "Value" "150R2F-1-GP"
			(at 0.064008 -3.993896 0)
			(unlocked yes)
			(layer "F.Fab")
			(hide yes)
			(effects
				(font
					(size 1.016 1.016)
					(thickness 0.1524)
				)
			)
		)
		(property "Device Type" "R402H16"
			(at 0.064008 -5.517896 0)
			(unlocked yes)
			(layer "F.Fab")
			(hide yes)
			(effects
				(font
					(size 1.016 1.016)
					(thickness 0.1524)
				)
			)
		)
		(duplicate_pad_numbers_are_jumpers no)
		(fp_line
			(start -0.508 -0.9398)
			(end -0.508 0.9398)
			(stroke
				(width 0.1524)
				(type default)
			)
			(layer "F.SilkS")
		)
		(fp_line
			(start 0.508 -0.9398)
			(end -0.508 -0.9398)
			(stroke
				(width 0.1524)
				(type default)
			)
			(layer "F.SilkS")
		)
		(fp_rect
			(start -0.508 0.9398)
			(end 0.508 -0.9398)
			(stroke
				(width 0)
				(type default)
			)
			(fill no)
			(layer "F.CrtYd")
		)
		(fp_rect
			(start -0.508 0.9398)
			(end 0.508 -0.9398)
			(stroke
				(width 0)
				(type default)
			)
			(fill no)
			(layer "F.Fab")
		)
		(pad "1" smd custom
			(at 0 -0.4445)
			(size 0.1397 0.1397)
			(layers "F.Cu" "F.Mask" "F.Paste")
			(net "P3V3_STBY")
			(options
				(clearance outline)
				(anchor circle)
			)
			(primitives
				(gr_poly
					(pts
						(arc
							(start -0.1778 -0.2794)
							(mid -0.249642 -0.249642)
							(end -0.2794 -0.1778)
						)
						(arc
							(start -0.2794 0.1778)
							(mid -0.249642 0.249642)
							(end -0.1778 0.2794)
						)
						(arc
							(start 0.1778 0.2794)
							(mid 0.249642 0.249642)
							(end 0.2794 0.1778)
						)
						(arc
							(start 0.2794 -0.1778)
							(mid 0.249642 -0.249642)
							(end 0.1778 -0.2794)
						)
					)
					(width 0)
					(fill yes)
				)
			)
		)
		(pad "2" smd custom
			(at 0 0.4445)
			(size 0.1397 0.1397)
			(layers "F.Cu" "F.Mask" "F.Paste")
			(net "CONSOLE_LED_1")
			(options
				(clearance outline)
				(anchor circle)
			)
			(primitives
				(gr_poly
					(pts
						(arc
							(start -0.1778 -0.2794)
							(mid -0.249642 -0.249642)
							(end -0.2794 -0.1778)
						)
						(arc
							(start -0.2794 0.1778)
							(mid -0.249642 0.249642)
							(end -0.1778 0.2794)
						)
						(arc
							(start 0.1778 0.2794)
							(mid 0.249642 0.249642)
							(end 0.2794 0.1778)
						)
						(arc
							(start 0.2794 -0.1778)
							(mid 0.249642 -0.249642)
							(end 0.1778 -0.2794)
						)
					)
					(width 0)
					(fill yes)
				)
			)
		)
	)
	(footprint ""
		(layer "F.Cu")
		(at 90.683842 -121.483882 90)
		(property "Reference" "SR753"
			(at 0 0 90)
			(layer "F.SilkS")
			(hide yes)
			(effects
				(font
					(size 1.27 1.27)
				)
			)
		)
		(property "Value" "4K7R2F-GP"
			(at 0.064008 -3.993896 90)
			(unlocked yes)
			(layer "F.Fab")
			(hide yes)
			(effects
				(font
					(size 1.016 1.016)
					(thickness 0.1524)
				)
			)
		)
		(property "Device Type" "R402H16"
			(at 0.064008 -5.517896 90)
			(unlocked yes)
			(layer "F.Fab")
			(hide yes)
			(effects
				(font
					(size 1.016 1.016)
					(thickness 0.1524)
				)
			)
		)
		(duplicate_pad_numbers_are_jumpers no)
		(fp_line
			(start 0.508 -0.9398)
			(end -0.508 -0.9398)
			(stroke
				(width 0.1524)
				(type default)
			)
			(layer "F.SilkS")
		)
		(fp_line
			(start -0.508 -0.9398)
			(end -0.508 0.9398)
			(stroke
				(width 0.1524)
				(type default)
			)
			(layer "F.SilkS")
		)
		(fp_rect
			(start -0.508 0.9398)
			(end 0.508 -0.9398)
			(stroke
				(width 0)
				(type default)
			)
			(fill no)
			(layer "F.CrtYd")
		)
		(fp_rect
			(start -0.508 0.9398)
			(end 0.508 -0.9398)
			(stroke
				(width 0)
				(type default)
			)
			(fill no)
			(layer "F.Fab")
		)
		(pad "1" smd custom
			(at 0 -0.4445 90)
			(size 0.1397 0.1397)
			(layers "F.Cu" "F.Mask" "F.Paste")
			(net "BMC_I2C_F_SCL")
			(options
				(clearance outline)
				(anchor circle)
			)
			(primitives
				(gr_poly
					(pts
						(arc
							(start -0.1778 -0.2794)
							(mid -0.249642 -0.249642)
							(end -0.2794 -0.1778)
						)
						(arc
							(start -0.2794 0.1778)
							(mid -0.249642 0.249642)
							(end -0.1778 0.2794)
						)
						(arc
							(start 0.1778 0.2794)
							(mid 0.249642 0.249642)
							(end 0.2794 0.1778)
						)
						(arc
							(start 0.2794 -0.1778)
							(mid 0.249642 -0.249642)
							(end 0.1778 -0.2794)
						)
					)
					(width 0)
					(fill yes)
				)
			)
		)
		(pad "2" smd custom
			(at 0 0.4445 90)
			(size 0.1397 0.1397)
			(layers "F.Cu" "F.Mask" "F.Paste")
			(net "P3V3_STBY")
			(options
				(clearance outline)
				(anchor circle)
			)
			(primitives
				(gr_poly
					(pts
						(arc
							(start -0.1778 -0.2794)
							(mid -0.249642 -0.249642)
							(end -0.2794 -0.1778)
						)
						(arc
							(start -0.2794 0.1778)
							(mid -0.249642 0.249642)
							(end -0.1778 0.2794)
						)
						(arc
							(start 0.1778 0.2794)
							(mid 0.249642 0.249642)
							(end 0.2794 0.1778)
						)
						(arc
							(start 0.2794 -0.1778)
							(mid 0.249642 -0.249642)
							(end 0.1778 -0.2794)
						)
					)
					(width 0)
					(fill yes)
				)
			)
		)
	)
	(footprint ""
		(layer "F.Cu")
		(at 195.706492 -180.226716)
		(property "Reference" "R482"
			(at 0 0 0)
			(layer "F.SilkS")
			(hide yes)
			(effects
				(font
					(size 1.27 1.27)
				)
			)
		)
		(property "Value" "0R2J-2-GP"
			(at 0.064008 -3.993896 0)
			(unlocked yes)
			(layer "F.Fab")
			(hide yes)
			(effects
				(font
					(size 1.016 1.016)
					(thickness 0.1524)
				)
			)
		)
		(property "Device Type" "R402H16"
			(at 0.064008 -5.517896 0)
			(unlocked yes)
			(layer "F.Fab")
			(hide yes)
			(effects
				(font
					(size 1.016 1.016)
					(thickness 0.1524)
				)
			)
		)
		(duplicate_pad_numbers_are_jumpers no)
		(fp_line
			(start -0.508 -0.9398)
			(end -0.508 0.9398)
			(stroke
				(width 0.1524)
				(type default)
			)
			(layer "F.SilkS")
		)
		(fp_line
			(start 0.508 -0.9398)
			(end -0.508 -0.9398)
			(stroke
				(width 0.1524)
				(type default)
			)
			(layer "F.SilkS")
		)
		(fp_rect
			(start -0.508 0.9398)
			(end 0.508 -0.9398)
			(stroke
				(width 0)
				(type default)
			)
			(fill no)
			(layer "F.CrtYd")
		)
		(fp_rect
			(start -0.508 0.9398)
			(end 0.508 -0.9398)
			(stroke
				(width 0)
				(type default)
			)
			(fill no)
			(layer "F.Fab")
		)
		(pad "1" smd custom
			(at 0 -0.4445)
			(size 0.1397 0.1397)
			(layers "F.Cu" "F.Mask" "F.Paste")
			(net "HB_A_OUT")
			(options
				(clearance outline)
				(anchor circle)
			)
			(primitives
				(gr_poly
					(pts
						(arc
							(start -0.1778 -0.2794)
							(mid -0.249642 -0.249642)
							(end -0.2794 -0.1778)
						)
						(arc
							(start -0.2794 0.1778)
							(mid -0.249642 0.249642)
							(end -0.1778 0.2794)
						)
						(arc
							(start 0.1778 0.2794)
							(mid 0.249642 0.249642)
							(end 0.2794 0.1778)
						)
						(arc
							(start 0.2794 -0.1778)
							(mid 0.249642 -0.249642)
							(end 0.1778 -0.2794)
						)
					)
					(width 0)
					(fill yes)
				)
			)
		)
		(pad "2" smd custom
			(at 0 0.4445)
			(size 0.1397 0.1397)
			(layers "F.Cu" "F.Mask" "F.Paste")
			(net "INVERTER_G1")
			(options
				(clearance outline)
				(anchor circle)
			)
			(primitives
				(gr_poly
					(pts
						(arc
							(start -0.1778 -0.2794)
							(mid -0.249642 -0.249642)
							(end -0.2794 -0.1778)
						)
						(arc
							(start -0.2794 0.1778)
							(mid -0.249642 0.249642)
							(end -0.1778 0.2794)
						)
						(arc
							(start 0.1778 0.2794)
							(mid 0.249642 0.249642)
							(end 0.2794 0.1778)
						)
						(arc
							(start 0.2794 -0.1778)
							(mid 0.249642 -0.249642)
							(end 0.1778 -0.2794)
						)
					)
					(width 0)
					(fill yes)
				)
			)
		)
	)
	(footprint ""
		(layer "F.Cu")
		(at 297.163236 -154.221688 90)
		(property "Reference" "U21"
			(at 0 0 90)
			(layer "F.SilkS")
			(hide yes)
			(effects
				(font
					(size 1.27 1.27)
				)
			)
		)
		(property "Value" "ICS551MLFT-GP"
			(at -3.707384 -1.5367 90)
			(unlocked yes)
			(layer "F.Fab")
			(hide yes)
			(effects
				(font
					(size 1.016 1.016)
					(thickness 0.1524)
				)
			)
		)
		(property "Device Type" "SOIC8H69"
			(at -3.707384 -3.0607 90)
			(unlocked yes)
			(layer "F.Fab")
			(hide yes)
			(effects
				(font
					(size 1.016 1.016)
					(thickness 0.1524)
				)
			)
		)
		(duplicate_pad_numbers_are_jumpers no)
		(fp_line
			(start 2.1336 -1.4224)
			(end -2.7432 -1.4224)
			(stroke
				(width 0.1524)
				(type default)
			)
			(layer "F.SilkS")
		)
		(fp_line
			(start -2.7432 -1.4224)
			(end -2.7432 1.4224)
			(stroke
				(width 0.1524)
				(type default)
			)
			(layer "F.SilkS")
		)
		(fp_line
			(start -2.7178 -0.508)
			(end -2.1844 -0.0508)
			(stroke
				(width 0.1524)
				(type default)
			)
			(layer "F.SilkS")
		)
		(fp_line
			(start -2.1844 -0.0508)
			(end -2.7178 0.508)
			(stroke
				(width 0.1524)
				(type default)
			)
			(layer "F.SilkS")
		)
		(fp_line
			(start 2.1336 1.4224)
			(end 2.1336 -1.4224)
			(stroke
				(width 0.1524)
				(type default)
			)
			(layer "F.SilkS")
		)
		(fp_line
			(start -2.7432 1.4224)
			(end 2.1336 1.4224)
			(stroke
				(width 0.1524)
				(type default)
			)
			(layer "F.SilkS")
		)
		(fp_line
			(start -2.7432 1.4224)
			(end -2.6416 1.4224)
			(stroke
				(width 0.1524)
				(type default)
			)
			(layer "F.SilkS")
		)
		(fp_line
			(start -2.6289 3.4417)
			(end -2.6289 1.4732)
			(stroke
				(width 0.381)
				(type default)
			)
			(layer "F.SilkS")
		)
		(fp_poly
			(pts
				(xy -2.2098 -1.4224) (xy -2.2098 1.4224) (xy 2.2098 1.4224) (xy 2.2098 -1.4224)
			)
			(stroke
				(width 0)
				(type default)
			)
			(fill yes)
			(layer "F.SilkS")
		)
		(fp_rect
			(start -2.450084 2.999994)
			(end 2.450084 -2.999994)
			(stroke
				(width 0)
				(type default)
			)
			(fill no)
			(layer "F.CrtYd")
		)
		(fp_poly
			(pts
				(xy -2.8194 3.6322) (xy -2.8194 -3.6322) (xy 2.8194 -3.6322) (xy 2.8194 1.18364) (xy 2.450084 1.18364)
				(xy 2.450084 -2.999994) (xy -2.450084 -2.999994) (xy -2.450084 2.999994) (xy 2.450084 2.999994)
				(xy 2.450084 1.18618) (xy 2.8194 1.18618) (xy 2.8194 3.6322)
			)
			(stroke
				(width 0)
				(type default)
			)
			(fill no)
			(layer "F.CrtYd")
		)
		(fp_rect
			(start -2.8194 3.6322)
			(end 2.8194 -3.6322)
			(stroke
				(width 0)
				(type default)
			)
			(fill no)
			(layer "F.Fab")
		)
		(pad "1" smd rect
			(at -1.905 2.54 90)
			(size 0.635 1.651)
			(layers "F.Cu" "F.Mask" "F.Paste")
			(net "50M_CLK_OUT_R")
		)
		(pad "2" smd rect
			(at -0.635 2.54 90)
			(size 0.635 1.651)
			(layers "F.Cu" "F.Mask" "F.Paste")
			(net "CLK_50M_BMC_NCSI")
		)
		(pad "3" smd rect
			(at 0.635 2.54 90)
			(size 0.635 1.651)
			(layers "F.Cu" "F.Mask" "F.Paste")
			(net "CLK_50M_RMII_PHY")
		)
		(pad "4" smd rect
			(at 1.905 2.54 90)
			(size 0.635 1.651)
			(layers "F.Cu" "F.Mask" "F.Paste")
			(net "NCSI_10G_RCLK")
		)
		(pad "5" smd rect
			(at 1.905 -2.54 90)
			(size 0.635 1.651)
			(layers "F.Cu" "F.Mask" "F.Paste")
			(net "CLK_50M_BMC0")
		)
		(pad "6" smd rect
			(at 0.635 -2.54 90)
			(size 0.635 1.651)
			(layers "F.Cu" "F.Mask" "F.Paste")
			(net "GND")
		)
		(pad "7" smd rect
			(at -0.635 -2.54 90)
			(size 0.635 1.651)
			(layers "F.Cu" "F.Mask" "F.Paste")
			(net "P3V3_STBY")
		)
		(pad "8" smd rect
			(at -1.905 -2.54 90)
			(size 0.635 1.651)
			(layers "F.Cu" "F.Mask" "F.Paste")
			(net "50M_CLK_OE")
		)
	)
	(footprint ""
		(layer "F.Cu")
		(at 76.943966 -86.868 -90)
		(property "Reference" "SC1204"
			(at 0 0 270)
			(layer "F.SilkS")
			(hide yes)
			(effects
				(font
					(size 1.27 1.27)
				)
			)
		)
		(property "Value" "SC10U6D3V5KX-4GP"
			(at -0.0762 -6.1214 270)
			(unlocked yes)
			(layer "F.Fab")
			(hide yes)
			(effects
				(font
					(size 1.016 1.016)
					(thickness 0.1524)
				)
			)
		)
		(property "Device Type" "C805H58"
			(at -0.0762 -8.1534 270)
			(unlocked yes)
			(layer "F.Fab")
			(hide yes)
			(effects
				(font
					(size 1.016 1.016)
					(thickness 0.1524)
				)
			)
		)
		(duplicate_pad_numbers_are_jumpers no)
		(fp_line
			(start 0.635 0)
			(end -0.635 0)
			(stroke
				(width 0.508)
				(type default)
			)
			(layer "F.SilkS")
		)
		(fp_rect
			(start -0.9652 1.778)
			(end 0.9652 -1.778)
			(stroke
				(width 0)
				(type default)
			)
			(fill no)
			(layer "F.CrtYd")
		)
		(fp_poly
			(pts
				(xy -0.9652 -1.778) (xy 0.9652 -1.778) (xy 0.9652 1.778) (xy -0.9652 1.778)
			)
			(stroke
				(width 0)
				(type default)
			)
			(fill no)
			(layer "F.Fab")
		)
		(pad "1" smd rect
			(at 0 -0.9652 270)
			(size 1.397 1.143)
			(layers "F.Cu" "F.Mask" "F.Paste")
			(net "P1V8_E")
		)
		(pad "2" smd rect
			(at 0 0.9652 270)
			(size 1.397 1.143)
			(layers "F.Cu" "F.Mask" "F.Paste")
			(net "GND")
		)
	)
	(footprint ""
		(layer "F.Cu")
		(at 160.02 -147.066 -90)
		(property "Reference" "SR724"
			(at 0 0 270)
			(layer "F.SilkS")
			(hide yes)
			(effects
				(font
					(size 1.27 1.27)
				)
			)
		)
		(property "Value" "200KR2F-L-GP"
			(at 0.064008 -3.993896 270)
			(unlocked yes)
			(layer "F.Fab")
			(hide yes)
			(effects
				(font
					(size 1.016 1.016)
					(thickness 0.1524)
				)
			)
		)
		(property "Device Type" "R402H16"
			(at 0.064008 -5.517896 270)
			(unlocked yes)
			(layer "F.Fab")
			(hide yes)
			(effects
				(font
					(size 1.016 1.016)
					(thickness 0.1524)
				)
			)
		)
		(duplicate_pad_numbers_are_jumpers no)
		(fp_line
			(start -0.508 -0.9398)
			(end -0.508 0.9398)
			(stroke
				(width 0.1524)
				(type default)
			)
			(layer "F.SilkS")
		)
		(fp_line
			(start 0.508 -0.9398)
			(end -0.508 -0.9398)
			(stroke
				(width 0.1524)
				(type default)
			)
			(layer "F.SilkS")
		)
		(fp_rect
			(start -0.508 0.9398)
			(end 0.508 -0.9398)
			(stroke
				(width 0)
				(type default)
			)
			(fill no)
			(layer "F.CrtYd")
		)
		(fp_rect
			(start -0.508 0.9398)
			(end 0.508 -0.9398)
			(stroke
				(width 0)
				(type default)
			)
			(fill no)
			(layer "F.Fab")
		)
		(pad "1" smd custom
			(at 0 -0.4445 270)
			(size 0.1397 0.1397)
			(layers "F.Cu" "F.Mask" "F.Paste")
			(net "IOC_I2C_VREF")
			(options
				(clearance outline)
				(anchor circle)
			)
			(primitives
				(gr_poly
					(pts
						(arc
							(start -0.1778 -0.2794)
							(mid -0.249642 -0.249642)
							(end -0.2794 -0.1778)
						)
						(arc
							(start -0.2794 0.1778)
							(mid -0.249642 0.249642)
							(end -0.1778 0.2794)
						)
						(arc
							(start 0.1778 0.2794)
							(mid 0.249642 0.249642)
							(end 0.2794 0.1778)
						)
						(arc
							(start 0.2794 -0.1778)
							(mid 0.249642 -0.249642)
							(end 0.1778 -0.2794)
						)
					)
					(width 0)
					(fill yes)
				)
			)
		)
		(pad "2" smd custom
			(at 0 0.4445 270)
			(size 0.1397 0.1397)
			(layers "F.Cu" "F.Mask" "F.Paste")
			(net "P3V3")
			(options
				(clearance outline)
				(anchor circle)
			)
			(primitives
				(gr_poly
					(pts
						(arc
							(start -0.1778 -0.2794)
							(mid -0.249642 -0.249642)
							(end -0.2794 -0.1778)
						)
						(arc
							(start -0.2794 0.1778)
							(mid -0.249642 0.249642)
							(end -0.1778 0.2794)
						)
						(arc
							(start 0.1778 0.2794)
							(mid 0.249642 0.249642)
							(end 0.2794 0.1778)
						)
						(arc
							(start 0.2794 -0.1778)
							(mid 0.249642 -0.249642)
							(end 0.1778 -0.2794)
						)
					)
					(width 0)
					(fill yes)
				)
			)
		)
	)
	(footprint ""
		(layer "F.Cu")
		(at 187.442856 -141.868652 -90)
		(property "Reference" "R608"
			(at 0 0 270)
			(layer "F.SilkS")
			(hide yes)
			(effects
				(font
					(size 1.27 1.27)
				)
			)
		)
		(property "Value" "0R2J-2-GP"
			(at 0.064008 -3.993896 270)
			(unlocked yes)
			(layer "F.Fab")
			(hide yes)
			(effects
				(font
					(size 1.016 1.016)
					(thickness 0.1524)
				)
			)
		)
		(property "Device Type" "R402H16"
			(at 0.064008 -5.517896 270)
			(unlocked yes)
			(layer "F.Fab")
			(hide yes)
			(effects
				(font
					(size 1.016 1.016)
					(thickness 0.1524)
				)
			)
		)
		(duplicate_pad_numbers_are_jumpers no)
		(fp_line
			(start -0.508 -0.9398)
			(end -0.508 0.9398)
			(stroke
				(width 0.1524)
				(type default)
			)
			(layer "F.SilkS")
		)
		(fp_line
			(start 0.508 -0.9398)
			(end -0.508 -0.9398)
			(stroke
				(width 0.1524)
				(type default)
			)
			(layer "F.SilkS")
		)
		(fp_rect
			(start -0.508 0.9398)
			(end 0.508 -0.9398)
			(stroke
				(width 0)
				(type default)
			)
			(fill no)
			(layer "F.CrtYd")
		)
		(fp_rect
			(start -0.508 0.9398)
			(end 0.508 -0.9398)
			(stroke
				(width 0)
				(type default)
			)
			(fill no)
			(layer "F.Fab")
		)
		(pad "1" smd custom
			(at 0 -0.4445 270)
			(size 0.1397 0.1397)
			(layers "F.Cu" "F.Mask" "F.Paste")
			(net "EXP_EEPROM_SCL")
			(options
				(clearance outline)
				(anchor circle)
			)
			(primitives
				(gr_poly
					(pts
						(arc
							(start -0.1778 -0.2794)
							(mid -0.249642 -0.249642)
							(end -0.2794 -0.1778)
						)
						(arc
							(start -0.2794 0.1778)
							(mid -0.249642 0.249642)
							(end -0.1778 0.2794)
						)
						(arc
							(start 0.1778 0.2794)
							(mid 0.249642 0.249642)
							(end 0.2794 0.1778)
						)
						(arc
							(start 0.2794 -0.1778)
							(mid 0.249642 -0.249642)
							(end 0.1778 -0.2794)
						)
					)
					(width 0)
					(fill yes)
				)
			)
		)
		(pad "2" smd custom
			(at 0 0.4445 270)
			(size 0.1397 0.1397)
			(layers "F.Cu" "F.Mask" "F.Paste")
			(net "EXP_SCL_0")
			(options
				(clearance outline)
				(anchor circle)
			)
			(primitives
				(gr_poly
					(pts
						(arc
							(start -0.1778 -0.2794)
							(mid -0.249642 -0.249642)
							(end -0.2794 -0.1778)
						)
						(arc
							(start -0.2794 0.1778)
							(mid -0.249642 0.249642)
							(end -0.1778 0.2794)
						)
						(arc
							(start 0.1778 0.2794)
							(mid 0.249642 0.249642)
							(end 0.2794 0.1778)
						)
						(arc
							(start 0.2794 -0.1778)
							(mid 0.249642 -0.249642)
							(end 0.1778 -0.2794)
						)
					)
					(width 0)
					(fill yes)
				)
			)
		)
	)
	(footprint ""
		(layer "F.Cu")
		(at 221.361 -102.743 -90)
		(property "Reference" "PR125"
			(at 0 0 270)
			(layer "F.SilkS")
			(hide yes)
			(effects
				(font
					(size 1.27 1.27)
				)
			)
		)
		(property "Value" "2K7R2J-GP"
			(at 0.064008 -3.993896 270)
			(unlocked yes)
			(layer "F.Fab")
			(hide yes)
			(effects
				(font
					(size 1.016 1.016)
					(thickness 0.1524)
				)
			)
		)
		(property "Device Type" "R402H16"
			(at 0.064008 -5.517896 270)
			(unlocked yes)
			(layer "F.Fab")
			(hide yes)
			(effects
				(font
					(size 1.016 1.016)
					(thickness 0.1524)
				)
			)
		)
		(duplicate_pad_numbers_are_jumpers no)
		(fp_line
			(start -0.508 -0.9398)
			(end -0.508 0.9398)
			(stroke
				(width 0.1524)
				(type default)
			)
			(layer "F.SilkS")
		)
		(fp_line
			(start 0.508 -0.9398)
			(end -0.508 -0.9398)
			(stroke
				(width 0.1524)
				(type default)
			)
			(layer "F.SilkS")
		)
		(fp_rect
			(start -0.508 0.9398)
			(end 0.508 -0.9398)
			(stroke
				(width 0)
				(type default)
			)
			(fill no)
			(layer "F.CrtYd")
		)
		(fp_rect
			(start -0.508 0.9398)
			(end 0.508 -0.9398)
			(stroke
				(width 0)
				(type default)
			)
			(fill no)
			(layer "F.Fab")
		)
		(pad "1" smd custom
			(at 0 -0.4445 270)
			(size 0.1397 0.1397)
			(layers "F.Cu" "F.Mask" "F.Paste")
			(net "P3V3_STBY")
			(options
				(clearance outline)
				(anchor circle)
			)
			(primitives
				(gr_poly
					(pts
						(arc
							(start -0.1778 -0.2794)
							(mid -0.249642 -0.249642)
							(end -0.2794 -0.1778)
						)
						(arc
							(start -0.2794 0.1778)
							(mid -0.249642 0.249642)
							(end -0.1778 0.2794)
						)
						(arc
							(start 0.1778 0.2794)
							(mid 0.249642 0.249642)
							(end 0.2794 0.1778)
						)
						(arc
							(start 0.2794 -0.1778)
							(mid 0.249642 -0.249642)
							(end 0.1778 -0.2794)
						)
					)
					(width 0)
					(fill yes)
				)
			)
		)
		(pad "2" smd custom
			(at 0 0.4445 270)
			(size 0.1397 0.1397)
			(layers "F.Cu" "F.Mask" "F.Paste")
			(net "PWRGD_P1V5_C_PG")
			(options
				(clearance outline)
				(anchor circle)
			)
			(primitives
				(gr_poly
					(pts
						(arc
							(start -0.1778 -0.2794)
							(mid -0.249642 -0.249642)
							(end -0.2794 -0.1778)
						)
						(arc
							(start -0.2794 0.1778)
							(mid -0.249642 0.249642)
							(end -0.1778 0.2794)
						)
						(arc
							(start 0.1778 0.2794)
							(mid 0.249642 0.249642)
							(end 0.2794 0.1778)
						)
						(arc
							(start 0.2794 -0.1778)
							(mid 0.249642 -0.249642)
							(end 0.1778 -0.2794)
						)
					)
					(width 0)
					(fill yes)
				)
			)
		)
	)
	(footprint ""
		(layer "F.Cu")
		(at 258.318 -136.779)
		(property "Reference" "R7903"
			(at 0 0 0)
			(layer "F.SilkS")
			(hide yes)
			(effects
				(font
					(size 1.27 1.27)
				)
			)
		)
		(property "Value" "0R2J-2-GP"
			(at 0.064008 -3.993896 0)
			(unlocked yes)
			(layer "F.Fab")
			(hide yes)
			(effects
				(font
					(size 1.016 1.016)
					(thickness 0.1524)
				)
			)
		)
		(property "Device Type" "R402H16"
			(at 0.064008 -5.517896 0)
			(unlocked yes)
			(layer "F.Fab")
			(hide yes)
			(effects
				(font
					(size 1.016 1.016)
					(thickness 0.1524)
				)
			)
		)
		(duplicate_pad_numbers_are_jumpers no)
		(fp_line
			(start -0.508 -0.9398)
			(end -0.508 0.9398)
			(stroke
				(width 0.1524)
				(type default)
			)
			(layer "F.SilkS")
		)
		(fp_line
			(start 0.508 -0.9398)
			(end -0.508 -0.9398)
			(stroke
				(width 0.1524)
				(type default)
			)
			(layer "F.SilkS")
		)
		(fp_rect
			(start -0.508 0.9398)
			(end 0.508 -0.9398)
			(stroke
				(width 0)
				(type default)
			)
			(fill no)
			(layer "F.CrtYd")
		)
		(fp_rect
			(start -0.508 0.9398)
			(end 0.508 -0.9398)
			(stroke
				(width 0)
				(type default)
			)
			(fill no)
			(layer "F.Fab")
		)
		(pad "1" smd custom
			(at 0 -0.4445)
			(size 0.1397 0.1397)
			(layers "F.Cu" "F.Mask" "F.Paste")
			(net "CPU_S_RXD")
			(options
				(clearance outline)
				(anchor circle)
			)
			(primitives
				(gr_poly
					(pts
						(arc
							(start -0.1778 -0.2794)
							(mid -0.249642 -0.249642)
							(end -0.2794 -0.1778)
						)
						(arc
							(start -0.2794 0.1778)
							(mid -0.249642 0.249642)
							(end -0.1778 0.2794)
						)
						(arc
							(start 0.1778 0.2794)
							(mid 0.249642 0.249642)
							(end 0.2794 0.1778)
						)
						(arc
							(start 0.2794 -0.1778)
							(mid 0.249642 -0.249642)
							(end 0.1778 -0.2794)
						)
					)
					(width 0)
					(fill yes)
				)
			)
		)
		(pad "2" smd custom
			(at 0 0.4445)
			(size 0.1397 0.1397)
			(layers "F.Cu" "F.Mask" "F.Paste")
			(net "CPU_U192_PIN5_RX")
			(options
				(clearance outline)
				(anchor circle)
			)
			(primitives
				(gr_poly
					(pts
						(arc
							(start -0.1778 -0.2794)
							(mid -0.249642 -0.249642)
							(end -0.2794 -0.1778)
						)
						(arc
							(start -0.2794 0.1778)
							(mid -0.249642 0.249642)
							(end -0.1778 0.2794)
						)
						(arc
							(start 0.1778 0.2794)
							(mid 0.249642 0.249642)
							(end 0.2794 0.1778)
						)
						(arc
							(start 0.2794 -0.1778)
							(mid 0.249642 -0.249642)
							(end 0.1778 -0.2794)
						)
					)
					(width 0)
					(fill yes)
				)
			)
		)
	)
	(footprint ""
		(layer "F.Cu")
		(at 131.318 -88.519 90)
		(property "Reference" "SC1264"
			(at 0 0 90)
			(layer "F.SilkS")
			(hide yes)
			(effects
				(font
					(size 1.27 1.27)
				)
			)
		)
		(property "Value" "SCD01U10V1KX-GP"
			(at -2.8321 -1.7399 90)
			(unlocked yes)
			(layer "F.Fab")
			(hide yes)
			(effects
				(font
					(size 1.016 1.016)
					(thickness 0.1524)
				)
			)
		)
		(property "Device Type" "C0201H13"
			(at -2.8321 -3.2639 90)
			(unlocked yes)
			(layer "F.Fab")
			(hide yes)
			(effects
				(font
					(size 1.016 1.016)
					(thickness 0.1524)
				)
			)
		)
		(duplicate_pad_numbers_are_jumpers no)
		(fp_rect
			(start -0.2794 0.6477)
			(end 0.2794 -0.6477)
			(stroke
				(width 0)
				(type default)
			)
			(fill no)
			(layer "F.CrtYd")
		)
		(fp_rect
			(start -0.2794 0.6477)
			(end 0.2794 -0.6477)
			(stroke
				(width 0)
				(type default)
			)
			(fill no)
			(layer "F.Fab")
		)
		(pad "1" smd custom
			(at 0 -0.2794 90)
			(size 0.0762 0.0762)
			(layers "F.Cu" "F.Mask" "F.Paste")
			(net "3X24_SAS_TX17_P")
			(options
				(clearance outline)
				(anchor circle)
			)
			(primitives
				(gr_poly
					(pts
						(arc
							(start 0.1524 -0.127)
							(mid 0.137521 -0.162921)
							(end 0.1016 -0.1778)
						)
						(arc
							(start -0.1016 -0.1778)
							(mid -0.137521 -0.162921)
							(end -0.1524 -0.127)
						)
						(arc
							(start -0.1524 0.127)
							(mid -0.137521 0.162921)
							(end -0.1016 0.1778)
						)
						(arc
							(start 0.1016 0.1778)
							(mid 0.137521 0.162921)
							(end 0.1524 0.127)
						)
					)
					(width 0)
					(fill yes)
				)
			)
		)
		(pad "2" smd custom
			(at 0 0.2794 90)
			(size 0.0762 0.0762)
			(layers "F.Cu" "F.Mask" "F.Paste")
			(net "SAS_EXP2CONN_TX_P_21")
			(options
				(clearance outline)
				(anchor circle)
			)
			(primitives
				(gr_poly
					(pts
						(arc
							(start 0.1524 -0.127)
							(mid 0.137521 -0.162921)
							(end 0.1016 -0.1778)
						)
						(arc
							(start -0.1016 -0.1778)
							(mid -0.137521 -0.162921)
							(end -0.1524 -0.127)
						)
						(arc
							(start -0.1524 0.127)
							(mid -0.137521 0.162921)
							(end -0.1016 0.1778)
						)
						(arc
							(start 0.1016 0.1778)
							(mid 0.137521 0.162921)
							(end 0.1524 0.127)
						)
					)
					(width 0)
					(fill yes)
				)
			)
		)
	)
	(footprint ""
		(layer "F.Cu")
		(at 208.153 -215.773 -90)
		(property "Reference" "C43"
			(at 0 0 270)
			(layer "F.SilkS")
			(hide yes)
			(effects
				(font
					(size 1.27 1.27)
				)
			)
		)
		(property "Value" "SCD1U16V2KX-3GP"
			(at 1.1811 -2.7051 270)
			(unlocked yes)
			(layer "F.Fab")
			(hide yes)
			(effects
				(font
					(size 1.016 1.016)
					(thickness 0.1524)
				)
			)
		)
		(property "Device Type" "C402H22"
			(at 1.1811 -4.2291 270)
			(unlocked yes)
			(layer "F.Fab")
			(hide yes)
			(effects
				(font
					(size 1.016 1.016)
					(thickness 0.1524)
				)
			)
		)
		(duplicate_pad_numbers_are_jumpers no)
		(fp_rect
			(start -0.4318 0.9525)
			(end 0.4318 -0.9525)
			(stroke
				(width 0)
				(type default)
			)
			(fill no)
			(layer "F.CrtYd")
		)
		(fp_rect
			(start -0.4318 0.9525)
			(end 0.4318 -0.9525)
			(stroke
				(width 0)
				(type default)
			)
			(fill no)
			(layer "F.Fab")
		)
		(pad "1" smd custom
			(at 0 -0.4445 270)
			(size 0.1524 0.1524)
			(layers "F.Cu" "F.Mask" "F.Paste")
			(net "P3V3_STBY")
			(options
				(clearance outline)
				(anchor circle)
			)
			(primitives
				(gr_poly
					(pts
						(arc
							(start 0.3048 -0.2032)
							(mid 0.275042 -0.275042)
							(end 0.2032 -0.3048)
						)
						(arc
							(start -0.2032 -0.3048)
							(mid -0.275042 -0.275042)
							(end -0.3048 -0.2032)
						)
						(arc
							(start -0.3048 0.2032)
							(mid -0.275042 0.275042)
							(end -0.2032 0.3048)
						)
						(arc
							(start 0.2032 0.3048)
							(mid 0.275042 0.275042)
							(end 0.3048 0.2032)
						)
					)
					(width 0)
					(fill yes)
				)
			)
		)
		(pad "2" smd custom
			(at 0 0.4445 270)
			(size 0.1524 0.1524)
			(layers "F.Cu" "F.Mask" "F.Paste")
			(net "GND")
			(options
				(clearance outline)
				(anchor circle)
			)
			(primitives
				(gr_poly
					(pts
						(arc
							(start 0.3048 -0.2032)
							(mid 0.275042 -0.275042)
							(end 0.2032 -0.3048)
						)
						(arc
							(start -0.2032 -0.3048)
							(mid -0.275042 -0.275042)
							(end -0.3048 -0.2032)
						)
						(arc
							(start -0.3048 0.2032)
							(mid -0.275042 0.275042)
							(end -0.2032 0.3048)
						)
						(arc
							(start 0.2032 0.3048)
							(mid 0.275042 0.275042)
							(end 0.3048 0.2032)
						)
					)
					(width 0)
					(fill yes)
				)
			)
		)
	)
	(footprint ""
		(layer "F.Cu")
		(at 260.023864 -231.004872 180)
		(property "Reference" "PC102"
			(at 0 0 180)
			(layer "F.SilkS")
			(hide yes)
			(effects
				(font
					(size 1.27 1.27)
				)
			)
		)
		(property "Value" "SCD1U16V2KX-3GP"
			(at 1.1811 -2.7051 180)
			(unlocked yes)
			(layer "F.Fab")
			(hide yes)
			(effects
				(font
					(size 1.016 1.016)
					(thickness 0.1524)
				)
			)
		)
		(property "Device Type" "C402H22"
			(at 1.1811 -4.2291 180)
			(unlocked yes)
			(layer "F.Fab")
			(hide yes)
			(effects
				(font
					(size 1.016 1.016)
					(thickness 0.1524)
				)
			)
		)
		(duplicate_pad_numbers_are_jumpers no)
		(fp_rect
			(start -0.4318 0.9525)
			(end 0.4318 -0.9525)
			(stroke
				(width 0)
				(type default)
			)
			(fill no)
			(layer "F.CrtYd")
		)
		(fp_rect
			(start -0.4318 0.9525)
			(end 0.4318 -0.9525)
			(stroke
				(width 0)
				(type default)
			)
			(fill no)
			(layer "F.Fab")
		)
		(pad "1" smd custom
			(at 0 -0.4445 180)
			(size 0.1524 0.1524)
			(layers "F.Cu" "F.Mask" "F.Paste")
			(net "TPS74801_1V26_STBY_BIAS")
			(options
				(clearance outline)
				(anchor circle)
			)
			(primitives
				(gr_poly
					(pts
						(arc
							(start 0.3048 -0.2032)
							(mid 0.275042 -0.275042)
							(end 0.2032 -0.3048)
						)
						(arc
							(start -0.2032 -0.3048)
							(mid -0.275042 -0.275042)
							(end -0.3048 -0.2032)
						)
						(arc
							(start -0.3048 0.2032)
							(mid -0.275042 0.275042)
							(end -0.2032 0.3048)
						)
						(arc
							(start 0.2032 0.3048)
							(mid 0.275042 0.275042)
							(end 0.3048 0.2032)
						)
					)
					(width 0)
					(fill yes)
				)
			)
		)
		(pad "2" smd custom
			(at 0 0.4445 180)
			(size 0.1524 0.1524)
			(layers "F.Cu" "F.Mask" "F.Paste")
			(net "GND")
			(options
				(clearance outline)
				(anchor circle)
			)
			(primitives
				(gr_poly
					(pts
						(arc
							(start 0.3048 -0.2032)
							(mid 0.275042 -0.275042)
							(end 0.2032 -0.3048)
						)
						(arc
							(start -0.2032 -0.3048)
							(mid -0.275042 -0.275042)
							(end -0.3048 -0.2032)
						)
						(arc
							(start -0.3048 0.2032)
							(mid -0.275042 0.275042)
							(end -0.2032 0.3048)
						)
						(arc
							(start 0.2032 0.3048)
							(mid 0.275042 0.275042)
							(end 0.3048 0.2032)
						)
					)
					(width 0)
					(fill yes)
				)
			)
		)
	)
	(footprint ""
		(layer "F.Cu")
		(at 112.30737 -77.724)
		(property "Reference" "STP75"
			(at 0 0 0)
			(layer "F.SilkS")
			(hide yes)
			(effects
				(font
					(size 1.27 1.27)
				)
			)
		)
		(property "Value" "TPAD28"
			(at 0.0127 -1.8034 0)
			(unlocked yes)
			(layer "F.Fab")
			(hide yes)
			(effects
				(font
					(size 1.016 1.016)
					(thickness 0.1524)
				)
			)
		)
		(property "Device Type" "TPAD28"
			(at 0.0127 -3.3274 0)
			(unlocked yes)
			(layer "F.Fab")
			(hide yes)
			(effects
				(font
					(size 1.016 1.016)
					(thickness 0.1524)
				)
			)
		)
		(duplicate_pad_numbers_are_jumpers no)
		(fp_poly
			(pts
				(arc
					(start 0.3556 0)
					(mid -0.3556 0)
					(end 0.3556 0)
				)
			)
			(stroke
				(width 0)
				(type default)
			)
			(fill no)
			(layer "F.CrtYd")
		)
		(fp_poly
			(pts
				(arc
					(start 0.6096 0)
					(mid -0.6096 0)
					(end 0.6096 0)
				)
			)
			(stroke
				(width 0)
				(type default)
			)
			(fill no)
			(layer "F.Fab")
		)
		(pad "1" smd circle
			(at 0 0)
			(size 0.7112 0.7112)
			(layers "F.Cu" "F.Mask" "F.Paste")
			(net "EXP_TEST_MUX35")
		)
	)
	(footprint ""
		(layer "F.Cu")
		(at 191.697864 -29.663136 90)
		(property "Reference" "R394"
			(at 0 0 90)
			(layer "F.SilkS")
			(hide yes)
			(effects
				(font
					(size 1.27 1.27)
				)
			)
		)
		(property "Value" "4K75R2F-1-GP"
			(at 0.064008 -3.993896 90)
			(unlocked yes)
			(layer "F.Fab")
			(hide yes)
			(effects
				(font
					(size 1.016 1.016)
					(thickness 0.1524)
				)
			)
		)
		(property "Device Type" "R402H16"
			(at 0.064008 -5.517896 90)
			(unlocked yes)
			(layer "F.Fab")
			(hide yes)
			(effects
				(font
					(size 1.016 1.016)
					(thickness 0.1524)
				)
			)
		)
		(duplicate_pad_numbers_are_jumpers no)
		(fp_line
			(start 0.508 -0.9398)
			(end -0.508 -0.9398)
			(stroke
				(width 0.1524)
				(type default)
			)
			(layer "F.SilkS")
		)
		(fp_line
			(start -0.508 -0.9398)
			(end -0.508 0.9398)
			(stroke
				(width 0.1524)
				(type default)
			)
			(layer "F.SilkS")
		)
		(fp_rect
			(start -0.508 0.9398)
			(end 0.508 -0.9398)
			(stroke
				(width 0)
				(type default)
			)
			(fill no)
			(layer "F.CrtYd")
		)
		(fp_rect
			(start -0.508 0.9398)
			(end 0.508 -0.9398)
			(stroke
				(width 0)
				(type default)
			)
			(fill no)
			(layer "F.Fab")
		)
		(pad "1" smd custom
			(at 0 -0.4445 90)
			(size 0.1397 0.1397)
			(layers "F.Cu" "F.Mask" "F.Paste")
			(net "PHY_TX_ER_PD")
			(options
				(clearance outline)
				(anchor circle)
			)
			(primitives
				(gr_poly
					(pts
						(arc
							(start -0.1778 -0.2794)
							(mid -0.249642 -0.249642)
							(end -0.2794 -0.1778)
						)
						(arc
							(start -0.2794 0.1778)
							(mid -0.249642 0.249642)
							(end -0.1778 0.2794)
						)
						(arc
							(start 0.1778 0.2794)
							(mid 0.249642 0.249642)
							(end 0.2794 0.1778)
						)
						(arc
							(start 0.2794 -0.1778)
							(mid 0.249642 -0.249642)
							(end 0.1778 -0.2794)
						)
					)
					(width 0)
					(fill yes)
				)
			)
		)
		(pad "2" smd custom
			(at 0 0.4445 90)
			(size 0.1397 0.1397)
			(layers "F.Cu" "F.Mask" "F.Paste")
			(net "GND")
			(options
				(clearance outline)
				(anchor circle)
			)
			(primitives
				(gr_poly
					(pts
						(arc
							(start -0.1778 -0.2794)
							(mid -0.249642 -0.249642)
							(end -0.2794 -0.1778)
						)
						(arc
							(start -0.2794 0.1778)
							(mid -0.249642 0.249642)
							(end -0.1778 0.2794)
						)
						(arc
							(start 0.1778 0.2794)
							(mid 0.249642 0.249642)
							(end 0.2794 0.1778)
						)
						(arc
							(start 0.2794 -0.1778)
							(mid 0.249642 -0.249642)
							(end 0.1778 -0.2794)
						)
					)
					(width 0)
					(fill yes)
				)
			)
		)
	)
	(footprint ""
		(layer "F.Cu")
		(at 201.295 -167.64 180)
		(property "Reference" "R580"
			(at 0 0 180)
			(layer "F.SilkS")
			(hide yes)
			(effects
				(font
					(size 1.27 1.27)
				)
			)
		)
		(property "Value" "4K7R2F-GP"
			(at 0.064008 -3.993896 180)
			(unlocked yes)
			(layer "F.Fab")
			(hide yes)
			(effects
				(font
					(size 1.016 1.016)
					(thickness 0.1524)
				)
			)
		)
		(property "Device Type" "R402H16"
			(at 0.064008 -5.517896 180)
			(unlocked yes)
			(layer "F.Fab")
			(hide yes)
			(effects
				(font
					(size 1.016 1.016)
					(thickness 0.1524)
				)
			)
		)
		(duplicate_pad_numbers_are_jumpers no)
		(fp_line
			(start 0.508 -0.9398)
			(end -0.508 -0.9398)
			(stroke
				(width 0.1524)
				(type default)
			)
			(layer "F.SilkS")
		)
		(fp_line
			(start -0.508 -0.9398)
			(end -0.508 0.9398)
			(stroke
				(width 0.1524)
				(type default)
			)
			(layer "F.SilkS")
		)
		(fp_rect
			(start -0.508 0.9398)
			(end 0.508 -0.9398)
			(stroke
				(width 0)
				(type default)
			)
			(fill no)
			(layer "F.CrtYd")
		)
		(fp_rect
			(start -0.508 0.9398)
			(end 0.508 -0.9398)
			(stroke
				(width 0)
				(type default)
			)
			(fill no)
			(layer "F.Fab")
		)
		(pad "1" smd custom
			(at 0 -0.4445 180)
			(size 0.1397 0.1397)
			(layers "F.Cu" "F.Mask" "F.Paste")
			(net "P3V3_B")
			(options
				(clearance outline)
				(anchor circle)
			)
			(primitives
				(gr_poly
					(pts
						(arc
							(start -0.1778 -0.2794)
							(mid -0.249642 -0.249642)
							(end -0.2794 -0.1778)
						)
						(arc
							(start -0.2794 0.1778)
							(mid -0.249642 0.249642)
							(end -0.1778 0.2794)
						)
						(arc
							(start 0.1778 0.2794)
							(mid 0.249642 0.249642)
							(end 0.2794 0.1778)
						)
						(arc
							(start 0.2794 -0.1778)
							(mid 0.249642 -0.249642)
							(end 0.1778 -0.2794)
						)
					)
					(width 0)
					(fill yes)
				)
			)
		)
		(pad "2" smd custom
			(at 0 0.4445 180)
			(size 0.1397 0.1397)
			(layers "F.Cu" "F.Mask" "F.Paste")
			(net "P3V3")
			(options
				(clearance outline)
				(anchor circle)
			)
			(primitives
				(gr_poly
					(pts
						(arc
							(start -0.1778 -0.2794)
							(mid -0.249642 -0.249642)
							(end -0.2794 -0.1778)
						)
						(arc
							(start -0.2794 0.1778)
							(mid -0.249642 0.249642)
							(end -0.1778 0.2794)
						)
						(arc
							(start 0.1778 0.2794)
							(mid 0.249642 0.249642)
							(end 0.2794 0.1778)
						)
						(arc
							(start 0.2794 -0.1778)
							(mid 0.249642 -0.249642)
							(end 0.1778 -0.2794)
						)
					)
					(width 0)
					(fill yes)
				)
			)
		)
	)
	(footprint ""
		(layer "F.Cu")
		(at 95.758 -4.191)
		(property "Reference" "SC1046"
			(at 0 0 0)
			(layer "F.SilkS")
			(hide yes)
			(effects
				(font
					(size 1.27 1.27)
				)
			)
		)
		(property "Value" "SCD1U16V2KX-3GP"
			(at 1.1811 -2.7051 0)
			(unlocked yes)
			(layer "F.Fab")
			(hide yes)
			(effects
				(font
					(size 1.016 1.016)
					(thickness 0.1524)
				)
			)
		)
		(property "Device Type" "C402H22"
			(at 1.1811 -4.2291 0)
			(unlocked yes)
			(layer "F.Fab")
			(hide yes)
			(effects
				(font
					(size 1.016 1.016)
					(thickness 0.1524)
				)
			)
		)
		(duplicate_pad_numbers_are_jumpers no)
		(fp_rect
			(start -0.4318 0.9525)
			(end 0.4318 -0.9525)
			(stroke
				(width 0)
				(type default)
			)
			(fill no)
			(layer "F.CrtYd")
		)
		(fp_rect
			(start -0.4318 0.9525)
			(end 0.4318 -0.9525)
			(stroke
				(width 0)
				(type default)
			)
			(fill no)
			(layer "F.Fab")
		)
		(pad "1" smd custom
			(at 0 -0.4445)
			(size 0.1524 0.1524)
			(layers "F.Cu" "F.Mask" "F.Paste")
			(net "P0V955_C")
			(options
				(clearance outline)
				(anchor circle)
			)
			(primitives
				(gr_poly
					(pts
						(arc
							(start 0.3048 -0.2032)
							(mid 0.275042 -0.275042)
							(end 0.2032 -0.3048)
						)
						(arc
							(start -0.2032 -0.3048)
							(mid -0.275042 -0.275042)
							(end -0.3048 -0.2032)
						)
						(arc
							(start -0.3048 0.2032)
							(mid -0.275042 0.275042)
							(end -0.2032 0.3048)
						)
						(arc
							(start 0.2032 0.3048)
							(mid 0.275042 0.275042)
							(end 0.3048 0.2032)
						)
					)
					(width 0)
					(fill yes)
				)
			)
		)
		(pad "2" smd custom
			(at 0 0.4445)
			(size 0.1524 0.1524)
			(layers "F.Cu" "F.Mask" "F.Paste")
			(net "GND")
			(options
				(clearance outline)
				(anchor circle)
			)
			(primitives
				(gr_poly
					(pts
						(arc
							(start 0.3048 -0.2032)
							(mid 0.275042 -0.275042)
							(end 0.2032 -0.3048)
						)
						(arc
							(start -0.2032 -0.3048)
							(mid -0.275042 -0.275042)
							(end -0.3048 -0.2032)
						)
						(arc
							(start -0.3048 0.2032)
							(mid -0.275042 0.275042)
							(end -0.2032 0.3048)
						)
						(arc
							(start 0.2032 0.3048)
							(mid 0.275042 0.275042)
							(end 0.3048 0.2032)
						)
					)
					(width 0)
					(fill yes)
				)
			)
		)
	)
	(footprint ""
		(layer "F.Cu")
		(at 289.687 -67.691 90)
		(property "Reference" "PR9003"
			(at 0 0 90)
			(layer "F.SilkS")
			(hide yes)
			(effects
				(font
					(size 1.27 1.27)
				)
			)
		)
		(property "Value" "0R2J-2-GP"
			(at 0.064008 -3.993896 90)
			(unlocked yes)
			(layer "F.Fab")
			(hide yes)
			(effects
				(font
					(size 1.016 1.016)
					(thickness 0.1524)
				)
			)
		)
		(property "Device Type" "R402H16"
			(at 0.064008 -5.517896 90)
			(unlocked yes)
			(layer "F.Fab")
			(hide yes)
			(effects
				(font
					(size 1.016 1.016)
					(thickness 0.1524)
				)
			)
		)
		(duplicate_pad_numbers_are_jumpers no)
		(fp_line
			(start 0.508 -0.9398)
			(end -0.508 -0.9398)
			(stroke
				(width 0.1524)
				(type default)
			)
			(layer "F.SilkS")
		)
		(fp_line
			(start -0.508 -0.9398)
			(end -0.508 0.9398)
			(stroke
				(width 0.1524)
				(type default)
			)
			(layer "F.SilkS")
		)
		(fp_rect
			(start -0.508 0.9398)
			(end 0.508 -0.9398)
			(stroke
				(width 0)
				(type default)
			)
			(fill no)
			(layer "F.CrtYd")
		)
		(fp_rect
			(start -0.508 0.9398)
			(end 0.508 -0.9398)
			(stroke
				(width 0)
				(type default)
			)
			(fill no)
			(layer "F.Fab")
		)
		(pad "1" smd custom
			(at 0 -0.4445 90)
			(size 0.1397 0.1397)
			(layers "F.Cu" "F.Mask" "F.Paste")
			(net "HSW_SDA1")
			(options
				(clearance outline)
				(anchor circle)
			)
			(primitives
				(gr_poly
					(pts
						(arc
							(start -0.1778 -0.2794)
							(mid -0.249642 -0.249642)
							(end -0.2794 -0.1778)
						)
						(arc
							(start -0.2794 0.1778)
							(mid -0.249642 0.249642)
							(end -0.1778 0.2794)
						)
						(arc
							(start 0.1778 0.2794)
							(mid 0.249642 0.249642)
							(end 0.2794 0.1778)
						)
						(arc
							(start 0.2794 -0.1778)
							(mid 0.249642 -0.249642)
							(end 0.1778 -0.2794)
						)
					)
					(width 0)
					(fill yes)
				)
			)
		)
		(pad "2" smd custom
			(at 0 0.4445 90)
			(size 0.1397 0.1397)
			(layers "F.Cu" "F.Mask" "F.Paste")
			(net "BMC_I2C_SDA_10")
			(options
				(clearance outline)
				(anchor circle)
			)
			(primitives
				(gr_poly
					(pts
						(arc
							(start -0.1778 -0.2794)
							(mid -0.249642 -0.249642)
							(end -0.2794 -0.1778)
						)
						(arc
							(start -0.2794 0.1778)
							(mid -0.249642 0.249642)
							(end -0.1778 0.2794)
						)
						(arc
							(start 0.1778 0.2794)
							(mid 0.249642 0.249642)
							(end 0.2794 0.1778)
						)
						(arc
							(start 0.2794 -0.1778)
							(mid 0.249642 -0.249642)
							(end 0.1778 -0.2794)
						)
					)
					(width 0)
					(fill yes)
				)
			)
		)
	)
	(footprint ""
		(layer "F.Cu")
		(at 327.406 -96.52 -90)
		(property "Reference" "PC39"
			(at 0 0 270)
			(layer "F.SilkS")
			(hide yes)
			(effects
				(font
					(size 1.27 1.27)
				)
			)
		)
		(property "Value" "SC100U6D3V6MX-GP"
			(at -0.0762 -5.1308 270)
			(unlocked yes)
			(layer "F.Fab")
			(hide yes)
			(effects
				(font
					(size 1.016 1.016)
					(thickness 0.1524)
				)
			)
		)
		(property "Device Type" "C1206H71"
			(at -0.127 -6.6548 270)
			(unlocked yes)
			(layer "F.Fab")
			(hide yes)
			(effects
				(font
					(size 1.016 1.016)
					(thickness 0.1524)
				)
			)
		)
		(duplicate_pad_numbers_are_jumpers no)
		(fp_line
			(start -1.016 2.2352)
			(end -1.016 0.8382)
			(stroke
				(width 0.1524)
				(type default)
			)
			(layer "F.SilkS")
		)
		(fp_line
			(start 1.016 2.2352)
			(end -1.016 2.2352)
			(stroke
				(width 0.1524)
				(type default)
			)
			(layer "F.SilkS")
		)
		(fp_line
			(start 1.016 0.8382)
			(end 1.016 2.2352)
			(stroke
				(width 0.1524)
				(type default)
			)
			(layer "F.SilkS")
		)
		(fp_line
			(start -1.016 -0.8382)
			(end -1.016 -2.2352)
			(stroke
				(width 0.1524)
				(type default)
			)
			(layer "F.SilkS")
		)
		(fp_line
			(start -1.016 -2.2352)
			(end 1.016 -2.2352)
			(stroke
				(width 0.1524)
				(type default)
			)
			(layer "F.SilkS")
		)
		(fp_line
			(start 1.016 -2.2352)
			(end 1.016 -0.8382)
			(stroke
				(width 0.1524)
				(type default)
			)
			(layer "F.SilkS")
		)
		(fp_rect
			(start -1.0922 2.3114)
			(end 1.0922 -2.3114)
			(stroke
				(width 0)
				(type default)
			)
			(fill no)
			(layer "F.CrtYd")
		)
		(fp_poly
			(pts
				(xy 1.0922 -2.3114) (xy 1.0922 2.3114) (xy -1.0922 2.3114) (xy -1.0922 -2.3114)
			)
			(stroke
				(width 0)
				(type default)
			)
			(fill no)
			(layer "F.Fab")
		)
		(pad "1" smd rect
			(at 0 -1.397 270)
			(size 1.651 1.27)
			(layers "F.Cu" "F.Mask" "F.Paste")
			(net "P3V3_STBY")
		)
		(pad "2" smd rect
			(at 0 1.397 270)
			(size 1.651 1.27)
			(layers "F.Cu" "F.Mask" "F.Paste")
			(net "GND")
		)
	)
	(footprint ""
		(layer "F.Cu")
		(at 267.2334 -45.6184 180)
		(property "Reference" "PR39"
			(at 0 0 180)
			(layer "F.SilkS")
			(hide yes)
			(effects
				(font
					(size 1.27 1.27)
				)
			)
		)
		(property "Value" "2D2R3J-2-GP"
			(at -0.0254 -2.5146 180)
			(unlocked yes)
			(layer "F.Fab")
			(hide yes)
			(effects
				(font
					(size 1.016 1.016)
					(thickness 0.1524)
				)
			)
		)
		(property "Device Type" "R603H22"
			(at -0.0254 -4.0386 180)
			(unlocked yes)
			(layer "F.Fab")
			(hide yes)
			(effects
				(font
					(size 1.016 1.016)
					(thickness 0.1524)
				)
			)
		)
		(duplicate_pad_numbers_are_jumpers no)
		(fp_line
			(start 0.2032 0)
			(end 0.4826 0)
			(stroke
				(width 0.2032)
				(type default)
			)
			(layer "F.SilkS")
		)
		(fp_line
			(start -0.4826 0)
			(end -0.2032 0)
			(stroke
				(width 0.2032)
				(type default)
			)
			(layer "F.SilkS")
		)
		(fp_rect
			(start -0.5842 1.3335)
			(end 0.5842 -1.3335)
			(stroke
				(width 0)
				(type default)
			)
			(fill no)
			(layer "F.CrtYd")
		)
		(fp_rect
			(start -0.5842 1.3335)
			(end 0.5842 -1.3335)
			(stroke
				(width 0)
				(type default)
			)
			(fill no)
			(layer "F.Fab")
		)
		(pad "1" smd custom
			(at 0 -0.762 180)
			(size 0.2159 0.2159)
			(layers "F.Cu" "F.Mask" "F.Paste")
			(net "P1V8_STBY_VDD")
			(options
				(clearance outline)
				(anchor circle)
			)
			(primitives
				(gr_poly
					(pts
						(arc
							(start -0.3302 -0.4318)
							(mid -0.402042 -0.402042)
							(end -0.4318 -0.3302)
						)
						(arc
							(start -0.4318 0.3302)
							(mid -0.402042 0.402042)
							(end -0.3302 0.4318)
						)
						(arc
							(start 0.3302 0.4318)
							(mid 0.402042 0.402042)
							(end 0.4318 0.3302)
						)
						(arc
							(start 0.4318 -0.3302)
							(mid 0.402042 -0.402042)
							(end 0.3302 -0.4318)
						)
					)
					(width 0)
					(fill yes)
				)
			)
		)
		(pad "2" smd custom
			(at 0 0.762 180)
			(size 0.2159 0.2159)
			(layers "F.Cu" "F.Mask" "F.Paste")
			(net "P12V")
			(options
				(clearance outline)
				(anchor circle)
			)
			(primitives
				(gr_poly
					(pts
						(arc
							(start -0.3302 -0.4318)
							(mid -0.402042 -0.402042)
							(end -0.4318 -0.3302)
						)
						(arc
							(start -0.4318 0.3302)
							(mid -0.402042 0.402042)
							(end -0.3302 0.4318)
						)
						(arc
							(start 0.3302 0.4318)
							(mid 0.402042 0.402042)
							(end 0.4318 0.3302)
						)
						(arc
							(start 0.4318 -0.3302)
							(mid 0.402042 -0.402042)
							(end 0.3302 -0.4318)
						)
					)
					(width 0)
					(fill yes)
				)
			)
		)
	)
	(footprint ""
		(layer "F.Cu")
		(at 271.804892 -192.934336)
		(property "Reference" "R333"
			(at 0 0 0)
			(layer "F.SilkS")
			(hide yes)
			(effects
				(font
					(size 1.27 1.27)
				)
			)
		)
		(property "Value" "47KR2F-GP"
			(at 0.064008 -3.993896 0)
			(unlocked yes)
			(layer "F.Fab")
			(hide yes)
			(effects
				(font
					(size 1.016 1.016)
					(thickness 0.1524)
				)
			)
		)
		(property "Device Type" "R402H16"
			(at 0.064008 -5.517896 0)
			(unlocked yes)
			(layer "F.Fab")
			(hide yes)
			(effects
				(font
					(size 1.016 1.016)
					(thickness 0.1524)
				)
			)
		)
		(duplicate_pad_numbers_are_jumpers no)
		(fp_line
			(start -0.508 -0.9398)
			(end -0.508 0.9398)
			(stroke
				(width 0.1524)
				(type default)
			)
			(layer "F.SilkS")
		)
		(fp_line
			(start 0.508 -0.9398)
			(end -0.508 -0.9398)
			(stroke
				(width 0.1524)
				(type default)
			)
			(layer "F.SilkS")
		)
		(fp_rect
			(start -0.508 0.9398)
			(end 0.508 -0.9398)
			(stroke
				(width 0)
				(type default)
			)
			(fill no)
			(layer "F.CrtYd")
		)
		(fp_rect
			(start -0.508 0.9398)
			(end 0.508 -0.9398)
			(stroke
				(width 0)
				(type default)
			)
			(fill no)
			(layer "F.Fab")
		)
		(pad "1" smd custom
			(at 0 -0.4445)
			(size 0.1397 0.1397)
			(layers "F.Cu" "F.Mask" "F.Paste")
			(net "P3V3_STBY")
			(options
				(clearance outline)
				(anchor circle)
			)
			(primitives
				(gr_poly
					(pts
						(arc
							(start -0.1778 -0.2794)
							(mid -0.249642 -0.249642)
							(end -0.2794 -0.1778)
						)
						(arc
							(start -0.2794 0.1778)
							(mid -0.249642 0.249642)
							(end -0.1778 0.2794)
						)
						(arc
							(start 0.1778 0.2794)
							(mid 0.249642 0.249642)
							(end 0.2794 0.1778)
						)
						(arc
							(start 0.2794 -0.1778)
							(mid 0.249642 -0.249642)
							(end 0.1778 -0.2794)
						)
					)
					(width 0)
					(fill yes)
				)
			)
		)
		(pad "2" smd custom
			(at 0 0.4445)
			(size 0.1397 0.1397)
			(layers "F.Cu" "F.Mask" "F.Paste")
			(net "FM_BMC_RESET_N")
			(options
				(clearance outline)
				(anchor circle)
			)
			(primitives
				(gr_poly
					(pts
						(arc
							(start -0.1778 -0.2794)
							(mid -0.249642 -0.249642)
							(end -0.2794 -0.1778)
						)
						(arc
							(start -0.2794 0.1778)
							(mid -0.249642 0.249642)
							(end -0.1778 0.2794)
						)
						(arc
							(start 0.1778 0.2794)
							(mid 0.249642 0.249642)
							(end 0.2794 0.1778)
						)
						(arc
							(start 0.2794 -0.1778)
							(mid 0.249642 -0.249642)
							(end 0.1778 -0.2794)
						)
					)
					(width 0)
					(fill yes)
				)
			)
		)
	)
	(footprint ""
		(layer "F.Cu")
		(at 199.898 -185.166)
		(property "Reference" "SC1310"
			(at 0 0 0)
			(layer "F.SilkS")
			(hide yes)
			(effects
				(font
					(size 1.27 1.27)
				)
			)
		)
		(property "Value" "SC10U6D3V5KX-4GP"
			(at -0.0762 -6.1214 0)
			(unlocked yes)
			(layer "F.Fab")
			(hide yes)
			(effects
				(font
					(size 1.016 1.016)
					(thickness 0.1524)
				)
			)
		)
		(property "Device Type" "C805H58"
			(at -0.0762 -8.1534 0)
			(unlocked yes)
			(layer "F.Fab")
			(hide yes)
			(effects
				(font
					(size 1.016 1.016)
					(thickness 0.1524)
				)
			)
		)
		(duplicate_pad_numbers_are_jumpers no)
		(fp_line
			(start 0.635 0)
			(end -0.635 0)
			(stroke
				(width 0.508)
				(type default)
			)
			(layer "F.SilkS")
		)
		(fp_rect
			(start -0.9652 1.778)
			(end 0.9652 -1.778)
			(stroke
				(width 0)
				(type default)
			)
			(fill no)
			(layer "F.CrtYd")
		)
		(fp_poly
			(pts
				(xy -0.9652 -1.778) (xy 0.9652 -1.778) (xy 0.9652 1.778) (xy -0.9652 1.778)
			)
			(stroke
				(width 0)
				(type default)
			)
			(fill no)
			(layer "F.Fab")
		)
		(pad "1" smd rect
			(at 0 -0.9652)
			(size 1.397 1.143)
			(layers "F.Cu" "F.Mask" "F.Paste")
			(net "HB_A_IN")
		)
		(pad "2" smd rect
			(at 0 0.9652)
			(size 1.397 1.143)
			(layers "F.Cu" "F.Mask" "F.Paste")
			(net "GND")
		)
	)
	(footprint ""
		(layer "F.Cu")
		(at 305.054 -160.655)
		(property "Reference" "R562"
			(at 0 0 0)
			(layer "F.SilkS")
			(hide yes)
			(effects
				(font
					(size 1.27 1.27)
				)
			)
		)
		(property "Value" "0R2J-2-GP"
			(at 0.064008 -3.993896 0)
			(unlocked yes)
			(layer "F.Fab")
			(hide yes)
			(effects
				(font
					(size 1.016 1.016)
					(thickness 0.1524)
				)
			)
		)
		(property "Device Type" "R402H16"
			(at 0.064008 -5.517896 0)
			(unlocked yes)
			(layer "F.Fab")
			(hide yes)
			(effects
				(font
					(size 1.016 1.016)
					(thickness 0.1524)
				)
			)
		)
		(duplicate_pad_numbers_are_jumpers no)
		(fp_line
			(start -0.508 -0.9398)
			(end -0.508 0.9398)
			(stroke
				(width 0.1524)
				(type default)
			)
			(layer "F.SilkS")
		)
		(fp_line
			(start 0.508 -0.9398)
			(end -0.508 -0.9398)
			(stroke
				(width 0.1524)
				(type default)
			)
			(layer "F.SilkS")
		)
		(fp_rect
			(start -0.508 0.9398)
			(end 0.508 -0.9398)
			(stroke
				(width 0)
				(type default)
			)
			(fill no)
			(layer "F.CrtYd")
		)
		(fp_rect
			(start -0.508 0.9398)
			(end 0.508 -0.9398)
			(stroke
				(width 0)
				(type default)
			)
			(fill no)
			(layer "F.Fab")
		)
		(pad "1" smd custom
			(at 0 -0.4445)
			(size 0.1397 0.1397)
			(layers "F.Cu" "F.Mask" "F.Paste")
			(net "BMC_JTAG_L_EN_R")
			(options
				(clearance outline)
				(anchor circle)
			)
			(primitives
				(gr_poly
					(pts
						(arc
							(start -0.1778 -0.2794)
							(mid -0.249642 -0.249642)
							(end -0.2794 -0.1778)
						)
						(arc
							(start -0.2794 0.1778)
							(mid -0.249642 0.249642)
							(end -0.1778 0.2794)
						)
						(arc
							(start 0.1778 0.2794)
							(mid 0.249642 0.249642)
							(end 0.2794 0.1778)
						)
						(arc
							(start 0.2794 -0.1778)
							(mid 0.249642 -0.249642)
							(end 0.1778 -0.2794)
						)
					)
					(width 0)
					(fill yes)
				)
			)
		)
		(pad "2" smd custom
			(at 0 0.4445)
			(size 0.1397 0.1397)
			(layers "F.Cu" "F.Mask" "F.Paste")
			(net "BMC_JTAG_L_EN")
			(options
				(clearance outline)
				(anchor circle)
			)
			(primitives
				(gr_poly
					(pts
						(arc
							(start -0.1778 -0.2794)
							(mid -0.249642 -0.249642)
							(end -0.2794 -0.1778)
						)
						(arc
							(start -0.2794 0.1778)
							(mid -0.249642 0.249642)
							(end -0.1778 0.2794)
						)
						(arc
							(start 0.1778 0.2794)
							(mid 0.249642 0.249642)
							(end 0.2794 0.1778)
						)
						(arc
							(start 0.2794 -0.1778)
							(mid 0.249642 -0.249642)
							(end 0.1778 -0.2794)
						)
					)
					(width 0)
					(fill yes)
				)
			)
		)
	)
	(footprint ""
		(layer "F.Cu")
		(at 347.345 -94.361 90)
		(property "Reference" "PC17"
			(at 0 0 90)
			(layer "F.SilkS")
			(hide yes)
			(effects
				(font
					(size 1.27 1.27)
				)
			)
		)
		(property "Value" "SC47U10V6MX-GP"
			(at -0.0762 -5.1308 90)
			(unlocked yes)
			(layer "F.Fab")
			(hide yes)
			(effects
				(font
					(size 1.016 1.016)
					(thickness 0.1524)
				)
			)
		)
		(property "Device Type" "C1206H71"
			(at -0.127 -6.6548 90)
			(unlocked yes)
			(layer "F.Fab")
			(hide yes)
			(effects
				(font
					(size 1.016 1.016)
					(thickness 0.1524)
				)
			)
		)
		(duplicate_pad_numbers_are_jumpers no)
		(fp_line
			(start 1.016 -2.2352)
			(end 1.016 -0.8382)
			(stroke
				(width 0.1524)
				(type default)
			)
			(layer "F.SilkS")
		)
		(fp_line
			(start -1.016 -2.2352)
			(end 1.016 -2.2352)
			(stroke
				(width 0.1524)
				(type default)
			)
			(layer "F.SilkS")
		)
		(fp_line
			(start -1.016 -0.8382)
			(end -1.016 -2.2352)
			(stroke
				(width 0.1524)
				(type default)
			)
			(layer "F.SilkS")
		)
		(fp_line
			(start 1.016 0.8382)
			(end 1.016 2.2352)
			(stroke
				(width 0.1524)
				(type default)
			)
			(layer "F.SilkS")
		)
		(fp_line
			(start 1.016 2.2352)
			(end -1.016 2.2352)
			(stroke
				(width 0.1524)
				(type default)
			)
			(layer "F.SilkS")
		)
		(fp_line
			(start -1.016 2.2352)
			(end -1.016 0.8382)
			(stroke
				(width 0.1524)
				(type default)
			)
			(layer "F.SilkS")
		)
		(fp_rect
			(start -1.0922 2.3114)
			(end 1.0922 -2.3114)
			(stroke
				(width 0)
				(type default)
			)
			(fill no)
			(layer "F.CrtYd")
		)
		(fp_poly
			(pts
				(xy 1.0922 -2.3114) (xy 1.0922 2.3114) (xy -1.0922 2.3114) (xy -1.0922 -2.3114)
			)
			(stroke
				(width 0)
				(type default)
			)
			(fill no)
			(layer "F.Fab")
		)
		(pad "1" smd rect
			(at 0 -1.397 90)
			(size 1.651 1.27)
			(layers "F.Cu" "F.Mask" "F.Paste")
			(net "P5V_STBY")
		)
		(pad "2" smd rect
			(at 0 1.397 90)
			(size 1.651 1.27)
			(layers "F.Cu" "F.Mask" "F.Paste")
			(net "GND")
		)
	)
	(footprint ""
		(layer "F.Cu")
		(at 95.70847 -108.331 -90)
		(property "Reference" "SR735"
			(at 0 0 270)
			(layer "F.SilkS")
			(hide yes)
			(effects
				(font
					(size 1.27 1.27)
				)
			)
		)
		(property "Value" "2K2R2F-GP"
			(at 0.064008 -3.993896 270)
			(unlocked yes)
			(layer "F.Fab")
			(hide yes)
			(effects
				(font
					(size 1.016 1.016)
					(thickness 0.1524)
				)
			)
		)
		(property "Device Type" "R402H16"
			(at 0.064008 -5.517896 270)
			(unlocked yes)
			(layer "F.Fab")
			(hide yes)
			(effects
				(font
					(size 1.016 1.016)
					(thickness 0.1524)
				)
			)
		)
		(duplicate_pad_numbers_are_jumpers no)
		(fp_line
			(start -0.508 -0.9398)
			(end -0.508 0.9398)
			(stroke
				(width 0.1524)
				(type default)
			)
			(layer "F.SilkS")
		)
		(fp_line
			(start 0.508 -0.9398)
			(end -0.508 -0.9398)
			(stroke
				(width 0.1524)
				(type default)
			)
			(layer "F.SilkS")
		)
		(fp_rect
			(start -0.508 0.9398)
			(end 0.508 -0.9398)
			(stroke
				(width 0)
				(type default)
			)
			(fill no)
			(layer "F.CrtYd")
		)
		(fp_rect
			(start -0.508 0.9398)
			(end 0.508 -0.9398)
			(stroke
				(width 0)
				(type default)
			)
			(fill no)
			(layer "F.Fab")
		)
		(pad "1" smd custom
			(at 0 -0.4445 270)
			(size 0.1397 0.1397)
			(layers "F.Cu" "F.Mask" "F.Paste")
			(net "EXP_I2C_SDA_4")
			(options
				(clearance outline)
				(anchor circle)
			)
			(primitives
				(gr_poly
					(pts
						(arc
							(start -0.1778 -0.2794)
							(mid -0.249642 -0.249642)
							(end -0.2794 -0.1778)
						)
						(arc
							(start -0.2794 0.1778)
							(mid -0.249642 0.249642)
							(end -0.1778 0.2794)
						)
						(arc
							(start 0.1778 0.2794)
							(mid 0.249642 0.249642)
							(end 0.2794 0.1778)
						)
						(arc
							(start 0.2794 -0.1778)
							(mid 0.249642 -0.249642)
							(end 0.1778 -0.2794)
						)
					)
					(width 0)
					(fill yes)
				)
			)
		)
		(pad "2" smd custom
			(at 0 0.4445 270)
			(size 0.1397 0.1397)
			(layers "F.Cu" "F.Mask" "F.Paste")
			(net "P1V8_E")
			(options
				(clearance outline)
				(anchor circle)
			)
			(primitives
				(gr_poly
					(pts
						(arc
							(start -0.1778 -0.2794)
							(mid -0.249642 -0.249642)
							(end -0.2794 -0.1778)
						)
						(arc
							(start -0.2794 0.1778)
							(mid -0.249642 0.249642)
							(end -0.1778 0.2794)
						)
						(arc
							(start 0.1778 0.2794)
							(mid 0.249642 0.249642)
							(end 0.2794 0.1778)
						)
						(arc
							(start 0.2794 -0.1778)
							(mid 0.249642 -0.249642)
							(end 0.1778 -0.2794)
						)
					)
					(width 0)
					(fill yes)
				)
			)
		)
	)
	(footprint ""
		(layer "F.Cu")
		(at 107.442 -68.072 -90)
		(property "Reference" "SR865"
			(at 0 0 270)
			(layer "F.SilkS")
			(hide yes)
			(effects
				(font
					(size 1.27 1.27)
				)
			)
		)
		(property "Value" "0R2J-2-GP"
			(at 0.064008 -3.993896 270)
			(unlocked yes)
			(layer "F.Fab")
			(hide yes)
			(effects
				(font
					(size 1.016 1.016)
					(thickness 0.1524)
				)
			)
		)
		(property "Device Type" "R402H16"
			(at 0.064008 -5.517896 270)
			(unlocked yes)
			(layer "F.Fab")
			(hide yes)
			(effects
				(font
					(size 1.016 1.016)
					(thickness 0.1524)
				)
			)
		)
		(duplicate_pad_numbers_are_jumpers no)
		(fp_line
			(start -0.508 -0.9398)
			(end -0.508 0.9398)
			(stroke
				(width 0.1524)
				(type default)
			)
			(layer "F.SilkS")
		)
		(fp_line
			(start 0.508 -0.9398)
			(end -0.508 -0.9398)
			(stroke
				(width 0.1524)
				(type default)
			)
			(layer "F.SilkS")
		)
		(fp_rect
			(start -0.508 0.9398)
			(end 0.508 -0.9398)
			(stroke
				(width 0)
				(type default)
			)
			(fill no)
			(layer "F.CrtYd")
		)
		(fp_rect
			(start -0.508 0.9398)
			(end 0.508 -0.9398)
			(stroke
				(width 0)
				(type default)
			)
			(fill no)
			(layer "F.Fab")
		)
		(pad "1" smd custom
			(at 0 -0.4445 270)
			(size 0.1397 0.1397)
			(layers "F.Cu" "F.Mask" "F.Paste")
			(net "JTAG_IOC_TMS")
			(options
				(clearance outline)
				(anchor circle)
			)
			(primitives
				(gr_poly
					(pts
						(arc
							(start -0.1778 -0.2794)
							(mid -0.249642 -0.249642)
							(end -0.2794 -0.1778)
						)
						(arc
							(start -0.2794 0.1778)
							(mid -0.249642 0.249642)
							(end -0.1778 0.2794)
						)
						(arc
							(start 0.1778 0.2794)
							(mid 0.249642 0.249642)
							(end 0.2794 0.1778)
						)
						(arc
							(start 0.2794 -0.1778)
							(mid 0.249642 -0.249642)
							(end 0.1778 -0.2794)
						)
					)
					(width 0)
					(fill yes)
				)
			)
		)
		(pad "2" smd custom
			(at 0 0.4445 270)
			(size 0.1397 0.1397)
			(layers "F.Cu" "F.Mask" "F.Paste")
			(net "JTAG_EXP_IOC_TMS")
			(options
				(clearance outline)
				(anchor circle)
			)
			(primitives
				(gr_poly
					(pts
						(arc
							(start -0.1778 -0.2794)
							(mid -0.249642 -0.249642)
							(end -0.2794 -0.1778)
						)
						(arc
							(start -0.2794 0.1778)
							(mid -0.249642 0.249642)
							(end -0.1778 0.2794)
						)
						(arc
							(start 0.1778 0.2794)
							(mid 0.249642 0.249642)
							(end 0.2794 0.1778)
						)
						(arc
							(start 0.2794 -0.1778)
							(mid 0.249642 -0.249642)
							(end 0.1778 -0.2794)
						)
					)
					(width 0)
					(fill yes)
				)
			)
		)
	)
	(footprint ""
		(layer "F.Cu")
		(at 317.881 -52.197 90)
		(property "Reference" "C280"
			(at 0 0 90)
			(layer "F.SilkS")
			(hide yes)
			(effects
				(font
					(size 1.27 1.27)
				)
			)
		)
		(property "Value" "SCD1U25V2KX-2-GP"
			(at 1.1811 -2.7051 90)
			(unlocked yes)
			(layer "F.Fab")
			(hide yes)
			(effects
				(font
					(size 1.016 1.016)
					(thickness 0.1524)
				)
			)
		)
		(property "Device Type" "C402H22"
			(at 1.1811 -4.2291 90)
			(unlocked yes)
			(layer "F.Fab")
			(hide yes)
			(effects
				(font
					(size 1.016 1.016)
					(thickness 0.1524)
				)
			)
		)
		(duplicate_pad_numbers_are_jumpers no)
		(fp_rect
			(start -0.4318 0.9525)
			(end 0.4318 -0.9525)
			(stroke
				(width 0)
				(type default)
			)
			(fill no)
			(layer "F.CrtYd")
		)
		(fp_rect
			(start -0.4318 0.9525)
			(end 0.4318 -0.9525)
			(stroke
				(width 0)
				(type default)
			)
			(fill no)
			(layer "F.Fab")
		)
		(pad "1" smd custom
			(at 0 -0.4445 90)
			(size 0.1524 0.1524)
			(layers "F.Cu" "F.Mask" "F.Paste")
			(net "P5V_STBY")
			(options
				(clearance outline)
				(anchor circle)
			)
			(primitives
				(gr_poly
					(pts
						(arc
							(start 0.3048 -0.2032)
							(mid 0.275042 -0.275042)
							(end 0.2032 -0.3048)
						)
						(arc
							(start -0.2032 -0.3048)
							(mid -0.275042 -0.275042)
							(end -0.3048 -0.2032)
						)
						(arc
							(start -0.3048 0.2032)
							(mid -0.275042 0.275042)
							(end -0.2032 0.3048)
						)
						(arc
							(start 0.2032 0.3048)
							(mid 0.275042 0.275042)
							(end 0.3048 0.2032)
						)
					)
					(width 0)
					(fill yes)
				)
			)
		)
		(pad "2" smd custom
			(at 0 0.4445 90)
			(size 0.1524 0.1524)
			(layers "F.Cu" "F.Mask" "F.Paste")
			(net "GND")
			(options
				(clearance outline)
				(anchor circle)
			)
			(primitives
				(gr_poly
					(pts
						(arc
							(start 0.3048 -0.2032)
							(mid 0.275042 -0.275042)
							(end 0.2032 -0.3048)
						)
						(arc
							(start -0.2032 -0.3048)
							(mid -0.275042 -0.275042)
							(end -0.3048 -0.2032)
						)
						(arc
							(start -0.3048 0.2032)
							(mid -0.275042 0.275042)
							(end -0.2032 0.3048)
						)
						(arc
							(start 0.2032 0.3048)
							(mid 0.275042 0.275042)
							(end 0.3048 0.2032)
						)
					)
					(width 0)
					(fill yes)
				)
			)
		)
	)
	(footprint ""
		(layer "F.Cu")
		(at 193.167 -15.113 -90)
		(property "Reference" "R190"
			(at 0 0 270)
			(layer "F.SilkS")
			(hide yes)
			(effects
				(font
					(size 1.27 1.27)
				)
			)
		)
		(property "Value" "0R2J-2-GP"
			(at 0.064008 -3.993896 270)
			(unlocked yes)
			(layer "F.Fab")
			(hide yes)
			(effects
				(font
					(size 1.016 1.016)
					(thickness 0.1524)
				)
			)
		)
		(property "Device Type" "R402H16"
			(at 0.064008 -5.517896 270)
			(unlocked yes)
			(layer "F.Fab")
			(hide yes)
			(effects
				(font
					(size 1.016 1.016)
					(thickness 0.1524)
				)
			)
		)
		(duplicate_pad_numbers_are_jumpers no)
		(fp_line
			(start -0.508 -0.9398)
			(end -0.508 0.9398)
			(stroke
				(width 0.1524)
				(type default)
			)
			(layer "F.SilkS")
		)
		(fp_line
			(start 0.508 -0.9398)
			(end -0.508 -0.9398)
			(stroke
				(width 0.1524)
				(type default)
			)
			(layer "F.SilkS")
		)
		(fp_rect
			(start -0.508 0.9398)
			(end 0.508 -0.9398)
			(stroke
				(width 0)
				(type default)
			)
			(fill no)
			(layer "F.CrtYd")
		)
		(fp_rect
			(start -0.508 0.9398)
			(end 0.508 -0.9398)
			(stroke
				(width 0)
				(type default)
			)
			(fill no)
			(layer "F.Fab")
		)
		(pad "1" smd custom
			(at 0 -0.4445 270)
			(size 0.1397 0.1397)
			(layers "F.Cu" "F.Mask" "F.Paste")
			(net "BMC_I2C_D_SCL")
			(options
				(clearance outline)
				(anchor circle)
			)
			(primitives
				(gr_poly
					(pts
						(arc
							(start -0.1778 -0.2794)
							(mid -0.249642 -0.249642)
							(end -0.2794 -0.1778)
						)
						(arc
							(start -0.2794 0.1778)
							(mid -0.249642 0.249642)
							(end -0.1778 0.2794)
						)
						(arc
							(start 0.1778 0.2794)
							(mid 0.249642 0.249642)
							(end 0.2794 0.1778)
						)
						(arc
							(start 0.2794 -0.1778)
							(mid 0.249642 -0.249642)
							(end 0.1778 -0.2794)
						)
					)
					(width 0)
					(fill yes)
				)
			)
		)
		(pad "2" smd custom
			(at 0 0.4445 270)
			(size 0.1397 0.1397)
			(layers "F.Cu" "F.Mask" "F.Paste")
			(net "TEMP_1_SCL")
			(options
				(clearance outline)
				(anchor circle)
			)
			(primitives
				(gr_poly
					(pts
						(arc
							(start -0.1778 -0.2794)
							(mid -0.249642 -0.249642)
							(end -0.2794 -0.1778)
						)
						(arc
							(start -0.2794 0.1778)
							(mid -0.249642 0.249642)
							(end -0.1778 0.2794)
						)
						(arc
							(start 0.1778 0.2794)
							(mid 0.249642 0.249642)
							(end 0.2794 0.1778)
						)
						(arc
							(start 0.2794 -0.1778)
							(mid 0.249642 -0.249642)
							(end 0.1778 -0.2794)
						)
					)
					(width 0)
					(fill yes)
				)
			)
		)
	)
	(footprint ""
		(layer "F.Cu")
		(at 148.59 -64.643 180)
		(property "Reference" "SR696"
			(at 0 0 180)
			(layer "F.SilkS")
			(hide yes)
			(effects
				(font
					(size 1.27 1.27)
				)
			)
		)
		(property "Value" "10KR2F-2-GP"
			(at 0.064008 -3.993896 180)
			(unlocked yes)
			(layer "F.Fab")
			(hide yes)
			(effects
				(font
					(size 1.016 1.016)
					(thickness 0.1524)
				)
			)
		)
		(property "Device Type" "R402H16"
			(at 0.064008 -5.517896 180)
			(unlocked yes)
			(layer "F.Fab")
			(hide yes)
			(effects
				(font
					(size 1.016 1.016)
					(thickness 0.1524)
				)
			)
		)
		(duplicate_pad_numbers_are_jumpers no)
		(fp_line
			(start 0.508 -0.9398)
			(end -0.508 -0.9398)
			(stroke
				(width 0.1524)
				(type default)
			)
			(layer "F.SilkS")
		)
		(fp_line
			(start -0.508 -0.9398)
			(end -0.508 0.9398)
			(stroke
				(width 0.1524)
				(type default)
			)
			(layer "F.SilkS")
		)
		(fp_rect
			(start -0.508 0.9398)
			(end 0.508 -0.9398)
			(stroke
				(width 0)
				(type default)
			)
			(fill no)
			(layer "F.CrtYd")
		)
		(fp_rect
			(start -0.508 0.9398)
			(end 0.508 -0.9398)
			(stroke
				(width 0)
				(type default)
			)
			(fill no)
			(layer "F.Fab")
		)
		(pad "1" smd custom
			(at 0 -0.4445 180)
			(size 0.1397 0.1397)
			(layers "F.Cu" "F.Mask" "F.Paste")
			(net "XM_ADDR_1")
			(options
				(clearance outline)
				(anchor circle)
			)
			(primitives
				(gr_poly
					(pts
						(arc
							(start -0.1778 -0.2794)
							(mid -0.249642 -0.249642)
							(end -0.2794 -0.1778)
						)
						(arc
							(start -0.2794 0.1778)
							(mid -0.249642 0.249642)
							(end -0.1778 0.2794)
						)
						(arc
							(start 0.1778 0.2794)
							(mid 0.249642 0.249642)
							(end 0.2794 0.1778)
						)
						(arc
							(start 0.2794 -0.1778)
							(mid 0.249642 -0.249642)
							(end 0.1778 -0.2794)
						)
					)
					(width 0)
					(fill yes)
				)
			)
		)
		(pad "2" smd custom
			(at 0 0.4445 180)
			(size 0.1397 0.1397)
			(layers "F.Cu" "F.Mask" "F.Paste")
			(net "GND")
			(options
				(clearance outline)
				(anchor circle)
			)
			(primitives
				(gr_poly
					(pts
						(arc
							(start -0.1778 -0.2794)
							(mid -0.249642 -0.249642)
							(end -0.2794 -0.1778)
						)
						(arc
							(start -0.2794 0.1778)
							(mid -0.249642 0.249642)
							(end -0.1778 0.2794)
						)
						(arc
							(start 0.1778 0.2794)
							(mid 0.249642 0.249642)
							(end 0.2794 0.1778)
						)
						(arc
							(start 0.2794 -0.1778)
							(mid 0.249642 -0.249642)
							(end 0.1778 -0.2794)
						)
					)
					(width 0)
					(fill yes)
				)
			)
		)
	)
	(footprint ""
		(layer "F.Cu")
		(at 342.040718 -157.838648 180)
		(property "Reference" "C163"
			(at 0 0 180)
			(layer "F.SilkS")
			(hide yes)
			(effects
				(font
					(size 1.27 1.27)
				)
			)
		)
		(property "Value" "SC1U10V2KX-4-GP"
			(at 1.1811 -2.7051 180)
			(unlocked yes)
			(layer "F.Fab")
			(hide yes)
			(effects
				(font
					(size 1.016 1.016)
					(thickness 0.1524)
				)
			)
		)
		(property "Device Type" "C402H22"
			(at 1.1811 -4.2291 180)
			(unlocked yes)
			(layer "F.Fab")
			(hide yes)
			(effects
				(font
					(size 1.016 1.016)
					(thickness 0.1524)
				)
			)
		)
		(duplicate_pad_numbers_are_jumpers no)
		(fp_rect
			(start -0.4318 0.9525)
			(end 0.4318 -0.9525)
			(stroke
				(width 0)
				(type default)
			)
			(fill no)
			(layer "F.CrtYd")
		)
		(fp_rect
			(start -0.4318 0.9525)
			(end 0.4318 -0.9525)
			(stroke
				(width 0)
				(type default)
			)
			(fill no)
			(layer "F.Fab")
		)
		(pad "1" smd custom
			(at 0 -0.4445 180)
			(size 0.1524 0.1524)
			(layers "F.Cu" "F.Mask" "F.Paste")
			(net "P3V3_STBY")
			(options
				(clearance outline)
				(anchor circle)
			)
			(primitives
				(gr_poly
					(pts
						(arc
							(start 0.3048 -0.2032)
							(mid 0.275042 -0.275042)
							(end 0.2032 -0.3048)
						)
						(arc
							(start -0.2032 -0.3048)
							(mid -0.275042 -0.275042)
							(end -0.3048 -0.2032)
						)
						(arc
							(start -0.3048 0.2032)
							(mid -0.275042 0.275042)
							(end -0.2032 0.3048)
						)
						(arc
							(start 0.2032 0.3048)
							(mid 0.275042 0.275042)
							(end 0.3048 0.2032)
						)
					)
					(width 0)
					(fill yes)
				)
			)
		)
		(pad "2" smd custom
			(at 0 0.4445 180)
			(size 0.1524 0.1524)
			(layers "F.Cu" "F.Mask" "F.Paste")
			(net "GND")
			(options
				(clearance outline)
				(anchor circle)
			)
			(primitives
				(gr_poly
					(pts
						(arc
							(start 0.3048 -0.2032)
							(mid 0.275042 -0.275042)
							(end 0.2032 -0.3048)
						)
						(arc
							(start -0.2032 -0.3048)
							(mid -0.275042 -0.275042)
							(end -0.3048 -0.2032)
						)
						(arc
							(start -0.3048 0.2032)
							(mid -0.275042 0.275042)
							(end -0.2032 0.3048)
						)
						(arc
							(start 0.2032 0.3048)
							(mid 0.275042 0.275042)
							(end 0.3048 0.2032)
						)
					)
					(width 0)
					(fill yes)
				)
			)
		)
	)
	(footprint ""
		(layer "F.Cu")
		(at 94.3356 -16.764 -90)
		(property "Reference" "SC946"
			(at 0 0 270)
			(layer "F.SilkS")
			(hide yes)
			(effects
				(font
					(size 1.27 1.27)
				)
			)
		)
		(property "Value" "SC22U6D3V5MX-2GP"
			(at -0.0762 -6.1214 270)
			(unlocked yes)
			(layer "F.Fab")
			(hide yes)
			(effects
				(font
					(size 1.016 1.016)
					(thickness 0.1524)
				)
			)
		)
		(property "Device Type" "C805H58"
			(at -0.0762 -8.1534 270)
			(unlocked yes)
			(layer "F.Fab")
			(hide yes)
			(effects
				(font
					(size 1.016 1.016)
					(thickness 0.1524)
				)
			)
		)
		(duplicate_pad_numbers_are_jumpers no)
		(fp_line
			(start 0.635 0)
			(end -0.635 0)
			(stroke
				(width 0.508)
				(type default)
			)
			(layer "F.SilkS")
		)
		(fp_rect
			(start -0.9652 1.778)
			(end 0.9652 -1.778)
			(stroke
				(width 0)
				(type default)
			)
			(fill no)
			(layer "F.CrtYd")
		)
		(fp_poly
			(pts
				(xy -0.9652 -1.778) (xy 0.9652 -1.778) (xy 0.9652 1.778) (xy -0.9652 1.778)
			)
			(stroke
				(width 0)
				(type default)
			)
			(fill no)
			(layer "F.Fab")
		)
		(pad "1" smd rect
			(at 0 -0.9652 270)
			(size 1.397 1.143)
			(layers "F.Cu" "F.Mask" "F.Paste")
			(net "PCE_AVDD")
		)
		(pad "2" smd rect
			(at 0 0.9652 270)
			(size 1.397 1.143)
			(layers "F.Cu" "F.Mask" "F.Paste")
			(net "GND")
		)
	)
	(footprint ""
		(layer "F.Cu")
		(at 208.534 -93.599 -90)
		(property "Reference" "PC146"
			(at 0 0 270)
			(layer "F.SilkS")
			(hide yes)
			(effects
				(font
					(size 1.27 1.27)
				)
			)
		)
		(property "Value" "SCD1U10V2KX-5GP"
			(at 1.1811 -2.7051 270)
			(unlocked yes)
			(layer "F.Fab")
			(hide yes)
			(effects
				(font
					(size 1.016 1.016)
					(thickness 0.1524)
				)
			)
		)
		(property "Device Type" "C402H22"
			(at 1.1811 -4.2291 270)
			(unlocked yes)
			(layer "F.Fab")
			(hide yes)
			(effects
				(font
					(size 1.016 1.016)
					(thickness 0.1524)
				)
			)
		)
		(duplicate_pad_numbers_are_jumpers no)
		(fp_rect
			(start -0.4318 0.9525)
			(end 0.4318 -0.9525)
			(stroke
				(width 0)
				(type default)
			)
			(fill no)
			(layer "F.CrtYd")
		)
		(fp_rect
			(start -0.4318 0.9525)
			(end 0.4318 -0.9525)
			(stroke
				(width 0)
				(type default)
			)
			(fill no)
			(layer "F.Fab")
		)
		(pad "1" smd custom
			(at 0 -0.4445 270)
			(size 0.1524 0.1524)
			(layers "F.Cu" "F.Mask" "F.Paste")
			(net "P1V5_C")
			(options
				(clearance outline)
				(anchor circle)
			)
			(primitives
				(gr_poly
					(pts
						(arc
							(start 0.3048 -0.2032)
							(mid 0.275042 -0.275042)
							(end 0.2032 -0.3048)
						)
						(arc
							(start -0.2032 -0.3048)
							(mid -0.275042 -0.275042)
							(end -0.3048 -0.2032)
						)
						(arc
							(start -0.3048 0.2032)
							(mid -0.275042 0.275042)
							(end -0.2032 0.3048)
						)
						(arc
							(start 0.2032 0.3048)
							(mid 0.275042 0.275042)
							(end 0.3048 0.2032)
						)
					)
					(width 0)
					(fill yes)
				)
			)
		)
		(pad "2" smd custom
			(at 0 0.4445 270)
			(size 0.1524 0.1524)
			(layers "F.Cu" "F.Mask" "F.Paste")
			(net "GND")
			(options
				(clearance outline)
				(anchor circle)
			)
			(primitives
				(gr_poly
					(pts
						(arc
							(start 0.3048 -0.2032)
							(mid 0.275042 -0.275042)
							(end 0.2032 -0.3048)
						)
						(arc
							(start -0.2032 -0.3048)
							(mid -0.275042 -0.275042)
							(end -0.3048 -0.2032)
						)
						(arc
							(start -0.3048 0.2032)
							(mid -0.275042 0.275042)
							(end -0.2032 0.3048)
						)
						(arc
							(start 0.2032 0.3048)
							(mid 0.275042 0.275042)
							(end 0.3048 0.2032)
						)
					)
					(width 0)
					(fill yes)
				)
			)
		)
	)
	(footprint ""
		(layer "F.Cu")
		(at 95.89897 -88.519 -90)
		(property "Reference" "SR787"
			(at 0 0 270)
			(layer "F.SilkS")
			(hide yes)
			(effects
				(font
					(size 1.27 1.27)
				)
			)
		)
		(property "Value" "4K75R2F-1-GP"
			(at 0.064008 -3.993896 270)
			(unlocked yes)
			(layer "F.Fab")
			(hide yes)
			(effects
				(font
					(size 1.016 1.016)
					(thickness 0.1524)
				)
			)
		)
		(property "Device Type" "R402H16"
			(at 0.064008 -5.517896 270)
			(unlocked yes)
			(layer "F.Fab")
			(hide yes)
			(effects
				(font
					(size 1.016 1.016)
					(thickness 0.1524)
				)
			)
		)
		(duplicate_pad_numbers_are_jumpers no)
		(fp_line
			(start -0.508 -0.9398)
			(end -0.508 0.9398)
			(stroke
				(width 0.1524)
				(type default)
			)
			(layer "F.SilkS")
		)
		(fp_line
			(start 0.508 -0.9398)
			(end -0.508 -0.9398)
			(stroke
				(width 0.1524)
				(type default)
			)
			(layer "F.SilkS")
		)
		(fp_rect
			(start -0.508 0.9398)
			(end 0.508 -0.9398)
			(stroke
				(width 0)
				(type default)
			)
			(fill no)
			(layer "F.CrtYd")
		)
		(fp_rect
			(start -0.508 0.9398)
			(end 0.508 -0.9398)
			(stroke
				(width 0)
				(type default)
			)
			(fill no)
			(layer "F.Fab")
		)
		(pad "1" smd custom
			(at 0 -0.4445 270)
			(size 0.1397 0.1397)
			(layers "F.Cu" "F.Mask" "F.Paste")
			(net "EXP_CPU_MODE_0")
			(options
				(clearance outline)
				(anchor circle)
			)
			(primitives
				(gr_poly
					(pts
						(arc
							(start -0.1778 -0.2794)
							(mid -0.249642 -0.249642)
							(end -0.2794 -0.1778)
						)
						(arc
							(start -0.2794 0.1778)
							(mid -0.249642 0.249642)
							(end -0.1778 0.2794)
						)
						(arc
							(start 0.1778 0.2794)
							(mid 0.249642 0.249642)
							(end 0.2794 0.1778)
						)
						(arc
							(start 0.2794 -0.1778)
							(mid 0.249642 -0.249642)
							(end 0.1778 -0.2794)
						)
					)
					(width 0)
					(fill yes)
				)
			)
		)
		(pad "2" smd custom
			(at 0 0.4445 270)
			(size 0.1397 0.1397)
			(layers "F.Cu" "F.Mask" "F.Paste")
			(net "GND")
			(options
				(clearance outline)
				(anchor circle)
			)
			(primitives
				(gr_poly
					(pts
						(arc
							(start -0.1778 -0.2794)
							(mid -0.249642 -0.249642)
							(end -0.2794 -0.1778)
						)
						(arc
							(start -0.2794 0.1778)
							(mid -0.249642 0.249642)
							(end -0.1778 0.2794)
						)
						(arc
							(start 0.1778 0.2794)
							(mid 0.249642 0.249642)
							(end 0.2794 0.1778)
						)
						(arc
							(start 0.2794 -0.1778)
							(mid 0.249642 -0.249642)
							(end 0.1778 -0.2794)
						)
					)
					(width 0)
					(fill yes)
				)
			)
		)
	)
	(footprint ""
		(layer "F.Cu")
		(at 314.706 -185.293 90)
		(property "Reference" "R311"
			(at 0 0 90)
			(layer "F.SilkS")
			(hide yes)
			(effects
				(font
					(size 1.27 1.27)
				)
			)
		)
		(property "Value" "0R2J-2-GP"
			(at 0.064008 -3.993896 90)
			(unlocked yes)
			(layer "F.Fab")
			(hide yes)
			(effects
				(font
					(size 1.016 1.016)
					(thickness 0.1524)
				)
			)
		)
		(property "Device Type" "R402H16"
			(at 0.064008 -5.517896 90)
			(unlocked yes)
			(layer "F.Fab")
			(hide yes)
			(effects
				(font
					(size 1.016 1.016)
					(thickness 0.1524)
				)
			)
		)
		(duplicate_pad_numbers_are_jumpers no)
		(fp_line
			(start 0.508 -0.9398)
			(end -0.508 -0.9398)
			(stroke
				(width 0.1524)
				(type default)
			)
			(layer "F.SilkS")
		)
		(fp_line
			(start -0.508 -0.9398)
			(end -0.508 0.9398)
			(stroke
				(width 0.1524)
				(type default)
			)
			(layer "F.SilkS")
		)
		(fp_rect
			(start -0.508 0.9398)
			(end 0.508 -0.9398)
			(stroke
				(width 0)
				(type default)
			)
			(fill no)
			(layer "F.CrtYd")
		)
		(fp_rect
			(start -0.508 0.9398)
			(end 0.508 -0.9398)
			(stroke
				(width 0)
				(type default)
			)
			(fill no)
			(layer "F.Fab")
		)
		(pad "1" smd custom
			(at 0 -0.4445 90)
			(size 0.1397 0.1397)
			(layers "F.Cu" "F.Mask" "F.Paste")
			(net "BMC0_LED_DR_R_LED0")
			(options
				(clearance outline)
				(anchor circle)
			)
			(primitives
				(gr_poly
					(pts
						(arc
							(start -0.1778 -0.2794)
							(mid -0.249642 -0.249642)
							(end -0.2794 -0.1778)
						)
						(arc
							(start -0.2794 0.1778)
							(mid -0.249642 0.249642)
							(end -0.1778 0.2794)
						)
						(arc
							(start 0.1778 0.2794)
							(mid 0.249642 0.249642)
							(end 0.2794 0.1778)
						)
						(arc
							(start 0.2794 -0.1778)
							(mid 0.249642 -0.249642)
							(end 0.1778 -0.2794)
						)
					)
					(width 0)
					(fill yes)
				)
			)
		)
		(pad "2" smd custom
			(at 0 0.4445 90)
			(size 0.1397 0.1397)
			(layers "F.Cu" "F.Mask" "F.Paste")
			(net "LED_DR_LED0")
			(options
				(clearance outline)
				(anchor circle)
			)
			(primitives
				(gr_poly
					(pts
						(arc
							(start -0.1778 -0.2794)
							(mid -0.249642 -0.249642)
							(end -0.2794 -0.1778)
						)
						(arc
							(start -0.2794 0.1778)
							(mid -0.249642 0.249642)
							(end -0.1778 0.2794)
						)
						(arc
							(start 0.1778 0.2794)
							(mid 0.249642 0.249642)
							(end 0.2794 0.1778)
						)
						(arc
							(start 0.2794 -0.1778)
							(mid 0.249642 -0.249642)
							(end 0.1778 -0.2794)
						)
					)
					(width 0)
					(fill yes)
				)
			)
		)
	)
	(footprint ""
		(layer "F.Cu")
		(at 325.374 -182.372 180)
		(property "Reference" "R5765"
			(at 0 0 180)
			(layer "F.SilkS")
			(hide yes)
			(effects
				(font
					(size 1.27 1.27)
				)
			)
		)
		(property "Value" "1K8R2F-GP"
			(at 0.064008 -3.993896 180)
			(unlocked yes)
			(layer "F.Fab")
			(hide yes)
			(effects
				(font
					(size 1.016 1.016)
					(thickness 0.1524)
				)
			)
		)
		(property "Device Type" "R402H16"
			(at 0.064008 -5.517896 180)
			(unlocked yes)
			(layer "F.Fab")
			(hide yes)
			(effects
				(font
					(size 1.016 1.016)
					(thickness 0.1524)
				)
			)
		)
		(duplicate_pad_numbers_are_jumpers no)
		(fp_line
			(start 0.508 -0.9398)
			(end -0.508 -0.9398)
			(stroke
				(width 0.1524)
				(type default)
			)
			(layer "F.SilkS")
		)
		(fp_line
			(start -0.508 -0.9398)
			(end -0.508 0.9398)
			(stroke
				(width 0.1524)
				(type default)
			)
			(layer "F.SilkS")
		)
		(fp_rect
			(start -0.508 0.9398)
			(end 0.508 -0.9398)
			(stroke
				(width 0)
				(type default)
			)
			(fill no)
			(layer "F.CrtYd")
		)
		(fp_rect
			(start -0.508 0.9398)
			(end 0.508 -0.9398)
			(stroke
				(width 0)
				(type default)
			)
			(fill no)
			(layer "F.Fab")
		)
		(pad "1" smd custom
			(at 0 -0.4445 180)
			(size 0.1397 0.1397)
			(layers "F.Cu" "F.Mask" "F.Paste")
			(net "P1V8_STBY")
			(options
				(clearance outline)
				(anchor circle)
			)
			(primitives
				(gr_poly
					(pts
						(arc
							(start -0.1778 -0.2794)
							(mid -0.249642 -0.249642)
							(end -0.2794 -0.1778)
						)
						(arc
							(start -0.2794 0.1778)
							(mid -0.249642 0.249642)
							(end -0.1778 0.2794)
						)
						(arc
							(start 0.1778 0.2794)
							(mid 0.249642 0.249642)
							(end 0.2794 0.1778)
						)
						(arc
							(start 0.2794 -0.1778)
							(mid 0.249642 -0.249642)
							(end 0.1778 -0.2794)
						)
					)
					(width 0)
					(fill yes)
				)
			)
		)
		(pad "2" smd custom
			(at 0 0.4445 180)
			(size 0.1397 0.1397)
			(layers "F.Cu" "F.Mask" "F.Paste")
			(net "ADC_P1V8_STBY")
			(options
				(clearance outline)
				(anchor circle)
			)
			(primitives
				(gr_poly
					(pts
						(arc
							(start -0.1778 -0.2794)
							(mid -0.249642 -0.249642)
							(end -0.2794 -0.1778)
						)
						(arc
							(start -0.2794 0.1778)
							(mid -0.249642 0.249642)
							(end -0.1778 0.2794)
						)
						(arc
							(start 0.1778 0.2794)
							(mid 0.249642 0.249642)
							(end 0.2794 0.1778)
						)
						(arc
							(start 0.2794 -0.1778)
							(mid 0.249642 -0.249642)
							(end 0.1778 -0.2794)
						)
					)
					(width 0)
					(fill yes)
				)
			)
		)
	)
	(footprint ""
		(layer "F.Cu")
		(at 86.0806 -3.683)
		(property "Reference" "PC202"
			(at 0 0 0)
			(layer "F.SilkS")
			(hide yes)
			(effects
				(font
					(size 1.27 1.27)
				)
			)
		)
		(property "Value" "SC22U6D3V6KX-2-GP"
			(at -0.0762 -5.1308 0)
			(unlocked yes)
			(layer "F.Fab")
			(hide yes)
			(effects
				(font
					(size 1.016 1.016)
					(thickness 0.1524)
				)
			)
		)
		(property "Device Type" "C1206H71"
			(at -0.127 -6.6548 0)
			(unlocked yes)
			(layer "F.Fab")
			(hide yes)
			(effects
				(font
					(size 1.016 1.016)
					(thickness 0.1524)
				)
			)
		)
		(duplicate_pad_numbers_are_jumpers no)
		(fp_line
			(start -1.016 -2.2352)
			(end 1.016 -2.2352)
			(stroke
				(width 0.1524)
				(type default)
			)
			(layer "F.SilkS")
		)
		(fp_line
			(start -1.016 -0.8382)
			(end -1.016 -2.2352)
			(stroke
				(width 0.1524)
				(type default)
			)
			(layer "F.SilkS")
		)
		(fp_line
			(start -1.016 2.2352)
			(end -1.016 0.8382)
			(stroke
				(width 0.1524)
				(type default)
			)
			(layer "F.SilkS")
		)
		(fp_line
			(start 1.016 -2.2352)
			(end 1.016 -0.8382)
			(stroke
				(width 0.1524)
				(type default)
			)
			(layer "F.SilkS")
		)
		(fp_line
			(start 1.016 0.8382)
			(end 1.016 2.2352)
			(stroke
				(width 0.1524)
				(type default)
			)
			(layer "F.SilkS")
		)
		(fp_line
			(start 1.016 2.2352)
			(end -1.016 2.2352)
			(stroke
				(width 0.1524)
				(type default)
			)
			(layer "F.SilkS")
		)
		(fp_rect
			(start -1.0922 2.3114)
			(end 1.0922 -2.3114)
			(stroke
				(width 0)
				(type default)
			)
			(fill no)
			(layer "F.CrtYd")
		)
		(fp_poly
			(pts
				(xy 1.0922 -2.3114) (xy 1.0922 2.3114) (xy -1.0922 2.3114) (xy -1.0922 -2.3114)
			)
			(stroke
				(width 0)
				(type default)
			)
			(fill no)
			(layer "F.Fab")
		)
		(pad "1" smd rect
			(at 0 -1.397)
			(size 1.651 1.27)
			(layers "F.Cu" "F.Mask" "F.Paste")
			(net "P0V955_C")
		)
		(pad "2" smd rect
			(at 0 1.397)
			(size 1.651 1.27)
			(layers "F.Cu" "F.Mask" "F.Paste")
			(net "GND")
		)
	)
	(footprint ""
		(layer "F.Cu")
		(at 45.98797 -144.653)
		(property "Reference" "SU75"
			(at 0 0 0)
			(layer "F.SilkS")
			(hide yes)
			(effects
				(font
					(size 1.27 1.27)
				)
			)
		)
		(property "Value" "TPS3808G18DRVT-GP-U"
			(at -2.7813 -0.4572 0)
			(unlocked yes)
			(layer "F.Fab")
			(hide yes)
			(effects
				(font
					(size 1.016 1.016)
					(thickness 0.1524)
				)
			)
		)
		(property "Device Type" "DFN6F2-G1711-UH32"
			(at -2.7813 -1.9812 0)
			(unlocked yes)
			(layer "F.Fab")
			(hide yes)
			(effects
				(font
					(size 1.016 1.016)
					(thickness 0.1524)
				)
			)
		)
		(duplicate_pad_numbers_are_jumpers no)
		(fp_line
			(start -1.5113 -1.7653)
			(end -0.7493 -1.7653)
			(stroke
				(width 0.1524)
				(type default)
			)
			(layer "F.SilkS")
		)
		(fp_line
			(start -1.5113 -1.0033)
			(end -1.5113 -1.7653)
			(stroke
				(width 0.1524)
				(type default)
			)
			(layer "F.SilkS")
		)
		(fp_line
			(start -1.5113 1.0033)
			(end -1.5113 1.7653)
			(stroke
				(width 0.1524)
				(type default)
			)
			(layer "F.SilkS")
		)
		(fp_line
			(start -1.5113 1.7653)
			(end -0.7493 1.7653)
			(stroke
				(width 0.1524)
				(type default)
			)
			(layer "F.SilkS")
		)
		(fp_line
			(start 0 1.5113)
			(end 0 2.0193)
			(stroke
				(width 0.1524)
				(type default)
			)
			(layer "F.SilkS")
		)
		(fp_line
			(start 1.5113 1.0033)
			(end 1.5113 1.7653)
			(stroke
				(width 0.1524)
				(type default)
			)
			(layer "F.SilkS")
		)
		(fp_line
			(start 1.5113 1.7653)
			(end 0.7493 1.7653)
			(stroke
				(width 0.1524)
				(type default)
			)
			(layer "F.SilkS")
		)
		(fp_poly
			(pts
				(xy 0.7493 -1.7653) (xy 1.5113 -1.0033) (xy 1.5113 -1.7653)
			)
			(stroke
				(width 0)
				(type default)
			)
			(fill yes)
			(layer "F.SilkS")
		)
		(fp_rect
			(start -1.0033 1.0033)
			(end 1.0033 -1.0033)
			(stroke
				(width 0)
				(type default)
			)
			(fill no)
			(layer "F.CrtYd")
		)
		(fp_poly
			(pts
				(xy -1.5113 1.7653) (xy -1.5113 -1.7653) (xy 1.5113 -1.7653) (xy 1.5113 0.99822) (xy 1.0033 0.99822)
				(xy 1.0033 -1.0033) (xy -1.0033 -1.0033) (xy -1.0033 1.0033) (xy 1.5113 1.0033) (xy 1.5113 1.7653)
			)
			(stroke
				(width 0)
				(type default)
			)
			(fill no)
			(layer "F.CrtYd")
		)
		(fp_rect
			(start -1.5113 1.7653)
			(end 1.5113 -1.7653)
			(stroke
				(width 0)
				(type default)
			)
			(fill no)
			(layer "F.Fab")
		)
		(pad "1" smd rect
			(at 0.649986 -1.1303)
			(size 0.4064 0.508)
			(drill
				(offset 0 0.127)
			)
			(layers "F.Cu" "F.Mask" "F.Paste")
			(net "P1V8_STBY")
		)
		(pad "2" smd rect
			(at 0 -1.1303)
			(size 0.4064 0.508)
			(drill
				(offset 0 0.127)
			)
			(layers "F.Cu" "F.Mask" "F.Paste")
			(net "P1V8_STBY")
		)
		(pad "3" smd rect
			(at -0.649986 -1.1303)
			(size 0.4064 0.508)
			(drill
				(offset 0 0.127)
			)
			(layers "F.Cu" "F.Mask" "F.Paste")
			(net "Net_7")
		)
		(pad "4" smd rect
			(at -0.649986 1.1303)
			(size 0.4064 0.508)
			(drill
				(offset 0 -0.127)
			)
			(layers "F.Cu" "F.Mask" "F.Paste")
			(net "EXP_RESET_MR_N")
		)
		(pad "5" smd rect
			(at 0 1.1303)
			(size 0.4064 0.508)
			(drill
				(offset 0 -0.127)
			)
			(layers "F.Cu" "F.Mask" "F.Paste")
			(net "GND")
		)
		(pad "6" smd rect
			(at 0.649986 1.1303)
			(size 0.4064 0.508)
			(drill
				(offset 0 -0.127)
			)
			(layers "F.Cu" "F.Mask" "F.Paste")
			(net "EXP_RESET_N")
		)
		(pad "7" smd rect
			(at 0 0)
			(size 1.7018 1.0922)
			(layers "F.Cu" "F.Mask" "F.Paste")
			(net "GND")
		)
	)
	(footprint ""
		(layer "F.Cu")
		(at 96.647 -99.822)
		(property "Reference" "STP81"
			(at 0 0 0)
			(layer "F.SilkS")
			(hide yes)
			(effects
				(font
					(size 1.27 1.27)
				)
			)
		)
		(property "Value" "TPAD28"
			(at 0.0127 -1.8034 0)
			(unlocked yes)
			(layer "F.Fab")
			(hide yes)
			(effects
				(font
					(size 1.016 1.016)
					(thickness 0.1524)
				)
			)
		)
		(property "Device Type" "TPAD28"
			(at 0.0127 -3.3274 0)
			(unlocked yes)
			(layer "F.Fab")
			(hide yes)
			(effects
				(font
					(size 1.016 1.016)
					(thickness 0.1524)
				)
			)
		)
		(duplicate_pad_numbers_are_jumpers no)
		(fp_poly
			(pts
				(arc
					(start 0.3556 0)
					(mid -0.3556 0)
					(end 0.3556 0)
				)
			)
			(stroke
				(width 0)
				(type default)
			)
			(fill no)
			(layer "F.CrtYd")
		)
		(fp_poly
			(pts
				(arc
					(start 0.6096 0)
					(mid -0.6096 0)
					(end 0.6096 0)
				)
			)
			(stroke
				(width 0)
				(type default)
			)
			(fill no)
			(layer "F.Fab")
		)
		(pad "1" smd circle
			(at 0 0)
			(size 0.7112 0.7112)
			(layers "F.Cu" "F.Mask" "F.Paste")
			(net "EXP_TACH_IN1")
		)
	)
	(footprint ""
		(layer "F.Cu")
		(at 269.739872 -55.698136 90)
		(property "Reference" "PR117"
			(at 0 0 90)
			(layer "F.SilkS")
			(hide yes)
			(effects
				(font
					(size 1.27 1.27)
				)
			)
		)
		(property "Value" "0R2J-2-GP"
			(at 0.064008 -3.993896 90)
			(unlocked yes)
			(layer "F.Fab")
			(hide yes)
			(effects
				(font
					(size 1.016 1.016)
					(thickness 0.1524)
				)
			)
		)
		(property "Device Type" "R402H16"
			(at 0.064008 -5.517896 90)
			(unlocked yes)
			(layer "F.Fab")
			(hide yes)
			(effects
				(font
					(size 1.016 1.016)
					(thickness 0.1524)
				)
			)
		)
		(duplicate_pad_numbers_are_jumpers no)
		(fp_line
			(start 0.508 -0.9398)
			(end -0.508 -0.9398)
			(stroke
				(width 0.1524)
				(type default)
			)
			(layer "F.SilkS")
		)
		(fp_line
			(start -0.508 -0.9398)
			(end -0.508 0.9398)
			(stroke
				(width 0.1524)
				(type default)
			)
			(layer "F.SilkS")
		)
		(fp_rect
			(start -0.508 0.9398)
			(end 0.508 -0.9398)
			(stroke
				(width 0)
				(type default)
			)
			(fill no)
			(layer "F.CrtYd")
		)
		(fp_rect
			(start -0.508 0.9398)
			(end 0.508 -0.9398)
			(stroke
				(width 0)
				(type default)
			)
			(fill no)
			(layer "F.Fab")
		)
		(pad "1" smd custom
			(at 0 -0.4445 90)
			(size 0.1397 0.1397)
			(layers "F.Cu" "F.Mask" "F.Paste")
			(net "P0V9_E_PG")
			(options
				(clearance outline)
				(anchor circle)
			)
			(primitives
				(gr_poly
					(pts
						(arc
							(start -0.1778 -0.2794)
							(mid -0.249642 -0.249642)
							(end -0.2794 -0.1778)
						)
						(arc
							(start -0.2794 0.1778)
							(mid -0.249642 0.249642)
							(end -0.1778 0.2794)
						)
						(arc
							(start 0.1778 0.2794)
							(mid 0.249642 0.249642)
							(end 0.2794 0.1778)
						)
						(arc
							(start 0.2794 -0.1778)
							(mid 0.249642 -0.249642)
							(end 0.1778 -0.2794)
						)
					)
					(width 0)
					(fill yes)
				)
			)
		)
		(pad "2" smd custom
			(at 0 0.4445 90)
			(size 0.1397 0.1397)
			(layers "F.Cu" "F.Mask" "F.Paste")
			(net "P3V3_EN_B")
			(options
				(clearance outline)
				(anchor circle)
			)
			(primitives
				(gr_poly
					(pts
						(arc
							(start -0.1778 -0.2794)
							(mid -0.249642 -0.249642)
							(end -0.2794 -0.1778)
						)
						(arc
							(start -0.2794 0.1778)
							(mid -0.249642 0.249642)
							(end -0.1778 0.2794)
						)
						(arc
							(start 0.1778 0.2794)
							(mid 0.249642 0.249642)
							(end 0.2794 0.1778)
						)
						(arc
							(start 0.2794 -0.1778)
							(mid 0.249642 -0.249642)
							(end 0.1778 -0.2794)
						)
					)
					(width 0)
					(fill yes)
				)
			)
		)
	)
	(footprint ""
		(layer "F.Cu")
		(at 186.244992 -48.133 -90)
		(property "Reference" "R21"
			(at 0 0 270)
			(layer "F.SilkS")
			(hide yes)
			(effects
				(font
					(size 1.27 1.27)
				)
			)
		)
		(property "Value" "10KR2F-2-GP"
			(at 0.064008 -3.993896 270)
			(unlocked yes)
			(layer "F.Fab")
			(hide yes)
			(effects
				(font
					(size 1.016 1.016)
					(thickness 0.1524)
				)
			)
		)
		(property "Device Type" "R402H16"
			(at 0.064008 -5.517896 270)
			(unlocked yes)
			(layer "F.Fab")
			(hide yes)
			(effects
				(font
					(size 1.016 1.016)
					(thickness 0.1524)
				)
			)
		)
		(duplicate_pad_numbers_are_jumpers no)
		(fp_line
			(start -0.508 -0.9398)
			(end -0.508 0.9398)
			(stroke
				(width 0.1524)
				(type default)
			)
			(layer "F.SilkS")
		)
		(fp_line
			(start 0.508 -0.9398)
			(end -0.508 -0.9398)
			(stroke
				(width 0.1524)
				(type default)
			)
			(layer "F.SilkS")
		)
		(fp_rect
			(start -0.508 0.9398)
			(end 0.508 -0.9398)
			(stroke
				(width 0)
				(type default)
			)
			(fill no)
			(layer "F.CrtYd")
		)
		(fp_rect
			(start -0.508 0.9398)
			(end 0.508 -0.9398)
			(stroke
				(width 0)
				(type default)
			)
			(fill no)
			(layer "F.Fab")
		)
		(pad "1" smd custom
			(at 0 -0.4445 270)
			(size 0.1397 0.1397)
			(layers "F.Cu" "F.Mask" "F.Paste")
			(net "PRSNT_MSB_AND_1")
			(options
				(clearance outline)
				(anchor circle)
			)
			(primitives
				(gr_poly
					(pts
						(arc
							(start -0.1778 -0.2794)
							(mid -0.249642 -0.249642)
							(end -0.2794 -0.1778)
						)
						(arc
							(start -0.2794 0.1778)
							(mid -0.249642 0.249642)
							(end -0.1778 0.2794)
						)
						(arc
							(start 0.1778 0.2794)
							(mid 0.249642 0.249642)
							(end 0.2794 0.1778)
						)
						(arc
							(start 0.2794 -0.1778)
							(mid 0.249642 -0.249642)
							(end 0.1778 -0.2794)
						)
					)
					(width 0)
					(fill yes)
				)
			)
		)
		(pad "2" smd custom
			(at 0 0.4445 270)
			(size 0.1397 0.1397)
			(layers "F.Cu" "F.Mask" "F.Paste")
			(net "P3V3_STBY")
			(options
				(clearance outline)
				(anchor circle)
			)
			(primitives
				(gr_poly
					(pts
						(arc
							(start -0.1778 -0.2794)
							(mid -0.249642 -0.249642)
							(end -0.2794 -0.1778)
						)
						(arc
							(start -0.2794 0.1778)
							(mid -0.249642 0.249642)
							(end -0.1778 0.2794)
						)
						(arc
							(start 0.1778 0.2794)
							(mid 0.249642 0.249642)
							(end 0.2794 0.1778)
						)
						(arc
							(start 0.2794 -0.1778)
							(mid 0.249642 -0.249642)
							(end 0.1778 -0.2794)
						)
					)
					(width 0)
					(fill yes)
				)
			)
		)
	)
	(footprint ""
		(layer "F.Cu")
		(at 276.1488 -168.8846)
		(property "Reference" "TP88"
			(at 0 0 0)
			(layer "F.SilkS")
			(hide yes)
			(effects
				(font
					(size 1.27 1.27)
				)
			)
		)
		(property "Value" "TPAD28"
			(at 0.0127 -1.8034 0)
			(unlocked yes)
			(layer "F.Fab")
			(hide yes)
			(effects
				(font
					(size 1.016 1.016)
					(thickness 0.1524)
				)
			)
		)
		(property "Device Type" "TPAD28"
			(at 0.0127 -3.3274 0)
			(unlocked yes)
			(layer "F.Fab")
			(hide yes)
			(effects
				(font
					(size 1.016 1.016)
					(thickness 0.1524)
				)
			)
		)
		(duplicate_pad_numbers_are_jumpers no)
		(fp_poly
			(pts
				(arc
					(start 0.3556 0)
					(mid -0.3556 0)
					(end 0.3556 0)
				)
			)
			(stroke
				(width 0)
				(type default)
			)
			(fill no)
			(layer "F.CrtYd")
		)
		(fp_poly
			(pts
				(arc
					(start 0.6096 0)
					(mid -0.6096 0)
					(end 0.6096 0)
				)
			)
			(stroke
				(width 0)
				(type default)
			)
			(fill no)
			(layer "F.Fab")
		)
		(pad "1" smd circle
			(at 0 0)
			(size 0.7112 0.7112)
			(layers "F.Cu" "F.Mask" "F.Paste")
			(net "BMC_MSB_I2C_E_ALERT_#")
		)
	)
	(footprint ""
		(layer "F.Cu")
		(at 116.47297 -74.93)
		(property "Reference" "SR801"
			(at 0 0 0)
			(layer "F.SilkS")
			(hide yes)
			(effects
				(font
					(size 1.27 1.27)
				)
			)
		)
		(property "Value" "4K75R2F-1-GP"
			(at 0.064008 -3.993896 0)
			(unlocked yes)
			(layer "F.Fab")
			(hide yes)
			(effects
				(font
					(size 1.016 1.016)
					(thickness 0.1524)
				)
			)
		)
		(property "Device Type" "R402H16"
			(at 0.064008 -5.517896 0)
			(unlocked yes)
			(layer "F.Fab")
			(hide yes)
			(effects
				(font
					(size 1.016 1.016)
					(thickness 0.1524)
				)
			)
		)
		(duplicate_pad_numbers_are_jumpers no)
		(fp_line
			(start -0.508 -0.9398)
			(end -0.508 0.9398)
			(stroke
				(width 0.1524)
				(type default)
			)
			(layer "F.SilkS")
		)
		(fp_line
			(start 0.508 -0.9398)
			(end -0.508 -0.9398)
			(stroke
				(width 0.1524)
				(type default)
			)
			(layer "F.SilkS")
		)
		(fp_rect
			(start -0.508 0.9398)
			(end 0.508 -0.9398)
			(stroke
				(width 0)
				(type default)
			)
			(fill no)
			(layer "F.CrtYd")
		)
		(fp_rect
			(start -0.508 0.9398)
			(end 0.508 -0.9398)
			(stroke
				(width 0)
				(type default)
			)
			(fill no)
			(layer "F.Fab")
		)
		(pad "1" smd custom
			(at 0 -0.4445)
			(size 0.1397 0.1397)
			(layers "F.Cu" "F.Mask" "F.Paste")
			(net "TEST_MUX_46")
			(options
				(clearance outline)
				(anchor circle)
			)
			(primitives
				(gr_poly
					(pts
						(arc
							(start -0.1778 -0.2794)
							(mid -0.249642 -0.249642)
							(end -0.2794 -0.1778)
						)
						(arc
							(start -0.2794 0.1778)
							(mid -0.249642 0.249642)
							(end -0.1778 0.2794)
						)
						(arc
							(start 0.1778 0.2794)
							(mid 0.249642 0.249642)
							(end 0.2794 0.1778)
						)
						(arc
							(start 0.2794 -0.1778)
							(mid 0.249642 -0.249642)
							(end 0.1778 -0.2794)
						)
					)
					(width 0)
					(fill yes)
				)
			)
		)
		(pad "2" smd custom
			(at 0 0.4445)
			(size 0.1397 0.1397)
			(layers "F.Cu" "F.Mask" "F.Paste")
			(net "GND")
			(options
				(clearance outline)
				(anchor circle)
			)
			(primitives
				(gr_poly
					(pts
						(arc
							(start -0.1778 -0.2794)
							(mid -0.249642 -0.249642)
							(end -0.2794 -0.1778)
						)
						(arc
							(start -0.2794 0.1778)
							(mid -0.249642 0.249642)
							(end -0.1778 0.2794)
						)
						(arc
							(start 0.1778 0.2794)
							(mid 0.249642 0.249642)
							(end 0.2794 0.1778)
						)
						(arc
							(start 0.2794 -0.1778)
							(mid 0.249642 -0.249642)
							(end 0.1778 -0.2794)
						)
					)
					(width 0)
					(fill yes)
				)
			)
		)
	)
	(footprint ""
		(layer "F.Cu")
		(at 195.199 -216.789 90)
		(property "Reference" "R326"
			(at 0 0 90)
			(layer "F.SilkS")
			(hide yes)
			(effects
				(font
					(size 1.27 1.27)
				)
			)
		)
		(property "Value" "4K7R2F-GP"
			(at 0.064008 -3.993896 90)
			(unlocked yes)
			(layer "F.Fab")
			(hide yes)
			(effects
				(font
					(size 1.016 1.016)
					(thickness 0.1524)
				)
			)
		)
		(property "Device Type" "R402H16"
			(at 0.064008 -5.517896 90)
			(unlocked yes)
			(layer "F.Fab")
			(hide yes)
			(effects
				(font
					(size 1.016 1.016)
					(thickness 0.1524)
				)
			)
		)
		(duplicate_pad_numbers_are_jumpers no)
		(fp_line
			(start 0.508 -0.9398)
			(end -0.508 -0.9398)
			(stroke
				(width 0.1524)
				(type default)
			)
			(layer "F.SilkS")
		)
		(fp_line
			(start -0.508 -0.9398)
			(end -0.508 0.9398)
			(stroke
				(width 0.1524)
				(type default)
			)
			(layer "F.SilkS")
		)
		(fp_rect
			(start -0.508 0.9398)
			(end 0.508 -0.9398)
			(stroke
				(width 0)
				(type default)
			)
			(fill no)
			(layer "F.CrtYd")
		)
		(fp_rect
			(start -0.508 0.9398)
			(end 0.508 -0.9398)
			(stroke
				(width 0)
				(type default)
			)
			(fill no)
			(layer "F.Fab")
		)
		(pad "1" smd custom
			(at 0 -0.4445 90)
			(size 0.1397 0.1397)
			(layers "F.Cu" "F.Mask" "F.Paste")
			(net "P3V3_STBY")
			(options
				(clearance outline)
				(anchor circle)
			)
			(primitives
				(gr_poly
					(pts
						(arc
							(start -0.1778 -0.2794)
							(mid -0.249642 -0.249642)
							(end -0.2794 -0.1778)
						)
						(arc
							(start -0.2794 0.1778)
							(mid -0.249642 0.249642)
							(end -0.1778 0.2794)
						)
						(arc
							(start 0.1778 0.2794)
							(mid 0.249642 0.249642)
							(end 0.2794 0.1778)
						)
						(arc
							(start 0.2794 -0.1778)
							(mid 0.249642 -0.249642)
							(end 0.1778 -0.2794)
						)
					)
					(width 0)
					(fill yes)
				)
			)
		)
		(pad "2" smd custom
			(at 0 0.4445 90)
			(size 0.1397 0.1397)
			(layers "F.Cu" "F.Mask" "F.Paste")
			(net "BMC_RSTBTN_N")
			(options
				(clearance outline)
				(anchor circle)
			)
			(primitives
				(gr_poly
					(pts
						(arc
							(start -0.1778 -0.2794)
							(mid -0.249642 -0.249642)
							(end -0.2794 -0.1778)
						)
						(arc
							(start -0.2794 0.1778)
							(mid -0.249642 0.249642)
							(end -0.1778 0.2794)
						)
						(arc
							(start 0.1778 0.2794)
							(mid 0.249642 0.249642)
							(end 0.2794 0.1778)
						)
						(arc
							(start 0.2794 -0.1778)
							(mid 0.249642 -0.249642)
							(end 0.1778 -0.2794)
						)
					)
					(width 0)
					(fill yes)
				)
			)
		)
	)
	(footprint ""
		(layer "F.Cu")
		(at 274.193 -174.625 90)
		(property "Reference" "R352"
			(at 0 0 90)
			(layer "F.SilkS")
			(hide yes)
			(effects
				(font
					(size 1.27 1.27)
				)
			)
		)
		(property "Value" "3K3R2F-2-GP"
			(at 0.064008 -3.993896 90)
			(unlocked yes)
			(layer "F.Fab")
			(hide yes)
			(effects
				(font
					(size 1.016 1.016)
					(thickness 0.1524)
				)
			)
		)
		(property "Device Type" "R402H16"
			(at 0.064008 -5.517896 90)
			(unlocked yes)
			(layer "F.Fab")
			(hide yes)
			(effects
				(font
					(size 1.016 1.016)
					(thickness 0.1524)
				)
			)
		)
		(duplicate_pad_numbers_are_jumpers no)
		(fp_line
			(start 0.508 -0.9398)
			(end -0.508 -0.9398)
			(stroke
				(width 0.1524)
				(type default)
			)
			(layer "F.SilkS")
		)
		(fp_line
			(start -0.508 -0.9398)
			(end -0.508 0.9398)
			(stroke
				(width 0.1524)
				(type default)
			)
			(layer "F.SilkS")
		)
		(fp_rect
			(start -0.508 0.9398)
			(end 0.508 -0.9398)
			(stroke
				(width 0)
				(type default)
			)
			(fill no)
			(layer "F.CrtYd")
		)
		(fp_rect
			(start -0.508 0.9398)
			(end 0.508 -0.9398)
			(stroke
				(width 0)
				(type default)
			)
			(fill no)
			(layer "F.Fab")
		)
		(pad "1" smd custom
			(at 0 -0.4445 90)
			(size 0.1397 0.1397)
			(layers "F.Cu" "F.Mask" "F.Paste")
			(net "P3V3_STBY")
			(options
				(clearance outline)
				(anchor circle)
			)
			(primitives
				(gr_poly
					(pts
						(arc
							(start -0.1778 -0.2794)
							(mid -0.249642 -0.249642)
							(end -0.2794 -0.1778)
						)
						(arc
							(start -0.2794 0.1778)
							(mid -0.249642 0.249642)
							(end -0.1778 0.2794)
						)
						(arc
							(start 0.1778 0.2794)
							(mid 0.249642 0.249642)
							(end 0.2794 0.1778)
						)
						(arc
							(start 0.2794 -0.1778)
							(mid 0.249642 -0.249642)
							(end 0.1778 -0.2794)
						)
					)
					(width 0)
					(fill yes)
				)
			)
		)
		(pad "2" smd custom
			(at 0 0.4445 90)
			(size 0.1397 0.1397)
			(layers "F.Cu" "F.Mask" "F.Paste")
			(net "ROMA11")
			(options
				(clearance outline)
				(anchor circle)
			)
			(primitives
				(gr_poly
					(pts
						(arc
							(start -0.1778 -0.2794)
							(mid -0.249642 -0.249642)
							(end -0.2794 -0.1778)
						)
						(arc
							(start -0.2794 0.1778)
							(mid -0.249642 0.249642)
							(end -0.1778 0.2794)
						)
						(arc
							(start 0.1778 0.2794)
							(mid 0.249642 0.249642)
							(end 0.2794 0.1778)
						)
						(arc
							(start 0.2794 -0.1778)
							(mid 0.249642 -0.249642)
							(end 0.1778 -0.2794)
						)
					)
					(width 0)
					(fill yes)
				)
			)
		)
	)
	(footprint ""
		(layer "F.Cu")
		(at 261.039864 -231.004872)
		(property "Reference" "PR90"
			(at 0 0 0)
			(layer "F.SilkS")
			(hide yes)
			(effects
				(font
					(size 1.27 1.27)
				)
			)
		)
		(property "Value" "0R2J-2-GP"
			(at 0.064008 -3.993896 0)
			(unlocked yes)
			(layer "F.Fab")
			(hide yes)
			(effects
				(font
					(size 1.016 1.016)
					(thickness 0.1524)
				)
			)
		)
		(property "Device Type" "R402H16"
			(at 0.064008 -5.517896 0)
			(unlocked yes)
			(layer "F.Fab")
			(hide yes)
			(effects
				(font
					(size 1.016 1.016)
					(thickness 0.1524)
				)
			)
		)
		(duplicate_pad_numbers_are_jumpers no)
		(fp_line
			(start -0.508 -0.9398)
			(end -0.508 0.9398)
			(stroke
				(width 0.1524)
				(type default)
			)
			(layer "F.SilkS")
		)
		(fp_line
			(start 0.508 -0.9398)
			(end -0.508 -0.9398)
			(stroke
				(width 0.1524)
				(type default)
			)
			(layer "F.SilkS")
		)
		(fp_rect
			(start -0.508 0.9398)
			(end 0.508 -0.9398)
			(stroke
				(width 0)
				(type default)
			)
			(fill no)
			(layer "F.CrtYd")
		)
		(fp_rect
			(start -0.508 0.9398)
			(end 0.508 -0.9398)
			(stroke
				(width 0)
				(type default)
			)
			(fill no)
			(layer "F.Fab")
		)
		(pad "1" smd custom
			(at 0 -0.4445)
			(size 0.1397 0.1397)
			(layers "F.Cu" "F.Mask" "F.Paste")
			(net "P3V3_STBY")
			(options
				(clearance outline)
				(anchor circle)
			)
			(primitives
				(gr_poly
					(pts
						(arc
							(start -0.1778 -0.2794)
							(mid -0.249642 -0.249642)
							(end -0.2794 -0.1778)
						)
						(arc
							(start -0.2794 0.1778)
							(mid -0.249642 0.249642)
							(end -0.1778 0.2794)
						)
						(arc
							(start 0.1778 0.2794)
							(mid 0.249642 0.249642)
							(end 0.2794 0.1778)
						)
						(arc
							(start 0.2794 -0.1778)
							(mid 0.249642 -0.249642)
							(end 0.1778 -0.2794)
						)
					)
					(width 0)
					(fill yes)
				)
			)
		)
		(pad "2" smd custom
			(at 0 0.4445)
			(size 0.1397 0.1397)
			(layers "F.Cu" "F.Mask" "F.Paste")
			(net "TPS74801_1V26_STBY_BIAS")
			(options
				(clearance outline)
				(anchor circle)
			)
			(primitives
				(gr_poly
					(pts
						(arc
							(start -0.1778 -0.2794)
							(mid -0.249642 -0.249642)
							(end -0.2794 -0.1778)
						)
						(arc
							(start -0.2794 0.1778)
							(mid -0.249642 0.249642)
							(end -0.1778 0.2794)
						)
						(arc
							(start 0.1778 0.2794)
							(mid 0.249642 0.249642)
							(end 0.2794 0.1778)
						)
						(arc
							(start 0.2794 -0.1778)
							(mid 0.249642 -0.249642)
							(end 0.1778 -0.2794)
						)
					)
					(width 0)
					(fill yes)
				)
			)
		)
	)
	(footprint ""
		(layer "F.Cu")
		(at 315.595 -149.352 90)
		(property "Reference" "TP800"
			(at 0 0 90)
			(layer "F.SilkS")
			(hide yes)
			(effects
				(font
					(size 1.27 1.27)
				)
			)
		)
		(property "Value" "TPAD28"
			(at -0.0127 -1.6637 90)
			(unlocked yes)
			(layer "F.Fab")
			(hide yes)
			(effects
				(font
					(size 1.016 1.016)
					(thickness 0.1524)
				)
			)
		)
		(property "Device Type" "TPAD28"
			(at -0.0127 -3.1877 90)
			(unlocked yes)
			(layer "F.Fab")
			(hide yes)
			(effects
				(font
					(size 1.016 1.016)
					(thickness 0.1524)
				)
			)
		)
		(duplicate_pad_numbers_are_jumpers no)
		(fp_poly
			(pts
				(arc
					(start 0 0.3556)
					(mid 0 -0.3556)
					(end 0 0.3556)
				)
			)
			(stroke
				(width 0)
				(type default)
			)
			(fill no)
			(layer "F.CrtYd")
		)
		(fp_poly
			(pts
				(arc
					(start 0 0.6096)
					(mid 0 -0.6096)
					(end 0 0.6096)
				)
			)
			(stroke
				(width 0)
				(type default)
			)
			(fill no)
			(layer "F.Fab")
		)
		(pad "1" smd circle
			(at 0 0 90)
			(size 0.7112 0.7112)
			(layers "F.Cu" "F.Mask" "F.Paste")
			(net "RTC_CLK_OUT")
		)
	)
	(footprint ""
		(layer "F.Cu")
		(at 209.799936 -77.0001 180)
		(property "Reference" "CN8"
			(at 0 0 180)
			(layer "F.SilkS")
			(hide yes)
			(effects
				(font
					(size 1.27 1.27)
				)
			)
		)
		(property "Value" "PCISLT164-44-GP"
			(at -23.3172 -6.8961 180)
			(unlocked yes)
			(layer "F.Fab")
			(hide yes)
			(effects
				(font
					(size 1.016 1.016)
					(thickness 0.1524)
				)
			)
		)
		(property "Device Type" "AAA-PCI-066-K06"
			(at -23.3172 -8.4201 180)
			(unlocked yes)
			(layer "F.Fab")
			(hide yes)
			(effects
				(font
					(size 1.016 1.016)
					(thickness 0.1524)
				)
			)
		)
		(duplicate_pad_numbers_are_jumpers no)
		(fp_line
			(start 74.5998 5.3594)
			(end -14.9098 5.3594)
			(stroke
				(width 0.1524)
				(type default)
			)
			(layer "F.SilkS")
		)
		(fp_line
			(start 74.5998 -4.0386)
			(end 74.5998 5.3594)
			(stroke
				(width 0.1524)
				(type default)
			)
			(layer "F.SilkS")
		)
		(fp_line
			(start -14.9098 5.3594)
			(end -14.9098 -4.0386)
			(stroke
				(width 0.1524)
				(type default)
			)
			(layer "F.SilkS")
		)
		(fp_line
			(start -14.9098 -4.0386)
			(end 74.5998 -4.0386)
			(stroke
				(width 0.1524)
				(type default)
			)
			(layer "F.SilkS")
		)
		(fp_rect
			(start -14.6558 5.1054)
			(end 74.3458 -3.683)
			(stroke
				(width 0)
				(type default)
			)
			(fill no)
			(layer "F.CrtYd")
		)
		(fp_poly
			(pts
				(xy -15.1638 5.6134) (xy -15.1638 0.00254) (xy -14.6558 0.00254) (xy -14.6558 5.1054) (xy 74.3458 5.1054)
				(xy 74.3458 -3.683) (xy -14.6558 -3.683) (xy -14.6558 -0.00254) (xy -15.1638 -0.00254) (xy -15.1638 -4.2926)
				(xy 74.8538 -4.2926) (xy 74.8538 5.6134)
			)
			(stroke
				(width 0)
				(type default)
			)
			(fill no)
			(layer "F.CrtYd")
		)
		(fp_rect
			(start -15.1638 5.6134)
			(end 74.8538 -4.2926)
			(stroke
				(width 0)
				(type default)
			)
			(fill no)
			(layer "F.Fab")
		)
		(pad "" np_thru_hole circle
			(at 0 0 180)
			(size 0.254 0.254)
			(drill 2.3622)
			(layers "*.Cu" "*.Mask")
			(clearance 1.4097)
			(thermal_gap 1.4097)
		)
		(pad "" np_thru_hole circle
			(at 73.14946 0 180)
			(size 0.254 0.254)
			(drill 2.3622)
			(layers "*.Cu" "*.Mask")
			(clearance 1.4097)
			(thermal_gap 1.4097)
		)
		(pad "A1" thru_hole circle
			(at -11.64971 -1.24968 180)
			(size 1.0922 1.0922)
			(drill 0.7366)
			(layers "*.Cu" "*.Mask")
			(remove_unused_layers no)
			(net "PRSNT_MSB_A1")
			(clearance 0.1778)
			(thermal_gap 0.1778)
		)
		(pad "A2" thru_hole circle
			(at -10.65022 -3.24993 180)
			(size 1.0922 1.0922)
			(drill 0.7366)
			(layers "*.Cu" "*.Mask")
			(remove_unused_layers no)
			(net "P12V_MSB")
			(clearance 0.1778)
			(thermal_gap 0.1778)
		)
		(pad "A3" thru_hole circle
			(at -9.64946 -1.24968 180)
			(size 1.0922 1.0922)
			(drill 0.7366)
			(layers "*.Cu" "*.Mask")
			(remove_unused_layers no)
			(net "P12V_MSB")
			(clearance 0.1778)
			(thermal_gap 0.1778)
		)
		(pad "A4" thru_hole circle
			(at -8.64997 -3.24993 180)
			(size 1.0922 1.0922)
			(drill 0.7366)
			(layers "*.Cu" "*.Mask")
			(remove_unused_layers no)
			(net "GND")
			(clearance 0.1778)
			(thermal_gap 0.1778)
		)
		(pad "A5" thru_hole circle
			(at -7.65048 -1.24968 180)
			(size 1.0922 1.0922)
			(drill 0.7366)
			(layers "*.Cu" "*.Mask")
			(remove_unused_layers no)
			(net "SVR_ID0")
			(clearance 0.1778)
			(thermal_gap 0.1778)
		)
		(pad "A6" thru_hole circle
			(at -6.64972 -3.24993 180)
			(size 1.0922 1.0922)
			(drill 0.7366)
			(layers "*.Cu" "*.Mask")
			(remove_unused_layers no)
			(net "SVR_ID1")
			(clearance 0.1778)
			(thermal_gap 0.1778)
		)
		(pad "A7" thru_hole circle
			(at -5.65023 -1.24968 180)
			(size 1.0922 1.0922)
			(drill 0.7366)
			(layers "*.Cu" "*.Mask")
			(remove_unused_layers no)
			(net "CPU_TXD")
			(clearance 0.1778)
			(thermal_gap 0.1778)
		)
		(pad "A8" thru_hole circle
			(at -4.64947 -3.24993 180)
			(size 1.0922 1.0922)
			(drill 0.7366)
			(layers "*.Cu" "*.Mask")
			(remove_unused_layers no)
			(net "CPU_RXD")
			(clearance 0.1778)
			(thermal_gap 0.1778)
		)
		(pad "A9" thru_hole circle
			(at -3.64998 -1.24968 180)
			(size 1.0922 1.0922)
			(drill 0.7366)
			(layers "*.Cu" "*.Mask")
			(remove_unused_layers no)
			(net "SVR_ID2")
			(clearance 0.1778)
			(thermal_gap 0.1778)
		)
		(pad "A10" thru_hole circle
			(at -2.65049 -3.24993 180)
			(size 1.0922 1.0922)
			(drill 0.7366)
			(layers "*.Cu" "*.Mask")
			(remove_unused_layers no)
			(net "SVR_ID3")
			(clearance 0.1778)
			(thermal_gap 0.1778)
		)
		(pad "A11" thru_hole circle
			(at -1.64973 -1.24968 180)
			(size 1.0922 1.0922)
			(drill 0.7366)
			(layers "*.Cu" "*.Mask")
			(remove_unused_layers no)
			(net "PMU_PLTRST#")
			(clearance 0.1778)
			(thermal_gap 0.1778)
		)
		(pad "A12" thru_hole circle
			(at 1.35001 -3.24993 180)
			(size 1.0922 1.0922)
			(drill 0.7366)
			(layers "*.Cu" "*.Mask")
			(remove_unused_layers no)
			(net "GND")
			(clearance 0.1778)
			(thermal_gap 0.1778)
		)
		(pad "A13" thru_hole circle
			(at 2.3495 -1.24968 180)
			(size 1.0922 1.0922)
			(drill 0.7366)
			(layers "*.Cu" "*.Mask")
			(remove_unused_layers no)
			(net "CLK_100M_PCIE_SAS_C_P")
			(clearance 0.1778)
			(thermal_gap 0.1778)
		)
		(pad "A14" thru_hole circle
			(at 3.35026 -3.24993 180)
			(size 1.0922 1.0922)
			(drill 0.7366)
			(layers "*.Cu" "*.Mask")
			(remove_unused_layers no)
			(net "CLK_100M_PCIE_SAS_C_N")
			(clearance 0.1778)
			(thermal_gap 0.1778)
		)
		(pad "A15" thru_hole circle
			(at 4.34975 -1.24968 180)
			(size 1.0922 1.0922)
			(drill 0.7366)
			(layers "*.Cu" "*.Mask")
			(remove_unused_layers no)
			(net "GND")
			(clearance 0.1778)
			(thermal_gap 0.1778)
		)
		(pad "A16" thru_hole circle
			(at 5.35051 -3.24993 180)
			(size 1.0922 1.0922)
			(drill 0.7366)
			(layers "*.Cu" "*.Mask")
			(remove_unused_layers no)
			(net "GND")
			(clearance 0.1778)
			(thermal_gap 0.1778)
		)
		(pad "A17" thru_hole circle
			(at 6.35 -1.24968 180)
			(size 1.0922 1.0922)
			(drill 0.7366)
			(layers "*.Cu" "*.Mask")
			(remove_unused_layers no)
			(net "PCIE_SAS_CPU_RX_P0")
			(clearance 0.1778)
			(thermal_gap 0.1778)
		)
		(pad "A18" thru_hole circle
			(at 7.34949 -3.24993 180)
			(size 1.0922 1.0922)
			(drill 0.7366)
			(layers "*.Cu" "*.Mask")
			(remove_unused_layers no)
			(net "PCIE_SAS_CPU_RX_N0")
			(clearance 0.1778)
			(thermal_gap 0.1778)
		)
		(pad "A19" thru_hole circle
			(at 8.35025 -1.24968 180)
			(size 1.0922 1.0922)
			(drill 0.7366)
			(layers "*.Cu" "*.Mask")
			(remove_unused_layers no)
			(net "GND")
			(clearance 0.1778)
			(thermal_gap 0.1778)
		)
		(pad "A20" thru_hole circle
			(at 9.34974 -3.24993 180)
			(size 1.0922 1.0922)
			(drill 0.7366)
			(layers "*.Cu" "*.Mask")
			(remove_unused_layers no)
			(net "GND")
			(clearance 0.1778)
			(thermal_gap 0.1778)
		)
		(pad "A21" thru_hole circle
			(at 10.3505 -1.24968 180)
			(size 1.0922 1.0922)
			(drill 0.7366)
			(layers "*.Cu" "*.Mask")
			(remove_unused_layers no)
			(net "PCIE_SAS_CPU_RX_P1")
			(clearance 0.1778)
			(thermal_gap 0.1778)
		)
		(pad "A22" thru_hole circle
			(at 11.34999 -3.24993 180)
			(size 1.0922 1.0922)
			(drill 0.7366)
			(layers "*.Cu" "*.Mask")
			(remove_unused_layers no)
			(net "PCIE_SAS_CPU_RX_N1")
			(clearance 0.1778)
			(thermal_gap 0.1778)
		)
		(pad "A23" thru_hole circle
			(at 12.34948 -1.24968 180)
			(size 1.0922 1.0922)
			(drill 0.7366)
			(layers "*.Cu" "*.Mask")
			(remove_unused_layers no)
			(net "GND")
			(clearance 0.1778)
			(thermal_gap 0.1778)
		)
		(pad "A24" thru_hole circle
			(at 13.35024 -3.24993 180)
			(size 1.0922 1.0922)
			(drill 0.7366)
			(layers "*.Cu" "*.Mask")
			(remove_unused_layers no)
			(net "GND")
			(clearance 0.1778)
			(thermal_gap 0.1778)
		)
		(pad "A25" thru_hole circle
			(at 14.34973 -1.24968 180)
			(size 1.0922 1.0922)
			(drill 0.7366)
			(layers "*.Cu" "*.Mask")
			(remove_unused_layers no)
			(net "PCIE_SAS_CPU_RX_P2")
			(clearance 0.1778)
			(thermal_gap 0.1778)
		)
		(pad "A26" thru_hole circle
			(at 15.35049 -3.24993 180)
			(size 1.0922 1.0922)
			(drill 0.7366)
			(layers "*.Cu" "*.Mask")
			(remove_unused_layers no)
			(net "PCIE_SAS_CPU_RX_N2")
			(clearance 0.1778)
			(thermal_gap 0.1778)
		)
		(pad "A27" thru_hole circle
			(at 16.34998 -1.24968 180)
			(size 1.0922 1.0922)
			(drill 0.7366)
			(layers "*.Cu" "*.Mask")
			(remove_unused_layers no)
			(net "GND")
			(clearance 0.1778)
			(thermal_gap 0.1778)
		)
		(pad "A28" thru_hole circle
			(at 17.34947 -3.24993 180)
			(size 1.0922 1.0922)
			(drill 0.7366)
			(layers "*.Cu" "*.Mask")
			(remove_unused_layers no)
			(net "GND")
			(clearance 0.1778)
			(thermal_gap 0.1778)
		)
		(pad "A29" thru_hole circle
			(at 18.35023 -1.24968 180)
			(size 1.0922 1.0922)
			(drill 0.7366)
			(layers "*.Cu" "*.Mask")
			(remove_unused_layers no)
			(net "PCIE_SAS_CPU_RX_P3")
			(clearance 0.1778)
			(thermal_gap 0.1778)
		)
		(pad "A30" thru_hole circle
			(at 19.34972 -3.24993 180)
			(size 1.0922 1.0922)
			(drill 0.7366)
			(layers "*.Cu" "*.Mask")
			(remove_unused_layers no)
			(net "PCIE_SAS_CPU_RX_N3")
			(clearance 0.1778)
			(thermal_gap 0.1778)
		)
		(pad "A31" thru_hole circle
			(at 20.35048 -1.24968 180)
			(size 1.0922 1.0922)
			(drill 0.7366)
			(layers "*.Cu" "*.Mask")
			(remove_unused_layers no)
			(net "GND")
			(clearance 0.1778)
			(thermal_gap 0.1778)
		)
		(pad "A32" thru_hole circle
			(at 21.34997 -3.24993 180)
			(size 1.0922 1.0922)
			(drill 0.7366)
			(layers "*.Cu" "*.Mask")
			(remove_unused_layers no)
			(net "GND")
			(clearance 0.1778)
			(thermal_gap 0.1778)
		)
		(pad "A33" thru_hole circle
			(at 22.34946 -1.24968 180)
			(size 1.0922 1.0922)
			(drill 0.7366)
			(layers "*.Cu" "*.Mask")
			(remove_unused_layers no)
			(net "TP_MSB_A33_CPU_SATA_RX_P")
			(clearance 0.1778)
			(thermal_gap 0.1778)
		)
		(pad "A34" thru_hole circle
			(at 23.35022 -3.24993 180)
			(size 1.0922 1.0922)
			(drill 0.7366)
			(layers "*.Cu" "*.Mask")
			(remove_unused_layers no)
			(net "TP_MSB_A34_CPU_SATA_RX_N")
			(clearance 0.1778)
			(thermal_gap 0.1778)
		)
		(pad "A35" thru_hole circle
			(at 24.34971 -1.24968 180)
			(size 1.0922 1.0922)
			(drill 0.7366)
			(layers "*.Cu" "*.Mask")
			(remove_unused_layers no)
			(net "GND")
			(clearance 0.1778)
			(thermal_gap 0.1778)
		)
		(pad "A36" thru_hole circle
			(at 25.35047 -3.24993 180)
			(size 1.0922 1.0922)
			(drill 0.7366)
			(layers "*.Cu" "*.Mask")
			(remove_unused_layers no)
			(net "GND")
			(clearance 0.1778)
			(thermal_gap 0.1778)
		)
		(pad "A37" thru_hole circle
			(at 26.34996 -1.24968 180)
			(size 1.0922 1.0922)
			(drill 0.7366)
			(layers "*.Cu" "*.Mask")
			(remove_unused_layers no)
			(net "CLK_100M_CLKBUFF_ENET2_DP")
			(clearance 0.1778)
			(thermal_gap 0.1778)
		)
		(pad "A38" thru_hole circle
			(at 27.34945 -3.24993 180)
			(size 1.0922 1.0922)
			(drill 0.7366)
			(layers "*.Cu" "*.Mask")
			(remove_unused_layers no)
			(net "CLK_100M_CLKBUFF_ENET2_DN")
			(clearance 0.1778)
			(thermal_gap 0.1778)
		)
		(pad "A39" thru_hole circle
			(at 28.35021 -1.24968 180)
			(size 1.0922 1.0922)
			(drill 0.7366)
			(layers "*.Cu" "*.Mask")
			(remove_unused_layers no)
			(net "GND")
			(clearance 0.1778)
			(thermal_gap 0.1778)
		)
		(pad "A40" thru_hole circle
			(at 29.3497 -3.24993 180)
			(size 1.0922 1.0922)
			(drill 0.7366)
			(layers "*.Cu" "*.Mask")
			(remove_unused_layers no)
			(net "GND")
			(clearance 0.1778)
			(thermal_gap 0.1778)
		)
		(pad "A41" thru_hole circle
			(at 30.35046 -1.24968 180)
			(size 1.0922 1.0922)
			(drill 0.7366)
			(layers "*.Cu" "*.Mask")
			(remove_unused_layers no)
			(net "TP_MSB_A41")
			(clearance 0.1778)
			(thermal_gap 0.1778)
		)
		(pad "A42" thru_hole circle
			(at 31.34995 -3.24993 180)
			(size 1.0922 1.0922)
			(drill 0.7366)
			(layers "*.Cu" "*.Mask")
			(remove_unused_layers no)
			(net "NIC_SMBUS_ALERT_N")
			(clearance 0.1778)
			(thermal_gap 0.1778)
		)
		(pad "A43" thru_hole circle
			(at 32.34944 -1.24968 180)
			(size 1.0922 1.0922)
			(drill 0.7366)
			(layers "*.Cu" "*.Mask")
			(remove_unused_layers no)
			(net "GND")
			(clearance 0.1778)
			(thermal_gap 0.1778)
		)
		(pad "A44" thru_hole circle
			(at 33.3502 -3.24993 180)
			(size 1.0922 1.0922)
			(drill 0.7366)
			(layers "*.Cu" "*.Mask")
			(remove_unused_layers no)
			(net "GND")
			(clearance 0.1778)
			(thermal_gap 0.1778)
		)
		(pad "A45" thru_hole circle
			(at 34.34969 -1.24968 180)
			(size 1.0922 1.0922)
			(drill 0.7366)
			(layers "*.Cu" "*.Mask")
			(remove_unused_layers no)
			(net "TP_MSB_A45_GBE_RX_P")
			(clearance 0.1778)
			(thermal_gap 0.1778)
		)
		(pad "A46" thru_hole circle
			(at 35.35045 -3.24993 180)
			(size 1.0922 1.0922)
			(drill 0.7366)
			(layers "*.Cu" "*.Mask")
			(remove_unused_layers no)
			(net "TP_MSB_A46_GBE_RX_N")
			(clearance 0.1778)
			(thermal_gap 0.1778)
		)
		(pad "A47" thru_hole circle
			(at 36.34994 -1.24968 180)
			(size 1.0922 1.0922)
			(drill 0.7366)
			(layers "*.Cu" "*.Mask")
			(remove_unused_layers no)
			(net "GND")
			(clearance 0.1778)
			(thermal_gap 0.1778)
		)
		(pad "A48" thru_hole circle
			(at 37.34943 -3.24993 180)
			(size 1.0922 1.0922)
			(drill 0.7366)
			(layers "*.Cu" "*.Mask")
			(remove_unused_layers no)
			(net "GND")
			(clearance 0.1778)
			(thermal_gap 0.1778)
		)
		(pad "A49" thru_hole circle
			(at 38.35019 -1.24968 180)
			(size 1.0922 1.0922)
			(drill 0.7366)
			(layers "*.Cu" "*.Mask")
			(remove_unused_layers no)
			(net "PCIE_SAS_CPU_RX_P4")
			(clearance 0.1778)
			(thermal_gap 0.1778)
		)
		(pad "A50" thru_hole circle
			(at 39.34968 -3.24993 180)
			(size 1.0922 1.0922)
			(drill 0.7366)
			(layers "*.Cu" "*.Mask")
			(remove_unused_layers no)
			(net "PCIE_SAS_CPU_RX_N4")
			(clearance 0.1778)
			(thermal_gap 0.1778)
		)
		(pad "A51" thru_hole circle
			(at 40.35044 -1.24968 180)
			(size 1.0922 1.0922)
			(drill 0.7366)
			(layers "*.Cu" "*.Mask")
			(remove_unused_layers no)
			(net "GND")
			(clearance 0.1778)
			(thermal_gap 0.1778)
		)
		(pad "A52" thru_hole circle
			(at 41.34993 -3.24993 180)
			(size 1.0922 1.0922)
			(drill 0.7366)
			(layers "*.Cu" "*.Mask")
			(remove_unused_layers no)
			(net "GND")
			(clearance 0.1778)
			(thermal_gap 0.1778)
		)
		(pad "A53" thru_hole circle
			(at 42.34942 -1.24968 180)
			(size 1.0922 1.0922)
			(drill 0.7366)
			(layers "*.Cu" "*.Mask")
			(remove_unused_layers no)
			(net "PCIE_SAS_CPU_RX_P5")
			(clearance 0.1778)
			(thermal_gap 0.1778)
		)
		(pad "A54" thru_hole circle
			(at 43.35018 -3.24993 180)
			(size 1.0922 1.0922)
			(drill 0.7366)
			(layers "*.Cu" "*.Mask")
			(remove_unused_layers no)
			(net "PCIE_SAS_CPU_RX_N5")
			(clearance 0.1778)
			(thermal_gap 0.1778)
		)
		(pad "A55" thru_hole circle
			(at 44.34967 -1.24968 180)
			(size 1.0922 1.0922)
			(drill 0.7366)
			(layers "*.Cu" "*.Mask")
			(remove_unused_layers no)
			(net "GND")
			(clearance 0.1778)
			(thermal_gap 0.1778)
		)
		(pad "A56" thru_hole circle
			(at 45.35043 -3.24993 180)
			(size 1.0922 1.0922)
			(drill 0.7366)
			(layers "*.Cu" "*.Mask")
			(remove_unused_layers no)
			(net "GND")
			(clearance 0.1778)
			(thermal_gap 0.1778)
		)
		(pad "A57" thru_hole circle
			(at 46.34992 -1.24968 180)
			(size 1.0922 1.0922)
			(drill 0.7366)
			(layers "*.Cu" "*.Mask")
			(remove_unused_layers no)
			(net "PCIE_SAS_CPU_RX_P6")
			(clearance 0.1778)
			(thermal_gap 0.1778)
		)
		(pad "A58" thru_hole circle
			(at 47.34941 -3.24993 180)
			(size 1.0922 1.0922)
			(drill 0.7366)
			(layers "*.Cu" "*.Mask")
			(remove_unused_layers no)
			(net "PCIE_SAS_CPU_RX_N6")
			(clearance 0.1778)
			(thermal_gap 0.1778)
		)
		(pad "A59" thru_hole circle
			(at 48.35017 -1.24968 180)
			(size 1.0922 1.0922)
			(drill 0.7366)
			(layers "*.Cu" "*.Mask")
			(remove_unused_layers no)
			(net "GND")
			(clearance 0.1778)
			(thermal_gap 0.1778)
		)
		(pad "A60" thru_hole circle
			(at 49.34966 -3.24993 180)
			(size 1.0922 1.0922)
			(drill 0.7366)
			(layers "*.Cu" "*.Mask")
			(remove_unused_layers no)
			(net "GND")
			(clearance 0.1778)
			(thermal_gap 0.1778)
		)
		(pad "A61" thru_hole circle
			(at 50.35042 -1.24968 180)
			(size 1.0922 1.0922)
			(drill 0.7366)
			(layers "*.Cu" "*.Mask")
			(remove_unused_layers no)
			(net "PCIE_SAS_CPU_RX_P7")
			(clearance 0.1778)
			(thermal_gap 0.1778)
		)
		(pad "A62" thru_hole circle
			(at 51.34991 -3.24993 180)
			(size 1.0922 1.0922)
			(drill 0.7366)
			(layers "*.Cu" "*.Mask")
			(remove_unused_layers no)
			(net "PCIE_SAS_CPU_RX_N7")
			(clearance 0.1778)
			(thermal_gap 0.1778)
		)
		(pad "A63" thru_hole circle
			(at 52.3494 -1.24968 180)
			(size 1.0922 1.0922)
			(drill 0.7366)
			(layers "*.Cu" "*.Mask")
			(remove_unused_layers no)
			(net "GND")
			(clearance 0.1778)
			(thermal_gap 0.1778)
		)
		(pad "A64" thru_hole circle
			(at 53.35016 -3.24993 180)
			(size 1.0922 1.0922)
			(drill 0.7366)
			(layers "*.Cu" "*.Mask")
			(remove_unused_layers no)
			(net "GND")
			(clearance 0.1778)
			(thermal_gap 0.1778)
		)
		(pad "A65" thru_hole circle
			(at 54.34965 -1.24968 180)
			(size 1.0922 1.0922)
			(drill 0.7366)
			(layers "*.Cu" "*.Mask")
			(remove_unused_layers no)
			(net "PCIE_10G_CPU_RX0_P")
			(clearance 0.1778)
			(thermal_gap 0.1778)
		)
		(pad "A66" thru_hole circle
			(at 55.35041 -3.24993 180)
			(size 1.0922 1.0922)
			(drill 0.7366)
			(layers "*.Cu" "*.Mask")
			(remove_unused_layers no)
			(net "PCIE_10G_CPU_RX0_N")
			(clearance 0.1778)
			(thermal_gap 0.1778)
		)
		(pad "A67" thru_hole circle
			(at 56.3499 -1.24968 180)
			(size 1.0922 1.0922)
			(drill 0.7366)
			(layers "*.Cu" "*.Mask")
			(remove_unused_layers no)
			(net "GND")
			(clearance 0.1778)
			(thermal_gap 0.1778)
		)
		(pad "A68" thru_hole circle
			(at 57.34939 -3.24993 180)
			(size 1.0922 1.0922)
			(drill 0.7366)
			(layers "*.Cu" "*.Mask")
			(remove_unused_layers no)
			(net "GND")
			(clearance 0.1778)
			(thermal_gap 0.1778)
		)
		(pad "A69" thru_hole circle
			(at 58.35015 -1.24968 180)
			(size 1.0922 1.0922)
			(drill 0.7366)
			(layers "*.Cu" "*.Mask")
			(remove_unused_layers no)
			(net "PCIE_10G_CPU_RX1_P")
			(clearance 0.1778)
			(thermal_gap 0.1778)
		)
		(pad "A70" thru_hole circle
			(at 59.34964 -3.24993 180)
			(size 1.0922 1.0922)
			(drill 0.7366)
			(layers "*.Cu" "*.Mask")
			(remove_unused_layers no)
			(net "PCIE_10G_CPU_RX1_N")
			(clearance 0.1778)
			(thermal_gap 0.1778)
		)
		(pad "A71" thru_hole circle
			(at 60.3504 -1.24968 180)
			(size 1.0922 1.0922)
			(drill 0.7366)
			(layers "*.Cu" "*.Mask")
			(remove_unused_layers no)
			(net "GND")
			(clearance 0.1778)
			(thermal_gap 0.1778)
		)
		(pad "A72" thru_hole circle
			(at 61.34989 -3.24993 180)
			(size 1.0922 1.0922)
			(drill 0.7366)
			(layers "*.Cu" "*.Mask")
			(remove_unused_layers no)
			(net "GND")
			(clearance 0.1778)
			(thermal_gap 0.1778)
		)
		(pad "A73" thru_hole circle
			(at 62.34938 -1.24968 180)
			(size 1.0922 1.0922)
			(drill 0.7366)
			(layers "*.Cu" "*.Mask")
			(remove_unused_layers no)
			(net "PCIE_10G_CPU_RX2_P")
			(clearance 0.1778)
			(thermal_gap 0.1778)
		)
		(pad "A74" thru_hole circle
			(at 63.35014 -3.24993 180)
			(size 1.0922 1.0922)
			(drill 0.7366)
			(layers "*.Cu" "*.Mask")
			(remove_unused_layers no)
			(net "PCIE_10G_CPU_RX2_N")
			(clearance 0.1778)
			(thermal_gap 0.1778)
		)
		(pad "A75" thru_hole circle
			(at 64.34963 -1.24968 180)
			(size 1.0922 1.0922)
			(drill 0.7366)
			(layers "*.Cu" "*.Mask")
			(remove_unused_layers no)
			(net "GND")
			(clearance 0.1778)
			(thermal_gap 0.1778)
		)
		(pad "A76" thru_hole circle
			(at 65.35039 -3.24993 180)
			(size 1.0922 1.0922)
			(drill 0.7366)
			(layers "*.Cu" "*.Mask")
			(remove_unused_layers no)
			(net "GND")
			(clearance 0.1778)
			(thermal_gap 0.1778)
		)
		(pad "A77" thru_hole circle
			(at 66.34988 -1.24968 180)
			(size 1.0922 1.0922)
			(drill 0.7366)
			(layers "*.Cu" "*.Mask")
			(remove_unused_layers no)
			(net "PCIE_10G_CPU_RX3_P")
			(clearance 0.1778)
			(thermal_gap 0.1778)
		)
		(pad "A78" thru_hole circle
			(at 67.34937 -3.24993 180)
			(size 1.0922 1.0922)
			(drill 0.7366)
			(layers "*.Cu" "*.Mask")
			(remove_unused_layers no)
			(net "PCIE_10G_CPU_RX3_N")
			(clearance 0.1778)
			(thermal_gap 0.1778)
		)
		(pad "A79" thru_hole circle
			(at 68.35013 -1.24968 180)
			(size 1.0922 1.0922)
			(drill 0.7366)
			(layers "*.Cu" "*.Mask")
			(remove_unused_layers no)
			(net "GND")
			(clearance 0.1778)
			(thermal_gap 0.1778)
		)
		(pad "A80" thru_hole circle
			(at 69.34962 -3.24993 180)
			(size 1.0922 1.0922)
			(drill 0.7366)
			(layers "*.Cu" "*.Mask")
			(remove_unused_layers no)
			(net "GND")
			(clearance 0.1778)
			(thermal_gap 0.1778)
		)
		(pad "A81" thru_hole circle
			(at 70.35038 -1.24968 180)
			(size 1.0922 1.0922)
			(drill 0.7366)
			(layers "*.Cu" "*.Mask")
			(remove_unused_layers no)
			(net "P12V_MSB")
			(clearance 0.1778)
			(thermal_gap 0.1778)
		)
		(pad "A82" thru_hole circle
			(at 71.34987 -3.24993 180)
			(size 1.0922 1.0922)
			(drill 0.7366)
			(layers "*.Cu" "*.Mask")
			(remove_unused_layers no)
			(net "P12V_MSB")
			(clearance 0.1778)
			(thermal_gap 0.1778)
		)
		(pad "B1" thru_hole circle
			(at -11.64971 1.24968 180)
			(size 1.0922 1.0922)
			(drill 0.7366)
			(layers "*.Cu" "*.Mask")
			(remove_unused_layers no)
			(net "P12V_MSB")
			(clearance 0.1778)
			(thermal_gap 0.1778)
		)
		(pad "B2" thru_hole circle
			(at -10.65022 3.24993 180)
			(size 1.0922 1.0922)
			(drill 0.7366)
			(layers "*.Cu" "*.Mask")
			(remove_unused_layers no)
			(net "P12V_MSB")
			(clearance 0.1778)
			(thermal_gap 0.1778)
		)
		(pad "B3" thru_hole circle
			(at -9.64946 1.24968 180)
			(size 1.0922 1.0922)
			(drill 0.7366)
			(layers "*.Cu" "*.Mask")
			(remove_unused_layers no)
			(net "P12V_MSB")
			(clearance 0.1778)
			(thermal_gap 0.1778)
		)
		(pad "B4" thru_hole circle
			(at -8.64997 3.24993 180)
			(size 1.0922 1.0922)
			(drill 0.7366)
			(layers "*.Cu" "*.Mask")
			(remove_unused_layers no)
			(net "GND")
			(clearance 0.1778)
			(thermal_gap 0.1778)
		)
		(pad "B5" thru_hole circle
			(at -7.65048 1.24968 180)
			(size 1.0922 1.0922)
			(drill 0.7366)
			(layers "*.Cu" "*.Mask")
			(remove_unused_layers no)
			(net "BMC_MBC_I2C_E_SCL")
			(clearance 0.1778)
			(thermal_gap 0.1778)
		)
		(pad "B6" thru_hole circle
			(at -6.64972 3.24993 180)
			(size 1.0922 1.0922)
			(drill 0.7366)
			(layers "*.Cu" "*.Mask")
			(remove_unused_layers no)
			(net "BMC_MBC_I2C_E_SDA")
			(clearance 0.1778)
			(thermal_gap 0.1778)
		)
		(pad "B7" thru_hole circle
			(at -5.65023 1.24968 180)
			(size 1.0922 1.0922)
			(drill 0.7366)
			(layers "*.Cu" "*.Mask")
			(remove_unused_layers no)
			(net "GND")
			(clearance 0.1778)
			(thermal_gap 0.1778)
		)
		(pad "B8" thru_hole circle
			(at -4.64947 3.24993 180)
			(size 1.0922 1.0922)
			(drill 0.7366)
			(layers "*.Cu" "*.Mask")
			(remove_unused_layers no)
			(net "PMU_PWRBTN_N")
			(clearance 0.1778)
			(thermal_gap 0.1778)
		)
		(pad "B9" thru_hole circle
			(at -3.64998 1.24968 180)
			(size 1.0922 1.0922)
			(drill 0.7366)
			(layers "*.Cu" "*.Mask")
			(remove_unused_layers no)
			(net "USB_P0_DP")
			(clearance 0.1778)
			(thermal_gap 0.1778)
		)
		(pad "B10" thru_hole circle
			(at -2.65049 3.24993 180)
			(size 1.0922 1.0922)
			(drill 0.7366)
			(layers "*.Cu" "*.Mask")
			(remove_unused_layers no)
			(net "USB_P0_DN")
			(clearance 0.1778)
			(thermal_gap 0.1778)
		)
		(pad "B11" thru_hole circle
			(at -1.64973 1.24968 180)
			(size 1.0922 1.0922)
			(drill 0.7366)
			(layers "*.Cu" "*.Mask")
			(remove_unused_layers no)
			(net "CPU_RESET_N_R")
			(clearance 0.1778)
			(thermal_gap 0.1778)
		)
		(pad "B12" thru_hole circle
			(at 1.35001 3.24993 180)
			(size 1.0922 1.0922)
			(drill 0.7366)
			(layers "*.Cu" "*.Mask")
			(remove_unused_layers no)
			(net "BMC_MSB_I2C_E_ALERT_#")
			(clearance 0.1778)
			(thermal_gap 0.1778)
		)
		(pad "B13" thru_hole circle
			(at 2.3495 1.24968 180)
			(size 1.0922 1.0922)
			(drill 0.7366)
			(layers "*.Cu" "*.Mask")
			(remove_unused_layers no)
			(net "GND")
			(clearance 0.1778)
			(thermal_gap 0.1778)
		)
		(pad "B14" thru_hole circle
			(at 3.35026 3.24993 180)
			(size 1.0922 1.0922)
			(drill 0.7366)
			(layers "*.Cu" "*.Mask")
			(remove_unused_layers no)
			(net "GND")
			(clearance 0.1778)
			(thermal_gap 0.1778)
		)
		(pad "B15" thru_hole circle
			(at 4.34975 1.24968 180)
			(size 1.0922 1.0922)
			(drill 0.7366)
			(layers "*.Cu" "*.Mask")
			(remove_unused_layers no)
			(net "PCIE_SAS_CPU_TX_P0")
			(clearance 0.1778)
			(thermal_gap 0.1778)
		)
		(pad "B16" thru_hole circle
			(at 5.35051 3.24993 180)
			(size 1.0922 1.0922)
			(drill 0.7366)
			(layers "*.Cu" "*.Mask")
			(remove_unused_layers no)
			(net "PCIE_SAS_CPU_TX_N0")
			(clearance 0.1778)
			(thermal_gap 0.1778)
		)
		(pad "B17" thru_hole circle
			(at 6.35 1.24968 180)
			(size 1.0922 1.0922)
			(drill 0.7366)
			(layers "*.Cu" "*.Mask")
			(remove_unused_layers no)
			(net "GND")
			(clearance 0.1778)
			(thermal_gap 0.1778)
		)
		(pad "B18" thru_hole circle
			(at 7.34949 3.24993 180)
			(size 1.0922 1.0922)
			(drill 0.7366)
			(layers "*.Cu" "*.Mask")
			(remove_unused_layers no)
			(net "GND")
			(clearance 0.1778)
			(thermal_gap 0.1778)
		)
		(pad "B19" thru_hole circle
			(at 8.35025 1.24968 180)
			(size 1.0922 1.0922)
			(drill 0.7366)
			(layers "*.Cu" "*.Mask")
			(remove_unused_layers no)
			(net "PCIE_SAS_CPU_TX_P1")
			(clearance 0.1778)
			(thermal_gap 0.1778)
		)
		(pad "B20" thru_hole circle
			(at 9.34974 3.24993 180)
			(size 1.0922 1.0922)
			(drill 0.7366)
			(layers "*.Cu" "*.Mask")
			(remove_unused_layers no)
			(net "PCIE_SAS_CPU_TX_N1")
			(clearance 0.1778)
			(thermal_gap 0.1778)
		)
		(pad "B21" thru_hole circle
			(at 10.3505 1.24968 180)
			(size 1.0922 1.0922)
			(drill 0.7366)
			(layers "*.Cu" "*.Mask")
			(remove_unused_layers no)
			(net "GND")
			(clearance 0.1778)
			(thermal_gap 0.1778)
		)
		(pad "B22" thru_hole circle
			(at 11.34999 3.24993 180)
			(size 1.0922 1.0922)
			(drill 0.7366)
			(layers "*.Cu" "*.Mask")
			(remove_unused_layers no)
			(net "GND")
			(clearance 0.1778)
			(thermal_gap 0.1778)
		)
		(pad "B23" thru_hole circle
			(at 12.34948 1.24968 180)
			(size 1.0922 1.0922)
			(drill 0.7366)
			(layers "*.Cu" "*.Mask")
			(remove_unused_layers no)
			(net "PCIE_SAS_CPU_TX_P2")
			(clearance 0.1778)
			(thermal_gap 0.1778)
		)
		(pad "B24" thru_hole circle
			(at 13.35024 3.24993 180)
			(size 1.0922 1.0922)
			(drill 0.7366)
			(layers "*.Cu" "*.Mask")
			(remove_unused_layers no)
			(net "PCIE_SAS_CPU_TX_N2")
			(clearance 0.1778)
			(thermal_gap 0.1778)
		)
		(pad "B25" thru_hole circle
			(at 14.34973 1.24968 180)
			(size 1.0922 1.0922)
			(drill 0.7366)
			(layers "*.Cu" "*.Mask")
			(remove_unused_layers no)
			(net "GND")
			(clearance 0.1778)
			(thermal_gap 0.1778)
		)
		(pad "B26" thru_hole circle
			(at 15.35049 3.24993 180)
			(size 1.0922 1.0922)
			(drill 0.7366)
			(layers "*.Cu" "*.Mask")
			(remove_unused_layers no)
			(net "GND")
			(clearance 0.1778)
			(thermal_gap 0.1778)
		)
		(pad "B27" thru_hole circle
			(at 16.34998 1.24968 180)
			(size 1.0922 1.0922)
			(drill 0.7366)
			(layers "*.Cu" "*.Mask")
			(remove_unused_layers no)
			(net "PCIE_SAS_CPU_TX_P3")
			(clearance 0.1778)
			(thermal_gap 0.1778)
		)
		(pad "B28" thru_hole circle
			(at 17.34947 3.24993 180)
			(size 1.0922 1.0922)
			(drill 0.7366)
			(layers "*.Cu" "*.Mask")
			(remove_unused_layers no)
			(net "PCIE_SAS_CPU_TX_N3")
			(clearance 0.1778)
			(thermal_gap 0.1778)
		)
		(pad "B29" thru_hole circle
			(at 18.35023 1.24968 180)
			(size 1.0922 1.0922)
			(drill 0.7366)
			(layers "*.Cu" "*.Mask")
			(remove_unused_layers no)
			(net "GND")
			(clearance 0.1778)
			(thermal_gap 0.1778)
		)
		(pad "B30" thru_hole circle
			(at 19.34972 3.24993 180)
			(size 1.0922 1.0922)
			(drill 0.7366)
			(layers "*.Cu" "*.Mask")
			(remove_unused_layers no)
			(net "GND")
			(clearance 0.1778)
			(thermal_gap 0.1778)
		)
		(pad "B31" thru_hole circle
			(at 20.35048 1.24968 180)
			(size 1.0922 1.0922)
			(drill 0.7366)
			(layers "*.Cu" "*.Mask")
			(remove_unused_layers no)
			(net "TP_MSB_B31_CPU_SATA_TX_P")
			(clearance 0.1778)
			(thermal_gap 0.1778)
		)
		(pad "B32" thru_hole circle
			(at 21.34997 3.24993 180)
			(size 1.0922 1.0922)
			(drill 0.7366)
			(layers "*.Cu" "*.Mask")
			(remove_unused_layers no)
			(net "TP_MSB_B32_CPU_SATA_TX_N")
			(clearance 0.1778)
			(thermal_gap 0.1778)
		)
		(pad "B33" thru_hole circle
			(at 22.34946 1.24968 180)
			(size 1.0922 1.0922)
			(drill 0.7366)
			(layers "*.Cu" "*.Mask")
			(remove_unused_layers no)
			(net "GND")
			(clearance 0.1778)
			(thermal_gap 0.1778)
		)
		(pad "B34" thru_hole circle
			(at 23.35022 3.24993 180)
			(size 1.0922 1.0922)
			(drill 0.7366)
			(layers "*.Cu" "*.Mask")
			(remove_unused_layers no)
			(net "GND")
			(clearance 0.1778)
			(thermal_gap 0.1778)
		)
		(pad "B35" thru_hole circle
			(at 24.34971 1.24968 180)
			(size 1.0922 1.0922)
			(drill 0.7366)
			(layers "*.Cu" "*.Mask")
			(remove_unused_layers no)
			(net "CLK_100M_CLKBUFF_ENET1_DP")
			(clearance 0.1778)
			(thermal_gap 0.1778)
		)
		(pad "B36" thru_hole circle
			(at 25.35047 3.24993 180)
			(size 1.0922 1.0922)
			(drill 0.7366)
			(layers "*.Cu" "*.Mask")
			(remove_unused_layers no)
			(net "CLK_100M_CLKBUFF_ENET1_DN")
			(clearance 0.1778)
			(thermal_gap 0.1778)
		)
		(pad "B37" thru_hole circle
			(at 26.34996 1.24968 180)
			(size 1.0922 1.0922)
			(drill 0.7366)
			(layers "*.Cu" "*.Mask")
			(remove_unused_layers no)
			(net "GND")
			(clearance 0.1778)
			(thermal_gap 0.1778)
		)
		(pad "B38" thru_hole circle
			(at 27.34945 3.24993 180)
			(size 1.0922 1.0922)
			(drill 0.7366)
			(layers "*.Cu" "*.Mask")
			(remove_unused_layers no)
			(net "GND")
			(clearance 0.1778)
			(thermal_gap 0.1778)
		)
		(pad "B39" thru_hole circle
			(at 28.35021 1.24968 180)
			(size 1.0922 1.0922)
			(drill 0.7366)
			(layers "*.Cu" "*.Mask")
			(remove_unused_layers no)
			(net "PMU_PLTRST#")
			(clearance 0.1778)
			(thermal_gap 0.1778)
		)
		(pad "B40" thru_hole circle
			(at 29.3497 3.24993 180)
			(size 1.0922 1.0922)
			(drill 0.7366)
			(layers "*.Cu" "*.Mask")
			(remove_unused_layers no)
			(net "TP_MSB_B40")
			(clearance 0.1778)
			(thermal_gap 0.1778)
		)
		(pad "B41" thru_hole circle
			(at 30.35046 1.24968 180)
			(size 1.0922 1.0922)
			(drill 0.7366)
			(layers "*.Cu" "*.Mask")
			(remove_unused_layers no)
			(net "GND")
			(clearance 0.1778)
			(thermal_gap 0.1778)
		)
		(pad "B42" thru_hole circle
			(at 31.34995 3.24993 180)
			(size 1.0922 1.0922)
			(drill 0.7366)
			(layers "*.Cu" "*.Mask")
			(remove_unused_layers no)
			(net "GND")
			(clearance 0.1778)
			(thermal_gap 0.1778)
		)
		(pad "B43" thru_hole circle
			(at 32.34944 1.24968 180)
			(size 1.0922 1.0922)
			(drill 0.7366)
			(layers "*.Cu" "*.Mask")
			(remove_unused_layers no)
			(net "NIC_SMBUS_SCL")
			(clearance 0.1778)
			(thermal_gap 0.1778)
		)
		(pad "B44" thru_hole circle
			(at 33.3502 3.24993 180)
			(size 1.0922 1.0922)
			(drill 0.7366)
			(layers "*.Cu" "*.Mask")
			(remove_unused_layers no)
			(net "NIC_SMBUS_SDA")
			(clearance 0.1778)
			(thermal_gap 0.1778)
		)
		(pad "B45" thru_hole circle
			(at 34.34969 1.24968 180)
			(size 1.0922 1.0922)
			(drill 0.7366)
			(layers "*.Cu" "*.Mask")
			(remove_unused_layers no)
			(net "GND")
			(clearance 0.1778)
			(thermal_gap 0.1778)
		)
		(pad "B46" thru_hole circle
			(at 35.35045 3.24993 180)
			(size 1.0922 1.0922)
			(drill 0.7366)
			(layers "*.Cu" "*.Mask")
			(remove_unused_layers no)
			(net "GND")
			(clearance 0.1778)
			(thermal_gap 0.1778)
		)
		(pad "B47" thru_hole circle
			(at 36.34994 1.24968 180)
			(size 1.0922 1.0922)
			(drill 0.7366)
			(layers "*.Cu" "*.Mask")
			(remove_unused_layers no)
			(net "TP_MSB_B47_CPU_GBE_TX_P")
			(clearance 0.1778)
			(thermal_gap 0.1778)
		)
		(pad "B48" thru_hole circle
			(at 37.34943 3.24993 180)
			(size 1.0922 1.0922)
			(drill 0.7366)
			(layers "*.Cu" "*.Mask")
			(remove_unused_layers no)
			(net "TP_MSB_B47_CPU_GBE_TX_N")
			(clearance 0.1778)
			(thermal_gap 0.1778)
		)
		(pad "B49" thru_hole circle
			(at 38.35019 1.24968 180)
			(size 1.0922 1.0922)
			(drill 0.7366)
			(layers "*.Cu" "*.Mask")
			(remove_unused_layers no)
			(net "GND")
			(clearance 0.1778)
			(thermal_gap 0.1778)
		)
		(pad "B50" thru_hole circle
			(at 39.34968 3.24993 180)
			(size 1.0922 1.0922)
			(drill 0.7366)
			(layers "*.Cu" "*.Mask")
			(remove_unused_layers no)
			(net "GND")
			(clearance 0.1778)
			(thermal_gap 0.1778)
		)
		(pad "B51" thru_hole circle
			(at 40.35044 1.24968 180)
			(size 1.0922 1.0922)
			(drill 0.7366)
			(layers "*.Cu" "*.Mask")
			(remove_unused_layers no)
			(net "PCIE_SAS_CPU_TX_P4")
			(clearance 0.1778)
			(thermal_gap 0.1778)
		)
		(pad "B52" thru_hole circle
			(at 41.34993 3.24993 180)
			(size 1.0922 1.0922)
			(drill 0.7366)
			(layers "*.Cu" "*.Mask")
			(remove_unused_layers no)
			(net "PCIE_SAS_CPU_TX_N4")
			(clearance 0.1778)
			(thermal_gap 0.1778)
		)
		(pad "B53" thru_hole circle
			(at 42.34942 1.24968 180)
			(size 1.0922 1.0922)
			(drill 0.7366)
			(layers "*.Cu" "*.Mask")
			(remove_unused_layers no)
			(net "GND")
			(clearance 0.1778)
			(thermal_gap 0.1778)
		)
		(pad "B54" thru_hole circle
			(at 43.35018 3.24993 180)
			(size 1.0922 1.0922)
			(drill 0.7366)
			(layers "*.Cu" "*.Mask")
			(remove_unused_layers no)
			(net "GND")
			(clearance 0.1778)
			(thermal_gap 0.1778)
		)
		(pad "B55" thru_hole circle
			(at 44.34967 1.24968 180)
			(size 1.0922 1.0922)
			(drill 0.7366)
			(layers "*.Cu" "*.Mask")
			(remove_unused_layers no)
			(net "PCIE_SAS_CPU_TX_P5")
			(clearance 0.1778)
			(thermal_gap 0.1778)
		)
		(pad "B56" thru_hole circle
			(at 45.35043 3.24993 180)
			(size 1.0922 1.0922)
			(drill 0.7366)
			(layers "*.Cu" "*.Mask")
			(remove_unused_layers no)
			(net "PCIE_SAS_CPU_TX_N5")
			(clearance 0.1778)
			(thermal_gap 0.1778)
		)
		(pad "B57" thru_hole circle
			(at 46.34992 1.24968 180)
			(size 1.0922 1.0922)
			(drill 0.7366)
			(layers "*.Cu" "*.Mask")
			(remove_unused_layers no)
			(net "GND")
			(clearance 0.1778)
			(thermal_gap 0.1778)
		)
		(pad "B58" thru_hole circle
			(at 47.34941 3.24993 180)
			(size 1.0922 1.0922)
			(drill 0.7366)
			(layers "*.Cu" "*.Mask")
			(remove_unused_layers no)
			(net "GND")
			(clearance 0.1778)
			(thermal_gap 0.1778)
		)
		(pad "B59" thru_hole circle
			(at 48.35017 1.24968 180)
			(size 1.0922 1.0922)
			(drill 0.7366)
			(layers "*.Cu" "*.Mask")
			(remove_unused_layers no)
			(net "PCIE_SAS_CPU_TX_P6")
			(clearance 0.1778)
			(thermal_gap 0.1778)
		)
		(pad "B60" thru_hole circle
			(at 49.34966 3.24993 180)
			(size 1.0922 1.0922)
			(drill 0.7366)
			(layers "*.Cu" "*.Mask")
			(remove_unused_layers no)
			(net "PCIE_SAS_CPU_TX_N6")
			(clearance 0.1778)
			(thermal_gap 0.1778)
		)
		(pad "B61" thru_hole circle
			(at 50.35042 1.24968 180)
			(size 1.0922 1.0922)
			(drill 0.7366)
			(layers "*.Cu" "*.Mask")
			(remove_unused_layers no)
			(net "GND")
			(clearance 0.1778)
			(thermal_gap 0.1778)
		)
		(pad "B62" thru_hole circle
			(at 51.34991 3.24993 180)
			(size 1.0922 1.0922)
			(drill 0.7366)
			(layers "*.Cu" "*.Mask")
			(remove_unused_layers no)
			(net "GND")
			(clearance 0.1778)
			(thermal_gap 0.1778)
		)
		(pad "B63" thru_hole circle
			(at 52.3494 1.24968 180)
			(size 1.0922 1.0922)
			(drill 0.7366)
			(layers "*.Cu" "*.Mask")
			(remove_unused_layers no)
			(net "PCIE_SAS_CPU_TX_P7")
			(clearance 0.1778)
			(thermal_gap 0.1778)
		)
		(pad "B64" thru_hole circle
			(at 53.35016 3.24993 180)
			(size 1.0922 1.0922)
			(drill 0.7366)
			(layers "*.Cu" "*.Mask")
			(remove_unused_layers no)
			(net "PCIE_SAS_CPU_TX_N7")
			(clearance 0.1778)
			(thermal_gap 0.1778)
		)
		(pad "B65" thru_hole circle
			(at 54.34965 1.24968 180)
			(size 1.0922 1.0922)
			(drill 0.7366)
			(layers "*.Cu" "*.Mask")
			(remove_unused_layers no)
			(net "GND")
			(clearance 0.1778)
			(thermal_gap 0.1778)
		)
		(pad "B66" thru_hole circle
			(at 55.35041 3.24993 180)
			(size 1.0922 1.0922)
			(drill 0.7366)
			(layers "*.Cu" "*.Mask")
			(remove_unused_layers no)
			(net "GND")
			(clearance 0.1778)
			(thermal_gap 0.1778)
		)
		(pad "B67" thru_hole circle
			(at 56.3499 1.24968 180)
			(size 1.0922 1.0922)
			(drill 0.7366)
			(layers "*.Cu" "*.Mask")
			(remove_unused_layers no)
			(net "PCIE_10G_CPU_TX0_P")
			(clearance 0.1778)
			(thermal_gap 0.1778)
		)
		(pad "B68" thru_hole circle
			(at 57.34939 3.24993 180)
			(size 1.0922 1.0922)
			(drill 0.7366)
			(layers "*.Cu" "*.Mask")
			(remove_unused_layers no)
			(net "PCIE_10G_CPU_TX0_N")
			(clearance 0.1778)
			(thermal_gap 0.1778)
		)
		(pad "B69" thru_hole circle
			(at 58.35015 1.24968 180)
			(size 1.0922 1.0922)
			(drill 0.7366)
			(layers "*.Cu" "*.Mask")
			(remove_unused_layers no)
			(net "GND")
			(clearance 0.1778)
			(thermal_gap 0.1778)
		)
		(pad "B70" thru_hole circle
			(at 59.34964 3.24993 180)
			(size 1.0922 1.0922)
			(drill 0.7366)
			(layers "*.Cu" "*.Mask")
			(remove_unused_layers no)
			(net "GND")
			(clearance 0.1778)
			(thermal_gap 0.1778)
		)
		(pad "B71" thru_hole circle
			(at 60.3504 1.24968 180)
			(size 1.0922 1.0922)
			(drill 0.7366)
			(layers "*.Cu" "*.Mask")
			(remove_unused_layers no)
			(net "PCIE_10G_CPU_TX1_P")
			(clearance 0.1778)
			(thermal_gap 0.1778)
		)
		(pad "B72" thru_hole circle
			(at 61.34989 3.24993 180)
			(size 1.0922 1.0922)
			(drill 0.7366)
			(layers "*.Cu" "*.Mask")
			(remove_unused_layers no)
			(net "PCIE_10G_CPU_TX1_N")
			(clearance 0.1778)
			(thermal_gap 0.1778)
		)
		(pad "B73" thru_hole circle
			(at 62.34938 1.24968 180)
			(size 1.0922 1.0922)
			(drill 0.7366)
			(layers "*.Cu" "*.Mask")
			(remove_unused_layers no)
			(net "GND")
			(clearance 0.1778)
			(thermal_gap 0.1778)
		)
		(pad "B74" thru_hole circle
			(at 63.35014 3.24993 180)
			(size 1.0922 1.0922)
			(drill 0.7366)
			(layers "*.Cu" "*.Mask")
			(remove_unused_layers no)
			(net "GND")
			(clearance 0.1778)
			(thermal_gap 0.1778)
		)
		(pad "B75" thru_hole circle
			(at 64.34963 1.24968 180)
			(size 1.0922 1.0922)
			(drill 0.7366)
			(layers "*.Cu" "*.Mask")
			(remove_unused_layers no)
			(net "PCIE_10G_CPU_TX2_P")
			(clearance 0.1778)
			(thermal_gap 0.1778)
		)
		(pad "B76" thru_hole circle
			(at 65.35039 3.24993 180)
			(size 1.0922 1.0922)
			(drill 0.7366)
			(layers "*.Cu" "*.Mask")
			(remove_unused_layers no)
			(net "PCIE_10G_CPU_TX2_N")
			(clearance 0.1778)
			(thermal_gap 0.1778)
		)
		(pad "B77" thru_hole circle
			(at 66.34988 1.24968 180)
			(size 1.0922 1.0922)
			(drill 0.7366)
			(layers "*.Cu" "*.Mask")
			(remove_unused_layers no)
			(net "GND")
			(clearance 0.1778)
			(thermal_gap 0.1778)
		)
		(pad "B78" thru_hole circle
			(at 67.34937 3.24993 180)
			(size 1.0922 1.0922)
			(drill 0.7366)
			(layers "*.Cu" "*.Mask")
			(remove_unused_layers no)
			(net "GND")
			(clearance 0.1778)
			(thermal_gap 0.1778)
		)
		(pad "B79" thru_hole circle
			(at 68.35013 1.24968 180)
			(size 1.0922 1.0922)
			(drill 0.7366)
			(layers "*.Cu" "*.Mask")
			(remove_unused_layers no)
			(net "PCIE_10G_CPU_TX3_P")
			(clearance 0.1778)
			(thermal_gap 0.1778)
		)
		(pad "B80" thru_hole circle
			(at 69.34962 3.24993 180)
			(size 1.0922 1.0922)
			(drill 0.7366)
			(layers "*.Cu" "*.Mask")
			(remove_unused_layers no)
			(net "PCIE_10G_CPU_TX3_N")
			(clearance 0.1778)
			(thermal_gap 0.1778)
		)
		(pad "B81" thru_hole circle
			(at 70.35038 1.24968 180)
			(size 1.0922 1.0922)
			(drill 0.7366)
			(layers "*.Cu" "*.Mask")
			(remove_unused_layers no)
			(net "PRSNT_MSB_B81")
			(clearance 0.1778)
			(thermal_gap 0.1778)
		)
		(pad "B82" thru_hole circle
			(at 71.34987 3.24993 180)
			(size 1.0922 1.0922)
			(drill 0.7366)
			(layers "*.Cu" "*.Mask")
			(remove_unused_layers no)
			(net "GND")
			(clearance 0.1778)
			(thermal_gap 0.1778)
		)
		(zone
			(layers "F.Cu" "B.Cu" "In1.Cu" "In2.Cu" "In3.Cu" "In4.Cu" "In5.Cu" "In6.Cu")
			(hatch none 0.5)
			(connect_pads
				(clearance 0)
			)
			(min_thickness 0.25)
			(keepout
				(tracks not_allowed)
				(vias allowed)
				(pads allowed)
				(copperpour not_allowed)
				(footprints allowed)
			)
			(placement
				(enabled no)
				(sheetname "")
			)
			(fill
				(thermal_gap 0.5)
				(thermal_bridge_width 0.5)
				(island_removal_mode 0)
			)
			(polygon
				(pts
					(arc
						(start 138.136376 -77.0001)
						(mid 135.164576 -77.0001)
						(end 138.136376 -77.0001)
					)
				)
			)
		)
		(zone
			(layers "F.Cu" "B.Cu" "In1.Cu" "In2.Cu" "In3.Cu" "In4.Cu" "In5.Cu" "In6.Cu")
			(hatch none 0.5)
			(connect_pads
				(clearance 0)
			)
			(min_thickness 0.25)
			(keepout
				(tracks not_allowed)
				(vias allowed)
				(pads allowed)
				(copperpour not_allowed)
				(footprints allowed)
			)
			(placement
				(enabled no)
				(sheetname "")
			)
			(fill
				(thermal_gap 0.5)
				(thermal_bridge_width 0.5)
				(island_removal_mode 0)
			)
			(polygon
				(pts
					(arc
						(start 211.285836 -77.0001)
						(mid 208.314036 -77.0001)
						(end 211.285836 -77.0001)
					)
				)
			)
		)
	)
	(footprint ""
		(layer "F.Cu")
		(at 41.402 -171.958)
		(property "Reference" "SQ15"
			(at 0 0 0)
			(layer "F.SilkS")
			(hide yes)
			(effects
				(font
					(size 1.27 1.27)
				)
			)
		)
		(property "Value" "2N7002A-7-GP"
			(at 0.127 -8.9662 0)
			(unlocked yes)
			(layer "F.Fab")
			(hide yes)
			(effects
				(font
					(size 1.016 1.016)
					(thickness 0.1524)
				)
			)
		)
		(property "Device Type" "SOT23DGS2D4H48"
			(at 0.127 -10.4902 0)
			(unlocked yes)
			(layer "F.Fab")
			(hide yes)
			(effects
				(font
					(size 1.016 1.016)
					(thickness 0.1524)
				)
			)
		)
		(duplicate_pad_numbers_are_jumpers no)
		(fp_line
			(start -1.651 -1.778)
			(end -1.651 1.778)
			(stroke
				(width 0.1524)
				(type default)
			)
			(layer "F.SilkS")
		)
		(fp_line
			(start -1.651 1.778)
			(end 1.651 1.778)
			(stroke
				(width 0.1524)
				(type default)
			)
			(layer "F.SilkS")
		)
		(fp_line
			(start 1.651 -1.778)
			(end -1.651 -1.778)
			(stroke
				(width 0.1524)
				(type default)
			)
			(layer "F.SilkS")
		)
		(fp_line
			(start 1.651 1.778)
			(end 1.651 -1.778)
			(stroke
				(width 0.1524)
				(type default)
			)
			(layer "F.SilkS")
		)
		(fp_poly
			(pts
				(xy -1.778 1.8796) (xy -1.778 -1.8796) (xy 1.778 -1.8796) (xy 1.778 1.8796)
			)
			(stroke
				(width 0)
				(type default)
			)
			(fill no)
			(layer "F.CrtYd")
		)
		(fp_poly
			(pts
				(xy -1.778 1.8796) (xy -1.778 -1.8796) (xy 1.778 -1.8796) (xy 1.778 1.8796)
			)
			(stroke
				(width 0)
				(type default)
			)
			(fill no)
			(layer "F.Fab")
		)
		(pad "D" smd custom
			(at 0 -0.9525)
			(size 0.1905 0.1905)
			(layers "F.Cu" "F.Mask" "F.Paste")
			(net "P3V3_STBY_R7")
			(options
				(clearance outline)
				(anchor circle)
			)
			(primitives
				(gr_poly
					(pts
						(arc
							(start -0.1778 0.5715)
							(mid -0.321484 0.511984)
							(end -0.381 0.3683)
						)
						(arc
							(start -0.381 -0.3683)
							(mid -0.321484 -0.511984)
							(end -0.1778 -0.5715)
						)
						(arc
							(start 0.1778 -0.5715)
							(mid 0.321484 -0.511984)
							(end 0.381 -0.3683)
						)
						(arc
							(start 0.381 0.3683)
							(mid 0.321484 0.511984)
							(end 0.1778 0.5715)
						)
					)
					(width 0)
					(fill yes)
				)
			)
		)
		(pad "G" smd custom
			(at -0.98425 0.9525)
			(size 0.1905 0.1905)
			(layers "F.Cu" "F.Mask" "F.Paste")
			(net "CPU_EXP_RESET_N")
			(options
				(clearance outline)
				(anchor circle)
			)
			(primitives
				(gr_poly
					(pts
						(arc
							(start -0.1778 0.5715)
							(mid -0.321484 0.511984)
							(end -0.381 0.3683)
						)
						(arc
							(start -0.381 -0.3683)
							(mid -0.321484 -0.511984)
							(end -0.1778 -0.5715)
						)
						(arc
							(start 0.1778 -0.5715)
							(mid 0.321484 -0.511984)
							(end 0.381 -0.3683)
						)
						(arc
							(start 0.381 0.3683)
							(mid 0.321484 0.511984)
							(end 0.1778 0.5715)
						)
					)
					(width 0)
					(fill yes)
				)
			)
		)
		(pad "S" smd custom
			(at 0.98425 0.9525)
			(size 0.1905 0.1905)
			(layers "F.Cu" "F.Mask" "F.Paste")
			(net "GND")
			(options
				(clearance outline)
				(anchor circle)
			)
			(primitives
				(gr_poly
					(pts
						(arc
							(start -0.1778 0.5715)
							(mid -0.321484 0.511984)
							(end -0.381 0.3683)
						)
						(arc
							(start -0.381 -0.3683)
							(mid -0.321484 -0.511984)
							(end -0.1778 -0.5715)
						)
						(arc
							(start 0.1778 -0.5715)
							(mid 0.321484 -0.511984)
							(end 0.381 -0.3683)
						)
						(arc
							(start 0.381 0.3683)
							(mid 0.321484 0.511984)
							(end 0.1778 0.5715)
						)
					)
					(width 0)
					(fill yes)
				)
			)
		)
	)
	(footprint ""
		(layer "F.Cu")
		(at 201.041 -197.231 180)
		(property "Reference" "C263"
			(at 0 0 180)
			(layer "F.SilkS")
			(hide yes)
			(effects
				(font
					(size 1.27 1.27)
				)
			)
		)
		(property "Value" "SCD1U16V2KX-3GP"
			(at 1.1811 -2.7051 180)
			(unlocked yes)
			(layer "F.Fab")
			(hide yes)
			(effects
				(font
					(size 1.016 1.016)
					(thickness 0.1524)
				)
			)
		)
		(property "Device Type" "C402H22"
			(at 1.1811 -4.2291 180)
			(unlocked yes)
			(layer "F.Fab")
			(hide yes)
			(effects
				(font
					(size 1.016 1.016)
					(thickness 0.1524)
				)
			)
		)
		(duplicate_pad_numbers_are_jumpers no)
		(fp_rect
			(start -0.4318 0.9525)
			(end 0.4318 -0.9525)
			(stroke
				(width 0)
				(type default)
			)
			(fill no)
			(layer "F.CrtYd")
		)
		(fp_rect
			(start -0.4318 0.9525)
			(end 0.4318 -0.9525)
			(stroke
				(width 0)
				(type default)
			)
			(fill no)
			(layer "F.Fab")
		)
		(pad "1" smd custom
			(at 0 -0.4445 180)
			(size 0.1524 0.1524)
			(layers "F.Cu" "F.Mask" "F.Paste")
			(net "P3V3_STBY")
			(options
				(clearance outline)
				(anchor circle)
			)
			(primitives
				(gr_poly
					(pts
						(arc
							(start 0.3048 -0.2032)
							(mid 0.275042 -0.275042)
							(end 0.2032 -0.3048)
						)
						(arc
							(start -0.2032 -0.3048)
							(mid -0.275042 -0.275042)
							(end -0.3048 -0.2032)
						)
						(arc
							(start -0.3048 0.2032)
							(mid -0.275042 0.275042)
							(end -0.2032 0.3048)
						)
						(arc
							(start 0.2032 0.3048)
							(mid 0.275042 0.275042)
							(end 0.3048 0.2032)
						)
					)
					(width 0)
					(fill yes)
				)
			)
		)
		(pad "2" smd custom
			(at 0 0.4445 180)
			(size 0.1524 0.1524)
			(layers "F.Cu" "F.Mask" "F.Paste")
			(net "GND")
			(options
				(clearance outline)
				(anchor circle)
			)
			(primitives
				(gr_poly
					(pts
						(arc
							(start 0.3048 -0.2032)
							(mid 0.275042 -0.275042)
							(end 0.2032 -0.3048)
						)
						(arc
							(start -0.2032 -0.3048)
							(mid -0.275042 -0.275042)
							(end -0.3048 -0.2032)
						)
						(arc
							(start -0.3048 0.2032)
							(mid -0.275042 0.275042)
							(end -0.2032 0.3048)
						)
						(arc
							(start 0.2032 0.3048)
							(mid 0.275042 0.275042)
							(end 0.3048 0.2032)
						)
					)
					(width 0)
					(fill yes)
				)
			)
		)
	)
	(footprint ""
		(layer "F.Cu")
		(at 240.411 -15.113 90)
		(property "Reference" "R683"
			(at 0 0 90)
			(layer "F.SilkS")
			(hide yes)
			(effects
				(font
					(size 1.27 1.27)
				)
			)
		)
		(property "Value" "0R2J-2-GP"
			(at 0.064008 -3.993896 90)
			(unlocked yes)
			(layer "F.Fab")
			(hide yes)
			(effects
				(font
					(size 1.016 1.016)
					(thickness 0.1524)
				)
			)
		)
		(property "Device Type" "R402H16"
			(at 0.064008 -5.517896 90)
			(unlocked yes)
			(layer "F.Fab")
			(hide yes)
			(effects
				(font
					(size 1.016 1.016)
					(thickness 0.1524)
				)
			)
		)
		(duplicate_pad_numbers_are_jumpers no)
		(fp_line
			(start 0.508 -0.9398)
			(end -0.508 -0.9398)
			(stroke
				(width 0.1524)
				(type default)
			)
			(layer "F.SilkS")
		)
		(fp_line
			(start -0.508 -0.9398)
			(end -0.508 0.9398)
			(stroke
				(width 0.1524)
				(type default)
			)
			(layer "F.SilkS")
		)
		(fp_rect
			(start -0.508 0.9398)
			(end 0.508 -0.9398)
			(stroke
				(width 0)
				(type default)
			)
			(fill no)
			(layer "F.CrtYd")
		)
		(fp_rect
			(start -0.508 0.9398)
			(end 0.508 -0.9398)
			(stroke
				(width 0)
				(type default)
			)
			(fill no)
			(layer "F.Fab")
		)
		(pad "1" smd custom
			(at 0 -0.4445 90)
			(size 0.1397 0.1397)
			(layers "F.Cu" "F.Mask" "F.Paste")
			(net "BMC_ENCLOSURE_LED_R")
			(options
				(clearance outline)
				(anchor circle)
			)
			(primitives
				(gr_poly
					(pts
						(arc
							(start -0.1778 -0.2794)
							(mid -0.249642 -0.249642)
							(end -0.2794 -0.1778)
						)
						(arc
							(start -0.2794 0.1778)
							(mid -0.249642 0.249642)
							(end -0.1778 0.2794)
						)
						(arc
							(start 0.1778 0.2794)
							(mid 0.249642 0.249642)
							(end 0.2794 0.1778)
						)
						(arc
							(start 0.2794 -0.1778)
							(mid 0.249642 -0.249642)
							(end 0.1778 -0.2794)
						)
					)
					(width 0)
					(fill yes)
				)
			)
		)
		(pad "2" smd custom
			(at 0 0.4445 90)
			(size 0.1397 0.1397)
			(layers "F.Cu" "F.Mask" "F.Paste")
			(net "BMC_ENCLOSURE_LED")
			(options
				(clearance outline)
				(anchor circle)
			)
			(primitives
				(gr_poly
					(pts
						(arc
							(start -0.1778 -0.2794)
							(mid -0.249642 -0.249642)
							(end -0.2794 -0.1778)
						)
						(arc
							(start -0.2794 0.1778)
							(mid -0.249642 0.249642)
							(end -0.1778 0.2794)
						)
						(arc
							(start 0.1778 0.2794)
							(mid 0.249642 0.249642)
							(end 0.2794 0.1778)
						)
						(arc
							(start 0.2794 -0.1778)
							(mid 0.249642 -0.249642)
							(end 0.1778 -0.2794)
						)
					)
					(width 0)
					(fill yes)
				)
			)
		)
	)
	(footprint ""
		(layer "F.Cu")
		(at 292.481 -157.734 180)
		(property "Reference" "R618"
			(at 0 0 180)
			(layer "F.SilkS")
			(hide yes)
			(effects
				(font
					(size 1.27 1.27)
				)
			)
		)
		(property "Value" "0R2J-2-GP"
			(at 0.064008 -3.993896 180)
			(unlocked yes)
			(layer "F.Fab")
			(hide yes)
			(effects
				(font
					(size 1.016 1.016)
					(thickness 0.1524)
				)
			)
		)
		(property "Device Type" "R402H16"
			(at 0.064008 -5.517896 180)
			(unlocked yes)
			(layer "F.Fab")
			(hide yes)
			(effects
				(font
					(size 1.016 1.016)
					(thickness 0.1524)
				)
			)
		)
		(duplicate_pad_numbers_are_jumpers no)
		(fp_line
			(start 0.508 -0.9398)
			(end -0.508 -0.9398)
			(stroke
				(width 0.1524)
				(type default)
			)
			(layer "F.SilkS")
		)
		(fp_line
			(start -0.508 -0.9398)
			(end -0.508 0.9398)
			(stroke
				(width 0.1524)
				(type default)
			)
			(layer "F.SilkS")
		)
		(fp_rect
			(start -0.508 0.9398)
			(end 0.508 -0.9398)
			(stroke
				(width 0)
				(type default)
			)
			(fill no)
			(layer "F.CrtYd")
		)
		(fp_rect
			(start -0.508 0.9398)
			(end 0.508 -0.9398)
			(stroke
				(width 0)
				(type default)
			)
			(fill no)
			(layer "F.Fab")
		)
		(pad "1" smd custom
			(at 0 -0.4445 180)
			(size 0.1397 0.1397)
			(layers "F.Cu" "F.Mask" "F.Paste")
			(net "EXP_HDD_PRE_INT_N")
			(options
				(clearance outline)
				(anchor circle)
			)
			(primitives
				(gr_poly
					(pts
						(arc
							(start -0.1778 -0.2794)
							(mid -0.249642 -0.249642)
							(end -0.2794 -0.1778)
						)
						(arc
							(start -0.2794 0.1778)
							(mid -0.249642 0.249642)
							(end -0.1778 0.2794)
						)
						(arc
							(start 0.1778 0.2794)
							(mid 0.249642 0.249642)
							(end 0.2794 0.1778)
						)
						(arc
							(start 0.2794 -0.1778)
							(mid 0.249642 -0.249642)
							(end 0.1778 -0.2794)
						)
					)
					(width 0)
					(fill yes)
				)
			)
		)
		(pad "2" smd custom
			(at 0 0.4445 180)
			(size 0.1397 0.1397)
			(layers "F.Cu" "F.Mask" "F.Paste")
			(net "HDD_PRE_IO_INT_N")
			(options
				(clearance outline)
				(anchor circle)
			)
			(primitives
				(gr_poly
					(pts
						(arc
							(start -0.1778 -0.2794)
							(mid -0.249642 -0.249642)
							(end -0.2794 -0.1778)
						)
						(arc
							(start -0.2794 0.1778)
							(mid -0.249642 0.249642)
							(end -0.1778 0.2794)
						)
						(arc
							(start 0.1778 0.2794)
							(mid 0.249642 0.249642)
							(end 0.2794 0.1778)
						)
						(arc
							(start 0.2794 -0.1778)
							(mid 0.249642 -0.249642)
							(end 0.1778 -0.2794)
						)
					)
					(width 0)
					(fill yes)
				)
			)
		)
	)
	(footprint ""
		(layer "F.Cu")
		(at 318.008 -173.736 90)
		(property "Reference" "R279"
			(at 0 0 90)
			(layer "F.SilkS")
			(hide yes)
			(effects
				(font
					(size 1.27 1.27)
				)
			)
		)
		(property "Value" "0R2J-2-GP"
			(at 0.064008 -3.993896 90)
			(unlocked yes)
			(layer "F.Fab")
			(hide yes)
			(effects
				(font
					(size 1.016 1.016)
					(thickness 0.1524)
				)
			)
		)
		(property "Device Type" "R402H16"
			(at 0.064008 -5.517896 90)
			(unlocked yes)
			(layer "F.Fab")
			(hide yes)
			(effects
				(font
					(size 1.016 1.016)
					(thickness 0.1524)
				)
			)
		)
		(duplicate_pad_numbers_are_jumpers no)
		(fp_line
			(start 0.508 -0.9398)
			(end -0.508 -0.9398)
			(stroke
				(width 0.1524)
				(type default)
			)
			(layer "F.SilkS")
		)
		(fp_line
			(start -0.508 -0.9398)
			(end -0.508 0.9398)
			(stroke
				(width 0.1524)
				(type default)
			)
			(layer "F.SilkS")
		)
		(fp_rect
			(start -0.508 0.9398)
			(end 0.508 -0.9398)
			(stroke
				(width 0)
				(type default)
			)
			(fill no)
			(layer "F.CrtYd")
		)
		(fp_rect
			(start -0.508 0.9398)
			(end 0.508 -0.9398)
			(stroke
				(width 0)
				(type default)
			)
			(fill no)
			(layer "F.Fab")
		)
		(pad "1" smd custom
			(at 0 -0.4445 90)
			(size 0.1397 0.1397)
			(layers "F.Cu" "F.Mask" "F.Paste")
			(net "BMC_RXD5_R")
			(options
				(clearance outline)
				(anchor circle)
			)
			(primitives
				(gr_poly
					(pts
						(arc
							(start -0.1778 -0.2794)
							(mid -0.249642 -0.249642)
							(end -0.2794 -0.1778)
						)
						(arc
							(start -0.2794 0.1778)
							(mid -0.249642 0.249642)
							(end -0.1778 0.2794)
						)
						(arc
							(start 0.1778 0.2794)
							(mid 0.249642 0.249642)
							(end 0.2794 0.1778)
						)
						(arc
							(start 0.2794 -0.1778)
							(mid 0.249642 -0.249642)
							(end 0.1778 -0.2794)
						)
					)
					(width 0)
					(fill yes)
				)
			)
		)
		(pad "2" smd custom
			(at 0 0.4445 90)
			(size 0.1397 0.1397)
			(layers "F.Cu" "F.Mask" "F.Paste")
			(net "BMC_RXD5")
			(options
				(clearance outline)
				(anchor circle)
			)
			(primitives
				(gr_poly
					(pts
						(arc
							(start -0.1778 -0.2794)
							(mid -0.249642 -0.249642)
							(end -0.2794 -0.1778)
						)
						(arc
							(start -0.2794 0.1778)
							(mid -0.249642 0.249642)
							(end -0.1778 0.2794)
						)
						(arc
							(start 0.1778 0.2794)
							(mid 0.249642 0.249642)
							(end 0.2794 0.1778)
						)
						(arc
							(start 0.2794 -0.1778)
							(mid 0.249642 -0.249642)
							(end 0.1778 -0.2794)
						)
					)
					(width 0)
					(fill yes)
				)
			)
		)
	)
	(footprint ""
		(layer "F.Cu")
		(at 108.585 -60.071 90)
		(property "Reference" "SR706"
			(at 0 0 90)
			(layer "F.SilkS")
			(hide yes)
			(effects
				(font
					(size 1.27 1.27)
				)
			)
		)
		(property "Value" "10KR2F-2-GP"
			(at 0.064008 -3.993896 90)
			(unlocked yes)
			(layer "F.Fab")
			(hide yes)
			(effects
				(font
					(size 1.016 1.016)
					(thickness 0.1524)
				)
			)
		)
		(property "Device Type" "R402H16"
			(at 0.064008 -5.517896 90)
			(unlocked yes)
			(layer "F.Fab")
			(hide yes)
			(effects
				(font
					(size 1.016 1.016)
					(thickness 0.1524)
				)
			)
		)
		(duplicate_pad_numbers_are_jumpers no)
		(fp_line
			(start 0.508 -0.9398)
			(end -0.508 -0.9398)
			(stroke
				(width 0.1524)
				(type default)
			)
			(layer "F.SilkS")
		)
		(fp_line
			(start -0.508 -0.9398)
			(end -0.508 0.9398)
			(stroke
				(width 0.1524)
				(type default)
			)
			(layer "F.SilkS")
		)
		(fp_rect
			(start -0.508 0.9398)
			(end 0.508 -0.9398)
			(stroke
				(width 0)
				(type default)
			)
			(fill no)
			(layer "F.CrtYd")
		)
		(fp_rect
			(start -0.508 0.9398)
			(end 0.508 -0.9398)
			(stroke
				(width 0)
				(type default)
			)
			(fill no)
			(layer "F.Fab")
		)
		(pad "1" smd custom
			(at 0 -0.4445 90)
			(size 0.1397 0.1397)
			(layers "F.Cu" "F.Mask" "F.Paste")
			(net "P1V8_C")
			(options
				(clearance outline)
				(anchor circle)
			)
			(primitives
				(gr_poly
					(pts
						(arc
							(start -0.1778 -0.2794)
							(mid -0.249642 -0.249642)
							(end -0.2794 -0.1778)
						)
						(arc
							(start -0.2794 0.1778)
							(mid -0.249642 0.249642)
							(end -0.1778 0.2794)
						)
						(arc
							(start 0.1778 0.2794)
							(mid 0.249642 0.249642)
							(end 0.2794 0.1778)
						)
						(arc
							(start 0.2794 -0.1778)
							(mid 0.249642 -0.249642)
							(end 0.1778 -0.2794)
						)
					)
					(width 0)
					(fill yes)
				)
			)
		)
		(pad "2" smd custom
			(at 0 0.4445 90)
			(size 0.1397 0.1397)
			(layers "F.Cu" "F.Mask" "F.Paste")
			(net "XM_RB")
			(options
				(clearance outline)
				(anchor circle)
			)
			(primitives
				(gr_poly
					(pts
						(arc
							(start -0.1778 -0.2794)
							(mid -0.249642 -0.249642)
							(end -0.2794 -0.1778)
						)
						(arc
							(start -0.2794 0.1778)
							(mid -0.249642 0.249642)
							(end -0.1778 0.2794)
						)
						(arc
							(start 0.1778 0.2794)
							(mid 0.249642 0.249642)
							(end 0.2794 0.1778)
						)
						(arc
							(start 0.2794 -0.1778)
							(mid 0.249642 -0.249642)
							(end 0.1778 -0.2794)
						)
					)
					(width 0)
					(fill yes)
				)
			)
		)
	)
	(footprint ""
		(layer "F.Cu")
		(at 45.466 -217.043)
		(property "Reference" "C7278"
			(at 0 0 0)
			(layer "F.SilkS")
			(hide yes)
			(effects
				(font
					(size 1.27 1.27)
				)
			)
		)
		(property "Value" "SCD1U25V3JX-GP"
			(at 0 -2.8194 0)
			(unlocked yes)
			(layer "F.Fab")
			(hide yes)
			(effects
				(font
					(size 1.016 1.016)
					(thickness 0.1524)
				)
			)
		)
		(property "Device Type" "C603H36"
			(at 0 -4.3434 0)
			(unlocked yes)
			(layer "F.Fab")
			(hide yes)
			(effects
				(font
					(size 1.016 1.016)
					(thickness 0.1524)
				)
			)
		)
		(duplicate_pad_numbers_are_jumpers no)
		(fp_line
			(start 0.508 0)
			(end -0.508 0)
			(stroke
				(width 0.2032)
				(type default)
			)
			(layer "F.SilkS")
		)
		(fp_rect
			(start -0.5842 1.3335)
			(end 0.5842 -1.3335)
			(stroke
				(width 0)
				(type default)
			)
			(fill no)
			(layer "F.CrtYd")
		)
		(fp_rect
			(start -0.5842 1.3335)
			(end 0.5842 -1.3335)
			(stroke
				(width 0)
				(type default)
			)
			(fill no)
			(layer "F.Fab")
		)
		(pad "1" smd custom
			(at 0 -0.762)
			(size 0.2159 0.2159)
			(layers "F.Cu" "F.Mask" "F.Paste")
			(net "MB0_ISET_R")
			(options
				(clearance outline)
				(anchor circle)
			)
			(primitives
				(gr_poly
					(pts
						(arc
							(start -0.3302 -0.4318)
							(mid -0.402042 -0.402042)
							(end -0.4318 -0.3302)
						)
						(arc
							(start -0.4318 0.3302)
							(mid -0.402042 0.402042)
							(end -0.3302 0.4318)
						)
						(arc
							(start 0.3302 0.4318)
							(mid 0.402042 0.402042)
							(end 0.4318 0.3302)
						)
						(arc
							(start 0.4318 -0.3302)
							(mid 0.402042 -0.402042)
							(end 0.3302 -0.4318)
						)
					)
					(width 0)
					(fill yes)
				)
			)
		)
		(pad "2" smd custom
			(at 0 0.762)
			(size 0.2159 0.2159)
			(layers "F.Cu" "F.Mask" "F.Paste")
			(net "AGND_CURRENT_MON")
			(options
				(clearance outline)
				(anchor circle)
			)
			(primitives
				(gr_poly
					(pts
						(arc
							(start -0.3302 -0.4318)
							(mid -0.402042 -0.402042)
							(end -0.4318 -0.3302)
						)
						(arc
							(start -0.4318 0.3302)
							(mid -0.402042 0.402042)
							(end -0.3302 0.4318)
						)
						(arc
							(start 0.3302 0.4318)
							(mid 0.402042 0.402042)
							(end 0.4318 0.3302)
						)
						(arc
							(start 0.4318 -0.3302)
							(mid 0.402042 -0.402042)
							(end 0.3302 -0.4318)
						)
					)
					(width 0)
					(fill yes)
				)
			)
		)
	)
	(footprint ""
		(layer "F.Cu")
		(at 337.566 -74.422 -90)
		(property "Reference" "R681"
			(at 0 0 270)
			(layer "F.SilkS")
			(hide yes)
			(effects
				(font
					(size 1.27 1.27)
				)
			)
		)
		(property "Value" "0R2J-2-GP"
			(at 0.064008 -3.993896 270)
			(unlocked yes)
			(layer "F.Fab")
			(hide yes)
			(effects
				(font
					(size 1.016 1.016)
					(thickness 0.1524)
				)
			)
		)
		(property "Device Type" "R402H16"
			(at 0.064008 -5.517896 270)
			(unlocked yes)
			(layer "F.Fab")
			(hide yes)
			(effects
				(font
					(size 1.016 1.016)
					(thickness 0.1524)
				)
			)
		)
		(duplicate_pad_numbers_are_jumpers no)
		(fp_line
			(start -0.508 -0.9398)
			(end -0.508 0.9398)
			(stroke
				(width 0.1524)
				(type default)
			)
			(layer "F.SilkS")
		)
		(fp_line
			(start 0.508 -0.9398)
			(end -0.508 -0.9398)
			(stroke
				(width 0.1524)
				(type default)
			)
			(layer "F.SilkS")
		)
		(fp_rect
			(start -0.508 0.9398)
			(end 0.508 -0.9398)
			(stroke
				(width 0)
				(type default)
			)
			(fill no)
			(layer "F.CrtYd")
		)
		(fp_rect
			(start -0.508 0.9398)
			(end 0.508 -0.9398)
			(stroke
				(width 0)
				(type default)
			)
			(fill no)
			(layer "F.Fab")
		)
		(pad "1" smd custom
			(at 0 -0.4445 270)
			(size 0.1397 0.1397)
			(layers "F.Cu" "F.Mask" "F.Paste")
			(net "ROMD0_R")
			(options
				(clearance outline)
				(anchor circle)
			)
			(primitives
				(gr_poly
					(pts
						(arc
							(start -0.1778 -0.2794)
							(mid -0.249642 -0.249642)
							(end -0.2794 -0.1778)
						)
						(arc
							(start -0.2794 0.1778)
							(mid -0.249642 0.249642)
							(end -0.1778 0.2794)
						)
						(arc
							(start 0.1778 0.2794)
							(mid 0.249642 0.249642)
							(end 0.2794 0.1778)
						)
						(arc
							(start 0.2794 -0.1778)
							(mid 0.249642 -0.249642)
							(end 0.1778 -0.2794)
						)
					)
					(width 0)
					(fill yes)
				)
			)
		)
		(pad "2" smd custom
			(at 0 0.4445 270)
			(size 0.1397 0.1397)
			(layers "F.Cu" "F.Mask" "F.Paste")
			(net "ROMD0_R_R")
			(options
				(clearance outline)
				(anchor circle)
			)
			(primitives
				(gr_poly
					(pts
						(arc
							(start -0.1778 -0.2794)
							(mid -0.249642 -0.249642)
							(end -0.2794 -0.1778)
						)
						(arc
							(start -0.2794 0.1778)
							(mid -0.249642 0.249642)
							(end -0.1778 0.2794)
						)
						(arc
							(start 0.1778 0.2794)
							(mid 0.249642 0.249642)
							(end 0.2794 0.1778)
						)
						(arc
							(start 0.2794 -0.1778)
							(mid 0.249642 -0.249642)
							(end 0.1778 -0.2794)
						)
					)
					(width 0)
					(fill yes)
				)
			)
		)
	)
	(footprint ""
		(layer "F.Cu")
		(at 143.256 -38.862 180)
		(property "Reference" "SR703"
			(at 0 0 180)
			(layer "F.SilkS")
			(hide yes)
			(effects
				(font
					(size 1.27 1.27)
				)
			)
		)
		(property "Value" "10KR2F-2-GP"
			(at 0.064008 -3.993896 180)
			(unlocked yes)
			(layer "F.Fab")
			(hide yes)
			(effects
				(font
					(size 1.016 1.016)
					(thickness 0.1524)
				)
			)
		)
		(property "Device Type" "R402H16"
			(at 0.064008 -5.517896 180)
			(unlocked yes)
			(layer "F.Fab")
			(hide yes)
			(effects
				(font
					(size 1.016 1.016)
					(thickness 0.1524)
				)
			)
		)
		(duplicate_pad_numbers_are_jumpers no)
		(fp_line
			(start 0.508 -0.9398)
			(end -0.508 -0.9398)
			(stroke
				(width 0.1524)
				(type default)
			)
			(layer "F.SilkS")
		)
		(fp_line
			(start -0.508 -0.9398)
			(end -0.508 0.9398)
			(stroke
				(width 0.1524)
				(type default)
			)
			(layer "F.SilkS")
		)
		(fp_rect
			(start -0.508 0.9398)
			(end 0.508 -0.9398)
			(stroke
				(width 0)
				(type default)
			)
			(fill no)
			(layer "F.CrtYd")
		)
		(fp_rect
			(start -0.508 0.9398)
			(end 0.508 -0.9398)
			(stroke
				(width 0)
				(type default)
			)
			(fill no)
			(layer "F.Fab")
		)
		(pad "1" smd custom
			(at 0 -0.4445 180)
			(size 0.1397 0.1397)
			(layers "F.Cu" "F.Mask" "F.Paste")
			(net "P1V8_C")
			(options
				(clearance outline)
				(anchor circle)
			)
			(primitives
				(gr_poly
					(pts
						(arc
							(start -0.1778 -0.2794)
							(mid -0.249642 -0.249642)
							(end -0.2794 -0.1778)
						)
						(arc
							(start -0.2794 0.1778)
							(mid -0.249642 0.249642)
							(end -0.1778 0.2794)
						)
						(arc
							(start 0.1778 0.2794)
							(mid 0.249642 0.249642)
							(end 0.2794 0.1778)
						)
						(arc
							(start 0.2794 -0.1778)
							(mid 0.249642 -0.249642)
							(end 0.1778 -0.2794)
						)
					)
					(width 0)
					(fill yes)
				)
			)
		)
		(pad "2" smd custom
			(at 0 0.4445 180)
			(size 0.1397 0.1397)
			(layers "F.Cu" "F.Mask" "F.Paste")
			(net "IOC_WP_N")
			(options
				(clearance outline)
				(anchor circle)
			)
			(primitives
				(gr_poly
					(pts
						(arc
							(start -0.1778 -0.2794)
							(mid -0.249642 -0.249642)
							(end -0.2794 -0.1778)
						)
						(arc
							(start -0.2794 0.1778)
							(mid -0.249642 0.249642)
							(end -0.1778 0.2794)
						)
						(arc
							(start 0.1778 0.2794)
							(mid 0.249642 0.249642)
							(end 0.2794 0.1778)
						)
						(arc
							(start 0.2794 -0.1778)
							(mid 0.249642 -0.249642)
							(end 0.1778 -0.2794)
						)
					)
					(width 0)
					(fill yes)
				)
			)
		)
	)
	(footprint ""
		(layer "F.Cu")
		(at 75.057 -32.385 180)
		(property "Reference" "SR716"
			(at 0 0 180)
			(layer "F.SilkS")
			(hide yes)
			(effects
				(font
					(size 1.27 1.27)
				)
			)
		)
		(property "Value" "D51R3F-2-GP"
			(at -0.0254 -2.5146 180)
			(unlocked yes)
			(layer "F.Fab")
			(hide yes)
			(effects
				(font
					(size 1.016 1.016)
					(thickness 0.1524)
				)
			)
		)
		(property "Device Type" "R603H22"
			(at -0.0254 -4.0386 180)
			(unlocked yes)
			(layer "F.Fab")
			(hide yes)
			(effects
				(font
					(size 1.016 1.016)
					(thickness 0.1524)
				)
			)
		)
		(duplicate_pad_numbers_are_jumpers no)
		(fp_line
			(start 0.2032 0)
			(end 0.4826 0)
			(stroke
				(width 0.2032)
				(type default)
			)
			(layer "F.SilkS")
		)
		(fp_line
			(start -0.4826 0)
			(end -0.2032 0)
			(stroke
				(width 0.2032)
				(type default)
			)
			(layer "F.SilkS")
		)
		(fp_rect
			(start -0.5842 1.3335)
			(end 0.5842 -1.3335)
			(stroke
				(width 0)
				(type default)
			)
			(fill no)
			(layer "F.CrtYd")
		)
		(fp_rect
			(start -0.5842 1.3335)
			(end 0.5842 -1.3335)
			(stroke
				(width 0)
				(type default)
			)
			(fill no)
			(layer "F.Fab")
		)
		(pad "1" smd custom
			(at 0 -0.762 180)
			(size 0.2159 0.2159)
			(layers "F.Cu" "F.Mask" "F.Paste")
			(net "P0V955_C")
			(options
				(clearance outline)
				(anchor circle)
			)
			(primitives
				(gr_poly
					(pts
						(arc
							(start -0.3302 -0.4318)
							(mid -0.402042 -0.402042)
							(end -0.4318 -0.3302)
						)
						(arc
							(start -0.4318 0.3302)
							(mid -0.402042 0.402042)
							(end -0.3302 0.4318)
						)
						(arc
							(start 0.3302 0.4318)
							(mid 0.402042 0.402042)
							(end 0.4318 0.3302)
						)
						(arc
							(start 0.4318 -0.3302)
							(mid 0.402042 -0.402042)
							(end 0.3302 -0.4318)
						)
					)
					(width 0)
					(fill yes)
				)
			)
		)
		(pad "2" smd custom
			(at 0 0.762 180)
			(size 0.2159 0.2159)
			(layers "F.Cu" "F.Mask" "F.Paste")
			(net "SAS0_AVDD")
			(options
				(clearance outline)
				(anchor circle)
			)
			(primitives
				(gr_poly
					(pts
						(arc
							(start -0.3302 -0.4318)
							(mid -0.402042 -0.402042)
							(end -0.4318 -0.3302)
						)
						(arc
							(start -0.4318 0.3302)
							(mid -0.402042 0.402042)
							(end -0.3302 0.4318)
						)
						(arc
							(start 0.3302 0.4318)
							(mid 0.402042 0.402042)
							(end 0.4318 0.3302)
						)
						(arc
							(start 0.4318 -0.3302)
							(mid 0.402042 -0.402042)
							(end 0.3302 -0.4318)
						)
					)
					(width 0)
					(fill yes)
				)
			)
		)
	)
	(footprint ""
		(layer "F.Cu")
		(at 220.345 -158.242 180)
		(property "Reference" "R577"
			(at 0 0 180)
			(layer "F.SilkS")
			(hide yes)
			(effects
				(font
					(size 1.27 1.27)
				)
			)
		)
		(property "Value" "10KR2F-2-GP"
			(at 0.064008 -3.993896 180)
			(unlocked yes)
			(layer "F.Fab")
			(hide yes)
			(effects
				(font
					(size 1.016 1.016)
					(thickness 0.1524)
				)
			)
		)
		(property "Device Type" "R402H16"
			(at 0.064008 -5.517896 180)
			(unlocked yes)
			(layer "F.Fab")
			(hide yes)
			(effects
				(font
					(size 1.016 1.016)
					(thickness 0.1524)
				)
			)
		)
		(duplicate_pad_numbers_are_jumpers no)
		(fp_line
			(start 0.508 -0.9398)
			(end -0.508 -0.9398)
			(stroke
				(width 0.1524)
				(type default)
			)
			(layer "F.SilkS")
		)
		(fp_line
			(start -0.508 -0.9398)
			(end -0.508 0.9398)
			(stroke
				(width 0.1524)
				(type default)
			)
			(layer "F.SilkS")
		)
		(fp_rect
			(start -0.508 0.9398)
			(end 0.508 -0.9398)
			(stroke
				(width 0)
				(type default)
			)
			(fill no)
			(layer "F.CrtYd")
		)
		(fp_rect
			(start -0.508 0.9398)
			(end 0.508 -0.9398)
			(stroke
				(width 0)
				(type default)
			)
			(fill no)
			(layer "F.Fab")
		)
		(pad "1" smd custom
			(at 0 -0.4445 180)
			(size 0.1397 0.1397)
			(layers "F.Cu" "F.Mask" "F.Paste")
			(net "P3V3_STBY")
			(options
				(clearance outline)
				(anchor circle)
			)
			(primitives
				(gr_poly
					(pts
						(arc
							(start -0.1778 -0.2794)
							(mid -0.249642 -0.249642)
							(end -0.2794 -0.1778)
						)
						(arc
							(start -0.2794 0.1778)
							(mid -0.249642 0.249642)
							(end -0.1778 0.2794)
						)
						(arc
							(start 0.1778 0.2794)
							(mid 0.249642 0.249642)
							(end 0.2794 0.1778)
						)
						(arc
							(start 0.2794 -0.1778)
							(mid 0.249642 -0.249642)
							(end 0.1778 -0.2794)
						)
					)
					(width 0)
					(fill yes)
				)
			)
		)
		(pad "2" smd custom
			(at 0 0.4445 180)
			(size 0.1397 0.1397)
			(layers "F.Cu" "F.Mask" "F.Paste")
			(net "JTAG_DT")
			(options
				(clearance outline)
				(anchor circle)
			)
			(primitives
				(gr_poly
					(pts
						(arc
							(start -0.1778 -0.2794)
							(mid -0.249642 -0.249642)
							(end -0.2794 -0.1778)
						)
						(arc
							(start -0.2794 0.1778)
							(mid -0.249642 0.249642)
							(end -0.1778 0.2794)
						)
						(arc
							(start 0.1778 0.2794)
							(mid 0.249642 0.249642)
							(end 0.2794 0.1778)
						)
						(arc
							(start 0.2794 -0.1778)
							(mid 0.249642 -0.249642)
							(end 0.1778 -0.2794)
						)
					)
					(width 0)
					(fill yes)
				)
			)
		)
	)
	(footprint ""
		(layer "F.Cu")
		(at 81.539842 -139.771882 180)
		(property "Reference" "SC1120"
			(at 0 0 180)
			(layer "F.SilkS")
			(hide yes)
			(effects
				(font
					(size 1.27 1.27)
				)
			)
		)
		(property "Value" "SCD1U16V2KX-3GP"
			(at 1.1811 -2.7051 180)
			(unlocked yes)
			(layer "F.Fab")
			(hide yes)
			(effects
				(font
					(size 1.016 1.016)
					(thickness 0.1524)
				)
			)
		)
		(property "Device Type" "C402H22"
			(at 1.1811 -4.2291 180)
			(unlocked yes)
			(layer "F.Fab")
			(hide yes)
			(effects
				(font
					(size 1.016 1.016)
					(thickness 0.1524)
				)
			)
		)
		(duplicate_pad_numbers_are_jumpers no)
		(fp_rect
			(start -0.4318 0.9525)
			(end 0.4318 -0.9525)
			(stroke
				(width 0)
				(type default)
			)
			(fill no)
			(layer "F.CrtYd")
		)
		(fp_rect
			(start -0.4318 0.9525)
			(end 0.4318 -0.9525)
			(stroke
				(width 0)
				(type default)
			)
			(fill no)
			(layer "F.Fab")
		)
		(pad "1" smd custom
			(at 0 -0.4445 180)
			(size 0.1524 0.1524)
			(layers "F.Cu" "F.Mask" "F.Paste")
			(net "P3V3_STBY")
			(options
				(clearance outline)
				(anchor circle)
			)
			(primitives
				(gr_poly
					(pts
						(arc
							(start 0.3048 -0.2032)
							(mid 0.275042 -0.275042)
							(end 0.2032 -0.3048)
						)
						(arc
							(start -0.2032 -0.3048)
							(mid -0.275042 -0.275042)
							(end -0.3048 -0.2032)
						)
						(arc
							(start -0.3048 0.2032)
							(mid -0.275042 0.275042)
							(end -0.2032 0.3048)
						)
						(arc
							(start 0.2032 0.3048)
							(mid 0.275042 0.275042)
							(end 0.3048 0.2032)
						)
					)
					(width 0)
					(fill yes)
				)
			)
		)
		(pad "2" smd custom
			(at 0 0.4445 180)
			(size 0.1524 0.1524)
			(layers "F.Cu" "F.Mask" "F.Paste")
			(net "GND")
			(options
				(clearance outline)
				(anchor circle)
			)
			(primitives
				(gr_poly
					(pts
						(arc
							(start 0.3048 -0.2032)
							(mid 0.275042 -0.275042)
							(end 0.2032 -0.3048)
						)
						(arc
							(start -0.2032 -0.3048)
							(mid -0.275042 -0.275042)
							(end -0.3048 -0.2032)
						)
						(arc
							(start -0.3048 0.2032)
							(mid -0.275042 0.275042)
							(end -0.2032 0.3048)
						)
						(arc
							(start 0.2032 0.3048)
							(mid 0.275042 0.275042)
							(end 0.3048 0.2032)
						)
					)
					(width 0)
					(fill yes)
				)
			)
		)
	)
	(footprint ""
		(layer "F.Cu")
		(at 223.647 -85.979 90)
		(property "Reference" "SR925"
			(at 0 0 90)
			(layer "F.SilkS")
			(hide yes)
			(effects
				(font
					(size 1.27 1.27)
				)
			)
		)
		(property "Value" "0R2J-2-GP"
			(at 0.064008 -3.993896 90)
			(unlocked yes)
			(layer "F.Fab")
			(hide yes)
			(effects
				(font
					(size 1.016 1.016)
					(thickness 0.1524)
				)
			)
		)
		(property "Device Type" "R402H16"
			(at 0.064008 -5.517896 90)
			(unlocked yes)
			(layer "F.Fab")
			(hide yes)
			(effects
				(font
					(size 1.016 1.016)
					(thickness 0.1524)
				)
			)
		)
		(duplicate_pad_numbers_are_jumpers no)
		(fp_line
			(start 0.508 -0.9398)
			(end -0.508 -0.9398)
			(stroke
				(width 0.1524)
				(type default)
			)
			(layer "F.SilkS")
		)
		(fp_line
			(start -0.508 -0.9398)
			(end -0.508 0.9398)
			(stroke
				(width 0.1524)
				(type default)
			)
			(layer "F.SilkS")
		)
		(fp_rect
			(start -0.508 0.9398)
			(end 0.508 -0.9398)
			(stroke
				(width 0)
				(type default)
			)
			(fill no)
			(layer "F.CrtYd")
		)
		(fp_rect
			(start -0.508 0.9398)
			(end 0.508 -0.9398)
			(stroke
				(width 0)
				(type default)
			)
			(fill no)
			(layer "F.Fab")
		)
		(pad "1" smd custom
			(at 0 -0.4445 90)
			(size 0.1397 0.1397)
			(layers "F.Cu" "F.Mask" "F.Paste")
			(net "IOC_UART_0_TX_R")
			(options
				(clearance outline)
				(anchor circle)
			)
			(primitives
				(gr_poly
					(pts
						(arc
							(start -0.1778 -0.2794)
							(mid -0.249642 -0.249642)
							(end -0.2794 -0.1778)
						)
						(arc
							(start -0.2794 0.1778)
							(mid -0.249642 0.249642)
							(end -0.1778 0.2794)
						)
						(arc
							(start 0.1778 0.2794)
							(mid 0.249642 0.249642)
							(end 0.2794 0.1778)
						)
						(arc
							(start 0.2794 -0.1778)
							(mid 0.249642 -0.249642)
							(end 0.1778 -0.2794)
						)
					)
					(width 0)
					(fill yes)
				)
			)
		)
		(pad "2" smd custom
			(at 0 0.4445 90)
			(size 0.1397 0.1397)
			(layers "F.Cu" "F.Mask" "F.Paste")
			(net "IOC_UART_0_TX")
			(options
				(clearance outline)
				(anchor circle)
			)
			(primitives
				(gr_poly
					(pts
						(arc
							(start -0.1778 -0.2794)
							(mid -0.249642 -0.249642)
							(end -0.2794 -0.1778)
						)
						(arc
							(start -0.2794 0.1778)
							(mid -0.249642 0.249642)
							(end -0.1778 0.2794)
						)
						(arc
							(start 0.1778 0.2794)
							(mid 0.249642 0.249642)
							(end 0.2794 0.1778)
						)
						(arc
							(start 0.2794 -0.1778)
							(mid 0.249642 -0.249642)
							(end 0.1778 -0.2794)
						)
					)
					(width 0)
					(fill yes)
				)
			)
		)
	)
	(footprint ""
		(layer "F.Cu")
		(at 320.0654 -214.4014 90)
		(property "Reference" "Q16"
			(at 0 0 90)
			(layer "F.SilkS")
			(hide yes)
			(effects
				(font
					(size 1.27 1.27)
				)
			)
		)
		(property "Value" "2N7002A-7-GP"
			(at 0.127 -8.9662 90)
			(unlocked yes)
			(layer "F.Fab")
			(hide yes)
			(effects
				(font
					(size 1.016 1.016)
					(thickness 0.1524)
				)
			)
		)
		(property "Device Type" "SOT23DGS2D4H48"
			(at 0.127 -10.4902 90)
			(unlocked yes)
			(layer "F.Fab")
			(hide yes)
			(effects
				(font
					(size 1.016 1.016)
					(thickness 0.1524)
				)
			)
		)
		(duplicate_pad_numbers_are_jumpers no)
		(fp_line
			(start 1.651 -1.778)
			(end -1.651 -1.778)
			(stroke
				(width 0.1524)
				(type default)
			)
			(layer "F.SilkS")
		)
		(fp_line
			(start -1.651 -1.778)
			(end -1.651 1.778)
			(stroke
				(width 0.1524)
				(type default)
			)
			(layer "F.SilkS")
		)
		(fp_line
			(start 1.651 1.778)
			(end 1.651 -1.778)
			(stroke
				(width 0.1524)
				(type default)
			)
			(layer "F.SilkS")
		)
		(fp_line
			(start -1.651 1.778)
			(end 1.651 1.778)
			(stroke
				(width 0.1524)
				(type default)
			)
			(layer "F.SilkS")
		)
		(fp_poly
			(pts
				(xy -1.778 1.8796) (xy -1.778 -1.8796) (xy 1.778 -1.8796) (xy 1.778 1.8796)
			)
			(stroke
				(width 0)
				(type default)
			)
			(fill no)
			(layer "F.CrtYd")
		)
		(fp_poly
			(pts
				(xy -1.778 1.8796) (xy -1.778 -1.8796) (xy 1.778 -1.8796) (xy 1.778 1.8796)
			)
			(stroke
				(width 0)
				(type default)
			)
			(fill no)
			(layer "F.Fab")
		)
		(pad "D" smd custom
			(at 0 -0.9525 90)
			(size 0.1905 0.1905)
			(layers "F.Cu" "F.Mask" "F.Paste")
			(net "EXP_TDO_EN")
			(options
				(clearance outline)
				(anchor circle)
			)
			(primitives
				(gr_poly
					(pts
						(arc
							(start -0.1778 0.5715)
							(mid -0.321484 0.511984)
							(end -0.381 0.3683)
						)
						(arc
							(start -0.381 -0.3683)
							(mid -0.321484 -0.511984)
							(end -0.1778 -0.5715)
						)
						(arc
							(start 0.1778 -0.5715)
							(mid 0.321484 -0.511984)
							(end 0.381 -0.3683)
						)
						(arc
							(start 0.381 0.3683)
							(mid 0.321484 0.511984)
							(end 0.1778 0.5715)
						)
					)
					(width 0)
					(fill yes)
				)
			)
		)
		(pad "G" smd custom
			(at -0.98425 0.9525 90)
			(size 0.1905 0.1905)
			(layers "F.Cu" "F.Mask" "F.Paste")
			(net "BMC_JTAG_L_EN")
			(options
				(clearance outline)
				(anchor circle)
			)
			(primitives
				(gr_poly
					(pts
						(arc
							(start -0.1778 0.5715)
							(mid -0.321484 0.511984)
							(end -0.381 0.3683)
						)
						(arc
							(start -0.381 -0.3683)
							(mid -0.321484 -0.511984)
							(end -0.1778 -0.5715)
						)
						(arc
							(start 0.1778 -0.5715)
							(mid 0.321484 -0.511984)
							(end 0.381 -0.3683)
						)
						(arc
							(start 0.381 0.3683)
							(mid 0.321484 0.511984)
							(end 0.1778 0.5715)
						)
					)
					(width 0)
					(fill yes)
				)
			)
		)
		(pad "S" smd custom
			(at 0.98425 0.9525 90)
			(size 0.1905 0.1905)
			(layers "F.Cu" "F.Mask" "F.Paste")
			(net "GND")
			(options
				(clearance outline)
				(anchor circle)
			)
			(primitives
				(gr_poly
					(pts
						(arc
							(start -0.1778 0.5715)
							(mid -0.321484 0.511984)
							(end -0.381 0.3683)
						)
						(arc
							(start -0.381 -0.3683)
							(mid -0.321484 -0.511984)
							(end -0.1778 -0.5715)
						)
						(arc
							(start 0.1778 -0.5715)
							(mid 0.321484 -0.511984)
							(end 0.381 -0.3683)
						)
						(arc
							(start 0.381 0.3683)
							(mid 0.321484 0.511984)
							(end 0.1778 0.5715)
						)
					)
					(width 0)
					(fill yes)
				)
			)
		)
	)
	(footprint ""
		(layer "F.Cu")
		(at 38.354 -214.376 90)
		(property "Reference" "SR842"
			(at 0 0 90)
			(layer "F.SilkS")
			(hide yes)
			(effects
				(font
					(size 1.27 1.27)
				)
			)
		)
		(property "Value" "200KR2F-L-GP"
			(at 0.064008 -3.993896 90)
			(unlocked yes)
			(layer "F.Fab")
			(hide yes)
			(effects
				(font
					(size 1.016 1.016)
					(thickness 0.1524)
				)
			)
		)
		(property "Device Type" "R402H16"
			(at 0.064008 -5.517896 90)
			(unlocked yes)
			(layer "F.Fab")
			(hide yes)
			(effects
				(font
					(size 1.016 1.016)
					(thickness 0.1524)
				)
			)
		)
		(duplicate_pad_numbers_are_jumpers no)
		(fp_line
			(start 0.508 -0.9398)
			(end -0.508 -0.9398)
			(stroke
				(width 0.1524)
				(type default)
			)
			(layer "F.SilkS")
		)
		(fp_line
			(start -0.508 -0.9398)
			(end -0.508 0.9398)
			(stroke
				(width 0.1524)
				(type default)
			)
			(layer "F.SilkS")
		)
		(fp_rect
			(start -0.508 0.9398)
			(end 0.508 -0.9398)
			(stroke
				(width 0)
				(type default)
			)
			(fill no)
			(layer "F.CrtYd")
		)
		(fp_rect
			(start -0.508 0.9398)
			(end 0.508 -0.9398)
			(stroke
				(width 0)
				(type default)
			)
			(fill no)
			(layer "F.Fab")
		)
		(pad "1" smd custom
			(at 0 -0.4445 90)
			(size 0.1397 0.1397)
			(layers "F.Cu" "F.Mask" "F.Paste")
			(net "EXP_I2C_VREF_4")
			(options
				(clearance outline)
				(anchor circle)
			)
			(primitives
				(gr_poly
					(pts
						(arc
							(start -0.1778 -0.2794)
							(mid -0.249642 -0.249642)
							(end -0.2794 -0.1778)
						)
						(arc
							(start -0.2794 0.1778)
							(mid -0.249642 0.249642)
							(end -0.1778 0.2794)
						)
						(arc
							(start 0.1778 0.2794)
							(mid 0.249642 0.249642)
							(end 0.2794 0.1778)
						)
						(arc
							(start 0.2794 -0.1778)
							(mid 0.249642 -0.249642)
							(end 0.1778 -0.2794)
						)
					)
					(width 0)
					(fill yes)
				)
			)
		)
		(pad "2" smd custom
			(at 0 0.4445 90)
			(size 0.1397 0.1397)
			(layers "F.Cu" "F.Mask" "F.Paste")
			(net "P3V3_STBY")
			(options
				(clearance outline)
				(anchor circle)
			)
			(primitives
				(gr_poly
					(pts
						(arc
							(start -0.1778 -0.2794)
							(mid -0.249642 -0.249642)
							(end -0.2794 -0.1778)
						)
						(arc
							(start -0.2794 0.1778)
							(mid -0.249642 0.249642)
							(end -0.1778 0.2794)
						)
						(arc
							(start 0.1778 0.2794)
							(mid 0.249642 0.249642)
							(end 0.2794 0.1778)
						)
						(arc
							(start 0.2794 -0.1778)
							(mid 0.249642 -0.249642)
							(end 0.1778 -0.2794)
						)
					)
					(width 0)
					(fill yes)
				)
			)
		)
	)
	(footprint ""
		(layer "F.Cu")
		(at 95.758 -10.033 180)
		(property "Reference" "PC200"
			(at 0 0 180)
			(layer "F.SilkS")
			(hide yes)
			(effects
				(font
					(size 1.27 1.27)
				)
			)
		)
		(property "Value" "SC22U6D3V6KX-2-GP"
			(at -0.0762 -5.1308 180)
			(unlocked yes)
			(layer "F.Fab")
			(hide yes)
			(effects
				(font
					(size 1.016 1.016)
					(thickness 0.1524)
				)
			)
		)
		(property "Device Type" "C1206H71"
			(at -0.127 -6.6548 180)
			(unlocked yes)
			(layer "F.Fab")
			(hide yes)
			(effects
				(font
					(size 1.016 1.016)
					(thickness 0.1524)
				)
			)
		)
		(duplicate_pad_numbers_are_jumpers no)
		(fp_line
			(start 1.016 2.2352)
			(end -1.016 2.2352)
			(stroke
				(width 0.1524)
				(type default)
			)
			(layer "F.SilkS")
		)
		(fp_line
			(start 1.016 0.8382)
			(end 1.016 2.2352)
			(stroke
				(width 0.1524)
				(type default)
			)
			(layer "F.SilkS")
		)
		(fp_line
			(start 1.016 -2.2352)
			(end 1.016 -0.8382)
			(stroke
				(width 0.1524)
				(type default)
			)
			(layer "F.SilkS")
		)
		(fp_line
			(start -1.016 2.2352)
			(end -1.016 0.8382)
			(stroke
				(width 0.1524)
				(type default)
			)
			(layer "F.SilkS")
		)
		(fp_line
			(start -1.016 -0.8382)
			(end -1.016 -2.2352)
			(stroke
				(width 0.1524)
				(type default)
			)
			(layer "F.SilkS")
		)
		(fp_line
			(start -1.016 -2.2352)
			(end 1.016 -2.2352)
			(stroke
				(width 0.1524)
				(type default)
			)
			(layer "F.SilkS")
		)
		(fp_rect
			(start -1.0922 2.3114)
			(end 1.0922 -2.3114)
			(stroke
				(width 0)
				(type default)
			)
			(fill no)
			(layer "F.CrtYd")
		)
		(fp_poly
			(pts
				(xy 1.0922 -2.3114) (xy 1.0922 2.3114) (xy -1.0922 2.3114) (xy -1.0922 -2.3114)
			)
			(stroke
				(width 0)
				(type default)
			)
			(fill no)
			(layer "F.Fab")
		)
		(pad "1" smd rect
			(at 0 -1.397 180)
			(size 1.651 1.27)
			(layers "F.Cu" "F.Mask" "F.Paste")
			(net "P0V955_C")
		)
		(pad "2" smd rect
			(at 0 1.397 180)
			(size 1.651 1.27)
			(layers "F.Cu" "F.Mask" "F.Paste")
			(net "GND")
		)
	)
	(footprint ""
		(layer "F.Cu")
		(at 80.372966 -88.519 90)
		(property "Reference" "SR828"
			(at 0 0 90)
			(layer "F.SilkS")
			(hide yes)
			(effects
				(font
					(size 1.27 1.27)
				)
			)
		)
		(property "Value" "10R2F-L-GP"
			(at 0.064008 -3.993896 90)
			(unlocked yes)
			(layer "F.Fab")
			(hide yes)
			(effects
				(font
					(size 1.016 1.016)
					(thickness 0.1524)
				)
			)
		)
		(property "Device Type" "R402H14"
			(at 0.064008 -5.517896 90)
			(unlocked yes)
			(layer "F.Fab")
			(hide yes)
			(effects
				(font
					(size 1.016 1.016)
					(thickness 0.1524)
				)
			)
		)
		(duplicate_pad_numbers_are_jumpers no)
		(fp_line
			(start 0.508 -0.9398)
			(end -0.508 -0.9398)
			(stroke
				(width 0.1524)
				(type default)
			)
			(layer "F.SilkS")
		)
		(fp_line
			(start -0.508 -0.9398)
			(end -0.508 0.9398)
			(stroke
				(width 0.1524)
				(type default)
			)
			(layer "F.SilkS")
		)
		(fp_rect
			(start -0.508 0.9398)
			(end 0.508 -0.9398)
			(stroke
				(width 0)
				(type default)
			)
			(fill no)
			(layer "F.CrtYd")
		)
		(fp_rect
			(start -0.508 0.9398)
			(end 0.508 -0.9398)
			(stroke
				(width 0)
				(type default)
			)
			(fill no)
			(layer "F.Fab")
		)
		(pad "1" smd custom
			(at 0 -0.4445 90)
			(size 0.1397 0.1397)
			(layers "F.Cu" "F.Mask" "F.Paste")
			(net "P1V8_E")
			(options
				(clearance outline)
				(anchor circle)
			)
			(primitives
				(gr_poly
					(pts
						(arc
							(start -0.1778 -0.2794)
							(mid -0.249642 -0.249642)
							(end -0.2794 -0.1778)
						)
						(arc
							(start -0.2794 0.1778)
							(mid -0.249642 0.249642)
							(end -0.1778 0.2794)
						)
						(arc
							(start 0.1778 0.2794)
							(mid 0.249642 0.249642)
							(end 0.2794 0.1778)
						)
						(arc
							(start 0.2794 -0.1778)
							(mid 0.249642 -0.249642)
							(end 0.1778 -0.2794)
						)
					)
					(width 0)
					(fill yes)
				)
			)
		)
		(pad "2" smd custom
			(at 0 0.4445 90)
			(size 0.1397 0.1397)
			(layers "F.Cu" "F.Mask" "F.Paste")
			(net "SYSPLL_VDDA18")
			(options
				(clearance outline)
				(anchor circle)
			)
			(primitives
				(gr_poly
					(pts
						(arc
							(start -0.1778 -0.2794)
							(mid -0.249642 -0.249642)
							(end -0.2794 -0.1778)
						)
						(arc
							(start -0.2794 0.1778)
							(mid -0.249642 0.249642)
							(end -0.1778 0.2794)
						)
						(arc
							(start 0.1778 0.2794)
							(mid 0.249642 0.249642)
							(end 0.2794 0.1778)
						)
						(arc
							(start 0.2794 -0.1778)
							(mid 0.249642 -0.249642)
							(end 0.1778 -0.2794)
						)
					)
					(width 0)
					(fill yes)
				)
			)
		)
	)
	(footprint ""
		(layer "F.Cu")
		(at 270.722852 -192.924176 180)
		(property "Reference" "R334"
			(at 0 0 180)
			(layer "F.SilkS")
			(hide yes)
			(effects
				(font
					(size 1.27 1.27)
				)
			)
		)
		(property "Value" "47KR2F-GP"
			(at 0.064008 -3.993896 180)
			(unlocked yes)
			(layer "F.Fab")
			(hide yes)
			(effects
				(font
					(size 1.016 1.016)
					(thickness 0.1524)
				)
			)
		)
		(property "Device Type" "R402H16"
			(at 0.064008 -5.517896 180)
			(unlocked yes)
			(layer "F.Fab")
			(hide yes)
			(effects
				(font
					(size 1.016 1.016)
					(thickness 0.1524)
				)
			)
		)
		(duplicate_pad_numbers_are_jumpers no)
		(fp_line
			(start 0.508 -0.9398)
			(end -0.508 -0.9398)
			(stroke
				(width 0.1524)
				(type default)
			)
			(layer "F.SilkS")
		)
		(fp_line
			(start -0.508 -0.9398)
			(end -0.508 0.9398)
			(stroke
				(width 0.1524)
				(type default)
			)
			(layer "F.SilkS")
		)
		(fp_rect
			(start -0.508 0.9398)
			(end 0.508 -0.9398)
			(stroke
				(width 0)
				(type default)
			)
			(fill no)
			(layer "F.CrtYd")
		)
		(fp_rect
			(start -0.508 0.9398)
			(end 0.508 -0.9398)
			(stroke
				(width 0)
				(type default)
			)
			(fill no)
			(layer "F.Fab")
		)
		(pad "1" smd custom
			(at 0 -0.4445 180)
			(size 0.1397 0.1397)
			(layers "F.Cu" "F.Mask" "F.Paste")
			(net "FM_BMC_RESET_N")
			(options
				(clearance outline)
				(anchor circle)
			)
			(primitives
				(gr_poly
					(pts
						(arc
							(start -0.1778 -0.2794)
							(mid -0.249642 -0.249642)
							(end -0.2794 -0.1778)
						)
						(arc
							(start -0.2794 0.1778)
							(mid -0.249642 0.249642)
							(end -0.1778 0.2794)
						)
						(arc
							(start 0.1778 0.2794)
							(mid 0.249642 0.249642)
							(end 0.2794 0.1778)
						)
						(arc
							(start 0.2794 -0.1778)
							(mid 0.249642 -0.249642)
							(end 0.1778 -0.2794)
						)
					)
					(width 0)
					(fill yes)
				)
			)
		)
		(pad "2" smd custom
			(at 0 0.4445 180)
			(size 0.1397 0.1397)
			(layers "F.Cu" "F.Mask" "F.Paste")
			(net "GND")
			(options
				(clearance outline)
				(anchor circle)
			)
			(primitives
				(gr_poly
					(pts
						(arc
							(start -0.1778 -0.2794)
							(mid -0.249642 -0.249642)
							(end -0.2794 -0.1778)
						)
						(arc
							(start -0.2794 0.1778)
							(mid -0.249642 0.249642)
							(end -0.1778 0.2794)
						)
						(arc
							(start 0.1778 0.2794)
							(mid 0.249642 0.249642)
							(end 0.2794 0.1778)
						)
						(arc
							(start 0.2794 -0.1778)
							(mid 0.249642 -0.249642)
							(end 0.1778 -0.2794)
						)
					)
					(width 0)
					(fill yes)
				)
			)
		)
	)
	(footprint ""
		(layer "F.Cu")
		(at 261.562596 -51.962812 90)
		(property "Reference" "SR720"
			(at 0 0 90)
			(layer "F.SilkS")
			(hide yes)
			(effects
				(font
					(size 1.27 1.27)
				)
			)
		)
		(property "Value" "4K7R2F-GP"
			(at 0.064008 -3.993896 90)
			(unlocked yes)
			(layer "F.Fab")
			(hide yes)
			(effects
				(font
					(size 1.016 1.016)
					(thickness 0.1524)
				)
			)
		)
		(property "Device Type" "R402H16"
			(at 0.064008 -5.517896 90)
			(unlocked yes)
			(layer "F.Fab")
			(hide yes)
			(effects
				(font
					(size 1.016 1.016)
					(thickness 0.1524)
				)
			)
		)
		(duplicate_pad_numbers_are_jumpers no)
		(fp_line
			(start 0.508 -0.9398)
			(end -0.508 -0.9398)
			(stroke
				(width 0.1524)
				(type default)
			)
			(layer "F.SilkS")
		)
		(fp_line
			(start -0.508 -0.9398)
			(end -0.508 0.9398)
			(stroke
				(width 0.1524)
				(type default)
			)
			(layer "F.SilkS")
		)
		(fp_rect
			(start -0.508 0.9398)
			(end 0.508 -0.9398)
			(stroke
				(width 0)
				(type default)
			)
			(fill no)
			(layer "F.CrtYd")
		)
		(fp_rect
			(start -0.508 0.9398)
			(end 0.508 -0.9398)
			(stroke
				(width 0)
				(type default)
			)
			(fill no)
			(layer "F.Fab")
		)
		(pad "1" smd custom
			(at 0 -0.4445 90)
			(size 0.1397 0.1397)
			(layers "F.Cu" "F.Mask" "F.Paste")
			(net "IOC_EEPROM_A1")
			(options
				(clearance outline)
				(anchor circle)
			)
			(primitives
				(gr_poly
					(pts
						(arc
							(start -0.1778 -0.2794)
							(mid -0.249642 -0.249642)
							(end -0.2794 -0.1778)
						)
						(arc
							(start -0.2794 0.1778)
							(mid -0.249642 0.249642)
							(end -0.1778 0.2794)
						)
						(arc
							(start 0.1778 0.2794)
							(mid 0.249642 0.249642)
							(end 0.2794 0.1778)
						)
						(arc
							(start 0.2794 -0.1778)
							(mid 0.249642 -0.249642)
							(end 0.1778 -0.2794)
						)
					)
					(width 0)
					(fill yes)
				)
			)
		)
		(pad "2" smd custom
			(at 0 0.4445 90)
			(size 0.1397 0.1397)
			(layers "F.Cu" "F.Mask" "F.Paste")
			(net "GND")
			(options
				(clearance outline)
				(anchor circle)
			)
			(primitives
				(gr_poly
					(pts
						(arc
							(start -0.1778 -0.2794)
							(mid -0.249642 -0.249642)
							(end -0.2794 -0.1778)
						)
						(arc
							(start -0.2794 0.1778)
							(mid -0.249642 0.249642)
							(end -0.1778 0.2794)
						)
						(arc
							(start 0.1778 0.2794)
							(mid 0.249642 0.249642)
							(end 0.2794 0.1778)
						)
						(arc
							(start 0.2794 -0.1778)
							(mid 0.249642 -0.249642)
							(end 0.1778 -0.2794)
						)
					)
					(width 0)
					(fill yes)
				)
			)
		)
	)
	(footprint ""
		(layer "F.Cu")
		(at 95.89897 -94.234 -90)
		(property "Reference" "SR806"
			(at 0 0 270)
			(layer "F.SilkS")
			(hide yes)
			(effects
				(font
					(size 1.27 1.27)
				)
			)
		)
		(property "Value" "4K75R2F-1-GP"
			(at 0.064008 -3.993896 270)
			(unlocked yes)
			(layer "F.Fab")
			(hide yes)
			(effects
				(font
					(size 1.016 1.016)
					(thickness 0.1524)
				)
			)
		)
		(property "Device Type" "R402H16"
			(at 0.064008 -5.517896 270)
			(unlocked yes)
			(layer "F.Fab")
			(hide yes)
			(effects
				(font
					(size 1.016 1.016)
					(thickness 0.1524)
				)
			)
		)
		(duplicate_pad_numbers_are_jumpers no)
		(fp_line
			(start -0.508 -0.9398)
			(end -0.508 0.9398)
			(stroke
				(width 0.1524)
				(type default)
			)
			(layer "F.SilkS")
		)
		(fp_line
			(start 0.508 -0.9398)
			(end -0.508 -0.9398)
			(stroke
				(width 0.1524)
				(type default)
			)
			(layer "F.SilkS")
		)
		(fp_rect
			(start -0.508 0.9398)
			(end 0.508 -0.9398)
			(stroke
				(width 0)
				(type default)
			)
			(fill no)
			(layer "F.CrtYd")
		)
		(fp_rect
			(start -0.508 0.9398)
			(end 0.508 -0.9398)
			(stroke
				(width 0)
				(type default)
			)
			(fill no)
			(layer "F.Fab")
		)
		(pad "1" smd custom
			(at 0 -0.4445 270)
			(size 0.1397 0.1397)
			(layers "F.Cu" "F.Mask" "F.Paste")
			(net "LSI_SCAN_ENABLE")
			(options
				(clearance outline)
				(anchor circle)
			)
			(primitives
				(gr_poly
					(pts
						(arc
							(start -0.1778 -0.2794)
							(mid -0.249642 -0.249642)
							(end -0.2794 -0.1778)
						)
						(arc
							(start -0.2794 0.1778)
							(mid -0.249642 0.249642)
							(end -0.1778 0.2794)
						)
						(arc
							(start 0.1778 0.2794)
							(mid 0.249642 0.249642)
							(end 0.2794 0.1778)
						)
						(arc
							(start 0.2794 -0.1778)
							(mid 0.249642 -0.249642)
							(end 0.1778 -0.2794)
						)
					)
					(width 0)
					(fill yes)
				)
			)
		)
		(pad "2" smd custom
			(at 0 0.4445 270)
			(size 0.1397 0.1397)
			(layers "F.Cu" "F.Mask" "F.Paste")
			(net "GND")
			(options
				(clearance outline)
				(anchor circle)
			)
			(primitives
				(gr_poly
					(pts
						(arc
							(start -0.1778 -0.2794)
							(mid -0.249642 -0.249642)
							(end -0.2794 -0.1778)
						)
						(arc
							(start -0.2794 0.1778)
							(mid -0.249642 0.249642)
							(end -0.1778 0.2794)
						)
						(arc
							(start 0.1778 0.2794)
							(mid 0.249642 0.249642)
							(end 0.2794 0.1778)
						)
						(arc
							(start 0.2794 -0.1778)
							(mid 0.249642 -0.249642)
							(end 0.1778 -0.2794)
						)
					)
					(width 0)
					(fill yes)
				)
			)
		)
	)
	(footprint ""
		(layer "F.Cu")
		(at 25.604216 -224.21088 -90)
		(property "Reference" "R637"
			(at 0 0 270)
			(layer "F.SilkS")
			(hide yes)
			(effects
				(font
					(size 1.27 1.27)
				)
			)
		)
		(property "Value" "4K7R2F-GP"
			(at 0.064008 -3.993896 270)
			(unlocked yes)
			(layer "F.Fab")
			(hide yes)
			(effects
				(font
					(size 1.016 1.016)
					(thickness 0.1524)
				)
			)
		)
		(property "Device Type" "R402H16"
			(at 0.064008 -5.517896 270)
			(unlocked yes)
			(layer "F.Fab")
			(hide yes)
			(effects
				(font
					(size 1.016 1.016)
					(thickness 0.1524)
				)
			)
		)
		(duplicate_pad_numbers_are_jumpers no)
		(fp_line
			(start -0.508 -0.9398)
			(end -0.508 0.9398)
			(stroke
				(width 0.1524)
				(type default)
			)
			(layer "F.SilkS")
		)
		(fp_line
			(start 0.508 -0.9398)
			(end -0.508 -0.9398)
			(stroke
				(width 0.1524)
				(type default)
			)
			(layer "F.SilkS")
		)
		(fp_rect
			(start -0.508 0.9398)
			(end 0.508 -0.9398)
			(stroke
				(width 0)
				(type default)
			)
			(fill no)
			(layer "F.CrtYd")
		)
		(fp_rect
			(start -0.508 0.9398)
			(end 0.508 -0.9398)
			(stroke
				(width 0)
				(type default)
			)
			(fill no)
			(layer "F.Fab")
		)
		(pad "1" smd custom
			(at 0 -0.4445 270)
			(size 0.1397 0.1397)
			(layers "F.Cu" "F.Mask" "F.Paste")
			(net "IO_EXP_HDD_PWR_A2")
			(options
				(clearance outline)
				(anchor circle)
			)
			(primitives
				(gr_poly
					(pts
						(arc
							(start -0.1778 -0.2794)
							(mid -0.249642 -0.249642)
							(end -0.2794 -0.1778)
						)
						(arc
							(start -0.2794 0.1778)
							(mid -0.249642 0.249642)
							(end -0.1778 0.2794)
						)
						(arc
							(start 0.1778 0.2794)
							(mid 0.249642 0.249642)
							(end 0.2794 0.1778)
						)
						(arc
							(start 0.2794 -0.1778)
							(mid 0.249642 -0.249642)
							(end 0.1778 -0.2794)
						)
					)
					(width 0)
					(fill yes)
				)
			)
		)
		(pad "2" smd custom
			(at 0 0.4445 270)
			(size 0.1397 0.1397)
			(layers "F.Cu" "F.Mask" "F.Paste")
			(net "GND")
			(options
				(clearance outline)
				(anchor circle)
			)
			(primitives
				(gr_poly
					(pts
						(arc
							(start -0.1778 -0.2794)
							(mid -0.249642 -0.249642)
							(end -0.2794 -0.1778)
						)
						(arc
							(start -0.2794 0.1778)
							(mid -0.249642 0.249642)
							(end -0.1778 0.2794)
						)
						(arc
							(start 0.1778 0.2794)
							(mid 0.249642 0.249642)
							(end 0.2794 0.1778)
						)
						(arc
							(start 0.2794 -0.1778)
							(mid 0.249642 -0.249642)
							(end 0.1778 -0.2794)
						)
					)
					(width 0)
					(fill yes)
				)
			)
		)
	)
	(footprint ""
		(layer "F.Cu")
		(at 42.926 -169.291 90)
		(property "Reference" "C316"
			(at 0 0 90)
			(layer "F.SilkS")
			(hide yes)
			(effects
				(font
					(size 1.27 1.27)
				)
			)
		)
		(property "Value" "SC1U16V3KX-5GP"
			(at 0 -2.8194 90)
			(unlocked yes)
			(layer "F.Fab")
			(hide yes)
			(effects
				(font
					(size 1.016 1.016)
					(thickness 0.1524)
				)
			)
		)
		(property "Device Type" "C603H36"
			(at 0 -4.3434 90)
			(unlocked yes)
			(layer "F.Fab")
			(hide yes)
			(effects
				(font
					(size 1.016 1.016)
					(thickness 0.1524)
				)
			)
		)
		(duplicate_pad_numbers_are_jumpers no)
		(fp_line
			(start 0.508 0)
			(end -0.508 0)
			(stroke
				(width 0.2032)
				(type default)
			)
			(layer "F.SilkS")
		)
		(fp_rect
			(start -0.5842 1.3335)
			(end 0.5842 -1.3335)
			(stroke
				(width 0)
				(type default)
			)
			(fill no)
			(layer "F.CrtYd")
		)
		(fp_rect
			(start -0.5842 1.3335)
			(end 0.5842 -1.3335)
			(stroke
				(width 0)
				(type default)
			)
			(fill no)
			(layer "F.Fab")
		)
		(pad "1" smd custom
			(at 0 -0.762 90)
			(size 0.2159 0.2159)
			(layers "F.Cu" "F.Mask" "F.Paste")
			(net "FP_PWR_BTN_N")
			(options
				(clearance outline)
				(anchor circle)
			)
			(primitives
				(gr_poly
					(pts
						(arc
							(start -0.3302 -0.4318)
							(mid -0.402042 -0.402042)
							(end -0.4318 -0.3302)
						)
						(arc
							(start -0.4318 0.3302)
							(mid -0.402042 0.402042)
							(end -0.3302 0.4318)
						)
						(arc
							(start 0.3302 0.4318)
							(mid 0.402042 0.402042)
							(end 0.4318 0.3302)
						)
						(arc
							(start 0.4318 -0.3302)
							(mid 0.402042 -0.402042)
							(end 0.3302 -0.4318)
						)
					)
					(width 0)
					(fill yes)
				)
			)
		)
		(pad "2" smd custom
			(at 0 0.762 90)
			(size 0.2159 0.2159)
			(layers "F.Cu" "F.Mask" "F.Paste")
			(net "GND")
			(options
				(clearance outline)
				(anchor circle)
			)
			(primitives
				(gr_poly
					(pts
						(arc
							(start -0.3302 -0.4318)
							(mid -0.402042 -0.402042)
							(end -0.4318 -0.3302)
						)
						(arc
							(start -0.4318 0.3302)
							(mid -0.402042 0.402042)
							(end -0.3302 0.4318)
						)
						(arc
							(start 0.3302 0.4318)
							(mid 0.402042 0.402042)
							(end 0.4318 0.3302)
						)
						(arc
							(start 0.4318 -0.3302)
							(mid 0.402042 -0.402042)
							(end 0.3302 -0.4318)
						)
					)
					(width 0)
					(fill yes)
				)
			)
		)
	)
	(footprint ""
		(layer "F.Cu")
		(at 255.847596 -52.597812 90)
		(property "Reference" "SU61"
			(at 0 0 90)
			(layer "F.SilkS")
			(hide yes)
			(effects
				(font
					(size 1.27 1.27)
				)
			)
		)
		(property "Value" "AT24C64D-SSHM-T-GP"
			(at -3.707384 -1.5367 90)
			(unlocked yes)
			(layer "F.Fab")
			(hide yes)
			(effects
				(font
					(size 1.016 1.016)
					(thickness 0.1524)
				)
			)
		)
		(property "Device Type" "SOIC8H69"
			(at -3.707384 -3.0607 90)
			(unlocked yes)
			(layer "F.Fab")
			(hide yes)
			(effects
				(font
					(size 1.016 1.016)
					(thickness 0.1524)
				)
			)
		)
		(duplicate_pad_numbers_are_jumpers no)
		(fp_line
			(start 2.1336 -1.4224)
			(end -2.7432 -1.4224)
			(stroke
				(width 0.1524)
				(type default)
			)
			(layer "F.SilkS")
		)
		(fp_line
			(start -2.7432 -1.4224)
			(end -2.7432 1.4224)
			(stroke
				(width 0.1524)
				(type default)
			)
			(layer "F.SilkS")
		)
		(fp_line
			(start -2.7178 -0.508)
			(end -2.1844 -0.0508)
			(stroke
				(width 0.1524)
				(type default)
			)
			(layer "F.SilkS")
		)
		(fp_line
			(start -2.1844 -0.0508)
			(end -2.7178 0.508)
			(stroke
				(width 0.1524)
				(type default)
			)
			(layer "F.SilkS")
		)
		(fp_line
			(start 2.1336 1.4224)
			(end 2.1336 -1.4224)
			(stroke
				(width 0.1524)
				(type default)
			)
			(layer "F.SilkS")
		)
		(fp_line
			(start -2.7432 1.4224)
			(end 2.1336 1.4224)
			(stroke
				(width 0.1524)
				(type default)
			)
			(layer "F.SilkS")
		)
		(fp_line
			(start -2.7432 1.4224)
			(end -2.6416 1.4224)
			(stroke
				(width 0.1524)
				(type default)
			)
			(layer "F.SilkS")
		)
		(fp_line
			(start -2.6289 3.4417)
			(end -2.6289 1.4732)
			(stroke
				(width 0.381)
				(type default)
			)
			(layer "F.SilkS")
		)
		(fp_poly
			(pts
				(xy -2.2098 -1.4224) (xy -2.2098 1.4224) (xy 2.2098 1.4224) (xy 2.2098 -1.4224)
			)
			(stroke
				(width 0)
				(type default)
			)
			(fill yes)
			(layer "F.SilkS")
		)
		(fp_rect
			(start -2.450084 2.999994)
			(end 2.450084 -2.999994)
			(stroke
				(width 0)
				(type default)
			)
			(fill no)
			(layer "F.CrtYd")
		)
		(fp_poly
			(pts
				(xy -2.8194 3.6322) (xy -2.8194 -3.6322) (xy 2.8194 -3.6322) (xy 2.8194 1.18364) (xy 2.450084 1.18364)
				(xy 2.450084 -2.999994) (xy -2.450084 -2.999994) (xy -2.450084 2.999994) (xy 2.450084 2.999994)
				(xy 2.450084 1.18618) (xy 2.8194 1.18618) (xy 2.8194 3.6322)
			)
			(stroke
				(width 0)
				(type default)
			)
			(fill no)
			(layer "F.CrtYd")
		)
		(fp_rect
			(start -2.8194 3.6322)
			(end 2.8194 -3.6322)
			(stroke
				(width 0)
				(type default)
			)
			(fill no)
			(layer "F.Fab")
		)
		(pad "1" smd rect
			(at -1.905 2.54 90)
			(size 0.635 1.651)
			(layers "F.Cu" "F.Mask" "F.Paste")
			(net "IOC_EEPROM_A0")
		)
		(pad "2" smd rect
			(at -0.635 2.54 90)
			(size 0.635 1.651)
			(layers "F.Cu" "F.Mask" "F.Paste")
			(net "IOC_EEPROM_A1")
		)
		(pad "3" smd rect
			(at 0.635 2.54 90)
			(size 0.635 1.651)
			(layers "F.Cu" "F.Mask" "F.Paste")
			(net "IOC_EEPROM_A2")
		)
		(pad "4" smd rect
			(at 1.905 2.54 90)
			(size 0.635 1.651)
			(layers "F.Cu" "F.Mask" "F.Paste")
			(net "GND")
		)
		(pad "5" smd rect
			(at 1.905 -2.54 90)
			(size 0.635 1.651)
			(layers "F.Cu" "F.Mask" "F.Paste")
			(net "IOC_EEPROM_SDA")
		)
		(pad "6" smd rect
			(at 0.635 -2.54 90)
			(size 0.635 1.651)
			(layers "F.Cu" "F.Mask" "F.Paste")
			(net "IOC_EEPROM_SCL")
		)
		(pad "7" smd rect
			(at -0.635 -2.54 90)
			(size 0.635 1.651)
			(layers "F.Cu" "F.Mask" "F.Paste")
			(net "IOC_EEPROM_WP")
		)
		(pad "8" smd rect
			(at -1.905 -2.54 90)
			(size 0.635 1.651)
			(layers "F.Cu" "F.Mask" "F.Paste")
			(net "P1V8_C")
		)
	)
	(footprint ""
		(layer "F.Cu")
		(at 342.904318 -156.416248 -90)
		(property "Reference" "TP169"
			(at 0 0 270)
			(layer "F.SilkS")
			(hide yes)
			(effects
				(font
					(size 1.27 1.27)
				)
			)
		)
		(property "Value" "TPAD28"
			(at 0.0127 -1.8034 270)
			(unlocked yes)
			(layer "F.Fab")
			(hide yes)
			(effects
				(font
					(size 1.016 1.016)
					(thickness 0.1524)
				)
			)
		)
		(property "Device Type" "TPAD28"
			(at 0.0127 -3.3274 270)
			(unlocked yes)
			(layer "F.Fab")
			(hide yes)
			(effects
				(font
					(size 1.016 1.016)
					(thickness 0.1524)
				)
			)
		)
		(duplicate_pad_numbers_are_jumpers no)
		(fp_poly
			(pts
				(arc
					(start 0 -0.3556)
					(mid 0 0.3556)
					(end 0 -0.3556)
				)
			)
			(stroke
				(width 0)
				(type default)
			)
			(fill no)
			(layer "F.CrtYd")
		)
		(fp_poly
			(pts
				(arc
					(start 0 -0.6096)
					(mid 0 0.6096)
					(end 0 -0.6096)
				)
			)
			(stroke
				(width 0)
				(type default)
			)
			(fill no)
			(layer "F.Fab")
		)
		(pad "1" smd circle
			(at 0 0 270)
			(size 0.7112 0.7112)
			(layers "F.Cu" "F.Mask" "F.Paste")
			(net "CRFILT")
		)
	)
	(footprint ""
		(layer "F.Cu")
		(at 140.95857 -93.9546)
		(property "Reference" "R596"
			(at 0 0 0)
			(layer "F.SilkS")
			(hide yes)
			(effects
				(font
					(size 1.27 1.27)
				)
			)
		)
		(property "Value" "0R2J-2-GP"
			(at 0.064008 -3.993896 0)
			(unlocked yes)
			(layer "F.Fab")
			(hide yes)
			(effects
				(font
					(size 1.016 1.016)
					(thickness 0.1524)
				)
			)
		)
		(property "Device Type" "R402H16"
			(at 0.064008 -5.517896 0)
			(unlocked yes)
			(layer "F.Fab")
			(hide yes)
			(effects
				(font
					(size 1.016 1.016)
					(thickness 0.1524)
				)
			)
		)
		(duplicate_pad_numbers_are_jumpers no)
		(fp_line
			(start -0.508 -0.9398)
			(end -0.508 0.9398)
			(stroke
				(width 0.1524)
				(type default)
			)
			(layer "F.SilkS")
		)
		(fp_line
			(start 0.508 -0.9398)
			(end -0.508 -0.9398)
			(stroke
				(width 0.1524)
				(type default)
			)
			(layer "F.SilkS")
		)
		(fp_rect
			(start -0.508 0.9398)
			(end 0.508 -0.9398)
			(stroke
				(width 0)
				(type default)
			)
			(fill no)
			(layer "F.CrtYd")
		)
		(fp_rect
			(start -0.508 0.9398)
			(end 0.508 -0.9398)
			(stroke
				(width 0)
				(type default)
			)
			(fill no)
			(layer "F.Fab")
		)
		(pad "1" smd custom
			(at 0 -0.4445)
			(size 0.1397 0.1397)
			(layers "F.Cu" "F.Mask" "F.Paste")
			(net "BMC_I2C_D_SCL")
			(options
				(clearance outline)
				(anchor circle)
			)
			(primitives
				(gr_poly
					(pts
						(arc
							(start -0.1778 -0.2794)
							(mid -0.249642 -0.249642)
							(end -0.2794 -0.1778)
						)
						(arc
							(start -0.2794 0.1778)
							(mid -0.249642 0.249642)
							(end -0.1778 0.2794)
						)
						(arc
							(start 0.1778 0.2794)
							(mid 0.249642 0.249642)
							(end 0.2794 0.1778)
						)
						(arc
							(start 0.2794 -0.1778)
							(mid 0.249642 -0.249642)
							(end 0.1778 -0.2794)
						)
					)
					(width 0)
					(fill yes)
				)
			)
		)
		(pad "2" smd custom
			(at 0 0.4445)
			(size 0.1397 0.1397)
			(layers "F.Cu" "F.Mask" "F.Paste")
			(net "TEMP_3_SCL")
			(options
				(clearance outline)
				(anchor circle)
			)
			(primitives
				(gr_poly
					(pts
						(arc
							(start -0.1778 -0.2794)
							(mid -0.249642 -0.249642)
							(end -0.2794 -0.1778)
						)
						(arc
							(start -0.2794 0.1778)
							(mid -0.249642 0.249642)
							(end -0.1778 0.2794)
						)
						(arc
							(start 0.1778 0.2794)
							(mid 0.249642 0.249642)
							(end 0.2794 0.1778)
						)
						(arc
							(start 0.2794 -0.1778)
							(mid 0.249642 -0.249642)
							(end 0.1778 -0.2794)
						)
					)
					(width 0)
					(fill yes)
				)
			)
		)
	)
	(footprint ""
		(layer "F.Cu")
		(at 131.66471 -98.92284 180)
		(property "Reference" "SC1272"
			(at 0 0 180)
			(layer "F.SilkS")
			(hide yes)
			(effects
				(font
					(size 1.27 1.27)
				)
			)
		)
		(property "Value" "SCD01U10V1KX-GP"
			(at -2.8321 -1.7399 180)
			(unlocked yes)
			(layer "F.Fab")
			(hide yes)
			(effects
				(font
					(size 1.016 1.016)
					(thickness 0.1524)
				)
			)
		)
		(property "Device Type" "C0201H13"
			(at -2.8321 -3.2639 180)
			(unlocked yes)
			(layer "F.Fab")
			(hide yes)
			(effects
				(font
					(size 1.016 1.016)
					(thickness 0.1524)
				)
			)
		)
		(duplicate_pad_numbers_are_jumpers no)
		(fp_rect
			(start -0.2794 0.6477)
			(end 0.2794 -0.6477)
			(stroke
				(width 0)
				(type default)
			)
			(fill no)
			(layer "F.CrtYd")
		)
		(fp_rect
			(start -0.2794 0.6477)
			(end 0.2794 -0.6477)
			(stroke
				(width 0)
				(type default)
			)
			(fill no)
			(layer "F.Fab")
		)
		(pad "1" smd custom
			(at 0 -0.2794 180)
			(size 0.0762 0.0762)
			(layers "F.Cu" "F.Mask" "F.Paste")
			(net "3X24_SAS_TX23_P")
			(options
				(clearance outline)
				(anchor circle)
			)
			(primitives
				(gr_poly
					(pts
						(arc
							(start 0.1524 -0.127)
							(mid 0.137521 -0.162921)
							(end 0.1016 -0.1778)
						)
						(arc
							(start -0.1016 -0.1778)
							(mid -0.137521 -0.162921)
							(end -0.1524 -0.127)
						)
						(arc
							(start -0.1524 0.127)
							(mid -0.137521 0.162921)
							(end -0.1016 0.1778)
						)
						(arc
							(start 0.1016 0.1778)
							(mid 0.137521 0.162921)
							(end 0.1524 0.127)
						)
					)
					(width 0)
					(fill yes)
				)
			)
		)
		(pad "2" smd custom
			(at 0 0.2794 180)
			(size 0.0762 0.0762)
			(layers "F.Cu" "F.Mask" "F.Paste")
			(net "SAS_EXP_GF_TX_DP3")
			(options
				(clearance outline)
				(anchor circle)
			)
			(primitives
				(gr_poly
					(pts
						(arc
							(start 0.1524 -0.127)
							(mid 0.137521 -0.162921)
							(end 0.1016 -0.1778)
						)
						(arc
							(start -0.1016 -0.1778)
							(mid -0.137521 -0.162921)
							(end -0.1524 -0.127)
						)
						(arc
							(start -0.1524 0.127)
							(mid -0.137521 0.162921)
							(end -0.1016 0.1778)
						)
						(arc
							(start 0.1016 0.1778)
							(mid 0.137521 0.162921)
							(end 0.1524 0.127)
						)
					)
					(width 0)
					(fill yes)
				)
			)
		)
	)
	(footprint ""
		(layer "F.Cu")
		(at 197.938136 -167.267128 90)
		(property "Reference" "Q12"
			(at 0 0 90)
			(layer "F.SilkS")
			(hide yes)
			(effects
				(font
					(size 1.27 1.27)
				)
			)
		)
		(property "Value" "2N7002A-7-GP"
			(at 0.127 -8.9662 90)
			(unlocked yes)
			(layer "F.Fab")
			(hide yes)
			(effects
				(font
					(size 1.016 1.016)
					(thickness 0.1524)
				)
			)
		)
		(property "Device Type" "SOT23DGS2D4H48"
			(at 0.127 -10.4902 90)
			(unlocked yes)
			(layer "F.Fab")
			(hide yes)
			(effects
				(font
					(size 1.016 1.016)
					(thickness 0.1524)
				)
			)
		)
		(duplicate_pad_numbers_are_jumpers no)
		(fp_line
			(start 1.651 -1.778)
			(end -1.651 -1.778)
			(stroke
				(width 0.1524)
				(type default)
			)
			(layer "F.SilkS")
		)
		(fp_line
			(start -1.651 -1.778)
			(end -1.651 1.778)
			(stroke
				(width 0.1524)
				(type default)
			)
			(layer "F.SilkS")
		)
		(fp_line
			(start 1.651 1.778)
			(end 1.651 -1.778)
			(stroke
				(width 0.1524)
				(type default)
			)
			(layer "F.SilkS")
		)
		(fp_line
			(start -1.651 1.778)
			(end 1.651 1.778)
			(stroke
				(width 0.1524)
				(type default)
			)
			(layer "F.SilkS")
		)
		(fp_poly
			(pts
				(xy -1.778 1.8796) (xy -1.778 -1.8796) (xy 1.778 -1.8796) (xy 1.778 1.8796)
			)
			(stroke
				(width 0)
				(type default)
			)
			(fill no)
			(layer "F.CrtYd")
		)
		(fp_poly
			(pts
				(xy -1.778 1.8796) (xy -1.778 -1.8796) (xy 1.778 -1.8796) (xy 1.778 1.8796)
			)
			(stroke
				(width 0)
				(type default)
			)
			(fill no)
			(layer "F.Fab")
		)
		(pad "D" smd custom
			(at 0 -0.9525 90)
			(size 0.1905 0.1905)
			(layers "F.Cu" "F.Mask" "F.Paste")
			(net "P3V3_STBY_R1")
			(options
				(clearance outline)
				(anchor circle)
			)
			(primitives
				(gr_poly
					(pts
						(arc
							(start -0.1778 0.5715)
							(mid -0.321484 0.511984)
							(end -0.381 0.3683)
						)
						(arc
							(start -0.381 -0.3683)
							(mid -0.321484 -0.511984)
							(end -0.1778 -0.5715)
						)
						(arc
							(start 0.1778 -0.5715)
							(mid 0.321484 -0.511984)
							(end 0.381 -0.3683)
						)
						(arc
							(start 0.381 0.3683)
							(mid 0.321484 0.511984)
							(end 0.1778 0.5715)
						)
					)
					(width 0)
					(fill yes)
				)
			)
		)
		(pad "G" smd custom
			(at -0.98425 0.9525 90)
			(size 0.1905 0.1905)
			(layers "F.Cu" "F.Mask" "F.Paste")
			(net "P3V3_B")
			(options
				(clearance outline)
				(anchor circle)
			)
			(primitives
				(gr_poly
					(pts
						(arc
							(start -0.1778 0.5715)
							(mid -0.321484 0.511984)
							(end -0.381 0.3683)
						)
						(arc
							(start -0.381 -0.3683)
							(mid -0.321484 -0.511984)
							(end -0.1778 -0.5715)
						)
						(arc
							(start 0.1778 -0.5715)
							(mid 0.321484 -0.511984)
							(end 0.381 -0.3683)
						)
						(arc
							(start 0.381 0.3683)
							(mid 0.321484 0.511984)
							(end 0.1778 0.5715)
						)
					)
					(width 0)
					(fill yes)
				)
			)
		)
		(pad "S" smd custom
			(at 0.98425 0.9525 90)
			(size 0.1905 0.1905)
			(layers "F.Cu" "F.Mask" "F.Paste")
			(net "GND")
			(options
				(clearance outline)
				(anchor circle)
			)
			(primitives
				(gr_poly
					(pts
						(arc
							(start -0.1778 0.5715)
							(mid -0.321484 0.511984)
							(end -0.381 0.3683)
						)
						(arc
							(start -0.381 -0.3683)
							(mid -0.321484 -0.511984)
							(end -0.1778 -0.5715)
						)
						(arc
							(start 0.1778 -0.5715)
							(mid 0.321484 -0.511984)
							(end 0.381 -0.3683)
						)
						(arc
							(start 0.381 0.3683)
							(mid 0.321484 0.511984)
							(end 0.1778 0.5715)
						)
					)
					(width 0)
					(fill yes)
				)
			)
		)
	)
	(footprint ""
		(layer "F.Cu")
		(at 179.324 -18.415 90)
		(property "Reference" "R201"
			(at 0 0 90)
			(layer "F.SilkS")
			(hide yes)
			(effects
				(font
					(size 1.27 1.27)
				)
			)
		)
		(property "Value" "49D9R2D-GP"
			(at 0.064008 -3.993896 90)
			(unlocked yes)
			(layer "F.Fab")
			(hide yes)
			(effects
				(font
					(size 1.016 1.016)
					(thickness 0.1524)
				)
			)
		)
		(property "Device Type" "R402H16"
			(at 0.064008 -5.517896 90)
			(unlocked yes)
			(layer "F.Fab")
			(hide yes)
			(effects
				(font
					(size 1.016 1.016)
					(thickness 0.1524)
				)
			)
		)
		(duplicate_pad_numbers_are_jumpers no)
		(fp_line
			(start 0.508 -0.9398)
			(end -0.508 -0.9398)
			(stroke
				(width 0.1524)
				(type default)
			)
			(layer "F.SilkS")
		)
		(fp_line
			(start -0.508 -0.9398)
			(end -0.508 0.9398)
			(stroke
				(width 0.1524)
				(type default)
			)
			(layer "F.SilkS")
		)
		(fp_rect
			(start -0.508 0.9398)
			(end 0.508 -0.9398)
			(stroke
				(width 0)
				(type default)
			)
			(fill no)
			(layer "F.CrtYd")
		)
		(fp_rect
			(start -0.508 0.9398)
			(end 0.508 -0.9398)
			(stroke
				(width 0)
				(type default)
			)
			(fill no)
			(layer "F.Fab")
		)
		(pad "1" smd custom
			(at 0 -0.4445 90)
			(size 0.1397 0.1397)
			(layers "F.Cu" "F.Mask" "F.Paste")
			(net "TEMP_SENSOR_DXP_R")
			(options
				(clearance outline)
				(anchor circle)
			)
			(primitives
				(gr_poly
					(pts
						(arc
							(start -0.1778 -0.2794)
							(mid -0.249642 -0.249642)
							(end -0.2794 -0.1778)
						)
						(arc
							(start -0.2794 0.1778)
							(mid -0.249642 0.249642)
							(end -0.1778 0.2794)
						)
						(arc
							(start 0.1778 0.2794)
							(mid 0.249642 0.249642)
							(end 0.2794 0.1778)
						)
						(arc
							(start 0.2794 -0.1778)
							(mid 0.249642 -0.249642)
							(end 0.1778 -0.2794)
						)
					)
					(width 0)
					(fill yes)
				)
			)
		)
		(pad "2" smd custom
			(at 0 0.4445 90)
			(size 0.1397 0.1397)
			(layers "F.Cu" "F.Mask" "F.Paste")
			(net "TEMP_SENSOR_DXP")
			(options
				(clearance outline)
				(anchor circle)
			)
			(primitives
				(gr_poly
					(pts
						(arc
							(start -0.1778 -0.2794)
							(mid -0.249642 -0.249642)
							(end -0.2794 -0.1778)
						)
						(arc
							(start -0.2794 0.1778)
							(mid -0.249642 0.249642)
							(end -0.1778 0.2794)
						)
						(arc
							(start 0.1778 0.2794)
							(mid 0.249642 0.249642)
							(end 0.2794 0.1778)
						)
						(arc
							(start 0.2794 -0.1778)
							(mid 0.249642 -0.249642)
							(end 0.1778 -0.2794)
						)
					)
					(width 0)
					(fill yes)
				)
			)
		)
	)
	(footprint ""
		(layer "F.Cu")
		(at 81.031842 -116.784882 -90)
		(property "Reference" "SR756"
			(at 0 0 270)
			(layer "F.SilkS")
			(hide yes)
			(effects
				(font
					(size 1.27 1.27)
				)
			)
		)
		(property "Value" "4K7R2F-GP"
			(at 0.064008 -3.993896 270)
			(unlocked yes)
			(layer "F.Fab")
			(hide yes)
			(effects
				(font
					(size 1.016 1.016)
					(thickness 0.1524)
				)
			)
		)
		(property "Device Type" "R402H16"
			(at 0.064008 -5.517896 270)
			(unlocked yes)
			(layer "F.Fab")
			(hide yes)
			(effects
				(font
					(size 1.016 1.016)
					(thickness 0.1524)
				)
			)
		)
		(duplicate_pad_numbers_are_jumpers no)
		(fp_line
			(start -0.508 -0.9398)
			(end -0.508 0.9398)
			(stroke
				(width 0.1524)
				(type default)
			)
			(layer "F.SilkS")
		)
		(fp_line
			(start 0.508 -0.9398)
			(end -0.508 -0.9398)
			(stroke
				(width 0.1524)
				(type default)
			)
			(layer "F.SilkS")
		)
		(fp_rect
			(start -0.508 0.9398)
			(end 0.508 -0.9398)
			(stroke
				(width 0)
				(type default)
			)
			(fill no)
			(layer "F.CrtYd")
		)
		(fp_rect
			(start -0.508 0.9398)
			(end 0.508 -0.9398)
			(stroke
				(width 0)
				(type default)
			)
			(fill no)
			(layer "F.Fab")
		)
		(pad "1" smd custom
			(at 0 -0.4445 270)
			(size 0.1397 0.1397)
			(layers "F.Cu" "F.Mask" "F.Paste")
			(net "EXP_IOC_BMC_SCL_14")
			(options
				(clearance outline)
				(anchor circle)
			)
			(primitives
				(gr_poly
					(pts
						(arc
							(start -0.1778 -0.2794)
							(mid -0.249642 -0.249642)
							(end -0.2794 -0.1778)
						)
						(arc
							(start -0.2794 0.1778)
							(mid -0.249642 0.249642)
							(end -0.1778 0.2794)
						)
						(arc
							(start 0.1778 0.2794)
							(mid 0.249642 0.249642)
							(end 0.2794 0.1778)
						)
						(arc
							(start 0.2794 -0.1778)
							(mid 0.249642 -0.249642)
							(end 0.1778 -0.2794)
						)
					)
					(width 0)
					(fill yes)
				)
			)
		)
		(pad "2" smd custom
			(at 0 0.4445 270)
			(size 0.1397 0.1397)
			(layers "F.Cu" "F.Mask" "F.Paste")
			(net "P3V3_STBY")
			(options
				(clearance outline)
				(anchor circle)
			)
			(primitives
				(gr_poly
					(pts
						(arc
							(start -0.1778 -0.2794)
							(mid -0.249642 -0.249642)
							(end -0.2794 -0.1778)
						)
						(arc
							(start -0.2794 0.1778)
							(mid -0.249642 0.249642)
							(end -0.1778 0.2794)
						)
						(arc
							(start 0.1778 0.2794)
							(mid 0.249642 0.249642)
							(end 0.2794 0.1778)
						)
						(arc
							(start 0.2794 -0.1778)
							(mid 0.249642 -0.249642)
							(end 0.1778 -0.2794)
						)
					)
					(width 0)
					(fill yes)
				)
			)
		)
	)
	(footprint ""
		(layer "F.Cu")
		(at 57.912 -211.074)
		(property "Reference" "PR9005"
			(at 0 0 0)
			(layer "F.SilkS")
			(hide yes)
			(effects
				(font
					(size 1.27 1.27)
				)
			)
		)
		(property "Value" "0R2J-2-GP"
			(at 0.064008 -3.993896 0)
			(unlocked yes)
			(layer "F.Fab")
			(hide yes)
			(effects
				(font
					(size 1.016 1.016)
					(thickness 0.1524)
				)
			)
		)
		(property "Device Type" "R402H16"
			(at 0.064008 -5.517896 0)
			(unlocked yes)
			(layer "F.Fab")
			(hide yes)
			(effects
				(font
					(size 1.016 1.016)
					(thickness 0.1524)
				)
			)
		)
		(duplicate_pad_numbers_are_jumpers no)
		(fp_line
			(start -0.508 -0.9398)
			(end -0.508 0.9398)
			(stroke
				(width 0.1524)
				(type default)
			)
			(layer "F.SilkS")
		)
		(fp_line
			(start 0.508 -0.9398)
			(end -0.508 -0.9398)
			(stroke
				(width 0.1524)
				(type default)
			)
			(layer "F.SilkS")
		)
		(fp_rect
			(start -0.508 0.9398)
			(end 0.508 -0.9398)
			(stroke
				(width 0)
				(type default)
			)
			(fill no)
			(layer "F.CrtYd")
		)
		(fp_rect
			(start -0.508 0.9398)
			(end 0.508 -0.9398)
			(stroke
				(width 0)
				(type default)
			)
			(fill no)
			(layer "F.Fab")
		)
		(pad "1" smd custom
			(at 0 -0.4445)
			(size 0.1397 0.1397)
			(layers "F.Cu" "F.Mask" "F.Paste")
			(net "HSW_SCL_2")
			(options
				(clearance outline)
				(anchor circle)
			)
			(primitives
				(gr_poly
					(pts
						(arc
							(start -0.1778 -0.2794)
							(mid -0.249642 -0.249642)
							(end -0.2794 -0.1778)
						)
						(arc
							(start -0.2794 0.1778)
							(mid -0.249642 0.249642)
							(end -0.1778 0.2794)
						)
						(arc
							(start 0.1778 0.2794)
							(mid 0.249642 0.249642)
							(end 0.2794 0.1778)
						)
						(arc
							(start 0.2794 -0.1778)
							(mid 0.249642 -0.249642)
							(end 0.1778 -0.2794)
						)
					)
					(width 0)
					(fill yes)
				)
			)
		)
		(pad "2" smd custom
			(at 0 0.4445)
			(size 0.1397 0.1397)
			(layers "F.Cu" "F.Mask" "F.Paste")
			(net "BMC_I2C_SCL_10")
			(options
				(clearance outline)
				(anchor circle)
			)
			(primitives
				(gr_poly
					(pts
						(arc
							(start -0.1778 -0.2794)
							(mid -0.249642 -0.249642)
							(end -0.2794 -0.1778)
						)
						(arc
							(start -0.2794 0.1778)
							(mid -0.249642 0.249642)
							(end -0.1778 0.2794)
						)
						(arc
							(start 0.1778 0.2794)
							(mid 0.249642 0.249642)
							(end 0.2794 0.1778)
						)
						(arc
							(start 0.2794 -0.1778)
							(mid 0.249642 -0.249642)
							(end 0.1778 -0.2794)
						)
					)
					(width 0)
					(fill yes)
				)
			)
		)
	)
	(footprint ""
		(layer "F.Cu")
		(at 344.17 -107.188 180)
		(property "Reference" "PR12"
			(at 0 0 180)
			(layer "F.SilkS")
			(hide yes)
			(effects
				(font
					(size 1.27 1.27)
				)
			)
		)
		(property "Value" "0R2J-2-GP"
			(at 0.064008 -3.993896 180)
			(unlocked yes)
			(layer "F.Fab")
			(hide yes)
			(effects
				(font
					(size 1.016 1.016)
					(thickness 0.1524)
				)
			)
		)
		(property "Device Type" "R402H16"
			(at 0.064008 -5.517896 180)
			(unlocked yes)
			(layer "F.Fab")
			(hide yes)
			(effects
				(font
					(size 1.016 1.016)
					(thickness 0.1524)
				)
			)
		)
		(duplicate_pad_numbers_are_jumpers no)
		(fp_line
			(start 0.508 -0.9398)
			(end -0.508 -0.9398)
			(stroke
				(width 0.1524)
				(type default)
			)
			(layer "F.SilkS")
		)
		(fp_line
			(start -0.508 -0.9398)
			(end -0.508 0.9398)
			(stroke
				(width 0.1524)
				(type default)
			)
			(layer "F.SilkS")
		)
		(fp_rect
			(start -0.508 0.9398)
			(end 0.508 -0.9398)
			(stroke
				(width 0)
				(type default)
			)
			(fill no)
			(layer "F.CrtYd")
		)
		(fp_rect
			(start -0.508 0.9398)
			(end 0.508 -0.9398)
			(stroke
				(width 0)
				(type default)
			)
			(fill no)
			(layer "F.Fab")
		)
		(pad "1" smd custom
			(at 0 -0.4445 180)
			(size 0.1397 0.1397)
			(layers "F.Cu" "F.Mask" "F.Paste")
			(net "P5V_STBY_VBST_RR")
			(options
				(clearance outline)
				(anchor circle)
			)
			(primitives
				(gr_poly
					(pts
						(arc
							(start -0.1778 -0.2794)
							(mid -0.249642 -0.249642)
							(end -0.2794 -0.1778)
						)
						(arc
							(start -0.2794 0.1778)
							(mid -0.249642 0.249642)
							(end -0.1778 0.2794)
						)
						(arc
							(start 0.1778 0.2794)
							(mid 0.249642 0.249642)
							(end 0.2794 0.1778)
						)
						(arc
							(start 0.2794 -0.1778)
							(mid 0.249642 -0.249642)
							(end 0.1778 -0.2794)
						)
					)
					(width 0)
					(fill yes)
				)
			)
		)
		(pad "2" smd custom
			(at 0 0.4445 180)
			(size 0.1397 0.1397)
			(layers "F.Cu" "F.Mask" "F.Paste")
			(net "P5V_STBY_VBST")
			(options
				(clearance outline)
				(anchor circle)
			)
			(primitives
				(gr_poly
					(pts
						(arc
							(start -0.1778 -0.2794)
							(mid -0.249642 -0.249642)
							(end -0.2794 -0.1778)
						)
						(arc
							(start -0.2794 0.1778)
							(mid -0.249642 0.249642)
							(end -0.1778 0.2794)
						)
						(arc
							(start 0.1778 0.2794)
							(mid 0.249642 0.249642)
							(end 0.2794 0.1778)
						)
						(arc
							(start 0.2794 -0.1778)
							(mid 0.249642 -0.249642)
							(end 0.1778 -0.2794)
						)
					)
					(width 0)
					(fill yes)
				)
			)
		)
	)
	(footprint ""
		(layer "F.Cu")
		(at 273.549872 -50.999136 -90)
		(property "Reference" "PR119"
			(at 0 0 270)
			(layer "F.SilkS")
			(hide yes)
			(effects
				(font
					(size 1.27 1.27)
				)
			)
		)
		(property "Value" "10KR2F-2-GP"
			(at 0.064008 -3.993896 270)
			(unlocked yes)
			(layer "F.Fab")
			(hide yes)
			(effects
				(font
					(size 1.016 1.016)
					(thickness 0.1524)
				)
			)
		)
		(property "Device Type" "R402H16"
			(at 0.064008 -5.517896 270)
			(unlocked yes)
			(layer "F.Fab")
			(hide yes)
			(effects
				(font
					(size 1.016 1.016)
					(thickness 0.1524)
				)
			)
		)
		(duplicate_pad_numbers_are_jumpers no)
		(fp_line
			(start -0.508 -0.9398)
			(end -0.508 0.9398)
			(stroke
				(width 0.1524)
				(type default)
			)
			(layer "F.SilkS")
		)
		(fp_line
			(start 0.508 -0.9398)
			(end -0.508 -0.9398)
			(stroke
				(width 0.1524)
				(type default)
			)
			(layer "F.SilkS")
		)
		(fp_rect
			(start -0.508 0.9398)
			(end 0.508 -0.9398)
			(stroke
				(width 0)
				(type default)
			)
			(fill no)
			(layer "F.CrtYd")
		)
		(fp_rect
			(start -0.508 0.9398)
			(end 0.508 -0.9398)
			(stroke
				(width 0)
				(type default)
			)
			(fill no)
			(layer "F.Fab")
		)
		(pad "1" smd custom
			(at 0 -0.4445 270)
			(size 0.1397 0.1397)
			(layers "F.Cu" "F.Mask" "F.Paste")
			(net "P12V")
			(options
				(clearance outline)
				(anchor circle)
			)
			(primitives
				(gr_poly
					(pts
						(arc
							(start -0.1778 -0.2794)
							(mid -0.249642 -0.249642)
							(end -0.2794 -0.1778)
						)
						(arc
							(start -0.2794 0.1778)
							(mid -0.249642 0.249642)
							(end -0.1778 0.2794)
						)
						(arc
							(start 0.1778 0.2794)
							(mid 0.249642 0.249642)
							(end 0.2794 0.1778)
						)
						(arc
							(start 0.2794 -0.1778)
							(mid 0.249642 -0.249642)
							(end 0.1778 -0.2794)
						)
					)
					(width 0)
					(fill yes)
				)
			)
		)
		(pad "2" smd custom
			(at 0 0.4445 270)
			(size 0.1397 0.1397)
			(layers "F.Cu" "F.Mask" "F.Paste")
			(net "P3V3_S_LV")
			(options
				(clearance outline)
				(anchor circle)
			)
			(primitives
				(gr_poly
					(pts
						(arc
							(start -0.1778 -0.2794)
							(mid -0.249642 -0.249642)
							(end -0.2794 -0.1778)
						)
						(arc
							(start -0.2794 0.1778)
							(mid -0.249642 0.249642)
							(end -0.1778 0.2794)
						)
						(arc
							(start 0.1778 0.2794)
							(mid 0.249642 0.249642)
							(end 0.2794 0.1778)
						)
						(arc
							(start 0.2794 -0.1778)
							(mid 0.249642 -0.249642)
							(end 0.1778 -0.2794)
						)
					)
					(width 0)
					(fill yes)
				)
			)
		)
	)
	(footprint ""
		(layer "F.Cu")
		(at 113.792 -26.924 -90)
		(property "Reference" "SR664"
			(at 0 0 270)
			(layer "F.SilkS")
			(hide yes)
			(effects
				(font
					(size 1.27 1.27)
				)
			)
		)
		(property "Value" "10KR2F-2-GP"
			(at 0.064008 -3.993896 270)
			(unlocked yes)
			(layer "F.Fab")
			(hide yes)
			(effects
				(font
					(size 1.016 1.016)
					(thickness 0.1524)
				)
			)
		)
		(property "Device Type" "R402H16"
			(at 0.064008 -5.517896 270)
			(unlocked yes)
			(layer "F.Fab")
			(hide yes)
			(effects
				(font
					(size 1.016 1.016)
					(thickness 0.1524)
				)
			)
		)
		(duplicate_pad_numbers_are_jumpers no)
		(fp_line
			(start -0.508 -0.9398)
			(end -0.508 0.9398)
			(stroke
				(width 0.1524)
				(type default)
			)
			(layer "F.SilkS")
		)
		(fp_line
			(start 0.508 -0.9398)
			(end -0.508 -0.9398)
			(stroke
				(width 0.1524)
				(type default)
			)
			(layer "F.SilkS")
		)
		(fp_rect
			(start -0.508 0.9398)
			(end 0.508 -0.9398)
			(stroke
				(width 0)
				(type default)
			)
			(fill no)
			(layer "F.CrtYd")
		)
		(fp_rect
			(start -0.508 0.9398)
			(end 0.508 -0.9398)
			(stroke
				(width 0)
				(type default)
			)
			(fill no)
			(layer "F.Fab")
		)
		(pad "1" smd custom
			(at 0 -0.4445 270)
			(size 0.1397 0.1397)
			(layers "F.Cu" "F.Mask" "F.Paste")
			(net "P1V8_C")
			(options
				(clearance outline)
				(anchor circle)
			)
			(primitives
				(gr_poly
					(pts
						(arc
							(start -0.1778 -0.2794)
							(mid -0.249642 -0.249642)
							(end -0.2794 -0.1778)
						)
						(arc
							(start -0.2794 0.1778)
							(mid -0.249642 0.249642)
							(end -0.1778 0.2794)
						)
						(arc
							(start 0.1778 0.2794)
							(mid 0.249642 0.249642)
							(end 0.2794 0.1778)
						)
						(arc
							(start 0.2794 -0.1778)
							(mid 0.249642 -0.249642)
							(end 0.1778 -0.2794)
						)
					)
					(width 0)
					(fill yes)
				)
			)
		)
		(pad "2" smd custom
			(at 0 0.4445 270)
			(size 0.1397 0.1397)
			(layers "F.Cu" "F.Mask" "F.Paste")
			(net "SYS_DBMODE1")
			(options
				(clearance outline)
				(anchor circle)
			)
			(primitives
				(gr_poly
					(pts
						(arc
							(start -0.1778 -0.2794)
							(mid -0.249642 -0.249642)
							(end -0.2794 -0.1778)
						)
						(arc
							(start -0.2794 0.1778)
							(mid -0.249642 0.249642)
							(end -0.1778 0.2794)
						)
						(arc
							(start 0.1778 0.2794)
							(mid 0.249642 0.249642)
							(end 0.2794 0.1778)
						)
						(arc
							(start 0.2794 -0.1778)
							(mid 0.249642 -0.249642)
							(end 0.1778 -0.2794)
						)
					)
					(width 0)
					(fill yes)
				)
			)
		)
	)
	(footprint ""
		(layer "F.Cu")
		(at 306.578 -193.802 180)
		(property "Reference" "R170"
			(at 0 0 180)
			(layer "F.SilkS")
			(hide yes)
			(effects
				(font
					(size 1.27 1.27)
				)
			)
		)
		(property "Value" "100KR2F-L1-GP"
			(at 0.064008 -3.993896 180)
			(unlocked yes)
			(layer "F.Fab")
			(hide yes)
			(effects
				(font
					(size 1.016 1.016)
					(thickness 0.1524)
				)
			)
		)
		(property "Device Type" "R402H16"
			(at 0.064008 -5.517896 180)
			(unlocked yes)
			(layer "F.Fab")
			(hide yes)
			(effects
				(font
					(size 1.016 1.016)
					(thickness 0.1524)
				)
			)
		)
		(duplicate_pad_numbers_are_jumpers no)
		(fp_line
			(start 0.508 -0.9398)
			(end -0.508 -0.9398)
			(stroke
				(width 0.1524)
				(type default)
			)
			(layer "F.SilkS")
		)
		(fp_line
			(start -0.508 -0.9398)
			(end -0.508 0.9398)
			(stroke
				(width 0.1524)
				(type default)
			)
			(layer "F.SilkS")
		)
		(fp_rect
			(start -0.508 0.9398)
			(end 0.508 -0.9398)
			(stroke
				(width 0)
				(type default)
			)
			(fill no)
			(layer "F.CrtYd")
		)
		(fp_rect
			(start -0.508 0.9398)
			(end 0.508 -0.9398)
			(stroke
				(width 0)
				(type default)
			)
			(fill no)
			(layer "F.Fab")
		)
		(pad "1" smd custom
			(at 0 -0.4445 180)
			(size 0.1397 0.1397)
			(layers "F.Cu" "F.Mask" "F.Paste")
			(net "P3V3_STBY")
			(options
				(clearance outline)
				(anchor circle)
			)
			(primitives
				(gr_poly
					(pts
						(arc
							(start -0.1778 -0.2794)
							(mid -0.249642 -0.249642)
							(end -0.2794 -0.1778)
						)
						(arc
							(start -0.2794 0.1778)
							(mid -0.249642 0.249642)
							(end -0.1778 0.2794)
						)
						(arc
							(start 0.1778 0.2794)
							(mid 0.249642 0.249642)
							(end 0.2794 0.1778)
						)
						(arc
							(start 0.2794 -0.1778)
							(mid 0.249642 -0.249642)
							(end 0.1778 -0.2794)
						)
					)
					(width 0)
					(fill yes)
				)
			)
		)
		(pad "2" smd custom
			(at 0 0.4445 180)
			(size 0.1397 0.1397)
			(layers "F.Cu" "F.Mask" "F.Paste")
			(net "LED_DR_LED0")
			(options
				(clearance outline)
				(anchor circle)
			)
			(primitives
				(gr_poly
					(pts
						(arc
							(start -0.1778 -0.2794)
							(mid -0.249642 -0.249642)
							(end -0.2794 -0.1778)
						)
						(arc
							(start -0.2794 0.1778)
							(mid -0.249642 0.249642)
							(end -0.1778 0.2794)
						)
						(arc
							(start 0.1778 0.2794)
							(mid 0.249642 0.249642)
							(end 0.2794 0.1778)
						)
						(arc
							(start 0.2794 -0.1778)
							(mid 0.249642 -0.249642)
							(end 0.1778 -0.2794)
						)
					)
					(width 0)
					(fill yes)
				)
			)
		)
	)
	(footprint ""
		(layer "F.Cu")
		(at 84.709 -240.8174 180)
		(property "Reference" "SC436"
			(at 0 0 180)
			(layer "F.SilkS")
			(hide yes)
			(effects
				(font
					(size 1.27 1.27)
				)
			)
		)
		(property "Value" "SCD1U16V2KX-3GP"
			(at 1.1811 -2.7051 180)
			(unlocked yes)
			(layer "F.Fab")
			(hide yes)
			(effects
				(font
					(size 1.016 1.016)
					(thickness 0.1524)
				)
			)
		)
		(property "Device Type" "C402H22"
			(at 1.1811 -4.2291 180)
			(unlocked yes)
			(layer "F.Fab")
			(hide yes)
			(effects
				(font
					(size 1.016 1.016)
					(thickness 0.1524)
				)
			)
		)
		(duplicate_pad_numbers_are_jumpers no)
		(fp_rect
			(start -0.4318 0.9525)
			(end 0.4318 -0.9525)
			(stroke
				(width 0)
				(type default)
			)
			(fill no)
			(layer "F.CrtYd")
		)
		(fp_rect
			(start -0.4318 0.9525)
			(end 0.4318 -0.9525)
			(stroke
				(width 0)
				(type default)
			)
			(fill no)
			(layer "F.Fab")
		)
		(pad "1" smd custom
			(at 0 -0.4445 180)
			(size 0.1524 0.1524)
			(layers "F.Cu" "F.Mask" "F.Paste")
			(net "P3V3_STBY")
			(options
				(clearance outline)
				(anchor circle)
			)
			(primitives
				(gr_poly
					(pts
						(arc
							(start 0.3048 -0.2032)
							(mid 0.275042 -0.275042)
							(end 0.2032 -0.3048)
						)
						(arc
							(start -0.2032 -0.3048)
							(mid -0.275042 -0.275042)
							(end -0.3048 -0.2032)
						)
						(arc
							(start -0.3048 0.2032)
							(mid -0.275042 0.275042)
							(end -0.2032 0.3048)
						)
						(arc
							(start 0.2032 0.3048)
							(mid 0.275042 0.275042)
							(end 0.3048 0.2032)
						)
					)
					(width 0)
					(fill yes)
				)
			)
		)
		(pad "2" smd custom
			(at 0 0.4445 180)
			(size 0.1524 0.1524)
			(layers "F.Cu" "F.Mask" "F.Paste")
			(net "GND")
			(options
				(clearance outline)
				(anchor circle)
			)
			(primitives
				(gr_poly
					(pts
						(arc
							(start 0.3048 -0.2032)
							(mid 0.275042 -0.275042)
							(end 0.2032 -0.3048)
						)
						(arc
							(start -0.2032 -0.3048)
							(mid -0.275042 -0.275042)
							(end -0.3048 -0.2032)
						)
						(arc
							(start -0.3048 0.2032)
							(mid -0.275042 0.275042)
							(end -0.2032 0.3048)
						)
						(arc
							(start 0.2032 0.3048)
							(mid 0.275042 0.275042)
							(end 0.3048 0.2032)
						)
					)
					(width 0)
					(fill yes)
				)
			)
		)
	)
	(footprint ""
		(layer "F.Cu")
		(at 211.72297 -69.088)
		(property "Reference" "R13"
			(at 0 0 0)
			(layer "F.SilkS")
			(hide yes)
			(effects
				(font
					(size 1.27 1.27)
				)
			)
		)
		(property "Value" "10KR2F-2-GP"
			(at 0.064008 -3.993896 0)
			(unlocked yes)
			(layer "F.Fab")
			(hide yes)
			(effects
				(font
					(size 1.016 1.016)
					(thickness 0.1524)
				)
			)
		)
		(property "Device Type" "R402H16"
			(at 0.064008 -5.517896 0)
			(unlocked yes)
			(layer "F.Fab")
			(hide yes)
			(effects
				(font
					(size 1.016 1.016)
					(thickness 0.1524)
				)
			)
		)
		(duplicate_pad_numbers_are_jumpers no)
		(fp_line
			(start -0.508 -0.9398)
			(end -0.508 0.9398)
			(stroke
				(width 0.1524)
				(type default)
			)
			(layer "F.SilkS")
		)
		(fp_line
			(start 0.508 -0.9398)
			(end -0.508 -0.9398)
			(stroke
				(width 0.1524)
				(type default)
			)
			(layer "F.SilkS")
		)
		(fp_rect
			(start -0.508 0.9398)
			(end 0.508 -0.9398)
			(stroke
				(width 0)
				(type default)
			)
			(fill no)
			(layer "F.CrtYd")
		)
		(fp_rect
			(start -0.508 0.9398)
			(end 0.508 -0.9398)
			(stroke
				(width 0)
				(type default)
			)
			(fill no)
			(layer "F.Fab")
		)
		(pad "1" smd custom
			(at 0 -0.4445)
			(size 0.1397 0.1397)
			(layers "F.Cu" "F.Mask" "F.Paste")
			(net "SVR_ID2")
			(options
				(clearance outline)
				(anchor circle)
			)
			(primitives
				(gr_poly
					(pts
						(arc
							(start -0.1778 -0.2794)
							(mid -0.249642 -0.249642)
							(end -0.2794 -0.1778)
						)
						(arc
							(start -0.2794 0.1778)
							(mid -0.249642 0.249642)
							(end -0.1778 0.2794)
						)
						(arc
							(start 0.1778 0.2794)
							(mid 0.249642 0.249642)
							(end 0.2794 0.1778)
						)
						(arc
							(start 0.2794 -0.1778)
							(mid 0.249642 -0.249642)
							(end 0.1778 -0.2794)
						)
					)
					(width 0)
					(fill yes)
				)
			)
		)
		(pad "2" smd custom
			(at 0 0.4445)
			(size 0.1397 0.1397)
			(layers "F.Cu" "F.Mask" "F.Paste")
			(net "P3V3_STBY")
			(options
				(clearance outline)
				(anchor circle)
			)
			(primitives
				(gr_poly
					(pts
						(arc
							(start -0.1778 -0.2794)
							(mid -0.249642 -0.249642)
							(end -0.2794 -0.1778)
						)
						(arc
							(start -0.2794 0.1778)
							(mid -0.249642 0.249642)
							(end -0.1778 0.2794)
						)
						(arc
							(start 0.1778 0.2794)
							(mid 0.249642 0.249642)
							(end 0.2794 0.1778)
						)
						(arc
							(start 0.2794 -0.1778)
							(mid 0.249642 -0.249642)
							(end 0.1778 -0.2794)
						)
					)
					(width 0)
					(fill yes)
				)
			)
		)
	)
	(footprint ""
		(layer "F.Cu")
		(at 283.21 -161.544)
		(property "Reference" "R259"
			(at 0 0 0)
			(layer "F.SilkS")
			(hide yes)
			(effects
				(font
					(size 1.27 1.27)
				)
			)
		)
		(property "Value" "100KR2F-L1-GP"
			(at 0.064008 -3.993896 0)
			(unlocked yes)
			(layer "F.Fab")
			(hide yes)
			(effects
				(font
					(size 1.016 1.016)
					(thickness 0.1524)
				)
			)
		)
		(property "Device Type" "R402H16"
			(at 0.064008 -5.517896 0)
			(unlocked yes)
			(layer "F.Fab")
			(hide yes)
			(effects
				(font
					(size 1.016 1.016)
					(thickness 0.1524)
				)
			)
		)
		(duplicate_pad_numbers_are_jumpers no)
		(fp_line
			(start -0.508 -0.9398)
			(end -0.508 0.9398)
			(stroke
				(width 0.1524)
				(type default)
			)
			(layer "F.SilkS")
		)
		(fp_line
			(start 0.508 -0.9398)
			(end -0.508 -0.9398)
			(stroke
				(width 0.1524)
				(type default)
			)
			(layer "F.SilkS")
		)
		(fp_rect
			(start -0.508 0.9398)
			(end 0.508 -0.9398)
			(stroke
				(width 0)
				(type default)
			)
			(fill no)
			(layer "F.CrtYd")
		)
		(fp_rect
			(start -0.508 0.9398)
			(end 0.508 -0.9398)
			(stroke
				(width 0)
				(type default)
			)
			(fill no)
			(layer "F.Fab")
		)
		(pad "1" smd custom
			(at 0 -0.4445)
			(size 0.1397 0.1397)
			(layers "F.Cu" "F.Mask" "F.Paste")
			(net "TP_IRQ_CPU_SERIAL")
			(options
				(clearance outline)
				(anchor circle)
			)
			(primitives
				(gr_poly
					(pts
						(arc
							(start -0.1778 -0.2794)
							(mid -0.249642 -0.249642)
							(end -0.2794 -0.1778)
						)
						(arc
							(start -0.2794 0.1778)
							(mid -0.249642 0.249642)
							(end -0.1778 0.2794)
						)
						(arc
							(start 0.1778 0.2794)
							(mid 0.249642 0.249642)
							(end 0.2794 0.1778)
						)
						(arc
							(start 0.2794 -0.1778)
							(mid 0.249642 -0.249642)
							(end 0.1778 -0.2794)
						)
					)
					(width 0)
					(fill yes)
				)
			)
		)
		(pad "2" smd custom
			(at 0 0.4445)
			(size 0.1397 0.1397)
			(layers "F.Cu" "F.Mask" "F.Paste")
			(net "GND")
			(options
				(clearance outline)
				(anchor circle)
			)
			(primitives
				(gr_poly
					(pts
						(arc
							(start -0.1778 -0.2794)
							(mid -0.249642 -0.249642)
							(end -0.2794 -0.1778)
						)
						(arc
							(start -0.2794 0.1778)
							(mid -0.249642 0.249642)
							(end -0.1778 0.2794)
						)
						(arc
							(start 0.1778 0.2794)
							(mid 0.249642 0.249642)
							(end 0.2794 0.1778)
						)
						(arc
							(start 0.2794 -0.1778)
							(mid 0.249642 -0.249642)
							(end 0.1778 -0.2794)
						)
					)
					(width 0)
					(fill yes)
				)
			)
		)
	)
	(footprint ""
		(layer "F.Cu")
		(at 301.752 -191.897 180)
		(property "Reference" "C319"
			(at 0 0 180)
			(layer "F.SilkS")
			(hide yes)
			(effects
				(font
					(size 1.27 1.27)
				)
			)
		)
		(property "Value" "SCD1U16V2KX-3GP"
			(at 1.1811 -2.7051 180)
			(unlocked yes)
			(layer "F.Fab")
			(hide yes)
			(effects
				(font
					(size 1.016 1.016)
					(thickness 0.1524)
				)
			)
		)
		(property "Device Type" "C402H22"
			(at 1.1811 -4.2291 180)
			(unlocked yes)
			(layer "F.Fab")
			(hide yes)
			(effects
				(font
					(size 1.016 1.016)
					(thickness 0.1524)
				)
			)
		)
		(duplicate_pad_numbers_are_jumpers no)
		(fp_rect
			(start -0.4318 0.9525)
			(end 0.4318 -0.9525)
			(stroke
				(width 0)
				(type default)
			)
			(fill no)
			(layer "F.CrtYd")
		)
		(fp_rect
			(start -0.4318 0.9525)
			(end 0.4318 -0.9525)
			(stroke
				(width 0)
				(type default)
			)
			(fill no)
			(layer "F.Fab")
		)
		(pad "1" smd custom
			(at 0 -0.4445 180)
			(size 0.1524 0.1524)
			(layers "F.Cu" "F.Mask" "F.Paste")
			(net "UART COUNT")
			(options
				(clearance outline)
				(anchor circle)
			)
			(primitives
				(gr_poly
					(pts
						(arc
							(start 0.3048 -0.2032)
							(mid 0.275042 -0.275042)
							(end 0.2032 -0.3048)
						)
						(arc
							(start -0.2032 -0.3048)
							(mid -0.275042 -0.275042)
							(end -0.3048 -0.2032)
						)
						(arc
							(start -0.3048 0.2032)
							(mid -0.275042 0.275042)
							(end -0.2032 0.3048)
						)
						(arc
							(start 0.2032 0.3048)
							(mid 0.275042 0.275042)
							(end 0.3048 0.2032)
						)
					)
					(width 0)
					(fill yes)
				)
			)
		)
		(pad "2" smd custom
			(at 0 0.4445 180)
			(size 0.1524 0.1524)
			(layers "F.Cu" "F.Mask" "F.Paste")
			(net "GND")
			(options
				(clearance outline)
				(anchor circle)
			)
			(primitives
				(gr_poly
					(pts
						(arc
							(start 0.3048 -0.2032)
							(mid 0.275042 -0.275042)
							(end 0.2032 -0.3048)
						)
						(arc
							(start -0.2032 -0.3048)
							(mid -0.275042 -0.275042)
							(end -0.3048 -0.2032)
						)
						(arc
							(start -0.3048 0.2032)
							(mid -0.275042 0.275042)
							(end -0.2032 0.3048)
						)
						(arc
							(start 0.2032 0.3048)
							(mid 0.275042 0.275042)
							(end 0.3048 0.2032)
						)
					)
					(width 0)
					(fill yes)
				)
			)
		)
	)
	(footprint ""
		(layer "F.Cu")
		(at 120.339612 -222.885)
		(property "Reference" "SR874"
			(at 0 0 0)
			(layer "F.SilkS")
			(hide yes)
			(effects
				(font
					(size 1.27 1.27)
				)
			)
		)
		(property "Value" "0R2J-2-GP"
			(at 0.064008 -3.993896 0)
			(unlocked yes)
			(layer "F.Fab")
			(hide yes)
			(effects
				(font
					(size 1.016 1.016)
					(thickness 0.1524)
				)
			)
		)
		(property "Device Type" "R402H16"
			(at 0.064008 -5.517896 0)
			(unlocked yes)
			(layer "F.Fab")
			(hide yes)
			(effects
				(font
					(size 1.016 1.016)
					(thickness 0.1524)
				)
			)
		)
		(duplicate_pad_numbers_are_jumpers no)
		(fp_line
			(start -0.508 -0.9398)
			(end -0.508 0.9398)
			(stroke
				(width 0.1524)
				(type default)
			)
			(layer "F.SilkS")
		)
		(fp_line
			(start 0.508 -0.9398)
			(end -0.508 -0.9398)
			(stroke
				(width 0.1524)
				(type default)
			)
			(layer "F.SilkS")
		)
		(fp_rect
			(start -0.508 0.9398)
			(end 0.508 -0.9398)
			(stroke
				(width 0)
				(type default)
			)
			(fill no)
			(layer "F.CrtYd")
		)
		(fp_rect
			(start -0.508 0.9398)
			(end 0.508 -0.9398)
			(stroke
				(width 0)
				(type default)
			)
			(fill no)
			(layer "F.Fab")
		)
		(pad "1" smd custom
			(at 0 -0.4445)
			(size 0.1397 0.1397)
			(layers "F.Cu" "F.Mask" "F.Paste")
			(net "SAS_HDD_CONN_SER_TX7_N")
			(options
				(clearance outline)
				(anchor circle)
			)
			(primitives
				(gr_poly
					(pts
						(arc
							(start -0.1778 -0.2794)
							(mid -0.249642 -0.249642)
							(end -0.2794 -0.1778)
						)
						(arc
							(start -0.2794 0.1778)
							(mid -0.249642 0.249642)
							(end -0.1778 0.2794)
						)
						(arc
							(start 0.1778 0.2794)
							(mid 0.249642 0.249642)
							(end 0.2794 0.1778)
						)
						(arc
							(start 0.2794 -0.1778)
							(mid 0.249642 -0.249642)
							(end 0.1778 -0.2794)
						)
					)
					(width 0)
					(fill yes)
				)
			)
		)
		(pad "2" smd custom
			(at 0 0.4445)
			(size 0.1397 0.1397)
			(layers "F.Cu" "F.Mask" "F.Paste")
			(net "SAS_HDD_CONN_TX7_N")
			(options
				(clearance outline)
				(anchor circle)
			)
			(primitives
				(gr_poly
					(pts
						(arc
							(start -0.1778 -0.2794)
							(mid -0.249642 -0.249642)
							(end -0.2794 -0.1778)
						)
						(arc
							(start -0.2794 0.1778)
							(mid -0.249642 0.249642)
							(end -0.1778 0.2794)
						)
						(arc
							(start 0.1778 0.2794)
							(mid 0.249642 0.249642)
							(end 0.2794 0.1778)
						)
						(arc
							(start 0.2794 -0.1778)
							(mid 0.249642 -0.249642)
							(end 0.1778 -0.2794)
						)
					)
					(width 0)
					(fill yes)
				)
			)
		)
	)
	(footprint ""
		(layer "F.Cu")
		(at 95.70847 -103.759 -90)
		(property "Reference" "SR790"
			(at 0 0 270)
			(layer "F.SilkS")
			(hide yes)
			(effects
				(font
					(size 1.27 1.27)
				)
			)
		)
		(property "Value" "0R2J-2-GP"
			(at 0.064008 -3.993896 270)
			(unlocked yes)
			(layer "F.Fab")
			(hide yes)
			(effects
				(font
					(size 1.016 1.016)
					(thickness 0.1524)
				)
			)
		)
		(property "Device Type" "R402H16"
			(at 0.064008 -5.517896 270)
			(unlocked yes)
			(layer "F.Fab")
			(hide yes)
			(effects
				(font
					(size 1.016 1.016)
					(thickness 0.1524)
				)
			)
		)
		(duplicate_pad_numbers_are_jumpers no)
		(fp_line
			(start -0.508 -0.9398)
			(end -0.508 0.9398)
			(stroke
				(width 0.1524)
				(type default)
			)
			(layer "F.SilkS")
		)
		(fp_line
			(start 0.508 -0.9398)
			(end -0.508 -0.9398)
			(stroke
				(width 0.1524)
				(type default)
			)
			(layer "F.SilkS")
		)
		(fp_rect
			(start -0.508 0.9398)
			(end 0.508 -0.9398)
			(stroke
				(width 0)
				(type default)
			)
			(fill no)
			(layer "F.CrtYd")
		)
		(fp_rect
			(start -0.508 0.9398)
			(end 0.508 -0.9398)
			(stroke
				(width 0)
				(type default)
			)
			(fill no)
			(layer "F.Fab")
		)
		(pad "1" smd custom
			(at 0 -0.4445 270)
			(size 0.1397 0.1397)
			(layers "F.Cu" "F.Mask" "F.Paste")
			(net "SDB_R_TX")
			(options
				(clearance outline)
				(anchor circle)
			)
			(primitives
				(gr_poly
					(pts
						(arc
							(start -0.1778 -0.2794)
							(mid -0.249642 -0.249642)
							(end -0.2794 -0.1778)
						)
						(arc
							(start -0.2794 0.1778)
							(mid -0.249642 0.249642)
							(end -0.1778 0.2794)
						)
						(arc
							(start 0.1778 0.2794)
							(mid 0.249642 0.249642)
							(end 0.2794 0.1778)
						)
						(arc
							(start 0.2794 -0.1778)
							(mid 0.249642 -0.249642)
							(end 0.1778 -0.2794)
						)
					)
					(width 0)
					(fill yes)
				)
			)
		)
		(pad "2" smd custom
			(at 0 0.4445 270)
			(size 0.1397 0.1397)
			(layers "F.Cu" "F.Mask" "F.Paste")
			(net "SDB_TX")
			(options
				(clearance outline)
				(anchor circle)
			)
			(primitives
				(gr_poly
					(pts
						(arc
							(start -0.1778 -0.2794)
							(mid -0.249642 -0.249642)
							(end -0.2794 -0.1778)
						)
						(arc
							(start -0.2794 0.1778)
							(mid -0.249642 0.249642)
							(end -0.1778 0.2794)
						)
						(arc
							(start 0.1778 0.2794)
							(mid 0.249642 0.249642)
							(end 0.2794 0.1778)
						)
						(arc
							(start 0.2794 -0.1778)
							(mid 0.249642 -0.249642)
							(end 0.1778 -0.2794)
						)
					)
					(width 0)
					(fill yes)
				)
			)
		)
	)
	(footprint ""
		(layer "F.Cu")
		(at 171.831 -195.199 90)
		(property "Reference" "R153"
			(at 0 0 90)
			(layer "F.SilkS")
			(hide yes)
			(effects
				(font
					(size 1.27 1.27)
				)
			)
		)
		(property "Value" "0R2J-2-GP"
			(at 0.064008 -3.993896 90)
			(unlocked yes)
			(layer "F.Fab")
			(hide yes)
			(effects
				(font
					(size 1.016 1.016)
					(thickness 0.1524)
				)
			)
		)
		(property "Device Type" "R402H16"
			(at 0.064008 -5.517896 90)
			(unlocked yes)
			(layer "F.Fab")
			(hide yes)
			(effects
				(font
					(size 1.016 1.016)
					(thickness 0.1524)
				)
			)
		)
		(duplicate_pad_numbers_are_jumpers no)
		(fp_line
			(start 0.508 -0.9398)
			(end -0.508 -0.9398)
			(stroke
				(width 0.1524)
				(type default)
			)
			(layer "F.SilkS")
		)
		(fp_line
			(start -0.508 -0.9398)
			(end -0.508 0.9398)
			(stroke
				(width 0.1524)
				(type default)
			)
			(layer "F.SilkS")
		)
		(fp_rect
			(start -0.508 0.9398)
			(end 0.508 -0.9398)
			(stroke
				(width 0)
				(type default)
			)
			(fill no)
			(layer "F.CrtYd")
		)
		(fp_rect
			(start -0.508 0.9398)
			(end 0.508 -0.9398)
			(stroke
				(width 0)
				(type default)
			)
			(fill no)
			(layer "F.Fab")
		)
		(pad "1" smd custom
			(at 0 -0.4445 90)
			(size 0.1397 0.1397)
			(layers "F.Cu" "F.Mask" "F.Paste")
			(net "SAS_I2C_C_BUF_SCL_R")
			(options
				(clearance outline)
				(anchor circle)
			)
			(primitives
				(gr_poly
					(pts
						(arc
							(start -0.1778 -0.2794)
							(mid -0.249642 -0.249642)
							(end -0.2794 -0.1778)
						)
						(arc
							(start -0.2794 0.1778)
							(mid -0.249642 0.249642)
							(end -0.1778 0.2794)
						)
						(arc
							(start 0.1778 0.2794)
							(mid 0.249642 0.249642)
							(end 0.2794 0.1778)
						)
						(arc
							(start 0.2794 -0.1778)
							(mid 0.249642 -0.249642)
							(end 0.1778 -0.2794)
						)
					)
					(width 0)
					(fill yes)
				)
			)
		)
		(pad "2" smd custom
			(at 0 0.4445 90)
			(size 0.1397 0.1397)
			(layers "F.Cu" "F.Mask" "F.Paste")
			(net "SAS_I2C_C_BUF_SCL")
			(options
				(clearance outline)
				(anchor circle)
			)
			(primitives
				(gr_poly
					(pts
						(arc
							(start -0.1778 -0.2794)
							(mid -0.249642 -0.249642)
							(end -0.2794 -0.1778)
						)
						(arc
							(start -0.2794 0.1778)
							(mid -0.249642 0.249642)
							(end -0.1778 0.2794)
						)
						(arc
							(start 0.1778 0.2794)
							(mid 0.249642 0.249642)
							(end 0.2794 0.1778)
						)
						(arc
							(start 0.2794 -0.1778)
							(mid 0.249642 -0.249642)
							(end 0.1778 -0.2794)
						)
					)
					(width 0)
					(fill yes)
				)
			)
		)
	)
	(footprint ""
		(layer "F.Cu")
		(at 185.855864 -38.172136)
		(property "Reference" "R371"
			(at 0 0 0)
			(layer "F.SilkS")
			(hide yes)
			(effects
				(font
					(size 1.27 1.27)
				)
			)
		)
		(property "Value" "10KR2F-2-GP"
			(at 0.064008 -3.993896 0)
			(unlocked yes)
			(layer "F.Fab")
			(hide yes)
			(effects
				(font
					(size 1.016 1.016)
					(thickness 0.1524)
				)
			)
		)
		(property "Device Type" "R402H16"
			(at 0.064008 -5.517896 0)
			(unlocked yes)
			(layer "F.Fab")
			(hide yes)
			(effects
				(font
					(size 1.016 1.016)
					(thickness 0.1524)
				)
			)
		)
		(duplicate_pad_numbers_are_jumpers no)
		(fp_line
			(start -0.508 -0.9398)
			(end -0.508 0.9398)
			(stroke
				(width 0.1524)
				(type default)
			)
			(layer "F.SilkS")
		)
		(fp_line
			(start 0.508 -0.9398)
			(end -0.508 -0.9398)
			(stroke
				(width 0.1524)
				(type default)
			)
			(layer "F.SilkS")
		)
		(fp_rect
			(start -0.508 0.9398)
			(end 0.508 -0.9398)
			(stroke
				(width 0)
				(type default)
			)
			(fill no)
			(layer "F.CrtYd")
		)
		(fp_rect
			(start -0.508 0.9398)
			(end 0.508 -0.9398)
			(stroke
				(width 0)
				(type default)
			)
			(fill no)
			(layer "F.Fab")
		)
		(pad "1" smd custom
			(at 0 -0.4445)
			(size 0.1397 0.1397)
			(layers "F.Cu" "F.Mask" "F.Paste")
			(net "P3V3_STBY")
			(options
				(clearance outline)
				(anchor circle)
			)
			(primitives
				(gr_poly
					(pts
						(arc
							(start -0.1778 -0.2794)
							(mid -0.249642 -0.249642)
							(end -0.2794 -0.1778)
						)
						(arc
							(start -0.2794 0.1778)
							(mid -0.249642 0.249642)
							(end -0.1778 0.2794)
						)
						(arc
							(start 0.1778 0.2794)
							(mid 0.249642 0.249642)
							(end 0.2794 0.1778)
						)
						(arc
							(start 0.2794 -0.1778)
							(mid 0.249642 -0.249642)
							(end 0.1778 -0.2794)
						)
					)
					(width 0)
					(fill yes)
				)
			)
		)
		(pad "2" smd custom
			(at 0 0.4445)
			(size 0.1397 0.1397)
			(layers "F.Cu" "F.Mask" "F.Paste")
			(net "PHY_RESET#")
			(options
				(clearance outline)
				(anchor circle)
			)
			(primitives
				(gr_poly
					(pts
						(arc
							(start -0.1778 -0.2794)
							(mid -0.249642 -0.249642)
							(end -0.2794 -0.1778)
						)
						(arc
							(start -0.2794 0.1778)
							(mid -0.249642 0.249642)
							(end -0.1778 0.2794)
						)
						(arc
							(start 0.1778 0.2794)
							(mid 0.249642 0.249642)
							(end 0.2794 0.1778)
						)
						(arc
							(start 0.2794 -0.1778)
							(mid 0.249642 -0.249642)
							(end 0.1778 -0.2794)
						)
					)
					(width 0)
					(fill yes)
				)
			)
		)
	)
	(footprint ""
		(layer "F.Cu")
		(at 250.259596 -53.232812 -90)
		(property "Reference" "SR722"
			(at 0 0 270)
			(layer "F.SilkS")
			(hide yes)
			(effects
				(font
					(size 1.27 1.27)
				)
			)
		)
		(property "Value" "0R2J-2-GP"
			(at 0.064008 -3.993896 270)
			(unlocked yes)
			(layer "F.Fab")
			(hide yes)
			(effects
				(font
					(size 1.016 1.016)
					(thickness 0.1524)
				)
			)
		)
		(property "Device Type" "R402H16"
			(at 0.064008 -5.517896 270)
			(unlocked yes)
			(layer "F.Fab")
			(hide yes)
			(effects
				(font
					(size 1.016 1.016)
					(thickness 0.1524)
				)
			)
		)
		(duplicate_pad_numbers_are_jumpers no)
		(fp_line
			(start -0.508 -0.9398)
			(end -0.508 0.9398)
			(stroke
				(width 0.1524)
				(type default)
			)
			(layer "F.SilkS")
		)
		(fp_line
			(start 0.508 -0.9398)
			(end -0.508 -0.9398)
			(stroke
				(width 0.1524)
				(type default)
			)
			(layer "F.SilkS")
		)
		(fp_rect
			(start -0.508 0.9398)
			(end 0.508 -0.9398)
			(stroke
				(width 0)
				(type default)
			)
			(fill no)
			(layer "F.CrtYd")
		)
		(fp_rect
			(start -0.508 0.9398)
			(end 0.508 -0.9398)
			(stroke
				(width 0)
				(type default)
			)
			(fill no)
			(layer "F.Fab")
		)
		(pad "1" smd custom
			(at 0 -0.4445 270)
			(size 0.1397 0.1397)
			(layers "F.Cu" "F.Mask" "F.Paste")
			(net "IOC_EEPROM_SCL")
			(options
				(clearance outline)
				(anchor circle)
			)
			(primitives
				(gr_poly
					(pts
						(arc
							(start -0.1778 -0.2794)
							(mid -0.249642 -0.249642)
							(end -0.2794 -0.1778)
						)
						(arc
							(start -0.2794 0.1778)
							(mid -0.249642 0.249642)
							(end -0.1778 0.2794)
						)
						(arc
							(start 0.1778 0.2794)
							(mid 0.249642 0.249642)
							(end 0.2794 0.1778)
						)
						(arc
							(start 0.2794 -0.1778)
							(mid 0.249642 -0.249642)
							(end 0.1778 -0.2794)
						)
					)
					(width 0)
					(fill yes)
				)
			)
		)
		(pad "2" smd custom
			(at 0 0.4445 270)
			(size 0.1397 0.1397)
			(layers "F.Cu" "F.Mask" "F.Paste")
			(net "SBL_SCL")
			(options
				(clearance outline)
				(anchor circle)
			)
			(primitives
				(gr_poly
					(pts
						(arc
							(start -0.1778 -0.2794)
							(mid -0.249642 -0.249642)
							(end -0.2794 -0.1778)
						)
						(arc
							(start -0.2794 0.1778)
							(mid -0.249642 0.249642)
							(end -0.1778 0.2794)
						)
						(arc
							(start 0.1778 0.2794)
							(mid 0.249642 0.249642)
							(end 0.2794 0.1778)
						)
						(arc
							(start 0.2794 -0.1778)
							(mid 0.249642 -0.249642)
							(end 0.1778 -0.2794)
						)
					)
					(width 0)
					(fill yes)
				)
			)
		)
	)
	(footprint ""
		(layer "F.Cu")
		(at 48.895 -223.139 -90)
		(property "Reference" "R9022"
			(at 0 0 270)
			(layer "F.SilkS")
			(hide yes)
			(effects
				(font
					(size 1.27 1.27)
				)
			)
		)
		(property "Value" "86K6R2F-GP"
			(at 0.064008 -3.993896 270)
			(unlocked yes)
			(layer "F.Fab")
			(hide yes)
			(effects
				(font
					(size 1.016 1.016)
					(thickness 0.1524)
				)
			)
		)
		(property "Device Type" "R402H16"
			(at 0.064008 -5.517896 270)
			(unlocked yes)
			(layer "F.Fab")
			(hide yes)
			(effects
				(font
					(size 1.016 1.016)
					(thickness 0.1524)
				)
			)
		)
		(duplicate_pad_numbers_are_jumpers no)
		(fp_line
			(start -0.508 -0.9398)
			(end -0.508 0.9398)
			(stroke
				(width 0.1524)
				(type default)
			)
			(layer "F.SilkS")
		)
		(fp_line
			(start 0.508 -0.9398)
			(end -0.508 -0.9398)
			(stroke
				(width 0.1524)
				(type default)
			)
			(layer "F.SilkS")
		)
		(fp_rect
			(start -0.508 0.9398)
			(end 0.508 -0.9398)
			(stroke
				(width 0)
				(type default)
			)
			(fill no)
			(layer "F.CrtYd")
		)
		(fp_rect
			(start -0.508 0.9398)
			(end 0.508 -0.9398)
			(stroke
				(width 0)
				(type default)
			)
			(fill no)
			(layer "F.Fab")
		)
		(pad "1" smd custom
			(at 0 -0.4445 270)
			(size 0.1397 0.1397)
			(layers "F.Cu" "F.Mask" "F.Paste")
			(net "MB0_PSET_R")
			(options
				(clearance outline)
				(anchor circle)
			)
			(primitives
				(gr_poly
					(pts
						(arc
							(start -0.1778 -0.2794)
							(mid -0.249642 -0.249642)
							(end -0.2794 -0.1778)
						)
						(arc
							(start -0.2794 0.1778)
							(mid -0.249642 0.249642)
							(end -0.1778 0.2794)
						)
						(arc
							(start 0.1778 0.2794)
							(mid 0.249642 0.249642)
							(end 0.2794 0.1778)
						)
						(arc
							(start 0.2794 -0.1778)
							(mid 0.249642 -0.249642)
							(end 0.1778 -0.2794)
						)
					)
					(width 0)
					(fill yes)
				)
			)
		)
		(pad "2" smd custom
			(at 0 0.4445 270)
			(size 0.1397 0.1397)
			(layers "F.Cu" "F.Mask" "F.Paste")
			(net "AGND_CURRENT_MON")
			(options
				(clearance outline)
				(anchor circle)
			)
			(primitives
				(gr_poly
					(pts
						(arc
							(start -0.1778 -0.2794)
							(mid -0.249642 -0.249642)
							(end -0.2794 -0.1778)
						)
						(arc
							(start -0.2794 0.1778)
							(mid -0.249642 0.249642)
							(end -0.1778 0.2794)
						)
						(arc
							(start 0.1778 0.2794)
							(mid 0.249642 0.249642)
							(end 0.2794 0.1778)
						)
						(arc
							(start 0.2794 -0.1778)
							(mid 0.249642 -0.249642)
							(end 0.1778 -0.2794)
						)
					)
					(width 0)
					(fill yes)
				)
			)
		)
	)
	(footprint ""
		(layer "F.Cu")
		(at 109.97057 -78.6638 -90)
		(property "Reference" "STP63"
			(at 0 0 270)
			(layer "F.SilkS")
			(hide yes)
			(effects
				(font
					(size 1.27 1.27)
				)
			)
		)
		(property "Value" "TPAD28"
			(at 0.0127 -1.8034 270)
			(unlocked yes)
			(layer "F.Fab")
			(hide yes)
			(effects
				(font
					(size 1.016 1.016)
					(thickness 0.1524)
				)
			)
		)
		(property "Device Type" "TPAD28"
			(at 0.0127 -3.3274 270)
			(unlocked yes)
			(layer "F.Fab")
			(hide yes)
			(effects
				(font
					(size 1.016 1.016)
					(thickness 0.1524)
				)
			)
		)
		(duplicate_pad_numbers_are_jumpers no)
		(fp_poly
			(pts
				(arc
					(start 0 -0.3556)
					(mid 0 0.3556)
					(end 0 -0.3556)
				)
			)
			(stroke
				(width 0)
				(type default)
			)
			(fill no)
			(layer "F.CrtYd")
		)
		(fp_poly
			(pts
				(arc
					(start 0 -0.6096)
					(mid 0 0.6096)
					(end 0 -0.6096)
				)
			)
			(stroke
				(width 0)
				(type default)
			)
			(fill no)
			(layer "F.Fab")
		)
		(pad "1" smd circle
			(at 0 0 270)
			(size 0.7112 0.7112)
			(layers "F.Cu" "F.Mask" "F.Paste")
			(net "EXP_TEST_MUX25")
		)
	)
	(footprint ""
		(layer "F.Cu")
		(at 289.687 -69.723 -90)
		(property "Reference" "PR6888"
			(at 0 0 270)
			(layer "F.SilkS")
			(hide yes)
			(effects
				(font
					(size 1.27 1.27)
				)
			)
		)
		(property "Value" "5K36R2F-GP"
			(at 0.064008 -3.993896 270)
			(unlocked yes)
			(layer "F.Fab")
			(hide yes)
			(effects
				(font
					(size 1.016 1.016)
					(thickness 0.1524)
				)
			)
		)
		(property "Device Type" "R402H16"
			(at 0.064008 -5.517896 270)
			(unlocked yes)
			(layer "F.Fab")
			(hide yes)
			(effects
				(font
					(size 1.016 1.016)
					(thickness 0.1524)
				)
			)
		)
		(duplicate_pad_numbers_are_jumpers no)
		(fp_line
			(start -0.508 -0.9398)
			(end -0.508 0.9398)
			(stroke
				(width 0.1524)
				(type default)
			)
			(layer "F.SilkS")
		)
		(fp_line
			(start 0.508 -0.9398)
			(end -0.508 -0.9398)
			(stroke
				(width 0.1524)
				(type default)
			)
			(layer "F.SilkS")
		)
		(fp_rect
			(start -0.508 0.9398)
			(end 0.508 -0.9398)
			(stroke
				(width 0)
				(type default)
			)
			(fill no)
			(layer "F.CrtYd")
		)
		(fp_rect
			(start -0.508 0.9398)
			(end 0.508 -0.9398)
			(stroke
				(width 0)
				(type default)
			)
			(fill no)
			(layer "F.Fab")
		)
		(pad "1" smd custom
			(at 0 -0.4445 270)
			(size 0.1397 0.1397)
			(layers "F.Cu" "F.Mask" "F.Paste")
			(net "P12V_PCIE")
			(options
				(clearance outline)
				(anchor circle)
			)
			(primitives
				(gr_poly
					(pts
						(arc
							(start -0.1778 -0.2794)
							(mid -0.249642 -0.249642)
							(end -0.2794 -0.1778)
						)
						(arc
							(start -0.2794 0.1778)
							(mid -0.249642 0.249642)
							(end -0.1778 0.2794)
						)
						(arc
							(start 0.1778 0.2794)
							(mid 0.249642 0.249642)
							(end 0.2794 0.1778)
						)
						(arc
							(start 0.2794 -0.1778)
							(mid 0.249642 -0.249642)
							(end 0.1778 -0.2794)
						)
					)
					(width 0)
					(fill yes)
				)
			)
		)
		(pad "2" smd custom
			(at 0 0.4445 270)
			(size 0.1397 0.1397)
			(layers "F.Cu" "F.Mask" "F.Paste")
			(net "HS_ADR")
			(options
				(clearance outline)
				(anchor circle)
			)
			(primitives
				(gr_poly
					(pts
						(arc
							(start -0.1778 -0.2794)
							(mid -0.249642 -0.249642)
							(end -0.2794 -0.1778)
						)
						(arc
							(start -0.2794 0.1778)
							(mid -0.249642 0.249642)
							(end -0.1778 0.2794)
						)
						(arc
							(start 0.1778 0.2794)
							(mid 0.249642 0.249642)
							(end 0.2794 0.1778)
						)
						(arc
							(start 0.2794 -0.1778)
							(mid 0.249642 -0.249642)
							(end 0.1778 -0.2794)
						)
					)
					(width 0)
					(fill yes)
				)
			)
		)
	)
	(footprint ""
		(layer "F.Cu")
		(at 174.107348 -123.815856 90)
		(property "Reference" "PC170"
			(at 0 0 90)
			(layer "F.SilkS")
			(hide yes)
			(effects
				(font
					(size 1.27 1.27)
				)
			)
		)
		(property "Value" "SC22U25V5MX-GP"
			(at -0.0762 -6.1214 90)
			(unlocked yes)
			(layer "F.Fab")
			(hide yes)
			(effects
				(font
					(size 1.016 1.016)
					(thickness 0.1524)
				)
			)
		)
		(property "Device Type" "C805H58"
			(at -0.0762 -8.1534 90)
			(unlocked yes)
			(layer "F.Fab")
			(hide yes)
			(effects
				(font
					(size 1.016 1.016)
					(thickness 0.1524)
				)
			)
		)
		(duplicate_pad_numbers_are_jumpers no)
		(fp_line
			(start 0.635 0)
			(end -0.635 0)
			(stroke
				(width 0.508)
				(type default)
			)
			(layer "F.SilkS")
		)
		(fp_rect
			(start -0.9652 1.778)
			(end 0.9652 -1.778)
			(stroke
				(width 0)
				(type default)
			)
			(fill no)
			(layer "F.CrtYd")
		)
		(fp_poly
			(pts
				(xy -0.9652 -1.778) (xy 0.9652 -1.778) (xy 0.9652 1.778) (xy -0.9652 1.778)
			)
			(stroke
				(width 0)
				(type default)
			)
			(fill no)
			(layer "F.Fab")
		)
		(pad "1" smd rect
			(at 0 -0.9652 90)
			(size 1.397 1.143)
			(layers "F.Cu" "F.Mask" "F.Paste")
			(net "P0V9_E_VIN")
		)
		(pad "2" smd rect
			(at 0 0.9652 90)
			(size 1.397 1.143)
			(layers "F.Cu" "F.Mask" "F.Paste")
			(net "GND")
		)
	)
	(footprint ""
		(layer "F.Cu")
		(at 132.212842 -83.129882 90)
		(property "Reference" "SC1094"
			(at 0 0 90)
			(layer "F.SilkS")
			(hide yes)
			(effects
				(font
					(size 1.27 1.27)
				)
			)
		)
		(property "Value" "SCD01U10V1KX-GP"
			(at -2.8321 -1.7399 90)
			(unlocked yes)
			(layer "F.Fab")
			(hide yes)
			(effects
				(font
					(size 1.016 1.016)
					(thickness 0.1524)
				)
			)
		)
		(property "Device Type" "C0201H13"
			(at -2.8321 -3.2639 90)
			(unlocked yes)
			(layer "F.Fab")
			(hide yes)
			(effects
				(font
					(size 1.016 1.016)
					(thickness 0.1524)
				)
			)
		)
		(duplicate_pad_numbers_are_jumpers no)
		(fp_rect
			(start -0.2794 0.6477)
			(end 0.2794 -0.6477)
			(stroke
				(width 0)
				(type default)
			)
			(fill no)
			(layer "F.CrtYd")
		)
		(fp_rect
			(start -0.2794 0.6477)
			(end 0.2794 -0.6477)
			(stroke
				(width 0)
				(type default)
			)
			(fill no)
			(layer "F.Fab")
		)
		(pad "1" smd custom
			(at 0 -0.2794 90)
			(size 0.0762 0.0762)
			(layers "F.Cu" "F.Mask" "F.Paste")
			(net "SAS_HDD_TX13_P")
			(options
				(clearance outline)
				(anchor circle)
			)
			(primitives
				(gr_poly
					(pts
						(arc
							(start 0.1524 -0.127)
							(mid 0.137521 -0.162921)
							(end 0.1016 -0.1778)
						)
						(arc
							(start -0.1016 -0.1778)
							(mid -0.137521 -0.162921)
							(end -0.1524 -0.127)
						)
						(arc
							(start -0.1524 0.127)
							(mid -0.137521 0.162921)
							(end -0.1016 0.1778)
						)
						(arc
							(start 0.1016 0.1778)
							(mid 0.137521 0.162921)
							(end 0.1524 0.127)
						)
					)
					(width 0)
					(fill yes)
				)
			)
		)
		(pad "2" smd custom
			(at 0 0.2794 90)
			(size 0.0762 0.0762)
			(layers "F.Cu" "F.Mask" "F.Paste")
			(net "3008_SAS_RX_P1")
			(options
				(clearance outline)
				(anchor circle)
			)
			(primitives
				(gr_poly
					(pts
						(arc
							(start 0.1524 -0.127)
							(mid 0.137521 -0.162921)
							(end 0.1016 -0.1778)
						)
						(arc
							(start -0.1016 -0.1778)
							(mid -0.137521 -0.162921)
							(end -0.1524 -0.127)
						)
						(arc
							(start -0.1524 0.127)
							(mid -0.137521 0.162921)
							(end -0.1016 0.1778)
						)
						(arc
							(start 0.1016 0.1778)
							(mid 0.137521 0.162921)
							(end 0.1524 0.127)
						)
					)
					(width 0)
					(fill yes)
				)
			)
		)
	)
	(footprint ""
		(layer "F.Cu")
		(at 284.48 -161.163)
		(property "Reference" "TP135"
			(at 0 0 0)
			(layer "F.SilkS")
			(hide yes)
			(effects
				(font
					(size 1.27 1.27)
				)
			)
		)
		(property "Value" "TPAD28"
			(at 0.0127 -1.8034 0)
			(unlocked yes)
			(layer "F.Fab")
			(hide yes)
			(effects
				(font
					(size 1.016 1.016)
					(thickness 0.1524)
				)
			)
		)
		(property "Device Type" "TPAD28"
			(at 0.0127 -3.3274 0)
			(unlocked yes)
			(layer "F.Fab")
			(hide yes)
			(effects
				(font
					(size 1.016 1.016)
					(thickness 0.1524)
				)
			)
		)
		(duplicate_pad_numbers_are_jumpers no)
		(fp_poly
			(pts
				(arc
					(start 0.3556 0)
					(mid -0.3556 0)
					(end 0.3556 0)
				)
			)
			(stroke
				(width 0)
				(type default)
			)
			(fill no)
			(layer "F.CrtYd")
		)
		(fp_poly
			(pts
				(arc
					(start 0.6096 0)
					(mid -0.6096 0)
					(end 0.6096 0)
				)
			)
			(stroke
				(width 0)
				(type default)
			)
			(fill no)
			(layer "F.Fab")
		)
		(pad "1" smd circle
			(at 0 0)
			(size 0.7112 0.7112)
			(layers "F.Cu" "F.Mask" "F.Paste")
			(net "TP_BMC_GPIOF1")
		)
	)
	(footprint ""
		(layer "F.Cu")
		(at 333.912718 -148.948648 -90)
		(property "Reference" "R550"
			(at 0 0 270)
			(layer "F.SilkS")
			(hide yes)
			(effects
				(font
					(size 1.27 1.27)
				)
			)
		)
		(property "Value" "4K7R2F-GP"
			(at 0.064008 -3.993896 270)
			(unlocked yes)
			(layer "F.Fab")
			(hide yes)
			(effects
				(font
					(size 1.016 1.016)
					(thickness 0.1524)
				)
			)
		)
		(property "Device Type" "R402H16"
			(at 0.064008 -5.517896 270)
			(unlocked yes)
			(layer "F.Fab")
			(hide yes)
			(effects
				(font
					(size 1.016 1.016)
					(thickness 0.1524)
				)
			)
		)
		(duplicate_pad_numbers_are_jumpers no)
		(fp_line
			(start -0.508 -0.9398)
			(end -0.508 0.9398)
			(stroke
				(width 0.1524)
				(type default)
			)
			(layer "F.SilkS")
		)
		(fp_line
			(start 0.508 -0.9398)
			(end -0.508 -0.9398)
			(stroke
				(width 0.1524)
				(type default)
			)
			(layer "F.SilkS")
		)
		(fp_rect
			(start -0.508 0.9398)
			(end 0.508 -0.9398)
			(stroke
				(width 0)
				(type default)
			)
			(fill no)
			(layer "F.CrtYd")
		)
		(fp_rect
			(start -0.508 0.9398)
			(end 0.508 -0.9398)
			(stroke
				(width 0)
				(type default)
			)
			(fill no)
			(layer "F.Fab")
		)
		(pad "1" smd custom
			(at 0 -0.4445 270)
			(size 0.1397 0.1397)
			(layers "F.Cu" "F.Mask" "F.Paste")
			(net "CFG_SEL1")
			(options
				(clearance outline)
				(anchor circle)
			)
			(primitives
				(gr_poly
					(pts
						(arc
							(start -0.1778 -0.2794)
							(mid -0.249642 -0.249642)
							(end -0.2794 -0.1778)
						)
						(arc
							(start -0.2794 0.1778)
							(mid -0.249642 0.249642)
							(end -0.1778 0.2794)
						)
						(arc
							(start 0.1778 0.2794)
							(mid 0.249642 0.249642)
							(end 0.2794 0.1778)
						)
						(arc
							(start 0.2794 -0.1778)
							(mid 0.249642 -0.249642)
							(end 0.1778 -0.2794)
						)
					)
					(width 0)
					(fill yes)
				)
			)
		)
		(pad "2" smd custom
			(at 0 0.4445 270)
			(size 0.1397 0.1397)
			(layers "F.Cu" "F.Mask" "F.Paste")
			(net "GND")
			(options
				(clearance outline)
				(anchor circle)
			)
			(primitives
				(gr_poly
					(pts
						(arc
							(start -0.1778 -0.2794)
							(mid -0.249642 -0.249642)
							(end -0.2794 -0.1778)
						)
						(arc
							(start -0.2794 0.1778)
							(mid -0.249642 0.249642)
							(end -0.1778 0.2794)
						)
						(arc
							(start 0.1778 0.2794)
							(mid 0.249642 0.249642)
							(end 0.2794 0.1778)
						)
						(arc
							(start 0.2794 -0.1778)
							(mid 0.249642 -0.249642)
							(end 0.1778 -0.2794)
						)
					)
					(width 0)
					(fill yes)
				)
			)
		)
	)
	(footprint ""
		(layer "F.Cu")
		(at 319.396872 -119.452136 180)
		(property "Reference" "PC26"
			(at 0 0 180)
			(layer "F.SilkS")
			(hide yes)
			(effects
				(font
					(size 1.27 1.27)
				)
			)
		)
		(property "Value" "SC4D7U25V5KX-1-GP"
			(at -0.0762 -6.1214 180)
			(unlocked yes)
			(layer "F.Fab")
			(hide yes)
			(effects
				(font
					(size 1.016 1.016)
					(thickness 0.1524)
				)
			)
		)
		(property "Device Type" "C805H58"
			(at -0.0762 -8.1534 180)
			(unlocked yes)
			(layer "F.Fab")
			(hide yes)
			(effects
				(font
					(size 1.016 1.016)
					(thickness 0.1524)
				)
			)
		)
		(duplicate_pad_numbers_are_jumpers no)
		(fp_line
			(start 0.635 0)
			(end -0.635 0)
			(stroke
				(width 0.508)
				(type default)
			)
			(layer "F.SilkS")
		)
		(fp_rect
			(start -0.9652 1.778)
			(end 0.9652 -1.778)
			(stroke
				(width 0)
				(type default)
			)
			(fill no)
			(layer "F.CrtYd")
		)
		(fp_poly
			(pts
				(xy -0.9652 -1.778) (xy 0.9652 -1.778) (xy 0.9652 1.778) (xy -0.9652 1.778)
			)
			(stroke
				(width 0)
				(type default)
			)
			(fill no)
			(layer "F.Fab")
		)
		(pad "1" smd rect
			(at 0 -0.9652 180)
			(size 1.397 1.143)
			(layers "F.Cu" "F.Mask" "F.Paste")
			(net "P3V3_STBY_VDD")
		)
		(pad "2" smd rect
			(at 0 0.9652 180)
			(size 1.397 1.143)
			(layers "F.Cu" "F.Mask" "F.Paste")
			(net "GND")
		)
	)
	(footprint ""
		(layer "F.Cu")
		(at 333.912718 -143.360648 90)
		(property "Reference" "R7896"
			(at 0 0 90)
			(layer "F.SilkS")
			(hide yes)
			(effects
				(font
					(size 1.27 1.27)
				)
			)
		)
		(property "Value" "4K7R2F-GP"
			(at 0.064008 -3.993896 90)
			(unlocked yes)
			(layer "F.Fab")
			(hide yes)
			(effects
				(font
					(size 1.016 1.016)
					(thickness 0.1524)
				)
			)
		)
		(property "Device Type" "R402H16"
			(at 0.064008 -5.517896 90)
			(unlocked yes)
			(layer "F.Fab")
			(hide yes)
			(effects
				(font
					(size 1.016 1.016)
					(thickness 0.1524)
				)
			)
		)
		(duplicate_pad_numbers_are_jumpers no)
		(fp_line
			(start 0.508 -0.9398)
			(end -0.508 -0.9398)
			(stroke
				(width 0.1524)
				(type default)
			)
			(layer "F.SilkS")
		)
		(fp_line
			(start -0.508 -0.9398)
			(end -0.508 0.9398)
			(stroke
				(width 0.1524)
				(type default)
			)
			(layer "F.SilkS")
		)
		(fp_rect
			(start -0.508 0.9398)
			(end 0.508 -0.9398)
			(stroke
				(width 0)
				(type default)
			)
			(fill no)
			(layer "F.CrtYd")
		)
		(fp_rect
			(start -0.508 0.9398)
			(end 0.508 -0.9398)
			(stroke
				(width 0)
				(type default)
			)
			(fill no)
			(layer "F.Fab")
		)
		(pad "1" smd custom
			(at 0 -0.4445 90)
			(size 0.1397 0.1397)
			(layers "F.Cu" "F.Mask" "F.Paste")
			(net "P3V3_STBY")
			(options
				(clearance outline)
				(anchor circle)
			)
			(primitives
				(gr_poly
					(pts
						(arc
							(start -0.1778 -0.2794)
							(mid -0.249642 -0.249642)
							(end -0.2794 -0.1778)
						)
						(arc
							(start -0.2794 0.1778)
							(mid -0.249642 0.249642)
							(end -0.1778 0.2794)
						)
						(arc
							(start 0.1778 0.2794)
							(mid 0.249642 0.249642)
							(end 0.2794 0.1778)
						)
						(arc
							(start 0.2794 -0.1778)
							(mid 0.249642 -0.249642)
							(end 0.1778 -0.2794)
						)
					)
					(width 0)
					(fill yes)
				)
			)
		)
		(pad "2" smd custom
			(at 0 0.4445 90)
			(size 0.1397 0.1397)
			(layers "F.Cu" "F.Mask" "F.Paste")
			(net "VBUS_DET")
			(options
				(clearance outline)
				(anchor circle)
			)
			(primitives
				(gr_poly
					(pts
						(arc
							(start -0.1778 -0.2794)
							(mid -0.249642 -0.249642)
							(end -0.2794 -0.1778)
						)
						(arc
							(start -0.2794 0.1778)
							(mid -0.249642 0.249642)
							(end -0.1778 0.2794)
						)
						(arc
							(start 0.1778 0.2794)
							(mid 0.249642 0.249642)
							(end 0.2794 0.1778)
						)
						(arc
							(start 0.2794 -0.1778)
							(mid 0.249642 -0.249642)
							(end 0.1778 -0.2794)
						)
					)
					(width 0)
					(fill yes)
				)
			)
		)
	)
	(footprint ""
		(layer "F.Cu")
		(at 62.357 -217.297 90)
		(property "Reference" "R2110"
			(at 0 0 90)
			(layer "F.SilkS")
			(hide yes)
			(effects
				(font
					(size 1.27 1.27)
				)
			)
		)
		(property "Value" "1KR2J-1-GP"
			(at 0.064008 -3.993896 90)
			(unlocked yes)
			(layer "F.Fab")
			(hide yes)
			(effects
				(font
					(size 1.016 1.016)
					(thickness 0.1524)
				)
			)
		)
		(property "Device Type" "R402H16"
			(at 0.064008 -5.517896 90)
			(unlocked yes)
			(layer "F.Fab")
			(hide yes)
			(effects
				(font
					(size 1.016 1.016)
					(thickness 0.1524)
				)
			)
		)
		(duplicate_pad_numbers_are_jumpers no)
		(fp_line
			(start 0.508 -0.9398)
			(end -0.508 -0.9398)
			(stroke
				(width 0.1524)
				(type default)
			)
			(layer "F.SilkS")
		)
		(fp_line
			(start -0.508 -0.9398)
			(end -0.508 0.9398)
			(stroke
				(width 0.1524)
				(type default)
			)
			(layer "F.SilkS")
		)
		(fp_rect
			(start -0.508 0.9398)
			(end 0.508 -0.9398)
			(stroke
				(width 0)
				(type default)
			)
			(fill no)
			(layer "F.CrtYd")
		)
		(fp_rect
			(start -0.508 0.9398)
			(end 0.508 -0.9398)
			(stroke
				(width 0)
				(type default)
			)
			(fill no)
			(layer "F.Fab")
		)
		(pad "1" smd custom
			(at 0 -0.4445 90)
			(size 0.1397 0.1397)
			(layers "F.Cu" "F.Mask" "F.Paste")
			(net "MB0_CM_VOUT_R")
			(options
				(clearance outline)
				(anchor circle)
			)
			(primitives
				(gr_poly
					(pts
						(arc
							(start -0.1778 -0.2794)
							(mid -0.249642 -0.249642)
							(end -0.2794 -0.1778)
						)
						(arc
							(start -0.2794 0.1778)
							(mid -0.249642 0.249642)
							(end -0.1778 0.2794)
						)
						(arc
							(start 0.1778 0.2794)
							(mid 0.249642 0.249642)
							(end 0.2794 0.1778)
						)
						(arc
							(start 0.2794 -0.1778)
							(mid 0.249642 -0.249642)
							(end 0.1778 -0.2794)
						)
					)
					(width 0)
					(fill yes)
				)
			)
		)
		(pad "2" smd custom
			(at 0 0.4445 90)
			(size 0.1397 0.1397)
			(layers "F.Cu" "F.Mask" "F.Paste")
			(net "P12V")
			(options
				(clearance outline)
				(anchor circle)
			)
			(primitives
				(gr_poly
					(pts
						(arc
							(start -0.1778 -0.2794)
							(mid -0.249642 -0.249642)
							(end -0.2794 -0.1778)
						)
						(arc
							(start -0.2794 0.1778)
							(mid -0.249642 0.249642)
							(end -0.1778 0.2794)
						)
						(arc
							(start 0.1778 0.2794)
							(mid 0.249642 0.249642)
							(end 0.2794 0.1778)
						)
						(arc
							(start 0.2794 -0.1778)
							(mid 0.249642 -0.249642)
							(end 0.1778 -0.2794)
						)
					)
					(width 0)
					(fill yes)
				)
			)
		)
	)
	(footprint ""
		(layer "F.Cu")
		(at 334.645 -229.743 180)
		(property "Reference" "R187"
			(at 0 0 180)
			(layer "F.SilkS")
			(hide yes)
			(effects
				(font
					(size 1.27 1.27)
				)
			)
		)
		(property "Value" "4K7R2F-GP"
			(at 0.064008 -3.993896 180)
			(unlocked yes)
			(layer "F.Fab")
			(hide yes)
			(effects
				(font
					(size 1.016 1.016)
					(thickness 0.1524)
				)
			)
		)
		(property "Device Type" "R402H16"
			(at 0.064008 -5.517896 180)
			(unlocked yes)
			(layer "F.Fab")
			(hide yes)
			(effects
				(font
					(size 1.016 1.016)
					(thickness 0.1524)
				)
			)
		)
		(duplicate_pad_numbers_are_jumpers no)
		(fp_line
			(start 0.508 -0.9398)
			(end -0.508 -0.9398)
			(stroke
				(width 0.1524)
				(type default)
			)
			(layer "F.SilkS")
		)
		(fp_line
			(start -0.508 -0.9398)
			(end -0.508 0.9398)
			(stroke
				(width 0.1524)
				(type default)
			)
			(layer "F.SilkS")
		)
		(fp_rect
			(start -0.508 0.9398)
			(end 0.508 -0.9398)
			(stroke
				(width 0)
				(type default)
			)
			(fill no)
			(layer "F.CrtYd")
		)
		(fp_rect
			(start -0.508 0.9398)
			(end 0.508 -0.9398)
			(stroke
				(width 0)
				(type default)
			)
			(fill no)
			(layer "F.Fab")
		)
		(pad "1" smd custom
			(at 0 -0.4445 180)
			(size 0.1397 0.1397)
			(layers "F.Cu" "F.Mask" "F.Paste")
			(net "VOL_SEN_ADDR")
			(options
				(clearance outline)
				(anchor circle)
			)
			(primitives
				(gr_poly
					(pts
						(arc
							(start -0.1778 -0.2794)
							(mid -0.249642 -0.249642)
							(end -0.2794 -0.1778)
						)
						(arc
							(start -0.2794 0.1778)
							(mid -0.249642 0.249642)
							(end -0.1778 0.2794)
						)
						(arc
							(start 0.1778 0.2794)
							(mid 0.249642 0.249642)
							(end 0.2794 0.1778)
						)
						(arc
							(start 0.2794 -0.1778)
							(mid 0.249642 -0.249642)
							(end 0.1778 -0.2794)
						)
					)
					(width 0)
					(fill yes)
				)
			)
		)
		(pad "2" smd custom
			(at 0 0.4445 180)
			(size 0.1397 0.1397)
			(layers "F.Cu" "F.Mask" "F.Paste")
			(net "GND")
			(options
				(clearance outline)
				(anchor circle)
			)
			(primitives
				(gr_poly
					(pts
						(arc
							(start -0.1778 -0.2794)
							(mid -0.249642 -0.249642)
							(end -0.2794 -0.1778)
						)
						(arc
							(start -0.2794 0.1778)
							(mid -0.249642 0.249642)
							(end -0.1778 0.2794)
						)
						(arc
							(start 0.1778 0.2794)
							(mid 0.249642 0.249642)
							(end 0.2794 0.1778)
						)
						(arc
							(start 0.2794 -0.1778)
							(mid 0.249642 -0.249642)
							(end 0.1778 -0.2794)
						)
					)
					(width 0)
					(fill yes)
				)
			)
		)
	)
	(footprint ""
		(layer "F.Cu")
		(at 319.278 -9.652)
		(property "Reference" "R531"
			(at 0 0 0)
			(layer "F.SilkS")
			(hide yes)
			(effects
				(font
					(size 1.27 1.27)
				)
			)
		)
		(property "Value" "220R2F-GP"
			(at 0.064008 -3.993896 0)
			(unlocked yes)
			(layer "F.Fab")
			(hide yes)
			(effects
				(font
					(size 1.016 1.016)
					(thickness 0.1524)
				)
			)
		)
		(property "Device Type" "R402H16"
			(at 0.064008 -5.517896 0)
			(unlocked yes)
			(layer "F.Fab")
			(hide yes)
			(effects
				(font
					(size 1.016 1.016)
					(thickness 0.1524)
				)
			)
		)
		(duplicate_pad_numbers_are_jumpers no)
		(fp_line
			(start -0.508 -0.9398)
			(end -0.508 0.9398)
			(stroke
				(width 0.1524)
				(type default)
			)
			(layer "F.SilkS")
		)
		(fp_line
			(start 0.508 -0.9398)
			(end -0.508 -0.9398)
			(stroke
				(width 0.1524)
				(type default)
			)
			(layer "F.SilkS")
		)
		(fp_rect
			(start -0.508 0.9398)
			(end 0.508 -0.9398)
			(stroke
				(width 0)
				(type default)
			)
			(fill no)
			(layer "F.CrtYd")
		)
		(fp_rect
			(start -0.508 0.9398)
			(end 0.508 -0.9398)
			(stroke
				(width 0)
				(type default)
			)
			(fill no)
			(layer "F.Fab")
		)
		(pad "1" smd custom
			(at 0 -0.4445)
			(size 0.1397 0.1397)
			(layers "F.Cu" "F.Mask" "F.Paste")
			(net "LED_SL_SW_ON")
			(options
				(clearance outline)
				(anchor circle)
			)
			(primitives
				(gr_poly
					(pts
						(arc
							(start -0.1778 -0.2794)
							(mid -0.249642 -0.249642)
							(end -0.2794 -0.1778)
						)
						(arc
							(start -0.2794 0.1778)
							(mid -0.249642 0.249642)
							(end -0.1778 0.2794)
						)
						(arc
							(start 0.1778 0.2794)
							(mid 0.249642 0.249642)
							(end 0.2794 0.1778)
						)
						(arc
							(start 0.2794 -0.1778)
							(mid 0.249642 -0.249642)
							(end 0.1778 -0.2794)
						)
					)
					(width 0)
					(fill yes)
				)
			)
		)
		(pad "2" smd custom
			(at 0 0.4445)
			(size 0.1397 0.1397)
			(layers "F.Cu" "F.Mask" "F.Paste")
			(net "P3V3_STBY")
			(options
				(clearance outline)
				(anchor circle)
			)
			(primitives
				(gr_poly
					(pts
						(arc
							(start -0.1778 -0.2794)
							(mid -0.249642 -0.249642)
							(end -0.2794 -0.1778)
						)
						(arc
							(start -0.2794 0.1778)
							(mid -0.249642 0.249642)
							(end -0.1778 0.2794)
						)
						(arc
							(start 0.1778 0.2794)
							(mid 0.249642 0.249642)
							(end 0.2794 0.1778)
						)
						(arc
							(start 0.2794 -0.1778)
							(mid 0.249642 -0.249642)
							(end 0.1778 -0.2794)
						)
					)
					(width 0)
					(fill yes)
				)
			)
		)
	)
	(footprint ""
		(layer "F.Cu")
		(at 54.4576 -230.0986 180)
		(property "Reference" "D37"
			(at 0 0 180)
			(layer "F.SilkS")
			(hide yes)
			(effects
				(font
					(size 1.27 1.27)
				)
			)
		)
		(property "Value" "SMF15A-GP"
			(at -2.0955 1.2192 180)
			(unlocked yes)
			(layer "F.Fab")
			(hide yes)
			(effects
				(font
					(size 1.016 1.016)
					(thickness 0.1524)
				)
			)
		)
		(property "Device Type" "SOD123AK-2H43"
			(at -2.0955 -0.3048 180)
			(unlocked yes)
			(layer "F.Fab")
			(hide yes)
			(effects
				(font
					(size 1.016 1.016)
					(thickness 0.1524)
				)
			)
		)
		(duplicate_pad_numbers_are_jumpers no)
		(fp_line
			(start 1.1557 2.921)
			(end -1.1557 2.921)
			(stroke
				(width 0.508)
				(type default)
			)
			(layer "F.SilkS")
		)
		(fp_line
			(start 1.1557 2.7686)
			(end 1.1557 -2.7686)
			(stroke
				(width 0.1524)
				(type default)
			)
			(layer "F.SilkS")
		)
		(fp_line
			(start 1.1557 -2.7686)
			(end -1.1557 -2.7686)
			(stroke
				(width 0.1524)
				(type default)
			)
			(layer "F.SilkS")
		)
		(fp_line
			(start -1.1557 2.7686)
			(end 1.1557 2.7686)
			(stroke
				(width 0.1524)
				(type default)
			)
			(layer "F.SilkS")
		)
		(fp_line
			(start -1.1557 -2.7686)
			(end -1.1557 2.7686)
			(stroke
				(width 0.1524)
				(type default)
			)
			(layer "F.SilkS")
		)
		(fp_poly
			(pts
				(xy -0.4572 1.8669) (xy -0.4572 1.397) (xy -0.9017 1.397) (xy -0.9017 -1.397) (xy -0.4572 -1.397)
				(xy -0.4572 -1.8669) (xy 0.4572 -1.8669) (xy 0.4572 -1.397) (xy 0.9017 -1.397) (xy 0.9017 1.397)
				(xy 0.4572 1.397) (xy 0.4572 1.8669)
			)
			(stroke
				(width 0)
				(type default)
			)
			(fill no)
			(layer "F.CrtYd")
		)
		(fp_poly
			(pts
				(xy -1.4097 2.8448) (xy -1.4097 -2.8448) (xy 1.4097 -2.8448) (xy 1.4097 1.3716) (xy 0.9017 1.3716)
				(xy 0.9017 -1.397) (xy 0.4572 -1.397) (xy 0.4572 -1.8669) (xy -0.4572 -1.8669) (xy -0.4572 -1.397)
				(xy -0.9017 -1.397) (xy -0.9017 1.397) (xy -0.4572 1.397) (xy -0.4572 1.8669) (xy 0.4572 1.8669)
				(xy 0.4572 1.397) (xy 0.9017 1.397) (xy 0.9017 1.3843) (xy 1.4097 1.3843) (xy 1.4097 2.8448)
			)
			(stroke
				(width 0)
				(type default)
			)
			(fill no)
			(layer "F.CrtYd")
		)
		(fp_rect
			(start -1.4097 2.8448)
			(end 1.4097 -2.8448)
			(stroke
				(width 0)
				(type default)
			)
			(fill no)
			(layer "F.Fab")
		)
		(pad "A" smd rect
			(at 0 -1.75768 180)
			(size 1.143 1.4986)
			(layers "F.Cu" "F.Mask" "F.Paste")
			(net "GND")
		)
		(pad "K" smd rect
			(at 0 1.75768 180)
			(size 1.143 1.4986)
			(layers "F.Cu" "F.Mask" "F.Paste")
			(net "P12V_PCIE")
		)
	)
	(footprint ""
		(layer "F.Cu")
		(at 6.300216 -215.82888 -90)
		(property "Reference" "R622"
			(at 0 0 270)
			(layer "F.SilkS")
			(hide yes)
			(effects
				(font
					(size 1.27 1.27)
				)
			)
		)
		(property "Value" "10KR2F-2-GP"
			(at 0.064008 -3.993896 270)
			(unlocked yes)
			(layer "F.Fab")
			(hide yes)
			(effects
				(font
					(size 1.016 1.016)
					(thickness 0.1524)
				)
			)
		)
		(property "Device Type" "R402H16"
			(at 0.064008 -5.517896 270)
			(unlocked yes)
			(layer "F.Fab")
			(hide yes)
			(effects
				(font
					(size 1.016 1.016)
					(thickness 0.1524)
				)
			)
		)
		(duplicate_pad_numbers_are_jumpers no)
		(fp_line
			(start -0.508 -0.9398)
			(end -0.508 0.9398)
			(stroke
				(width 0.1524)
				(type default)
			)
			(layer "F.SilkS")
		)
		(fp_line
			(start 0.508 -0.9398)
			(end -0.508 -0.9398)
			(stroke
				(width 0.1524)
				(type default)
			)
			(layer "F.SilkS")
		)
		(fp_rect
			(start -0.508 0.9398)
			(end 0.508 -0.9398)
			(stroke
				(width 0)
				(type default)
			)
			(fill no)
			(layer "F.CrtYd")
		)
		(fp_rect
			(start -0.508 0.9398)
			(end 0.508 -0.9398)
			(stroke
				(width 0)
				(type default)
			)
			(fill no)
			(layer "F.Fab")
		)
		(pad "1" smd custom
			(at 0 -0.4445 270)
			(size 0.1397 0.1397)
			(layers "F.Cu" "F.Mask" "F.Paste")
			(net "PRSNT_AND_3")
			(options
				(clearance outline)
				(anchor circle)
			)
			(primitives
				(gr_poly
					(pts
						(arc
							(start -0.1778 -0.2794)
							(mid -0.249642 -0.249642)
							(end -0.2794 -0.1778)
						)
						(arc
							(start -0.2794 0.1778)
							(mid -0.249642 0.249642)
							(end -0.1778 0.2794)
						)
						(arc
							(start 0.1778 0.2794)
							(mid 0.249642 0.249642)
							(end 0.2794 0.1778)
						)
						(arc
							(start 0.2794 -0.1778)
							(mid 0.249642 -0.249642)
							(end 0.1778 -0.2794)
						)
					)
					(width 0)
					(fill yes)
				)
			)
		)
		(pad "2" smd custom
			(at 0 0.4445 270)
			(size 0.1397 0.1397)
			(layers "F.Cu" "F.Mask" "F.Paste")
			(net "P3V3_STBY")
			(options
				(clearance outline)
				(anchor circle)
			)
			(primitives
				(gr_poly
					(pts
						(arc
							(start -0.1778 -0.2794)
							(mid -0.249642 -0.249642)
							(end -0.2794 -0.1778)
						)
						(arc
							(start -0.2794 0.1778)
							(mid -0.249642 0.249642)
							(end -0.1778 0.2794)
						)
						(arc
							(start 0.1778 0.2794)
							(mid 0.249642 0.249642)
							(end 0.2794 0.1778)
						)
						(arc
							(start 0.2794 -0.1778)
							(mid 0.249642 -0.249642)
							(end 0.1778 -0.2794)
						)
					)
					(width 0)
					(fill yes)
				)
			)
		)
	)
	(footprint ""
		(layer "F.Cu")
		(at 280.162 -161.544)
		(property "Reference" "R233"
			(at 0 0 0)
			(layer "F.SilkS")
			(hide yes)
			(effects
				(font
					(size 1.27 1.27)
				)
			)
		)
		(property "Value" "100KR2F-L1-GP"
			(at 0.064008 -3.993896 0)
			(unlocked yes)
			(layer "F.Fab")
			(hide yes)
			(effects
				(font
					(size 1.016 1.016)
					(thickness 0.1524)
				)
			)
		)
		(property "Device Type" "R402H16"
			(at 0.064008 -5.517896 0)
			(unlocked yes)
			(layer "F.Fab")
			(hide yes)
			(effects
				(font
					(size 1.016 1.016)
					(thickness 0.1524)
				)
			)
		)
		(duplicate_pad_numbers_are_jumpers no)
		(fp_line
			(start -0.508 -0.9398)
			(end -0.508 0.9398)
			(stroke
				(width 0.1524)
				(type default)
			)
			(layer "F.SilkS")
		)
		(fp_line
			(start 0.508 -0.9398)
			(end -0.508 -0.9398)
			(stroke
				(width 0.1524)
				(type default)
			)
			(layer "F.SilkS")
		)
		(fp_rect
			(start -0.508 0.9398)
			(end 0.508 -0.9398)
			(stroke
				(width 0)
				(type default)
			)
			(fill no)
			(layer "F.CrtYd")
		)
		(fp_rect
			(start -0.508 0.9398)
			(end 0.508 -0.9398)
			(stroke
				(width 0)
				(type default)
			)
			(fill no)
			(layer "F.Fab")
		)
		(pad "1" smd custom
			(at 0 -0.4445)
			(size 0.1397 0.1397)
			(layers "F.Cu" "F.Mask" "F.Paste")
			(net "TP_LPC_CPU_CLKOUT0")
			(options
				(clearance outline)
				(anchor circle)
			)
			(primitives
				(gr_poly
					(pts
						(arc
							(start -0.1778 -0.2794)
							(mid -0.249642 -0.249642)
							(end -0.2794 -0.1778)
						)
						(arc
							(start -0.2794 0.1778)
							(mid -0.249642 0.249642)
							(end -0.1778 0.2794)
						)
						(arc
							(start 0.1778 0.2794)
							(mid 0.249642 0.249642)
							(end 0.2794 0.1778)
						)
						(arc
							(start 0.2794 -0.1778)
							(mid 0.249642 -0.249642)
							(end 0.1778 -0.2794)
						)
					)
					(width 0)
					(fill yes)
				)
			)
		)
		(pad "2" smd custom
			(at 0 0.4445)
			(size 0.1397 0.1397)
			(layers "F.Cu" "F.Mask" "F.Paste")
			(net "GND")
			(options
				(clearance outline)
				(anchor circle)
			)
			(primitives
				(gr_poly
					(pts
						(arc
							(start -0.1778 -0.2794)
							(mid -0.249642 -0.249642)
							(end -0.2794 -0.1778)
						)
						(arc
							(start -0.2794 0.1778)
							(mid -0.249642 0.249642)
							(end -0.1778 0.2794)
						)
						(arc
							(start 0.1778 0.2794)
							(mid 0.249642 0.249642)
							(end 0.2794 0.1778)
						)
						(arc
							(start 0.2794 -0.1778)
							(mid 0.249642 -0.249642)
							(end 0.1778 -0.2794)
						)
					)
					(width 0)
					(fill yes)
				)
			)
		)
	)
	(footprint ""
		(layer "F.Cu")
		(at 326.39 -168.021)
		(property "Reference" "R289"
			(at 0 0 0)
			(layer "F.SilkS")
			(hide yes)
			(effects
				(font
					(size 1.27 1.27)
				)
			)
		)
		(property "Value" "10KR2F-2-GP"
			(at 0.064008 -3.993896 0)
			(unlocked yes)
			(layer "F.Fab")
			(hide yes)
			(effects
				(font
					(size 1.016 1.016)
					(thickness 0.1524)
				)
			)
		)
		(property "Device Type" "R402H16"
			(at 0.064008 -5.517896 0)
			(unlocked yes)
			(layer "F.Fab")
			(hide yes)
			(effects
				(font
					(size 1.016 1.016)
					(thickness 0.1524)
				)
			)
		)
		(duplicate_pad_numbers_are_jumpers no)
		(fp_line
			(start -0.508 -0.9398)
			(end -0.508 0.9398)
			(stroke
				(width 0.1524)
				(type default)
			)
			(layer "F.SilkS")
		)
		(fp_line
			(start 0.508 -0.9398)
			(end -0.508 -0.9398)
			(stroke
				(width 0.1524)
				(type default)
			)
			(layer "F.SilkS")
		)
		(fp_rect
			(start -0.508 0.9398)
			(end 0.508 -0.9398)
			(stroke
				(width 0)
				(type default)
			)
			(fill no)
			(layer "F.CrtYd")
		)
		(fp_rect
			(start -0.508 0.9398)
			(end 0.508 -0.9398)
			(stroke
				(width 0)
				(type default)
			)
			(fill no)
			(layer "F.Fab")
		)
		(pad "1" smd custom
			(at 0 -0.4445)
			(size 0.1397 0.1397)
			(layers "F.Cu" "F.Mask" "F.Paste")
			(net "P3V3_STBY")
			(options
				(clearance outline)
				(anchor circle)
			)
			(primitives
				(gr_poly
					(pts
						(arc
							(start -0.1778 -0.2794)
							(mid -0.249642 -0.249642)
							(end -0.2794 -0.1778)
						)
						(arc
							(start -0.2794 0.1778)
							(mid -0.249642 0.249642)
							(end -0.1778 0.2794)
						)
						(arc
							(start 0.1778 0.2794)
							(mid 0.249642 0.249642)
							(end 0.2794 0.1778)
						)
						(arc
							(start 0.2794 -0.1778)
							(mid 0.249642 -0.249642)
							(end 0.1778 -0.2794)
						)
					)
					(width 0)
					(fill yes)
				)
			)
		)
		(pad "2" smd custom
			(at 0 0.4445)
			(size 0.1397 0.1397)
			(layers "F.Cu" "F.Mask" "F.Paste")
			(net "BMC_UART_SWITCH_1R")
			(options
				(clearance outline)
				(anchor circle)
			)
			(primitives
				(gr_poly
					(pts
						(arc
							(start -0.1778 -0.2794)
							(mid -0.249642 -0.249642)
							(end -0.2794 -0.1778)
						)
						(arc
							(start -0.2794 0.1778)
							(mid -0.249642 0.249642)
							(end -0.1778 0.2794)
						)
						(arc
							(start 0.1778 0.2794)
							(mid 0.249642 0.249642)
							(end 0.2794 0.1778)
						)
						(arc
							(start 0.2794 -0.1778)
							(mid 0.249642 -0.249642)
							(end 0.1778 -0.2794)
						)
					)
					(width 0)
					(fill yes)
				)
			)
		)
	)
	(footprint ""
		(layer "F.Cu")
		(at 266.065 -177.038 90)
		(property "Reference" "R369"
			(at 0 0 90)
			(layer "F.SilkS")
			(hide yes)
			(effects
				(font
					(size 1.27 1.27)
				)
			)
		)
		(property "Value" "3K3R2F-2-GP"
			(at 0.064008 -3.993896 90)
			(unlocked yes)
			(layer "F.Fab")
			(hide yes)
			(effects
				(font
					(size 1.016 1.016)
					(thickness 0.1524)
				)
			)
		)
		(property "Device Type" "R402H16"
			(at 0.064008 -5.517896 90)
			(unlocked yes)
			(layer "F.Fab")
			(hide yes)
			(effects
				(font
					(size 1.016 1.016)
					(thickness 0.1524)
				)
			)
		)
		(duplicate_pad_numbers_are_jumpers no)
		(fp_line
			(start 0.508 -0.9398)
			(end -0.508 -0.9398)
			(stroke
				(width 0.1524)
				(type default)
			)
			(layer "F.SilkS")
		)
		(fp_line
			(start -0.508 -0.9398)
			(end -0.508 0.9398)
			(stroke
				(width 0.1524)
				(type default)
			)
			(layer "F.SilkS")
		)
		(fp_rect
			(start -0.508 0.9398)
			(end 0.508 -0.9398)
			(stroke
				(width 0)
				(type default)
			)
			(fill no)
			(layer "F.CrtYd")
		)
		(fp_rect
			(start -0.508 0.9398)
			(end 0.508 -0.9398)
			(stroke
				(width 0)
				(type default)
			)
			(fill no)
			(layer "F.Fab")
		)
		(pad "1" smd custom
			(at 0 -0.4445 90)
			(size 0.1397 0.1397)
			(layers "F.Cu" "F.Mask" "F.Paste")
			(net "P3V3_STBY")
			(options
				(clearance outline)
				(anchor circle)
			)
			(primitives
				(gr_poly
					(pts
						(arc
							(start -0.1778 -0.2794)
							(mid -0.249642 -0.249642)
							(end -0.2794 -0.1778)
						)
						(arc
							(start -0.2794 0.1778)
							(mid -0.249642 0.249642)
							(end -0.1778 0.2794)
						)
						(arc
							(start 0.1778 0.2794)
							(mid 0.249642 0.249642)
							(end 0.2794 0.1778)
						)
						(arc
							(start 0.2794 -0.1778)
							(mid 0.249642 -0.249642)
							(end 0.1778 -0.2794)
						)
					)
					(width 0)
					(fill yes)
				)
			)
		)
		(pad "2" smd custom
			(at 0 0.4445 90)
			(size 0.1397 0.1397)
			(layers "F.Cu" "F.Mask" "F.Paste")
			(net "ROMA23")
			(options
				(clearance outline)
				(anchor circle)
			)
			(primitives
				(gr_poly
					(pts
						(arc
							(start -0.1778 -0.2794)
							(mid -0.249642 -0.249642)
							(end -0.2794 -0.1778)
						)
						(arc
							(start -0.2794 0.1778)
							(mid -0.249642 0.249642)
							(end -0.1778 0.2794)
						)
						(arc
							(start 0.1778 0.2794)
							(mid 0.249642 0.249642)
							(end 0.2794 0.1778)
						)
						(arc
							(start 0.2794 -0.1778)
							(mid 0.249642 -0.249642)
							(end 0.1778 -0.2794)
						)
					)
					(width 0)
					(fill yes)
				)
			)
		)
	)
	(footprint ""
		(layer "F.Cu")
		(at 98.18497 -84.582)
		(property "Reference" "STP100"
			(at 0 0 0)
			(layer "F.SilkS")
			(hide yes)
			(effects
				(font
					(size 1.27 1.27)
				)
			)
		)
		(property "Value" "TPAD28"
			(at 0.0127 -1.8034 0)
			(unlocked yes)
			(layer "F.Fab")
			(hide yes)
			(effects
				(font
					(size 1.016 1.016)
					(thickness 0.1524)
				)
			)
		)
		(property "Device Type" "TPAD28"
			(at 0.0127 -3.3274 0)
			(unlocked yes)
			(layer "F.Fab")
			(hide yes)
			(effects
				(font
					(size 1.016 1.016)
					(thickness 0.1524)
				)
			)
		)
		(duplicate_pad_numbers_are_jumpers no)
		(fp_poly
			(pts
				(arc
					(start 0.3556 0)
					(mid -0.3556 0)
					(end 0.3556 0)
				)
			)
			(stroke
				(width 0)
				(type default)
			)
			(fill no)
			(layer "F.CrtYd")
		)
		(fp_poly
			(pts
				(arc
					(start 0.6096 0)
					(mid -0.6096 0)
					(end 0.6096 0)
				)
			)
			(stroke
				(width 0)
				(type default)
			)
			(fill no)
			(layer "F.Fab")
		)
		(pad "1" smd circle
			(at 0 0)
			(size 0.7112 0.7112)
			(layers "F.Cu" "F.Mask" "F.Paste")
			(net "LSI_T_N")
		)
	)
	(footprint ""
		(layer "F.Cu")
		(at 87.757 -223.139 -90)
		(property "Reference" "SR839"
			(at 0 0 270)
			(layer "F.SilkS")
			(hide yes)
			(effects
				(font
					(size 1.27 1.27)
				)
			)
		)
		(property "Value" "4K7R2F-GP"
			(at 0.064008 -3.993896 270)
			(unlocked yes)
			(layer "F.Fab")
			(hide yes)
			(effects
				(font
					(size 1.016 1.016)
					(thickness 0.1524)
				)
			)
		)
		(property "Device Type" "R402H16"
			(at 0.064008 -5.517896 270)
			(unlocked yes)
			(layer "F.Fab")
			(hide yes)
			(effects
				(font
					(size 1.016 1.016)
					(thickness 0.1524)
				)
			)
		)
		(duplicate_pad_numbers_are_jumpers no)
		(fp_line
			(start -0.508 -0.9398)
			(end -0.508 0.9398)
			(stroke
				(width 0.1524)
				(type default)
			)
			(layer "F.SilkS")
		)
		(fp_line
			(start 0.508 -0.9398)
			(end -0.508 -0.9398)
			(stroke
				(width 0.1524)
				(type default)
			)
			(layer "F.SilkS")
		)
		(fp_rect
			(start -0.508 0.9398)
			(end 0.508 -0.9398)
			(stroke
				(width 0)
				(type default)
			)
			(fill no)
			(layer "F.CrtYd")
		)
		(fp_rect
			(start -0.508 0.9398)
			(end 0.508 -0.9398)
			(stroke
				(width 0)
				(type default)
			)
			(fill no)
			(layer "F.Fab")
		)
		(pad "1" smd custom
			(at 0 -0.4445 270)
			(size 0.1397 0.1397)
			(layers "F.Cu" "F.Mask" "F.Paste")
			(net "EXP_SDA_L_0")
			(options
				(clearance outline)
				(anchor circle)
			)
			(primitives
				(gr_poly
					(pts
						(arc
							(start -0.1778 -0.2794)
							(mid -0.249642 -0.249642)
							(end -0.2794 -0.1778)
						)
						(arc
							(start -0.2794 0.1778)
							(mid -0.249642 0.249642)
							(end -0.1778 0.2794)
						)
						(arc
							(start 0.1778 0.2794)
							(mid 0.249642 0.249642)
							(end 0.2794 0.1778)
						)
						(arc
							(start 0.2794 -0.1778)
							(mid 0.249642 -0.249642)
							(end 0.1778 -0.2794)
						)
					)
					(width 0)
					(fill yes)
				)
			)
		)
		(pad "2" smd custom
			(at 0 0.4445 270)
			(size 0.1397 0.1397)
			(layers "F.Cu" "F.Mask" "F.Paste")
			(net "P3V3_STBY")
			(options
				(clearance outline)
				(anchor circle)
			)
			(primitives
				(gr_poly
					(pts
						(arc
							(start -0.1778 -0.2794)
							(mid -0.249642 -0.249642)
							(end -0.2794 -0.1778)
						)
						(arc
							(start -0.2794 0.1778)
							(mid -0.249642 0.249642)
							(end -0.1778 0.2794)
						)
						(arc
							(start 0.1778 0.2794)
							(mid 0.249642 0.249642)
							(end 0.2794 0.1778)
						)
						(arc
							(start 0.2794 -0.1778)
							(mid 0.249642 -0.249642)
							(end 0.1778 -0.2794)
						)
					)
					(width 0)
					(fill yes)
				)
			)
		)
	)
	(footprint ""
		(layer "F.Cu")
		(at 141.986 -38.862 180)
		(property "Reference" "SR692"
			(at 0 0 180)
			(layer "F.SilkS")
			(hide yes)
			(effects
				(font
					(size 1.27 1.27)
				)
			)
		)
		(property "Value" "10KR2F-2-GP"
			(at 0.064008 -3.993896 180)
			(unlocked yes)
			(layer "F.Fab")
			(hide yes)
			(effects
				(font
					(size 1.016 1.016)
					(thickness 0.1524)
				)
			)
		)
		(property "Device Type" "R402H16"
			(at 0.064008 -5.517896 180)
			(unlocked yes)
			(layer "F.Fab")
			(hide yes)
			(effects
				(font
					(size 1.016 1.016)
					(thickness 0.1524)
				)
			)
		)
		(duplicate_pad_numbers_are_jumpers no)
		(fp_line
			(start 0.508 -0.9398)
			(end -0.508 -0.9398)
			(stroke
				(width 0.1524)
				(type default)
			)
			(layer "F.SilkS")
		)
		(fp_line
			(start -0.508 -0.9398)
			(end -0.508 0.9398)
			(stroke
				(width 0.1524)
				(type default)
			)
			(layer "F.SilkS")
		)
		(fp_rect
			(start -0.508 0.9398)
			(end 0.508 -0.9398)
			(stroke
				(width 0)
				(type default)
			)
			(fill no)
			(layer "F.CrtYd")
		)
		(fp_rect
			(start -0.508 0.9398)
			(end 0.508 -0.9398)
			(stroke
				(width 0)
				(type default)
			)
			(fill no)
			(layer "F.Fab")
		)
		(pad "1" smd custom
			(at 0 -0.4445 180)
			(size 0.1397 0.1397)
			(layers "F.Cu" "F.Mask" "F.Paste")
			(net "P1V8_C")
			(options
				(clearance outline)
				(anchor circle)
			)
			(primitives
				(gr_poly
					(pts
						(arc
							(start -0.1778 -0.2794)
							(mid -0.249642 -0.249642)
							(end -0.2794 -0.1778)
						)
						(arc
							(start -0.2794 0.1778)
							(mid -0.249642 0.249642)
							(end -0.1778 0.2794)
						)
						(arc
							(start 0.1778 0.2794)
							(mid 0.249642 0.249642)
							(end 0.2794 0.1778)
						)
						(arc
							(start 0.2794 -0.1778)
							(mid 0.249642 -0.249642)
							(end 0.1778 -0.2794)
						)
					)
					(width 0)
					(fill yes)
				)
			)
		)
		(pad "2" smd custom
			(at 0 0.4445 180)
			(size 0.1397 0.1397)
			(layers "F.Cu" "F.Mask" "F.Paste")
			(net "XM_ADDR_22")
			(options
				(clearance outline)
				(anchor circle)
			)
			(primitives
				(gr_poly
					(pts
						(arc
							(start -0.1778 -0.2794)
							(mid -0.249642 -0.249642)
							(end -0.2794 -0.1778)
						)
						(arc
							(start -0.2794 0.1778)
							(mid -0.249642 0.249642)
							(end -0.1778 0.2794)
						)
						(arc
							(start 0.1778 0.2794)
							(mid 0.249642 0.249642)
							(end 0.2794 0.1778)
						)
						(arc
							(start 0.2794 -0.1778)
							(mid 0.249642 -0.249642)
							(end 0.1778 -0.2794)
						)
					)
					(width 0)
					(fill yes)
				)
			)
		)
	)
	(footprint ""
		(layer "F.Cu")
		(at 303.318672 -67.07124 -90)
		(property "Reference" "R270"
			(at 0 0 270)
			(layer "F.SilkS")
			(hide yes)
			(effects
				(font
					(size 1.27 1.27)
				)
			)
		)
		(property "Value" "0R2J-2-GP"
			(at 0.064008 -3.993896 270)
			(unlocked yes)
			(layer "F.Fab")
			(hide yes)
			(effects
				(font
					(size 1.016 1.016)
					(thickness 0.1524)
				)
			)
		)
		(property "Device Type" "R402H16"
			(at 0.064008 -5.517896 270)
			(unlocked yes)
			(layer "F.Fab")
			(hide yes)
			(effects
				(font
					(size 1.016 1.016)
					(thickness 0.1524)
				)
			)
		)
		(duplicate_pad_numbers_are_jumpers no)
		(fp_line
			(start -0.508 -0.9398)
			(end -0.508 0.9398)
			(stroke
				(width 0.1524)
				(type default)
			)
			(layer "F.SilkS")
		)
		(fp_line
			(start 0.508 -0.9398)
			(end -0.508 -0.9398)
			(stroke
				(width 0.1524)
				(type default)
			)
			(layer "F.SilkS")
		)
		(fp_rect
			(start -0.508 0.9398)
			(end 0.508 -0.9398)
			(stroke
				(width 0)
				(type default)
			)
			(fill no)
			(layer "F.CrtYd")
		)
		(fp_rect
			(start -0.508 0.9398)
			(end 0.508 -0.9398)
			(stroke
				(width 0)
				(type default)
			)
			(fill no)
			(layer "F.Fab")
		)
		(pad "1" smd custom
			(at 0 -0.4445 270)
			(size 0.1397 0.1397)
			(layers "F.Cu" "F.Mask" "F.Paste")
			(net "PCIE_10G_REFCLK_P")
			(options
				(clearance outline)
				(anchor circle)
			)
			(primitives
				(gr_poly
					(pts
						(arc
							(start -0.1778 -0.2794)
							(mid -0.249642 -0.249642)
							(end -0.2794 -0.1778)
						)
						(arc
							(start -0.2794 0.1778)
							(mid -0.249642 0.249642)
							(end -0.1778 0.2794)
						)
						(arc
							(start 0.1778 0.2794)
							(mid 0.249642 0.249642)
							(end 0.2794 0.1778)
						)
						(arc
							(start 0.2794 -0.1778)
							(mid 0.249642 -0.249642)
							(end 0.1778 -0.2794)
						)
					)
					(width 0)
					(fill yes)
				)
			)
		)
		(pad "2" smd custom
			(at 0 0.4445 270)
			(size 0.1397 0.1397)
			(layers "F.Cu" "F.Mask" "F.Paste")
			(net "CLK_100M_CLKBUFF_ENET1_DP")
			(options
				(clearance outline)
				(anchor circle)
			)
			(primitives
				(gr_poly
					(pts
						(arc
							(start -0.1778 -0.2794)
							(mid -0.249642 -0.249642)
							(end -0.2794 -0.1778)
						)
						(arc
							(start -0.2794 0.1778)
							(mid -0.249642 0.249642)
							(end -0.1778 0.2794)
						)
						(arc
							(start 0.1778 0.2794)
							(mid 0.249642 0.249642)
							(end 0.2794 0.1778)
						)
						(arc
							(start 0.2794 -0.1778)
							(mid 0.249642 -0.249642)
							(end 0.1778 -0.2794)
						)
					)
					(width 0)
					(fill yes)
				)
			)
		)
	)
	(footprint ""
		(layer "F.Cu")
		(at 38.354 -215.392 90)
		(property "Reference" "SC1286"
			(at 0 0 90)
			(layer "F.SilkS")
			(hide yes)
			(effects
				(font
					(size 1.27 1.27)
				)
			)
		)
		(property "Value" "SCD1U16V2KX-3GP"
			(at 1.1811 -2.7051 90)
			(unlocked yes)
			(layer "F.Fab")
			(hide yes)
			(effects
				(font
					(size 1.016 1.016)
					(thickness 0.1524)
				)
			)
		)
		(property "Device Type" "C402H22"
			(at 1.1811 -4.2291 90)
			(unlocked yes)
			(layer "F.Fab")
			(hide yes)
			(effects
				(font
					(size 1.016 1.016)
					(thickness 0.1524)
				)
			)
		)
		(duplicate_pad_numbers_are_jumpers no)
		(fp_rect
			(start -0.4318 0.9525)
			(end 0.4318 -0.9525)
			(stroke
				(width 0)
				(type default)
			)
			(fill no)
			(layer "F.CrtYd")
		)
		(fp_rect
			(start -0.4318 0.9525)
			(end 0.4318 -0.9525)
			(stroke
				(width 0)
				(type default)
			)
			(fill no)
			(layer "F.Fab")
		)
		(pad "1" smd custom
			(at 0 -0.4445 90)
			(size 0.1524 0.1524)
			(layers "F.Cu" "F.Mask" "F.Paste")
			(net "EXP_I2C_VREF_4")
			(options
				(clearance outline)
				(anchor circle)
			)
			(primitives
				(gr_poly
					(pts
						(arc
							(start 0.3048 -0.2032)
							(mid 0.275042 -0.275042)
							(end 0.2032 -0.3048)
						)
						(arc
							(start -0.2032 -0.3048)
							(mid -0.275042 -0.275042)
							(end -0.3048 -0.2032)
						)
						(arc
							(start -0.3048 0.2032)
							(mid -0.275042 0.275042)
							(end -0.2032 0.3048)
						)
						(arc
							(start 0.2032 0.3048)
							(mid 0.275042 0.275042)
							(end 0.3048 0.2032)
						)
					)
					(width 0)
					(fill yes)
				)
			)
		)
		(pad "2" smd custom
			(at 0 0.4445 90)
			(size 0.1524 0.1524)
			(layers "F.Cu" "F.Mask" "F.Paste")
			(net "GND")
			(options
				(clearance outline)
				(anchor circle)
			)
			(primitives
				(gr_poly
					(pts
						(arc
							(start 0.3048 -0.2032)
							(mid 0.275042 -0.275042)
							(end 0.2032 -0.3048)
						)
						(arc
							(start -0.2032 -0.3048)
							(mid -0.275042 -0.275042)
							(end -0.3048 -0.2032)
						)
						(arc
							(start -0.3048 0.2032)
							(mid -0.275042 0.275042)
							(end -0.2032 0.3048)
						)
						(arc
							(start 0.2032 0.3048)
							(mid 0.275042 0.275042)
							(end 0.3048 0.2032)
						)
					)
					(width 0)
					(fill yes)
				)
			)
		)
	)
	(footprint ""
		(layer "F.Cu")
		(at 306.578 -183.007)
		(property "Reference" "TP174"
			(at 0 0 0)
			(layer "F.SilkS")
			(hide yes)
			(effects
				(font
					(size 1.27 1.27)
				)
			)
		)
		(property "Value" "TPAD28"
			(at 0.0127 -1.8034 0)
			(unlocked yes)
			(layer "F.Fab")
			(hide yes)
			(effects
				(font
					(size 1.016 1.016)
					(thickness 0.1524)
				)
			)
		)
		(property "Device Type" "TPAD28"
			(at 0.0127 -3.3274 0)
			(unlocked yes)
			(layer "F.Fab")
			(hide yes)
			(effects
				(font
					(size 1.016 1.016)
					(thickness 0.1524)
				)
			)
		)
		(duplicate_pad_numbers_are_jumpers no)
		(fp_poly
			(pts
				(arc
					(start 0.3556 0)
					(mid -0.3556 0)
					(end 0.3556 0)
				)
			)
			(stroke
				(width 0)
				(type default)
			)
			(fill no)
			(layer "F.CrtYd")
		)
		(fp_poly
			(pts
				(arc
					(start 0.6096 0)
					(mid -0.6096 0)
					(end 0.6096 0)
				)
			)
			(stroke
				(width 0)
				(type default)
			)
			(fill no)
			(layer "F.Fab")
		)
		(pad "1" smd circle
			(at 0 0)
			(size 0.7112 0.7112)
			(layers "F.Cu" "F.Mask" "F.Paste")
			(net "TP_BMC_GPIOM2")
		)
	)
	(footprint ""
		(layer "F.Cu")
		(at 38.989 -172.847 180)
		(property "Reference" "SR1275"
			(at 0 0 180)
			(layer "F.SilkS")
			(hide yes)
			(effects
				(font
					(size 1.27 1.27)
				)
			)
		)
		(property "Value" "10KR2F-2-GP"
			(at 0.064008 -3.993896 180)
			(unlocked yes)
			(layer "F.Fab")
			(hide yes)
			(effects
				(font
					(size 1.016 1.016)
					(thickness 0.1524)
				)
			)
		)
		(property "Device Type" "R402H16"
			(at 0.064008 -5.517896 180)
			(unlocked yes)
			(layer "F.Fab")
			(hide yes)
			(effects
				(font
					(size 1.016 1.016)
					(thickness 0.1524)
				)
			)
		)
		(duplicate_pad_numbers_are_jumpers no)
		(fp_line
			(start 0.508 -0.9398)
			(end -0.508 -0.9398)
			(stroke
				(width 0.1524)
				(type default)
			)
			(layer "F.SilkS")
		)
		(fp_line
			(start -0.508 -0.9398)
			(end -0.508 0.9398)
			(stroke
				(width 0.1524)
				(type default)
			)
			(layer "F.SilkS")
		)
		(fp_rect
			(start -0.508 0.9398)
			(end 0.508 -0.9398)
			(stroke
				(width 0)
				(type default)
			)
			(fill no)
			(layer "F.CrtYd")
		)
		(fp_rect
			(start -0.508 0.9398)
			(end 0.508 -0.9398)
			(stroke
				(width 0)
				(type default)
			)
			(fill no)
			(layer "F.Fab")
		)
		(pad "1" smd custom
			(at 0 -0.4445 180)
			(size 0.1397 0.1397)
			(layers "F.Cu" "F.Mask" "F.Paste")
			(net "P3V3_STBY_R7")
			(options
				(clearance outline)
				(anchor circle)
			)
			(primitives
				(gr_poly
					(pts
						(arc
							(start -0.1778 -0.2794)
							(mid -0.249642 -0.249642)
							(end -0.2794 -0.1778)
						)
						(arc
							(start -0.2794 0.1778)
							(mid -0.249642 0.249642)
							(end -0.1778 0.2794)
						)
						(arc
							(start 0.1778 0.2794)
							(mid 0.249642 0.249642)
							(end 0.2794 0.1778)
						)
						(arc
							(start 0.2794 -0.1778)
							(mid 0.249642 -0.249642)
							(end 0.1778 -0.2794)
						)
					)
					(width 0)
					(fill yes)
				)
			)
		)
		(pad "2" smd custom
			(at 0 0.4445 180)
			(size 0.1397 0.1397)
			(layers "F.Cu" "F.Mask" "F.Paste")
			(net "P3V3_STBY_G7")
			(options
				(clearance outline)
				(anchor circle)
			)
			(primitives
				(gr_poly
					(pts
						(arc
							(start -0.1778 -0.2794)
							(mid -0.249642 -0.249642)
							(end -0.2794 -0.1778)
						)
						(arc
							(start -0.2794 0.1778)
							(mid -0.249642 0.249642)
							(end -0.1778 0.2794)
						)
						(arc
							(start 0.1778 0.2794)
							(mid 0.249642 0.249642)
							(end 0.2794 0.1778)
						)
						(arc
							(start 0.2794 -0.1778)
							(mid 0.249642 -0.249642)
							(end 0.1778 -0.2794)
						)
					)
					(width 0)
					(fill yes)
				)
			)
		)
	)
	(footprint ""
		(layer "F.Cu")
		(at 117.856 -72.771 -90)
		(property "Reference" "R5313"
			(at 0 0 270)
			(layer "F.SilkS")
			(hide yes)
			(effects
				(font
					(size 1.27 1.27)
				)
			)
		)
		(property "Value" "0R2J-2-GP"
			(at 0.064008 -3.993896 270)
			(unlocked yes)
			(layer "F.Fab")
			(hide yes)
			(effects
				(font
					(size 1.016 1.016)
					(thickness 0.1524)
				)
			)
		)
		(property "Device Type" "R402H16"
			(at 0.064008 -5.517896 270)
			(unlocked yes)
			(layer "F.Fab")
			(hide yes)
			(effects
				(font
					(size 1.016 1.016)
					(thickness 0.1524)
				)
			)
		)
		(duplicate_pad_numbers_are_jumpers no)
		(fp_line
			(start -0.508 -0.9398)
			(end -0.508 0.9398)
			(stroke
				(width 0.1524)
				(type default)
			)
			(layer "F.SilkS")
		)
		(fp_line
			(start 0.508 -0.9398)
			(end -0.508 -0.9398)
			(stroke
				(width 0.1524)
				(type default)
			)
			(layer "F.SilkS")
		)
		(fp_rect
			(start -0.508 0.9398)
			(end 0.508 -0.9398)
			(stroke
				(width 0)
				(type default)
			)
			(fill no)
			(layer "F.CrtYd")
		)
		(fp_rect
			(start -0.508 0.9398)
			(end 0.508 -0.9398)
			(stroke
				(width 0)
				(type default)
			)
			(fill no)
			(layer "F.Fab")
		)
		(pad "1" smd custom
			(at 0 -0.4445 270)
			(size 0.1397 0.1397)
			(layers "F.Cu" "F.Mask" "F.Paste")
			(net "BMC_I2C_SCL_10")
			(options
				(clearance outline)
				(anchor circle)
			)
			(primitives
				(gr_poly
					(pts
						(arc
							(start -0.1778 -0.2794)
							(mid -0.249642 -0.249642)
							(end -0.2794 -0.1778)
						)
						(arc
							(start -0.2794 0.1778)
							(mid -0.249642 0.249642)
							(end -0.1778 0.2794)
						)
						(arc
							(start 0.1778 0.2794)
							(mid 0.249642 0.249642)
							(end 0.2794 0.1778)
						)
						(arc
							(start 0.2794 -0.1778)
							(mid 0.249642 -0.249642)
							(end 0.1778 -0.2794)
						)
					)
					(width 0)
					(fill yes)
				)
			)
		)
		(pad "2" smd custom
			(at 0 0.4445 270)
			(size 0.1397 0.1397)
			(layers "F.Cu" "F.Mask" "F.Paste")
			(net "TEMP_4_SCL")
			(options
				(clearance outline)
				(anchor circle)
			)
			(primitives
				(gr_poly
					(pts
						(arc
							(start -0.1778 -0.2794)
							(mid -0.249642 -0.249642)
							(end -0.2794 -0.1778)
						)
						(arc
							(start -0.2794 0.1778)
							(mid -0.249642 0.249642)
							(end -0.1778 0.2794)
						)
						(arc
							(start 0.1778 0.2794)
							(mid 0.249642 0.249642)
							(end 0.2794 0.1778)
						)
						(arc
							(start 0.2794 -0.1778)
							(mid 0.249642 -0.249642)
							(end 0.1778 -0.2794)
						)
					)
					(width 0)
					(fill yes)
				)
			)
		)
	)
	(footprint ""
		(layer "F.Cu")
		(at 265.049 -22.733 -90)
		(property "Reference" "PC59"
			(at 0 0 270)
			(layer "F.SilkS")
			(hide yes)
			(effects
				(font
					(size 1.27 1.27)
				)
			)
		)
		(property "Value" "SC100U6D3V6MX-GP"
			(at -0.0762 -5.1308 270)
			(unlocked yes)
			(layer "F.Fab")
			(hide yes)
			(effects
				(font
					(size 1.016 1.016)
					(thickness 0.1524)
				)
			)
		)
		(property "Device Type" "C1206H71"
			(at -0.127 -6.6548 270)
			(unlocked yes)
			(layer "F.Fab")
			(hide yes)
			(effects
				(font
					(size 1.016 1.016)
					(thickness 0.1524)
				)
			)
		)
		(duplicate_pad_numbers_are_jumpers no)
		(fp_line
			(start -1.016 2.2352)
			(end -1.016 0.8382)
			(stroke
				(width 0.1524)
				(type default)
			)
			(layer "F.SilkS")
		)
		(fp_line
			(start 1.016 2.2352)
			(end -1.016 2.2352)
			(stroke
				(width 0.1524)
				(type default)
			)
			(layer "F.SilkS")
		)
		(fp_line
			(start 1.016 0.8382)
			(end 1.016 2.2352)
			(stroke
				(width 0.1524)
				(type default)
			)
			(layer "F.SilkS")
		)
		(fp_line
			(start -1.016 -0.8382)
			(end -1.016 -2.2352)
			(stroke
				(width 0.1524)
				(type default)
			)
			(layer "F.SilkS")
		)
		(fp_line
			(start -1.016 -2.2352)
			(end 1.016 -2.2352)
			(stroke
				(width 0.1524)
				(type default)
			)
			(layer "F.SilkS")
		)
		(fp_line
			(start 1.016 -2.2352)
			(end 1.016 -0.8382)
			(stroke
				(width 0.1524)
				(type default)
			)
			(layer "F.SilkS")
		)
		(fp_rect
			(start -1.0922 2.3114)
			(end 1.0922 -2.3114)
			(stroke
				(width 0)
				(type default)
			)
			(fill no)
			(layer "F.CrtYd")
		)
		(fp_poly
			(pts
				(xy 1.0922 -2.3114) (xy 1.0922 2.3114) (xy -1.0922 2.3114) (xy -1.0922 -2.3114)
			)
			(stroke
				(width 0)
				(type default)
			)
			(fill no)
			(layer "F.Fab")
		)
		(pad "1" smd rect
			(at 0 -1.397 270)
			(size 1.651 1.27)
			(layers "F.Cu" "F.Mask" "F.Paste")
			(net "P1V8_STBY")
		)
		(pad "2" smd rect
			(at 0 1.397 270)
			(size 1.651 1.27)
			(layers "F.Cu" "F.Mask" "F.Paste")
			(net "GND")
		)
	)
	(footprint ""
		(layer "F.Cu")
		(at 201.699876 -146.041872 90)
		(property "Reference" "SR763"
			(at 0 0 90)
			(layer "F.SilkS")
			(hide yes)
			(effects
				(font
					(size 1.27 1.27)
				)
			)
		)
		(property "Value" "4K7R2F-GP"
			(at 0.064008 -3.993896 90)
			(unlocked yes)
			(layer "F.Fab")
			(hide yes)
			(effects
				(font
					(size 1.016 1.016)
					(thickness 0.1524)
				)
			)
		)
		(property "Device Type" "R402H16"
			(at 0.064008 -5.517896 90)
			(unlocked yes)
			(layer "F.Fab")
			(hide yes)
			(effects
				(font
					(size 1.016 1.016)
					(thickness 0.1524)
				)
			)
		)
		(duplicate_pad_numbers_are_jumpers no)
		(fp_line
			(start 0.508 -0.9398)
			(end -0.508 -0.9398)
			(stroke
				(width 0.1524)
				(type default)
			)
			(layer "F.SilkS")
		)
		(fp_line
			(start -0.508 -0.9398)
			(end -0.508 0.9398)
			(stroke
				(width 0.1524)
				(type default)
			)
			(layer "F.SilkS")
		)
		(fp_rect
			(start -0.508 0.9398)
			(end 0.508 -0.9398)
			(stroke
				(width 0)
				(type default)
			)
			(fill no)
			(layer "F.CrtYd")
		)
		(fp_rect
			(start -0.508 0.9398)
			(end 0.508 -0.9398)
			(stroke
				(width 0)
				(type default)
			)
			(fill no)
			(layer "F.Fab")
		)
		(pad "1" smd custom
			(at 0 -0.4445 90)
			(size 0.1397 0.1397)
			(layers "F.Cu" "F.Mask" "F.Paste")
			(net "BMC_I2C_SCL_9")
			(options
				(clearance outline)
				(anchor circle)
			)
			(primitives
				(gr_poly
					(pts
						(arc
							(start -0.1778 -0.2794)
							(mid -0.249642 -0.249642)
							(end -0.2794 -0.1778)
						)
						(arc
							(start -0.2794 0.1778)
							(mid -0.249642 0.249642)
							(end -0.1778 0.2794)
						)
						(arc
							(start 0.1778 0.2794)
							(mid 0.249642 0.249642)
							(end 0.2794 0.1778)
						)
						(arc
							(start 0.2794 -0.1778)
							(mid 0.249642 -0.249642)
							(end 0.1778 -0.2794)
						)
					)
					(width 0)
					(fill yes)
				)
			)
		)
		(pad "2" smd custom
			(at 0 0.4445 90)
			(size 0.1397 0.1397)
			(layers "F.Cu" "F.Mask" "F.Paste")
			(net "P3V3_STBY")
			(options
				(clearance outline)
				(anchor circle)
			)
			(primitives
				(gr_poly
					(pts
						(arc
							(start -0.1778 -0.2794)
							(mid -0.249642 -0.249642)
							(end -0.2794 -0.1778)
						)
						(arc
							(start -0.2794 0.1778)
							(mid -0.249642 0.249642)
							(end -0.1778 0.2794)
						)
						(arc
							(start 0.1778 0.2794)
							(mid 0.249642 0.249642)
							(end 0.2794 0.1778)
						)
						(arc
							(start 0.2794 -0.1778)
							(mid 0.249642 -0.249642)
							(end 0.1778 -0.2794)
						)
					)
					(width 0)
					(fill yes)
				)
			)
		)
	)
	(footprint ""
		(layer "F.Cu")
		(at 285.1912 -191.77)
		(property "Reference" "C176"
			(at 0 0 0)
			(layer "F.SilkS")
			(hide yes)
			(effects
				(font
					(size 1.27 1.27)
				)
			)
		)
		(property "Value" "SCD1U16V2KX-3GP"
			(at 1.1811 -2.7051 0)
			(unlocked yes)
			(layer "F.Fab")
			(hide yes)
			(effects
				(font
					(size 1.016 1.016)
					(thickness 0.1524)
				)
			)
		)
		(property "Device Type" "C402H22"
			(at 1.1811 -4.2291 0)
			(unlocked yes)
			(layer "F.Fab")
			(hide yes)
			(effects
				(font
					(size 1.016 1.016)
					(thickness 0.1524)
				)
			)
		)
		(duplicate_pad_numbers_are_jumpers no)
		(fp_rect
			(start -0.4318 0.9525)
			(end 0.4318 -0.9525)
			(stroke
				(width 0)
				(type default)
			)
			(fill no)
			(layer "F.CrtYd")
		)
		(fp_rect
			(start -0.4318 0.9525)
			(end 0.4318 -0.9525)
			(stroke
				(width 0)
				(type default)
			)
			(fill no)
			(layer "F.Fab")
		)
		(pad "1" smd custom
			(at 0 -0.4445)
			(size 0.1524 0.1524)
			(layers "F.Cu" "F.Mask" "F.Paste")
			(net "P1V53_STBY")
			(options
				(clearance outline)
				(anchor circle)
			)
			(primitives
				(gr_poly
					(pts
						(arc
							(start 0.3048 -0.2032)
							(mid 0.275042 -0.275042)
							(end 0.2032 -0.3048)
						)
						(arc
							(start -0.2032 -0.3048)
							(mid -0.275042 -0.275042)
							(end -0.3048 -0.2032)
						)
						(arc
							(start -0.3048 0.2032)
							(mid -0.275042 0.275042)
							(end -0.2032 0.3048)
						)
						(arc
							(start 0.2032 0.3048)
							(mid 0.275042 0.275042)
							(end 0.3048 0.2032)
						)
					)
					(width 0)
					(fill yes)
				)
			)
		)
		(pad "2" smd custom
			(at 0 0.4445)
			(size 0.1524 0.1524)
			(layers "F.Cu" "F.Mask" "F.Paste")
			(net "GND")
			(options
				(clearance outline)
				(anchor circle)
			)
			(primitives
				(gr_poly
					(pts
						(arc
							(start 0.3048 -0.2032)
							(mid 0.275042 -0.275042)
							(end 0.2032 -0.3048)
						)
						(arc
							(start -0.2032 -0.3048)
							(mid -0.275042 -0.275042)
							(end -0.3048 -0.2032)
						)
						(arc
							(start -0.3048 0.2032)
							(mid -0.275042 0.275042)
							(end -0.2032 0.3048)
						)
						(arc
							(start 0.2032 0.3048)
							(mid 0.275042 0.275042)
							(end 0.3048 0.2032)
						)
					)
					(width 0)
					(fill yes)
				)
			)
		)
	)
	(footprint ""
		(layer "F.Cu")
		(at 307.721 -219.837 180)
		(property "Reference" "U44"
			(at 0 0 180)
			(layer "F.SilkS")
			(hide yes)
			(effects
				(font
					(size 1.27 1.27)
				)
			)
		)
		(property "Value" "SN74LVC1G00DC-1GP"
			(at -2.3368 -8.6868 180)
			(unlocked yes)
			(layer "F.Fab")
			(hide yes)
			(effects
				(font
					(size 1.016 1.016)
					(thickness 0.1524)
				)
			)
		)
		(property "Device Type" "SC70-5H44"
			(at -2.3114 -10.414 180)
			(unlocked yes)
			(layer "F.Fab")
			(hide yes)
			(effects
				(font
					(size 1.016 1.016)
					(thickness 0.1524)
				)
			)
		)
		(duplicate_pad_numbers_are_jumpers no)
		(fp_line
			(start 1.3843 -1.8034)
			(end 1.3843 -1.1176)
			(stroke
				(width 0.3302)
				(type default)
			)
			(layer "F.SilkS")
		)
		(fp_line
			(start 1.27 1.7018)
			(end -1.27 1.7018)
			(stroke
				(width 0.1524)
				(type default)
			)
			(layer "F.SilkS")
		)
		(fp_line
			(start 1.27 -1.7018)
			(end 1.27 1.7018)
			(stroke
				(width 0.1524)
				(type default)
			)
			(layer "F.SilkS")
		)
		(fp_line
			(start 0.6604 -1.8034)
			(end 1.3843 -1.8034)
			(stroke
				(width 0.3302)
				(type default)
			)
			(layer "F.SilkS")
		)
		(fp_line
			(start -1.27 1.7018)
			(end -1.27 -1.7018)
			(stroke
				(width 0.1524)
				(type default)
			)
			(layer "F.SilkS")
		)
		(fp_line
			(start -1.27 -1.7018)
			(end 1.27 -1.7018)
			(stroke
				(width 0.1524)
				(type default)
			)
			(layer "F.SilkS")
		)
		(fp_rect
			(start -1.524 1.9558)
			(end 1.524 -1.9558)
			(stroke
				(width 0)
				(type default)
			)
			(fill no)
			(layer "F.CrtYd")
		)
		(fp_poly
			(pts
				(xy -1.524 -1.9558) (xy 1.524 -1.9558) (xy 1.524 1.9558) (xy -1.524 1.9558)
			)
			(stroke
				(width 0)
				(type default)
			)
			(fill no)
			(layer "F.Fab")
		)
		(pad "1" smd rect
			(at 0.65024 -0.8255 180)
			(size 0.4064 1.2192)
			(layers "F.Cu" "F.Mask" "F.Paste")
			(net "PMU_PLTRST_N")
		)
		(pad "2" smd rect
			(at 0 -0.8255 180)
			(size 0.4064 1.2192)
			(layers "F.Cu" "F.Mask" "F.Paste")
			(net "BMC_DEBUG_OE_2_N")
		)
		(pad "3" smd rect
			(at -0.65024 -0.8255 180)
			(size 0.4064 1.2192)
			(layers "F.Cu" "F.Mask" "F.Paste")
			(net "GND")
		)
		(pad "4" smd rect
			(at -0.65024 0.8255 180)
			(size 0.4064 1.2192)
			(layers "F.Cu" "F.Mask" "F.Paste")
			(net "DEBUG_OE_2_N")
		)
		(pad "5" smd rect
			(at 0.65024 0.8255 180)
			(size 0.4064 1.2192)
			(layers "F.Cu" "F.Mask" "F.Paste")
			(net "P3V3_STBY")
		)
	)
	(footprint ""
		(layer "F.Cu")
		(at 11.126216 -237.29188 180)
		(property "Reference" "SC431"
			(at 0 0 180)
			(layer "F.SilkS")
			(hide yes)
			(effects
				(font
					(size 1.27 1.27)
				)
			)
		)
		(property "Value" "SCD1U16V2KX-3GP"
			(at 1.1811 -2.7051 180)
			(unlocked yes)
			(layer "F.Fab")
			(hide yes)
			(effects
				(font
					(size 1.016 1.016)
					(thickness 0.1524)
				)
			)
		)
		(property "Device Type" "C402H22"
			(at 1.1811 -4.2291 180)
			(unlocked yes)
			(layer "F.Fab")
			(hide yes)
			(effects
				(font
					(size 1.016 1.016)
					(thickness 0.1524)
				)
			)
		)
		(duplicate_pad_numbers_are_jumpers no)
		(fp_rect
			(start -0.4318 0.9525)
			(end 0.4318 -0.9525)
			(stroke
				(width 0)
				(type default)
			)
			(fill no)
			(layer "F.CrtYd")
		)
		(fp_rect
			(start -0.4318 0.9525)
			(end 0.4318 -0.9525)
			(stroke
				(width 0)
				(type default)
			)
			(fill no)
			(layer "F.Fab")
		)
		(pad "1" smd custom
			(at 0 -0.4445 180)
			(size 0.1524 0.1524)
			(layers "F.Cu" "F.Mask" "F.Paste")
			(net "P3V3_STBY")
			(options
				(clearance outline)
				(anchor circle)
			)
			(primitives
				(gr_poly
					(pts
						(arc
							(start 0.3048 -0.2032)
							(mid 0.275042 -0.275042)
							(end 0.2032 -0.3048)
						)
						(arc
							(start -0.2032 -0.3048)
							(mid -0.275042 -0.275042)
							(end -0.3048 -0.2032)
						)
						(arc
							(start -0.3048 0.2032)
							(mid -0.275042 0.275042)
							(end -0.2032 0.3048)
						)
						(arc
							(start 0.2032 0.3048)
							(mid 0.275042 0.275042)
							(end 0.3048 0.2032)
						)
					)
					(width 0)
					(fill yes)
				)
			)
		)
		(pad "2" smd custom
			(at 0 0.4445 180)
			(size 0.1524 0.1524)
			(layers "F.Cu" "F.Mask" "F.Paste")
			(net "GND")
			(options
				(clearance outline)
				(anchor circle)
			)
			(primitives
				(gr_poly
					(pts
						(arc
							(start 0.3048 -0.2032)
							(mid 0.275042 -0.275042)
							(end 0.2032 -0.3048)
						)
						(arc
							(start -0.2032 -0.3048)
							(mid -0.275042 -0.275042)
							(end -0.3048 -0.2032)
						)
						(arc
							(start -0.3048 0.2032)
							(mid -0.275042 0.275042)
							(end -0.2032 0.3048)
						)
						(arc
							(start 0.2032 0.3048)
							(mid 0.275042 0.275042)
							(end 0.3048 0.2032)
						)
					)
					(width 0)
					(fill yes)
				)
			)
		)
	)
	(footprint ""
		(layer "F.Cu")
		(at 271.907 -35.814 90)
		(property "Reference" "PC48"
			(at 0 0 90)
			(layer "F.SilkS")
			(hide yes)
			(effects
				(font
					(size 1.27 1.27)
				)
			)
		)
		(property "Value" "SC2K2P50V3KX-GP"
			(at 0 -2.8194 90)
			(unlocked yes)
			(layer "F.Fab")
			(hide yes)
			(effects
				(font
					(size 1.016 1.016)
					(thickness 0.1524)
				)
			)
		)
		(property "Device Type" "C603"
			(at 0 -4.3434 90)
			(unlocked yes)
			(layer "F.Fab")
			(hide yes)
			(effects
				(font
					(size 1.016 1.016)
					(thickness 0.1524)
				)
			)
		)
		(duplicate_pad_numbers_are_jumpers no)
		(fp_line
			(start 0.508 0)
			(end -0.508 0)
			(stroke
				(width 0.2032)
				(type default)
			)
			(layer "F.SilkS")
		)
		(fp_rect
			(start -0.5842 1.3335)
			(end 0.5842 -1.3335)
			(stroke
				(width 0)
				(type default)
			)
			(fill no)
			(layer "F.CrtYd")
		)
		(fp_rect
			(start -0.5842 1.3335)
			(end 0.5842 -1.3335)
			(stroke
				(width 0)
				(type default)
			)
			(fill no)
			(layer "F.Fab")
		)
		(pad "1" smd custom
			(at 0 -0.762 90)
			(size 0.2159 0.2159)
			(layers "F.Cu" "F.Mask" "F.Paste")
			(net "P1V8_STBY_LL")
			(options
				(clearance outline)
				(anchor circle)
			)
			(primitives
				(gr_poly
					(pts
						(arc
							(start -0.3302 -0.4318)
							(mid -0.402042 -0.402042)
							(end -0.4318 -0.3302)
						)
						(arc
							(start -0.4318 0.3302)
							(mid -0.402042 0.402042)
							(end -0.3302 0.4318)
						)
						(arc
							(start 0.3302 0.4318)
							(mid 0.402042 0.402042)
							(end 0.4318 0.3302)
						)
						(arc
							(start 0.4318 -0.3302)
							(mid 0.402042 -0.402042)
							(end 0.3302 -0.4318)
						)
					)
					(width 0)
					(fill yes)
				)
			)
		)
		(pad "2" smd custom
			(at 0 0.762 90)
			(size 0.2159 0.2159)
			(layers "F.Cu" "F.Mask" "F.Paste")
			(net "P1V8_STBY_SNB")
			(options
				(clearance outline)
				(anchor circle)
			)
			(primitives
				(gr_poly
					(pts
						(arc
							(start -0.3302 -0.4318)
							(mid -0.402042 -0.402042)
							(end -0.4318 -0.3302)
						)
						(arc
							(start -0.4318 0.3302)
							(mid -0.402042 0.402042)
							(end -0.3302 0.4318)
						)
						(arc
							(start 0.3302 0.4318)
							(mid 0.402042 0.402042)
							(end 0.4318 0.3302)
						)
						(arc
							(start 0.4318 -0.3302)
							(mid 0.402042 -0.402042)
							(end 0.3302 -0.4318)
						)
					)
					(width 0)
					(fill yes)
				)
			)
		)
	)
	(footprint ""
		(layer "F.Cu")
		(at 117.856 -50.038 -90)
		(property "Reference" "SR615"
			(at 0 0 270)
			(layer "F.SilkS")
			(hide yes)
			(effects
				(font
					(size 1.27 1.27)
				)
			)
		)
		(property "Value" "2K2R2F-GP"
			(at 0.064008 -3.993896 270)
			(unlocked yes)
			(layer "F.Fab")
			(hide yes)
			(effects
				(font
					(size 1.016 1.016)
					(thickness 0.1524)
				)
			)
		)
		(property "Device Type" "R402H16"
			(at 0.064008 -5.517896 270)
			(unlocked yes)
			(layer "F.Fab")
			(hide yes)
			(effects
				(font
					(size 1.016 1.016)
					(thickness 0.1524)
				)
			)
		)
		(duplicate_pad_numbers_are_jumpers no)
		(fp_line
			(start -0.508 -0.9398)
			(end -0.508 0.9398)
			(stroke
				(width 0.1524)
				(type default)
			)
			(layer "F.SilkS")
		)
		(fp_line
			(start 0.508 -0.9398)
			(end -0.508 -0.9398)
			(stroke
				(width 0.1524)
				(type default)
			)
			(layer "F.SilkS")
		)
		(fp_rect
			(start -0.508 0.9398)
			(end 0.508 -0.9398)
			(stroke
				(width 0)
				(type default)
			)
			(fill no)
			(layer "F.CrtYd")
		)
		(fp_rect
			(start -0.508 0.9398)
			(end 0.508 -0.9398)
			(stroke
				(width 0)
				(type default)
			)
			(fill no)
			(layer "F.Fab")
		)
		(pad "1" smd custom
			(at 0 -0.4445 270)
			(size 0.1397 0.1397)
			(layers "F.Cu" "F.Mask" "F.Paste")
			(net "P1V8_C")
			(options
				(clearance outline)
				(anchor circle)
			)
			(primitives
				(gr_poly
					(pts
						(arc
							(start -0.1778 -0.2794)
							(mid -0.249642 -0.249642)
							(end -0.2794 -0.1778)
						)
						(arc
							(start -0.2794 0.1778)
							(mid -0.249642 0.249642)
							(end -0.1778 0.2794)
						)
						(arc
							(start 0.1778 0.2794)
							(mid 0.249642 0.249642)
							(end 0.2794 0.1778)
						)
						(arc
							(start 0.2794 -0.1778)
							(mid 0.249642 -0.249642)
							(end 0.1778 -0.2794)
						)
					)
					(width 0)
					(fill yes)
				)
			)
		)
		(pad "2" smd custom
			(at 0 0.4445 270)
			(size 0.1397 0.1397)
			(layers "F.Cu" "F.Mask" "F.Paste")
			(net "SBL_SDA")
			(options
				(clearance outline)
				(anchor circle)
			)
			(primitives
				(gr_poly
					(pts
						(arc
							(start -0.1778 -0.2794)
							(mid -0.249642 -0.249642)
							(end -0.2794 -0.1778)
						)
						(arc
							(start -0.2794 0.1778)
							(mid -0.249642 0.249642)
							(end -0.1778 0.2794)
						)
						(arc
							(start 0.1778 0.2794)
							(mid 0.249642 0.249642)
							(end 0.2794 0.1778)
						)
						(arc
							(start 0.2794 -0.1778)
							(mid 0.249642 -0.249642)
							(end 0.1778 -0.2794)
						)
					)
					(width 0)
					(fill yes)
				)
			)
		)
	)
	(footprint ""
		(layer "F.Cu")
		(at 90.683842 -120.340882 90)
		(property "Reference" "SR752"
			(at 0 0 90)
			(layer "F.SilkS")
			(hide yes)
			(effects
				(font
					(size 1.27 1.27)
				)
			)
		)
		(property "Value" "4K7R2F-GP"
			(at 0.064008 -3.993896 90)
			(unlocked yes)
			(layer "F.Fab")
			(hide yes)
			(effects
				(font
					(size 1.016 1.016)
					(thickness 0.1524)
				)
			)
		)
		(property "Device Type" "R402H16"
			(at 0.064008 -5.517896 90)
			(unlocked yes)
			(layer "F.Fab")
			(hide yes)
			(effects
				(font
					(size 1.016 1.016)
					(thickness 0.1524)
				)
			)
		)
		(duplicate_pad_numbers_are_jumpers no)
		(fp_line
			(start 0.508 -0.9398)
			(end -0.508 -0.9398)
			(stroke
				(width 0.1524)
				(type default)
			)
			(layer "F.SilkS")
		)
		(fp_line
			(start -0.508 -0.9398)
			(end -0.508 0.9398)
			(stroke
				(width 0.1524)
				(type default)
			)
			(layer "F.SilkS")
		)
		(fp_rect
			(start -0.508 0.9398)
			(end 0.508 -0.9398)
			(stroke
				(width 0)
				(type default)
			)
			(fill no)
			(layer "F.CrtYd")
		)
		(fp_rect
			(start -0.508 0.9398)
			(end 0.508 -0.9398)
			(stroke
				(width 0)
				(type default)
			)
			(fill no)
			(layer "F.Fab")
		)
		(pad "1" smd custom
			(at 0 -0.4445 90)
			(size 0.1397 0.1397)
			(layers "F.Cu" "F.Mask" "F.Paste")
			(net "BMC_I2C_F_SDA")
			(options
				(clearance outline)
				(anchor circle)
			)
			(primitives
				(gr_poly
					(pts
						(arc
							(start -0.1778 -0.2794)
							(mid -0.249642 -0.249642)
							(end -0.2794 -0.1778)
						)
						(arc
							(start -0.2794 0.1778)
							(mid -0.249642 0.249642)
							(end -0.1778 0.2794)
						)
						(arc
							(start 0.1778 0.2794)
							(mid 0.249642 0.249642)
							(end 0.2794 0.1778)
						)
						(arc
							(start 0.2794 -0.1778)
							(mid 0.249642 -0.249642)
							(end 0.1778 -0.2794)
						)
					)
					(width 0)
					(fill yes)
				)
			)
		)
		(pad "2" smd custom
			(at 0 0.4445 90)
			(size 0.1397 0.1397)
			(layers "F.Cu" "F.Mask" "F.Paste")
			(net "P3V3_STBY")
			(options
				(clearance outline)
				(anchor circle)
			)
			(primitives
				(gr_poly
					(pts
						(arc
							(start -0.1778 -0.2794)
							(mid -0.249642 -0.249642)
							(end -0.2794 -0.1778)
						)
						(arc
							(start -0.2794 0.1778)
							(mid -0.249642 0.249642)
							(end -0.1778 0.2794)
						)
						(arc
							(start 0.1778 0.2794)
							(mid 0.249642 0.249642)
							(end 0.2794 0.1778)
						)
						(arc
							(start 0.2794 -0.1778)
							(mid 0.249642 -0.249642)
							(end 0.1778 -0.2794)
						)
					)
					(width 0)
					(fill yes)
				)
			)
		)
	)
	(footprint ""
		(layer "F.Cu")
		(at 189.357 -38.227 180)
		(property "Reference" "R445"
			(at 0 0 180)
			(layer "F.SilkS")
			(hide yes)
			(effects
				(font
					(size 1.27 1.27)
				)
			)
		)
		(property "Value" "0R2J-2-GP"
			(at 0.064008 -3.993896 180)
			(unlocked yes)
			(layer "F.Fab")
			(hide yes)
			(effects
				(font
					(size 1.016 1.016)
					(thickness 0.1524)
				)
			)
		)
		(property "Device Type" "R402H16"
			(at 0.064008 -5.517896 180)
			(unlocked yes)
			(layer "F.Fab")
			(hide yes)
			(effects
				(font
					(size 1.016 1.016)
					(thickness 0.1524)
				)
			)
		)
		(duplicate_pad_numbers_are_jumpers no)
		(fp_line
			(start 0.508 -0.9398)
			(end -0.508 -0.9398)
			(stroke
				(width 0.1524)
				(type default)
			)
			(layer "F.SilkS")
		)
		(fp_line
			(start -0.508 -0.9398)
			(end -0.508 0.9398)
			(stroke
				(width 0.1524)
				(type default)
			)
			(layer "F.SilkS")
		)
		(fp_rect
			(start -0.508 0.9398)
			(end 0.508 -0.9398)
			(stroke
				(width 0)
				(type default)
			)
			(fill no)
			(layer "F.CrtYd")
		)
		(fp_rect
			(start -0.508 0.9398)
			(end 0.508 -0.9398)
			(stroke
				(width 0)
				(type default)
			)
			(fill no)
			(layer "F.Fab")
		)
		(pad "1" smd custom
			(at 0 -0.4445 180)
			(size 0.1397 0.1397)
			(layers "F.Cu" "F.Mask" "F.Paste")
			(net "GND")
			(options
				(clearance outline)
				(anchor circle)
			)
			(primitives
				(gr_poly
					(pts
						(arc
							(start -0.1778 -0.2794)
							(mid -0.249642 -0.249642)
							(end -0.2794 -0.1778)
						)
						(arc
							(start -0.2794 0.1778)
							(mid -0.249642 0.249642)
							(end -0.1778 0.2794)
						)
						(arc
							(start 0.1778 0.2794)
							(mid 0.249642 0.249642)
							(end 0.2794 0.1778)
						)
						(arc
							(start 0.2794 -0.1778)
							(mid 0.249642 -0.249642)
							(end 0.1778 -0.2794)
						)
					)
					(width 0)
					(fill yes)
				)
			)
		)
		(pad "2" smd custom
			(at 0 0.4445 180)
			(size 0.1397 0.1397)
			(layers "F.Cu" "F.Mask" "F.Paste")
			(net "RMII_BMC_CRS_DV")
			(options
				(clearance outline)
				(anchor circle)
			)
			(primitives
				(gr_poly
					(pts
						(arc
							(start -0.1778 -0.2794)
							(mid -0.249642 -0.249642)
							(end -0.2794 -0.1778)
						)
						(arc
							(start -0.2794 0.1778)
							(mid -0.249642 0.249642)
							(end -0.1778 0.2794)
						)
						(arc
							(start 0.1778 0.2794)
							(mid 0.249642 0.249642)
							(end 0.2794 0.1778)
						)
						(arc
							(start 0.2794 -0.1778)
							(mid 0.249642 -0.249642)
							(end 0.1778 -0.2794)
						)
					)
					(width 0)
					(fill yes)
				)
			)
		)
	)
	(footprint ""
		(layer "F.Cu")
		(at 274.193 -175.641 90)
		(property "Reference" "R348"
			(at 0 0 90)
			(layer "F.SilkS")
			(hide yes)
			(effects
				(font
					(size 1.27 1.27)
				)
			)
		)
		(property "Value" "3K3R2F-2-GP"
			(at 0.064008 -3.993896 90)
			(unlocked yes)
			(layer "F.Fab")
			(hide yes)
			(effects
				(font
					(size 1.016 1.016)
					(thickness 0.1524)
				)
			)
		)
		(property "Device Type" "R402H16"
			(at 0.064008 -5.517896 90)
			(unlocked yes)
			(layer "F.Fab")
			(hide yes)
			(effects
				(font
					(size 1.016 1.016)
					(thickness 0.1524)
				)
			)
		)
		(duplicate_pad_numbers_are_jumpers no)
		(fp_line
			(start 0.508 -0.9398)
			(end -0.508 -0.9398)
			(stroke
				(width 0.1524)
				(type default)
			)
			(layer "F.SilkS")
		)
		(fp_line
			(start -0.508 -0.9398)
			(end -0.508 0.9398)
			(stroke
				(width 0.1524)
				(type default)
			)
			(layer "F.SilkS")
		)
		(fp_rect
			(start -0.508 0.9398)
			(end 0.508 -0.9398)
			(stroke
				(width 0)
				(type default)
			)
			(fill no)
			(layer "F.CrtYd")
		)
		(fp_rect
			(start -0.508 0.9398)
			(end 0.508 -0.9398)
			(stroke
				(width 0)
				(type default)
			)
			(fill no)
			(layer "F.Fab")
		)
		(pad "1" smd custom
			(at 0 -0.4445 90)
			(size 0.1397 0.1397)
			(layers "F.Cu" "F.Mask" "F.Paste")
			(net "P3V3_STBY")
			(options
				(clearance outline)
				(anchor circle)
			)
			(primitives
				(gr_poly
					(pts
						(arc
							(start -0.1778 -0.2794)
							(mid -0.249642 -0.249642)
							(end -0.2794 -0.1778)
						)
						(arc
							(start -0.2794 0.1778)
							(mid -0.249642 0.249642)
							(end -0.1778 0.2794)
						)
						(arc
							(start 0.1778 0.2794)
							(mid 0.249642 0.249642)
							(end 0.2794 0.1778)
						)
						(arc
							(start 0.2794 -0.1778)
							(mid 0.249642 -0.249642)
							(end 0.1778 -0.2794)
						)
					)
					(width 0)
					(fill yes)
				)
			)
		)
		(pad "2" smd custom
			(at 0 0.4445 90)
			(size 0.1397 0.1397)
			(layers "F.Cu" "F.Mask" "F.Paste")
			(net "ROMA10")
			(options
				(clearance outline)
				(anchor circle)
			)
			(primitives
				(gr_poly
					(pts
						(arc
							(start -0.1778 -0.2794)
							(mid -0.249642 -0.249642)
							(end -0.2794 -0.1778)
						)
						(arc
							(start -0.2794 0.1778)
							(mid -0.249642 0.249642)
							(end -0.1778 0.2794)
						)
						(arc
							(start 0.1778 0.2794)
							(mid 0.249642 0.249642)
							(end 0.2794 0.1778)
						)
						(arc
							(start 0.2794 -0.1778)
							(mid 0.249642 -0.249642)
							(end 0.1778 -0.2794)
						)
					)
					(width 0)
					(fill yes)
				)
			)
		)
	)
	(footprint ""
		(layer "F.Cu")
		(at 316.611 -118.618)
		(property "Reference" "PR30"
			(at 0 0 0)
			(layer "F.SilkS")
			(hide yes)
			(effects
				(font
					(size 1.27 1.27)
				)
			)
		)
		(property "Value" "100KR2F-L1-GP"
			(at 0.064008 -3.993896 0)
			(unlocked yes)
			(layer "F.Fab")
			(hide yes)
			(effects
				(font
					(size 1.016 1.016)
					(thickness 0.1524)
				)
			)
		)
		(property "Device Type" "R402H16"
			(at 0.064008 -5.517896 0)
			(unlocked yes)
			(layer "F.Fab")
			(hide yes)
			(effects
				(font
					(size 1.016 1.016)
					(thickness 0.1524)
				)
			)
		)
		(duplicate_pad_numbers_are_jumpers no)
		(fp_line
			(start -0.508 -0.9398)
			(end -0.508 0.9398)
			(stroke
				(width 0.1524)
				(type default)
			)
			(layer "F.SilkS")
		)
		(fp_line
			(start 0.508 -0.9398)
			(end -0.508 -0.9398)
			(stroke
				(width 0.1524)
				(type default)
			)
			(layer "F.SilkS")
		)
		(fp_rect
			(start -0.508 0.9398)
			(end 0.508 -0.9398)
			(stroke
				(width 0)
				(type default)
			)
			(fill no)
			(layer "F.CrtYd")
		)
		(fp_rect
			(start -0.508 0.9398)
			(end 0.508 -0.9398)
			(stroke
				(width 0)
				(type default)
			)
			(fill no)
			(layer "F.Fab")
		)
		(pad "1" smd custom
			(at 0 -0.4445)
			(size 0.1397 0.1397)
			(layers "F.Cu" "F.Mask" "F.Paste")
			(net "AGND_P3V3_STBY")
			(options
				(clearance outline)
				(anchor circle)
			)
			(primitives
				(gr_poly
					(pts
						(arc
							(start -0.1778 -0.2794)
							(mid -0.249642 -0.249642)
							(end -0.2794 -0.1778)
						)
						(arc
							(start -0.2794 0.1778)
							(mid -0.249642 0.249642)
							(end -0.1778 0.2794)
						)
						(arc
							(start 0.1778 0.2794)
							(mid 0.249642 0.249642)
							(end 0.2794 0.1778)
						)
						(arc
							(start 0.2794 -0.1778)
							(mid 0.249642 -0.249642)
							(end 0.1778 -0.2794)
						)
					)
					(width 0)
					(fill yes)
				)
			)
		)
		(pad "2" smd custom
			(at 0 0.4445)
			(size 0.1397 0.1397)
			(layers "F.Cu" "F.Mask" "F.Paste")
			(net "P3V3_STBY_MODE")
			(options
				(clearance outline)
				(anchor circle)
			)
			(primitives
				(gr_poly
					(pts
						(arc
							(start -0.1778 -0.2794)
							(mid -0.249642 -0.249642)
							(end -0.2794 -0.1778)
						)
						(arc
							(start -0.2794 0.1778)
							(mid -0.249642 0.249642)
							(end -0.1778 0.2794)
						)
						(arc
							(start 0.1778 0.2794)
							(mid 0.249642 0.249642)
							(end 0.2794 0.1778)
						)
						(arc
							(start 0.2794 -0.1778)
							(mid 0.249642 -0.249642)
							(end 0.1778 -0.2794)
						)
					)
					(width 0)
					(fill yes)
				)
			)
		)
	)
	(footprint ""
		(layer "F.Cu")
		(at 333.912718 -155.552648 -90)
		(property "Reference" "R549"
			(at 0 0 270)
			(layer "F.SilkS")
			(hide yes)
			(effects
				(font
					(size 1.27 1.27)
				)
			)
		)
		(property "Value" "4K7R2F-GP"
			(at 0.064008 -3.993896 270)
			(unlocked yes)
			(layer "F.Fab")
			(hide yes)
			(effects
				(font
					(size 1.016 1.016)
					(thickness 0.1524)
				)
			)
		)
		(property "Device Type" "R402H16"
			(at 0.064008 -5.517896 270)
			(unlocked yes)
			(layer "F.Fab")
			(hide yes)
			(effects
				(font
					(size 1.016 1.016)
					(thickness 0.1524)
				)
			)
		)
		(duplicate_pad_numbers_are_jumpers no)
		(fp_line
			(start -0.508 -0.9398)
			(end -0.508 0.9398)
			(stroke
				(width 0.1524)
				(type default)
			)
			(layer "F.SilkS")
		)
		(fp_line
			(start 0.508 -0.9398)
			(end -0.508 -0.9398)
			(stroke
				(width 0.1524)
				(type default)
			)
			(layer "F.SilkS")
		)
		(fp_rect
			(start -0.508 0.9398)
			(end 0.508 -0.9398)
			(stroke
				(width 0)
				(type default)
			)
			(fill no)
			(layer "F.CrtYd")
		)
		(fp_rect
			(start -0.508 0.9398)
			(end 0.508 -0.9398)
			(stroke
				(width 0)
				(type default)
			)
			(fill no)
			(layer "F.Fab")
		)
		(pad "1" smd custom
			(at 0 -0.4445 270)
			(size 0.1397 0.1397)
			(layers "F.Cu" "F.Mask" "F.Paste")
			(net "USB_EN_4")
			(options
				(clearance outline)
				(anchor circle)
			)
			(primitives
				(gr_poly
					(pts
						(arc
							(start -0.1778 -0.2794)
							(mid -0.249642 -0.249642)
							(end -0.2794 -0.1778)
						)
						(arc
							(start -0.2794 0.1778)
							(mid -0.249642 0.249642)
							(end -0.1778 0.2794)
						)
						(arc
							(start 0.1778 0.2794)
							(mid 0.249642 0.249642)
							(end 0.2794 0.1778)
						)
						(arc
							(start 0.2794 -0.1778)
							(mid 0.249642 -0.249642)
							(end 0.1778 -0.2794)
						)
					)
					(width 0)
					(fill yes)
				)
			)
		)
		(pad "2" smd custom
			(at 0 0.4445 270)
			(size 0.1397 0.1397)
			(layers "F.Cu" "F.Mask" "F.Paste")
			(net "GND")
			(options
				(clearance outline)
				(anchor circle)
			)
			(primitives
				(gr_poly
					(pts
						(arc
							(start -0.1778 -0.2794)
							(mid -0.249642 -0.249642)
							(end -0.2794 -0.1778)
						)
						(arc
							(start -0.2794 0.1778)
							(mid -0.249642 0.249642)
							(end -0.1778 0.2794)
						)
						(arc
							(start 0.1778 0.2794)
							(mid 0.249642 0.249642)
							(end 0.2794 0.1778)
						)
						(arc
							(start 0.2794 -0.1778)
							(mid 0.249642 -0.249642)
							(end 0.1778 -0.2794)
						)
					)
					(width 0)
					(fill yes)
				)
			)
		)
	)
	(footprint ""
		(layer "F.Cu")
		(at 282.194 -161.544 180)
		(property "Reference" "R237"
			(at 0 0 180)
			(layer "F.SilkS")
			(hide yes)
			(effects
				(font
					(size 1.27 1.27)
				)
			)
		)
		(property "Value" "100KR2F-L1-GP"
			(at 0.064008 -3.993896 180)
			(unlocked yes)
			(layer "F.Fab")
			(hide yes)
			(effects
				(font
					(size 1.016 1.016)
					(thickness 0.1524)
				)
			)
		)
		(property "Device Type" "R402H16"
			(at 0.064008 -5.517896 180)
			(unlocked yes)
			(layer "F.Fab")
			(hide yes)
			(effects
				(font
					(size 1.016 1.016)
					(thickness 0.1524)
				)
			)
		)
		(duplicate_pad_numbers_are_jumpers no)
		(fp_line
			(start 0.508 -0.9398)
			(end -0.508 -0.9398)
			(stroke
				(width 0.1524)
				(type default)
			)
			(layer "F.SilkS")
		)
		(fp_line
			(start -0.508 -0.9398)
			(end -0.508 0.9398)
			(stroke
				(width 0.1524)
				(type default)
			)
			(layer "F.SilkS")
		)
		(fp_rect
			(start -0.508 0.9398)
			(end 0.508 -0.9398)
			(stroke
				(width 0)
				(type default)
			)
			(fill no)
			(layer "F.CrtYd")
		)
		(fp_rect
			(start -0.508 0.9398)
			(end 0.508 -0.9398)
			(stroke
				(width 0)
				(type default)
			)
			(fill no)
			(layer "F.Fab")
		)
		(pad "1" smd custom
			(at 0 -0.4445 180)
			(size 0.1397 0.1397)
			(layers "F.Cu" "F.Mask" "F.Paste")
			(net "GND")
			(options
				(clearance outline)
				(anchor circle)
			)
			(primitives
				(gr_poly
					(pts
						(arc
							(start -0.1778 -0.2794)
							(mid -0.249642 -0.249642)
							(end -0.2794 -0.1778)
						)
						(arc
							(start -0.2794 0.1778)
							(mid -0.249642 0.249642)
							(end -0.1778 0.2794)
						)
						(arc
							(start 0.1778 0.2794)
							(mid 0.249642 0.249642)
							(end 0.2794 0.1778)
						)
						(arc
							(start 0.2794 -0.1778)
							(mid 0.249642 -0.249642)
							(end 0.1778 -0.2794)
						)
					)
					(width 0)
					(fill yes)
				)
			)
		)
		(pad "2" smd custom
			(at 0 0.4445 180)
			(size 0.1397 0.1397)
			(layers "F.Cu" "F.Mask" "F.Paste")
			(net "TP_BMC0_LPC_LAD3")
			(options
				(clearance outline)
				(anchor circle)
			)
			(primitives
				(gr_poly
					(pts
						(arc
							(start -0.1778 -0.2794)
							(mid -0.249642 -0.249642)
							(end -0.2794 -0.1778)
						)
						(arc
							(start -0.2794 0.1778)
							(mid -0.249642 0.249642)
							(end -0.1778 0.2794)
						)
						(arc
							(start 0.1778 0.2794)
							(mid 0.249642 0.249642)
							(end 0.2794 0.1778)
						)
						(arc
							(start 0.2794 -0.1778)
							(mid 0.249642 -0.249642)
							(end 0.1778 -0.2794)
						)
					)
					(width 0)
					(fill yes)
				)
			)
		)
	)
	(footprint ""
		(layer "F.Cu")
		(at 69.763386 -109.392212 -90)
		(property "Reference" "PQ4"
			(at 0 0 270)
			(layer "F.SilkS")
			(hide yes)
			(effects
				(font
					(size 1.27 1.27)
				)
			)
		)
		(property "Value" "2N7002A-7-GP"
			(at 0.127 -8.9662 270)
			(unlocked yes)
			(layer "F.Fab")
			(hide yes)
			(effects
				(font
					(size 1.016 1.016)
					(thickness 0.1524)
				)
			)
		)
		(property "Device Type" "SOT23DGS2D4H48"
			(at 0.127 -10.4902 270)
			(unlocked yes)
			(layer "F.Fab")
			(hide yes)
			(effects
				(font
					(size 1.016 1.016)
					(thickness 0.1524)
				)
			)
		)
		(duplicate_pad_numbers_are_jumpers no)
		(fp_line
			(start -1.651 1.778)
			(end 1.651 1.778)
			(stroke
				(width 0.1524)
				(type default)
			)
			(layer "F.SilkS")
		)
		(fp_line
			(start 1.651 1.778)
			(end 1.651 -1.778)
			(stroke
				(width 0.1524)
				(type default)
			)
			(layer "F.SilkS")
		)
		(fp_line
			(start -1.651 -1.778)
			(end -1.651 1.778)
			(stroke
				(width 0.1524)
				(type default)
			)
			(layer "F.SilkS")
		)
		(fp_line
			(start 1.651 -1.778)
			(end -1.651 -1.778)
			(stroke
				(width 0.1524)
				(type default)
			)
			(layer "F.SilkS")
		)
		(fp_poly
			(pts
				(xy -1.778 1.8796) (xy -1.778 -1.8796) (xy 1.778 -1.8796) (xy 1.778 1.8796)
			)
			(stroke
				(width 0)
				(type default)
			)
			(fill no)
			(layer "F.CrtYd")
		)
		(fp_poly
			(pts
				(xy -1.778 1.8796) (xy -1.778 -1.8796) (xy 1.778 -1.8796) (xy 1.778 1.8796)
			)
			(stroke
				(width 0)
				(type default)
			)
			(fill no)
			(layer "F.Fab")
		)
		(pad "D" smd custom
			(at 0 -0.9525 270)
			(size 0.1905 0.1905)
			(layers "F.Cu" "F.Mask" "F.Paste")
			(net "P1V8_EN_LV")
			(options
				(clearance outline)
				(anchor circle)
			)
			(primitives
				(gr_poly
					(pts
						(arc
							(start -0.1778 0.5715)
							(mid -0.321484 0.511984)
							(end -0.381 0.3683)
						)
						(arc
							(start -0.381 -0.3683)
							(mid -0.321484 -0.511984)
							(end -0.1778 -0.5715)
						)
						(arc
							(start 0.1778 -0.5715)
							(mid 0.321484 -0.511984)
							(end 0.381 -0.3683)
						)
						(arc
							(start 0.381 0.3683)
							(mid 0.321484 0.511984)
							(end 0.1778 0.5715)
						)
					)
					(width 0)
					(fill yes)
				)
			)
		)
		(pad "G" smd custom
			(at -0.98425 0.9525 270)
			(size 0.1905 0.1905)
			(layers "F.Cu" "F.Mask" "F.Paste")
			(net "P1V8_EN_G")
			(options
				(clearance outline)
				(anchor circle)
			)
			(primitives
				(gr_poly
					(pts
						(arc
							(start -0.1778 0.5715)
							(mid -0.321484 0.511984)
							(end -0.381 0.3683)
						)
						(arc
							(start -0.381 -0.3683)
							(mid -0.321484 -0.511984)
							(end -0.1778 -0.5715)
						)
						(arc
							(start 0.1778 -0.5715)
							(mid 0.321484 -0.511984)
							(end 0.381 -0.3683)
						)
						(arc
							(start 0.381 0.3683)
							(mid 0.321484 0.511984)
							(end 0.1778 0.5715)
						)
					)
					(width 0)
					(fill yes)
				)
			)
		)
		(pad "S" smd custom
			(at 0.98425 0.9525 270)
			(size 0.1905 0.1905)
			(layers "F.Cu" "F.Mask" "F.Paste")
			(net "P1V8_EN_S")
			(options
				(clearance outline)
				(anchor circle)
			)
			(primitives
				(gr_poly
					(pts
						(arc
							(start -0.1778 0.5715)
							(mid -0.321484 0.511984)
							(end -0.381 0.3683)
						)
						(arc
							(start -0.381 -0.3683)
							(mid -0.321484 -0.511984)
							(end -0.1778 -0.5715)
						)
						(arc
							(start 0.1778 -0.5715)
							(mid 0.321484 -0.511984)
							(end 0.381 -0.3683)
						)
						(arc
							(start 0.381 0.3683)
							(mid 0.321484 0.511984)
							(end 0.1778 0.5715)
						)
					)
					(width 0)
					(fill yes)
				)
			)
		)
	)
	(footprint ""
		(layer "F.Cu")
		(at 174.743872 -193.797936)
		(property "Reference" "C245"
			(at 0 0 0)
			(layer "F.SilkS")
			(hide yes)
			(effects
				(font
					(size 1.27 1.27)
				)
			)
		)
		(property "Value" "SC220P50V3JN-GP"
			(at 0 -2.8194 0)
			(unlocked yes)
			(layer "F.Fab")
			(hide yes)
			(effects
				(font
					(size 1.016 1.016)
					(thickness 0.1524)
				)
			)
		)
		(property "Device Type" "C603H36"
			(at 0 -4.3434 0)
			(unlocked yes)
			(layer "F.Fab")
			(hide yes)
			(effects
				(font
					(size 1.016 1.016)
					(thickness 0.1524)
				)
			)
		)
		(duplicate_pad_numbers_are_jumpers no)
		(fp_line
			(start 0.508 0)
			(end -0.508 0)
			(stroke
				(width 0.2032)
				(type default)
			)
			(layer "F.SilkS")
		)
		(fp_rect
			(start -0.5842 1.3335)
			(end 0.5842 -1.3335)
			(stroke
				(width 0)
				(type default)
			)
			(fill no)
			(layer "F.CrtYd")
		)
		(fp_rect
			(start -0.5842 1.3335)
			(end 0.5842 -1.3335)
			(stroke
				(width 0)
				(type default)
			)
			(fill no)
			(layer "F.Fab")
		)
		(pad "1" smd custom
			(at 0 -0.762)
			(size 0.2159 0.2159)
			(layers "F.Cu" "F.Mask" "F.Paste")
			(net "SAS_I2C_C_BUF_SCL")
			(options
				(clearance outline)
				(anchor circle)
			)
			(primitives
				(gr_poly
					(pts
						(arc
							(start -0.3302 -0.4318)
							(mid -0.402042 -0.402042)
							(end -0.4318 -0.3302)
						)
						(arc
							(start -0.4318 0.3302)
							(mid -0.402042 0.402042)
							(end -0.3302 0.4318)
						)
						(arc
							(start 0.3302 0.4318)
							(mid 0.402042 0.402042)
							(end 0.4318 0.3302)
						)
						(arc
							(start 0.4318 -0.3302)
							(mid 0.402042 -0.402042)
							(end 0.3302 -0.4318)
						)
					)
					(width 0)
					(fill yes)
				)
			)
		)
		(pad "2" smd custom
			(at 0 0.762)
			(size 0.2159 0.2159)
			(layers "F.Cu" "F.Mask" "F.Paste")
			(net "GND")
			(options
				(clearance outline)
				(anchor circle)
			)
			(primitives
				(gr_poly
					(pts
						(arc
							(start -0.3302 -0.4318)
							(mid -0.402042 -0.402042)
							(end -0.4318 -0.3302)
						)
						(arc
							(start -0.4318 0.3302)
							(mid -0.402042 0.402042)
							(end -0.3302 0.4318)
						)
						(arc
							(start 0.3302 0.4318)
							(mid 0.402042 0.402042)
							(end 0.4318 0.3302)
						)
						(arc
							(start 0.4318 -0.3302)
							(mid 0.402042 -0.402042)
							(end 0.3302 -0.4318)
						)
					)
					(width 0)
					(fill yes)
				)
			)
		)
	)
	(footprint ""
		(layer "F.Cu")
		(at 202.556872 -191.461136)
		(property "Reference" "U41"
			(at 0 0 0)
			(layer "F.SilkS")
			(hide yes)
			(effects
				(font
					(size 1.27 1.27)
				)
			)
		)
		(property "Value" "LM393ADR-1-GP"
			(at -3.707384 -1.5367 0)
			(unlocked yes)
			(layer "F.Fab")
			(hide yes)
			(effects
				(font
					(size 1.016 1.016)
					(thickness 0.1524)
				)
			)
		)
		(property "Device Type" "SOIC8H69"
			(at -3.707384 -3.0607 0)
			(unlocked yes)
			(layer "F.Fab")
			(hide yes)
			(effects
				(font
					(size 1.016 1.016)
					(thickness 0.1524)
				)
			)
		)
		(duplicate_pad_numbers_are_jumpers no)
		(fp_line
			(start -2.7432 -1.4224)
			(end -2.7432 1.4224)
			(stroke
				(width 0.1524)
				(type default)
			)
			(layer "F.SilkS")
		)
		(fp_line
			(start -2.7432 1.4224)
			(end -2.6416 1.4224)
			(stroke
				(width 0.1524)
				(type default)
			)
			(layer "F.SilkS")
		)
		(fp_line
			(start -2.7432 1.4224)
			(end 2.1336 1.4224)
			(stroke
				(width 0.1524)
				(type default)
			)
			(layer "F.SilkS")
		)
		(fp_line
			(start -2.7178 -0.508)
			(end -2.1844 -0.0508)
			(stroke
				(width 0.1524)
				(type default)
			)
			(layer "F.SilkS")
		)
		(fp_line
			(start -2.6289 3.4417)
			(end -2.6289 1.4732)
			(stroke
				(width 0.381)
				(type default)
			)
			(layer "F.SilkS")
		)
		(fp_line
			(start -2.1844 -0.0508)
			(end -2.7178 0.508)
			(stroke
				(width 0.1524)
				(type default)
			)
			(layer "F.SilkS")
		)
		(fp_line
			(start 2.1336 -1.4224)
			(end -2.7432 -1.4224)
			(stroke
				(width 0.1524)
				(type default)
			)
			(layer "F.SilkS")
		)
		(fp_line
			(start 2.1336 1.4224)
			(end 2.1336 -1.4224)
			(stroke
				(width 0.1524)
				(type default)
			)
			(layer "F.SilkS")
		)
		(fp_poly
			(pts
				(xy -2.2098 -1.4224) (xy -2.2098 1.4224) (xy 2.2098 1.4224) (xy 2.2098 -1.4224)
			)
			(stroke
				(width 0)
				(type default)
			)
			(fill yes)
			(layer "F.SilkS")
		)
		(fp_rect
			(start -2.450084 2.999994)
			(end 2.450084 -2.999994)
			(stroke
				(width 0)
				(type default)
			)
			(fill no)
			(layer "F.CrtYd")
		)
		(fp_poly
			(pts
				(xy -2.8194 3.6322) (xy -2.8194 -3.6322) (xy 2.8194 -3.6322) (xy 2.8194 1.18364) (xy 2.450084 1.18364)
				(xy 2.450084 -2.999994) (xy -2.450084 -2.999994) (xy -2.450084 2.999994) (xy 2.450084 2.999994)
				(xy 2.450084 1.18618) (xy 2.8194 1.18618) (xy 2.8194 3.6322)
			)
			(stroke
				(width 0)
				(type default)
			)
			(fill no)
			(layer "F.CrtYd")
		)
		(fp_rect
			(start -2.8194 3.6322)
			(end 2.8194 -3.6322)
			(stroke
				(width 0)
				(type default)
			)
			(fill no)
			(layer "F.Fab")
		)
		(pad "1" smd rect
			(at -1.905 2.54)
			(size 0.635 1.651)
			(layers "F.Cu" "F.Mask" "F.Paste")
			(net "HB_A_OUT")
		)
		(pad "2" smd rect
			(at -0.635 2.54)
			(size 0.635 1.651)
			(layers "F.Cu" "F.Mask" "F.Paste")
			(net "HB_A_IN")
		)
		(pad "3" smd rect
			(at 0.635 2.54)
			(size 0.635 1.651)
			(layers "F.Cu" "F.Mask" "F.Paste")
			(net "DIVIDER 1_IN")
		)
		(pad "4" smd rect
			(at 1.905 2.54)
			(size 0.635 1.651)
			(layers "F.Cu" "F.Mask" "F.Paste")
			(net "GND")
		)
		(pad "5" smd rect
			(at 1.905 -2.54)
			(size 0.635 1.651)
			(layers "F.Cu" "F.Mask" "F.Paste")
			(net "HB_A_IN")
		)
		(pad "6" smd rect
			(at 0.635 -2.54)
			(size 0.635 1.651)
			(layers "F.Cu" "F.Mask" "F.Paste")
			(net "DIVIDER 2_IN")
		)
		(pad "7" smd rect
			(at -0.635 -2.54)
			(size 0.635 1.651)
			(layers "F.Cu" "F.Mask" "F.Paste")
			(net "HB_A_OUT")
		)
		(pad "8" smd rect
			(at -1.905 -2.54)
			(size 0.635 1.651)
			(layers "F.Cu" "F.Mask" "F.Paste")
			(net "P3V3_STBY")
		)
	)
	(footprint ""
		(layer "F.Cu")
		(at 159.893 -154.1526 -90)
		(property "Reference" "SR729"
			(at 0 0 270)
			(layer "F.SilkS")
			(hide yes)
			(effects
				(font
					(size 1.27 1.27)
				)
			)
		)
		(property "Value" "0R2J-2-GP"
			(at 0.064008 -3.993896 270)
			(unlocked yes)
			(layer "F.Fab")
			(hide yes)
			(effects
				(font
					(size 1.016 1.016)
					(thickness 0.1524)
				)
			)
		)
		(property "Device Type" "R402H16"
			(at 0.064008 -5.517896 270)
			(unlocked yes)
			(layer "F.Fab")
			(hide yes)
			(effects
				(font
					(size 1.016 1.016)
					(thickness 0.1524)
				)
			)
		)
		(duplicate_pad_numbers_are_jumpers no)
		(fp_line
			(start -0.508 -0.9398)
			(end -0.508 0.9398)
			(stroke
				(width 0.1524)
				(type default)
			)
			(layer "F.SilkS")
		)
		(fp_line
			(start 0.508 -0.9398)
			(end -0.508 -0.9398)
			(stroke
				(width 0.1524)
				(type default)
			)
			(layer "F.SilkS")
		)
		(fp_rect
			(start -0.508 0.9398)
			(end 0.508 -0.9398)
			(stroke
				(width 0)
				(type default)
			)
			(fill no)
			(layer "F.CrtYd")
		)
		(fp_rect
			(start -0.508 0.9398)
			(end 0.508 -0.9398)
			(stroke
				(width 0)
				(type default)
			)
			(fill no)
			(layer "F.Fab")
		)
		(pad "1" smd custom
			(at 0 -0.4445 270)
			(size 0.1397 0.1397)
			(layers "F.Cu" "F.Mask" "F.Paste")
			(net "EXP_IOC_BMC_R_SDA_14")
			(options
				(clearance outline)
				(anchor circle)
			)
			(primitives
				(gr_poly
					(pts
						(arc
							(start -0.1778 -0.2794)
							(mid -0.249642 -0.249642)
							(end -0.2794 -0.1778)
						)
						(arc
							(start -0.2794 0.1778)
							(mid -0.249642 0.249642)
							(end -0.1778 0.2794)
						)
						(arc
							(start 0.1778 0.2794)
							(mid 0.249642 0.249642)
							(end 0.2794 0.1778)
						)
						(arc
							(start 0.2794 -0.1778)
							(mid 0.249642 -0.249642)
							(end 0.1778 -0.2794)
						)
					)
					(width 0)
					(fill yes)
				)
			)
		)
		(pad "2" smd custom
			(at 0 0.4445 270)
			(size 0.1397 0.1397)
			(layers "F.Cu" "F.Mask" "F.Paste")
			(net "EXP_IOC_BMC_SDA_14")
			(options
				(clearance outline)
				(anchor circle)
			)
			(primitives
				(gr_poly
					(pts
						(arc
							(start -0.1778 -0.2794)
							(mid -0.249642 -0.249642)
							(end -0.2794 -0.1778)
						)
						(arc
							(start -0.2794 0.1778)
							(mid -0.249642 0.249642)
							(end -0.1778 0.2794)
						)
						(arc
							(start 0.1778 0.2794)
							(mid 0.249642 0.249642)
							(end 0.2794 0.1778)
						)
						(arc
							(start 0.2794 -0.1778)
							(mid 0.249642 -0.249642)
							(end 0.1778 -0.2794)
						)
					)
					(width 0)
					(fill yes)
				)
			)
		)
	)
	(footprint ""
		(layer "F.Cu")
		(at 350.484948 -28.90012 180)
		(property "Reference" "SW3"
			(at 0 0 180)
			(layer "F.SilkS")
			(hide yes)
			(effects
				(font
					(size 1.27 1.27)
				)
			)
		)
		(property "Value" "PUSH-SW132-GP"
			(at -4.9657 -6.1341 180)
			(unlocked yes)
			(layer "F.Fab")
			(hide yes)
			(effects
				(font
					(size 1.016 1.016)
					(thickness 0.1524)
				)
			)
		)
		(property "Device Type" "PTCFGP2-Q-TR"
			(at -4.9657 -7.6581 180)
			(unlocked yes)
			(layer "F.Fab")
			(hide yes)
			(effects
				(font
					(size 1.016 1.016)
					(thickness 0.1524)
				)
			)
		)
		(duplicate_pad_numbers_are_jumpers no)
		(fp_line
			(start 3.556 1.6002)
			(end 2.7178 1.6002)
			(stroke
				(width 0.1524)
				(type default)
			)
			(layer "F.SilkS")
		)
		(fp_line
			(start 3.556 -2.0066)
			(end 3.556 1.6002)
			(stroke
				(width 0.1524)
				(type default)
			)
			(layer "F.SilkS")
		)
		(fp_line
			(start 2.7178 2.7686)
			(end 1.4986 2.7686)
			(stroke
				(width 0.1524)
				(type default)
			)
			(layer "F.SilkS")
		)
		(fp_line
			(start 2.7178 1.6002)
			(end 2.7178 2.7686)
			(stroke
				(width 0.1524)
				(type default)
			)
			(layer "F.SilkS")
		)
		(fp_line
			(start 1.4986 2.7686)
			(end 1.4986 2.0066)
			(stroke
				(width 0.1524)
				(type default)
			)
			(layer "F.SilkS")
		)
		(fp_line
			(start 1.4986 2.0066)
			(end -3.556 2.0066)
			(stroke
				(width 0.1524)
				(type default)
			)
			(layer "F.SilkS")
		)
		(fp_line
			(start -3.556 2.0066)
			(end -3.556 -2.0066)
			(stroke
				(width 0.1524)
				(type default)
			)
			(layer "F.SilkS")
		)
		(fp_line
			(start -3.556 -2.0066)
			(end 3.556 -2.0066)
			(stroke
				(width 0.1524)
				(type default)
			)
			(layer "F.SilkS")
		)
		(fp_line
			(start -3.6576 -0.6604)
			(end -3.6576 -1.0414)
			(stroke
				(width 0.3302)
				(type default)
			)
			(layer "F.SilkS")
		)
		(fp_poly
			(pts
				(xy -4.2545 -0.2159) (xy -4.2545 -1.4859) (xy -3.6195 -0.8509)
			)
			(stroke
				(width 0)
				(type default)
			)
			(fill yes)
			(layer "F.SilkS")
		)
		(fp_poly
			(pts
				(xy 1.7526 2.2606) (xy 1.7526 1.7526) (xy -2.3495 1.7526) (xy -2.3495 1.1049) (xy -2.9464 1.1049)
				(xy -2.9464 -1.1049) (xy -2.3495 -1.1049) (xy -2.3495 -1.7526) (xy 2.3495 -1.7526) (xy 2.3495 -1.1049)
				(xy 2.9464 -1.1049) (xy 2.9464 1.1049) (xy 2.3495 1.1049) (xy 2.3495 2.2606)
			)
			(stroke
				(width 0)
				(type default)
			)
			(fill no)
			(layer "F.CrtYd")
		)
		(fp_poly
			(pts
				(xy 1.2446 3.0226) (xy 1.2446 2.2606) (xy -3.81 2.2606) (xy -3.81 -2.2606) (xy -1.4097 -2.2606)
				(xy -1.4097 -1.752854) (xy -2.349754 -1.752854) (xy -2.349754 -1.105154) (xy -2.946654 -1.105154)
				(xy -2.946654 1.105154) (xy -2.349754 1.105154) (xy -2.349754 1.752854) (xy 1.752346 1.752854) (xy 1.752346 2.2606)
				(xy 2.349754 2.2606) (xy 2.349754 1.105154) (xy 2.946654 1.105154) (xy 2.946654 -1.105154) (xy 2.349754 -1.105154)
				(xy 2.349754 -1.752854) (xy -1.397 -1.752854) (xy -1.397 -2.2606) (xy 3.81 -2.2606) (xy 3.81 1.8542)
				(xy 2.9718 1.8542) (xy 2.9718 3.0226)
			)
			(stroke
				(width 0)
				(type default)
			)
			(fill no)
			(layer "F.CrtYd")
		)
		(fp_poly
			(pts
				(xy 1.2446 3.0226) (xy 1.2446 2.2606) (xy -3.81 2.2606) (xy -3.81 -2.2606) (xy 3.81 -2.2606) (xy 3.81 1.8542)
				(xy 2.9718 1.8542) (xy 2.9718 3.0226)
			)
			(stroke
				(width 0)
				(type default)
			)
			(fill no)
			(layer "F.Fab")
		)
		(pad "" np_thru_hole circle
			(at 0 -1.35001 180)
			(size 0.254 0.254)
			(drill 0.8128)
			(layers "*.Cu" "*.Mask")
			(clearance 0.635)
			(thermal_gap 0.635)
		)
		(pad "" np_thru_hole circle
			(at 0 1.35001 180)
			(size 0.254 0.254)
			(drill 0.8128)
			(layers "*.Cu" "*.Mask")
			(clearance 0.635)
			(thermal_gap 0.635)
		)
		(pad "1" smd rect
			(at -2.576068 -0.85471 180)
			(size 1.4478 0.9906)
			(layers "F.Cu" "F.Mask" "F.Paste")
			(net "GND")
		)
		(pad "2" smd rect
			(at -2.576068 0.85471 180)
			(size 1.4478 0.9906)
			(layers "F.Cu" "F.Mask" "F.Paste")
			(net "SHUTDOWN_RELEASE")
		)
		(pad "3" smd rect
			(at 2.576068 -0.85471 180)
			(size 1.4478 0.9906)
			(layers "F.Cu" "F.Mask" "F.Paste")
			(net "GND")
		)
		(pad "4" smd rect
			(at 2.576068 0.85471 180)
			(size 1.4478 0.9906)
			(layers "F.Cu" "F.Mask" "F.Paste")
			(net "SHUTDOWN_RELEASE")
		)
		(pad "5" smd rect
			(at 2.10566 2.13106 180)
			(size 0.7112 0.762)
			(layers "F.Cu" "F.Mask" "F.Paste")
			(net "Net_213")
		)
		(zone
			(layers "F.Cu" "B.Cu" "In1.Cu" "In2.Cu" "In3.Cu" "In4.Cu" "In5.Cu" "In6.Cu")
			(hatch none 0.5)
			(connect_pads
				(clearance 0)
			)
			(min_thickness 0.25)
			(keepout
				(tracks not_allowed)
				(vias allowed)
				(pads allowed)
				(copperpour not_allowed)
				(footprints allowed)
			)
			(placement
				(enabled no)
				(sheetname "")
			)
			(fill
				(thermal_gap 0.5)
				(thermal_bridge_width 0.5)
				(island_removal_mode 0)
			)
			(polygon
				(pts
					(arc
						(start 351.196148 -30.25013)
						(mid 349.773748 -30.25013)
						(end 351.196148 -30.25013)
					)
				)
			)
		)
		(zone
			(layers "F.Cu" "B.Cu" "In1.Cu" "In2.Cu" "In3.Cu" "In4.Cu" "In5.Cu" "In6.Cu")
			(hatch none 0.5)
			(connect_pads
				(clearance 0)
			)
			(min_thickness 0.25)
			(keepout
				(tracks not_allowed)
				(vias allowed)
				(pads allowed)
				(copperpour not_allowed)
				(footprints allowed)
			)
			(placement
				(enabled no)
				(sheetname "")
			)
			(fill
				(thermal_gap 0.5)
				(thermal_bridge_width 0.5)
				(island_removal_mode 0)
			)
			(polygon
				(pts
					(arc
						(start 351.196148 -27.55011)
						(mid 349.773748 -27.55011)
						(end 351.196148 -27.55011)
					)
				)
			)
		)
	)
	(footprint ""
		(layer "F.Cu")
		(at 95.26397 -118.3005 180)
		(property "Reference" "SR750"
			(at 0 0 180)
			(layer "F.SilkS")
			(hide yes)
			(effects
				(font
					(size 1.27 1.27)
				)
			)
		)
		(property "Value" "4K7R2F-GP"
			(at 0.064008 -3.993896 180)
			(unlocked yes)
			(layer "F.Fab")
			(hide yes)
			(effects
				(font
					(size 1.016 1.016)
					(thickness 0.1524)
				)
			)
		)
		(property "Device Type" "R402H16"
			(at 0.064008 -5.517896 180)
			(unlocked yes)
			(layer "F.Fab")
			(hide yes)
			(effects
				(font
					(size 1.016 1.016)
					(thickness 0.1524)
				)
			)
		)
		(duplicate_pad_numbers_are_jumpers no)
		(fp_line
			(start 0.508 -0.9398)
			(end -0.508 -0.9398)
			(stroke
				(width 0.1524)
				(type default)
			)
			(layer "F.SilkS")
		)
		(fp_line
			(start -0.508 -0.9398)
			(end -0.508 0.9398)
			(stroke
				(width 0.1524)
				(type default)
			)
			(layer "F.SilkS")
		)
		(fp_rect
			(start -0.508 0.9398)
			(end 0.508 -0.9398)
			(stroke
				(width 0)
				(type default)
			)
			(fill no)
			(layer "F.CrtYd")
		)
		(fp_rect
			(start -0.508 0.9398)
			(end 0.508 -0.9398)
			(stroke
				(width 0)
				(type default)
			)
			(fill no)
			(layer "F.Fab")
		)
		(pad "1" smd custom
			(at 0 -0.4445 180)
			(size 0.1397 0.1397)
			(layers "F.Cu" "F.Mask" "F.Paste")
			(net "SIO_LOAD_OUT")
			(options
				(clearance outline)
				(anchor circle)
			)
			(primitives
				(gr_poly
					(pts
						(arc
							(start -0.1778 -0.2794)
							(mid -0.249642 -0.249642)
							(end -0.2794 -0.1778)
						)
						(arc
							(start -0.2794 0.1778)
							(mid -0.249642 0.249642)
							(end -0.1778 0.2794)
						)
						(arc
							(start 0.1778 0.2794)
							(mid 0.249642 0.249642)
							(end 0.2794 0.1778)
						)
						(arc
							(start 0.2794 -0.1778)
							(mid 0.249642 -0.249642)
							(end 0.1778 -0.2794)
						)
					)
					(width 0)
					(fill yes)
				)
			)
		)
		(pad "2" smd custom
			(at 0 0.4445 180)
			(size 0.1397 0.1397)
			(layers "F.Cu" "F.Mask" "F.Paste")
			(net "P1V8_E")
			(options
				(clearance outline)
				(anchor circle)
			)
			(primitives
				(gr_poly
					(pts
						(arc
							(start -0.1778 -0.2794)
							(mid -0.249642 -0.249642)
							(end -0.2794 -0.1778)
						)
						(arc
							(start -0.2794 0.1778)
							(mid -0.249642 0.249642)
							(end -0.1778 0.2794)
						)
						(arc
							(start 0.1778 0.2794)
							(mid 0.249642 0.249642)
							(end 0.2794 0.1778)
						)
						(arc
							(start 0.2794 -0.1778)
							(mid 0.249642 -0.249642)
							(end 0.1778 -0.2794)
						)
					)
					(width 0)
					(fill yes)
				)
			)
		)
	)
	(footprint ""
		(layer "F.Cu")
		(at 216.281 -93.98 -90)
		(property "Reference" "PC140"
			(at 0 0 270)
			(layer "F.SilkS")
			(hide yes)
			(effects
				(font
					(size 1.27 1.27)
				)
			)
		)
		(property "Value" "SC10U6D3V5KX-1GP"
			(at -0.0762 -6.1214 270)
			(unlocked yes)
			(layer "F.Fab")
			(hide yes)
			(effects
				(font
					(size 1.016 1.016)
					(thickness 0.1524)
				)
			)
		)
		(property "Device Type" "C805H54"
			(at -0.0762 -8.1534 270)
			(unlocked yes)
			(layer "F.Fab")
			(hide yes)
			(effects
				(font
					(size 1.016 1.016)
					(thickness 0.1524)
				)
			)
		)
		(duplicate_pad_numbers_are_jumpers no)
		(fp_line
			(start 0.635 0)
			(end -0.635 0)
			(stroke
				(width 0.508)
				(type default)
			)
			(layer "F.SilkS")
		)
		(fp_rect
			(start -0.9652 1.778)
			(end 0.9652 -1.778)
			(stroke
				(width 0)
				(type default)
			)
			(fill no)
			(layer "F.CrtYd")
		)
		(fp_poly
			(pts
				(xy -0.9652 -1.778) (xy 0.9652 -1.778) (xy 0.9652 1.778) (xy -0.9652 1.778)
			)
			(stroke
				(width 0)
				(type default)
			)
			(fill no)
			(layer "F.Fab")
		)
		(pad "1" smd rect
			(at 0 -0.9652 270)
			(size 1.397 1.143)
			(layers "F.Cu" "F.Mask" "F.Paste")
			(net "TPS74801_P1V5_C_IN")
		)
		(pad "2" smd rect
			(at 0 0.9652 270)
			(size 1.397 1.143)
			(layers "F.Cu" "F.Mask" "F.Paste")
			(net "GND")
		)
	)
	(footprint ""
		(layer "F.Cu")
		(at 289.687 -66.675 90)
		(property "Reference" "PR9000"
			(at 0 0 90)
			(layer "F.SilkS")
			(hide yes)
			(effects
				(font
					(size 1.27 1.27)
				)
			)
		)
		(property "Value" "0R2J-2-GP"
			(at 0.064008 -3.993896 90)
			(unlocked yes)
			(layer "F.Fab")
			(hide yes)
			(effects
				(font
					(size 1.016 1.016)
					(thickness 0.1524)
				)
			)
		)
		(property "Device Type" "R402H16"
			(at 0.064008 -5.517896 90)
			(unlocked yes)
			(layer "F.Fab")
			(hide yes)
			(effects
				(font
					(size 1.016 1.016)
					(thickness 0.1524)
				)
			)
		)
		(duplicate_pad_numbers_are_jumpers no)
		(fp_line
			(start 0.508 -0.9398)
			(end -0.508 -0.9398)
			(stroke
				(width 0.1524)
				(type default)
			)
			(layer "F.SilkS")
		)
		(fp_line
			(start -0.508 -0.9398)
			(end -0.508 0.9398)
			(stroke
				(width 0.1524)
				(type default)
			)
			(layer "F.SilkS")
		)
		(fp_rect
			(start -0.508 0.9398)
			(end 0.508 -0.9398)
			(stroke
				(width 0)
				(type default)
			)
			(fill no)
			(layer "F.CrtYd")
		)
		(fp_rect
			(start -0.508 0.9398)
			(end 0.508 -0.9398)
			(stroke
				(width 0)
				(type default)
			)
			(fill no)
			(layer "F.Fab")
		)
		(pad "1" smd custom
			(at 0 -0.4445 90)
			(size 0.1397 0.1397)
			(layers "F.Cu" "F.Mask" "F.Paste")
			(net "HSW_SCL1")
			(options
				(clearance outline)
				(anchor circle)
			)
			(primitives
				(gr_poly
					(pts
						(arc
							(start -0.1778 -0.2794)
							(mid -0.249642 -0.249642)
							(end -0.2794 -0.1778)
						)
						(arc
							(start -0.2794 0.1778)
							(mid -0.249642 0.249642)
							(end -0.1778 0.2794)
						)
						(arc
							(start 0.1778 0.2794)
							(mid 0.249642 0.249642)
							(end 0.2794 0.1778)
						)
						(arc
							(start 0.2794 -0.1778)
							(mid 0.249642 -0.249642)
							(end 0.1778 -0.2794)
						)
					)
					(width 0)
					(fill yes)
				)
			)
		)
		(pad "2" smd custom
			(at 0 0.4445 90)
			(size 0.1397 0.1397)
			(layers "F.Cu" "F.Mask" "F.Paste")
			(net "BMC_I2C_A_SCL")
			(options
				(clearance outline)
				(anchor circle)
			)
			(primitives
				(gr_poly
					(pts
						(arc
							(start -0.1778 -0.2794)
							(mid -0.249642 -0.249642)
							(end -0.2794 -0.1778)
						)
						(arc
							(start -0.2794 0.1778)
							(mid -0.249642 0.249642)
							(end -0.1778 0.2794)
						)
						(arc
							(start 0.1778 0.2794)
							(mid 0.249642 0.249642)
							(end 0.2794 0.1778)
						)
						(arc
							(start 0.2794 -0.1778)
							(mid 0.249642 -0.249642)
							(end 0.1778 -0.2794)
						)
					)
					(width 0)
					(fill yes)
				)
			)
		)
	)
	(footprint ""
		(layer "F.Cu")
		(at 93.072966 -63.119)
		(property "Reference" "SR675"
			(at 0 0 0)
			(layer "F.SilkS")
			(hide yes)
			(effects
				(font
					(size 1.27 1.27)
				)
			)
		)
		(property "Value" "4K7R2F-GP"
			(at 0.064008 -3.993896 0)
			(unlocked yes)
			(layer "F.Fab")
			(hide yes)
			(effects
				(font
					(size 1.016 1.016)
					(thickness 0.1524)
				)
			)
		)
		(property "Device Type" "R402H16"
			(at 0.064008 -5.517896 0)
			(unlocked yes)
			(layer "F.Fab")
			(hide yes)
			(effects
				(font
					(size 1.016 1.016)
					(thickness 0.1524)
				)
			)
		)
		(duplicate_pad_numbers_are_jumpers no)
		(fp_line
			(start -0.508 -0.9398)
			(end -0.508 0.9398)
			(stroke
				(width 0.1524)
				(type default)
			)
			(layer "F.SilkS")
		)
		(fp_line
			(start 0.508 -0.9398)
			(end -0.508 -0.9398)
			(stroke
				(width 0.1524)
				(type default)
			)
			(layer "F.SilkS")
		)
		(fp_rect
			(start -0.508 0.9398)
			(end 0.508 -0.9398)
			(stroke
				(width 0)
				(type default)
			)
			(fill no)
			(layer "F.CrtYd")
		)
		(fp_rect
			(start -0.508 0.9398)
			(end 0.508 -0.9398)
			(stroke
				(width 0)
				(type default)
			)
			(fill no)
			(layer "F.Fab")
		)
		(pad "1" smd custom
			(at 0 -0.4445)
			(size 0.1397 0.1397)
			(layers "F.Cu" "F.Mask" "F.Paste")
			(net "P1V8_C")
			(options
				(clearance outline)
				(anchor circle)
			)
			(primitives
				(gr_poly
					(pts
						(arc
							(start -0.1778 -0.2794)
							(mid -0.249642 -0.249642)
							(end -0.2794 -0.1778)
						)
						(arc
							(start -0.2794 0.1778)
							(mid -0.249642 0.249642)
							(end -0.1778 0.2794)
						)
						(arc
							(start 0.1778 0.2794)
							(mid 0.249642 0.249642)
							(end 0.2794 0.1778)
						)
						(arc
							(start 0.2794 -0.1778)
							(mid 0.249642 -0.249642)
							(end 0.1778 -0.2794)
						)
					)
					(width 0)
					(fill yes)
				)
			)
		)
		(pad "2" smd custom
			(at 0 0.4445)
			(size 0.1397 0.1397)
			(layers "F.Cu" "F.Mask" "F.Paste")
			(net "ICE1_TCK")
			(options
				(clearance outline)
				(anchor circle)
			)
			(primitives
				(gr_poly
					(pts
						(arc
							(start -0.1778 -0.2794)
							(mid -0.249642 -0.249642)
							(end -0.2794 -0.1778)
						)
						(arc
							(start -0.2794 0.1778)
							(mid -0.249642 0.249642)
							(end -0.1778 0.2794)
						)
						(arc
							(start 0.1778 0.2794)
							(mid 0.249642 0.249642)
							(end 0.2794 0.1778)
						)
						(arc
							(start 0.2794 -0.1778)
							(mid 0.249642 -0.249642)
							(end 0.1778 -0.2794)
						)
					)
					(width 0)
					(fill yes)
				)
			)
		)
	)
	(footprint ""
		(layer "F.Cu")
		(at 266.065 -179.07 90)
		(property "Reference" "R351"
			(at 0 0 90)
			(layer "F.SilkS")
			(hide yes)
			(effects
				(font
					(size 1.27 1.27)
				)
			)
		)
		(property "Value" "3K3R2F-2-GP"
			(at 0.064008 -3.993896 90)
			(unlocked yes)
			(layer "F.Fab")
			(hide yes)
			(effects
				(font
					(size 1.016 1.016)
					(thickness 0.1524)
				)
			)
		)
		(property "Device Type" "R402H16"
			(at 0.064008 -5.517896 90)
			(unlocked yes)
			(layer "F.Fab")
			(hide yes)
			(effects
				(font
					(size 1.016 1.016)
					(thickness 0.1524)
				)
			)
		)
		(duplicate_pad_numbers_are_jumpers no)
		(fp_line
			(start 0.508 -0.9398)
			(end -0.508 -0.9398)
			(stroke
				(width 0.1524)
				(type default)
			)
			(layer "F.SilkS")
		)
		(fp_line
			(start -0.508 -0.9398)
			(end -0.508 0.9398)
			(stroke
				(width 0.1524)
				(type default)
			)
			(layer "F.SilkS")
		)
		(fp_rect
			(start -0.508 0.9398)
			(end 0.508 -0.9398)
			(stroke
				(width 0)
				(type default)
			)
			(fill no)
			(layer "F.CrtYd")
		)
		(fp_rect
			(start -0.508 0.9398)
			(end 0.508 -0.9398)
			(stroke
				(width 0)
				(type default)
			)
			(fill no)
			(layer "F.Fab")
		)
		(pad "1" smd custom
			(at 0 -0.4445 90)
			(size 0.1397 0.1397)
			(layers "F.Cu" "F.Mask" "F.Paste")
			(net "P3V3_STBY")
			(options
				(clearance outline)
				(anchor circle)
			)
			(primitives
				(gr_poly
					(pts
						(arc
							(start -0.1778 -0.2794)
							(mid -0.249642 -0.249642)
							(end -0.2794 -0.1778)
						)
						(arc
							(start -0.2794 0.1778)
							(mid -0.249642 0.249642)
							(end -0.1778 0.2794)
						)
						(arc
							(start 0.1778 0.2794)
							(mid 0.249642 0.249642)
							(end 0.2794 0.1778)
						)
						(arc
							(start 0.2794 -0.1778)
							(mid 0.249642 -0.249642)
							(end 0.1778 -0.2794)
						)
					)
					(width 0)
					(fill yes)
				)
			)
		)
		(pad "2" smd custom
			(at 0 0.4445 90)
			(size 0.1397 0.1397)
			(layers "F.Cu" "F.Mask" "F.Paste")
			(net "ROMA3")
			(options
				(clearance outline)
				(anchor circle)
			)
			(primitives
				(gr_poly
					(pts
						(arc
							(start -0.1778 -0.2794)
							(mid -0.249642 -0.249642)
							(end -0.2794 -0.1778)
						)
						(arc
							(start -0.2794 0.1778)
							(mid -0.249642 0.249642)
							(end -0.1778 0.2794)
						)
						(arc
							(start 0.1778 0.2794)
							(mid 0.249642 0.249642)
							(end 0.2794 0.1778)
						)
						(arc
							(start 0.2794 -0.1778)
							(mid 0.249642 -0.249642)
							(end 0.1778 -0.2794)
						)
					)
					(width 0)
					(fill yes)
				)
			)
		)
	)
	(footprint ""
		(layer "F.Cu")
		(at 86.49716 -43.561 -90)
		(property "Reference" "SC891"
			(at 0 0 270)
			(layer "F.SilkS")
			(hide yes)
			(effects
				(font
					(size 1.27 1.27)
				)
			)
		)
		(property "Value" "SCD01U10V1KX-GP"
			(at -2.8321 -1.7399 270)
			(unlocked yes)
			(layer "F.Fab")
			(hide yes)
			(effects
				(font
					(size 1.016 1.016)
					(thickness 0.1524)
				)
			)
		)
		(property "Device Type" "C0201H13"
			(at -2.8321 -3.2639 270)
			(unlocked yes)
			(layer "F.Fab")
			(hide yes)
			(effects
				(font
					(size 1.016 1.016)
					(thickness 0.1524)
				)
			)
		)
		(duplicate_pad_numbers_are_jumpers no)
		(fp_rect
			(start -0.2794 0.6477)
			(end 0.2794 -0.6477)
			(stroke
				(width 0)
				(type default)
			)
			(fill no)
			(layer "F.CrtYd")
		)
		(fp_rect
			(start -0.2794 0.6477)
			(end 0.2794 -0.6477)
			(stroke
				(width 0)
				(type default)
			)
			(fill no)
			(layer "F.Fab")
		)
		(pad "1" smd custom
			(at 0 -0.2794 270)
			(size 0.0762 0.0762)
			(layers "F.Cu" "F.Mask" "F.Paste")
			(net "SAS3008_RAID_TX_C_P5")
			(options
				(clearance outline)
				(anchor circle)
			)
			(primitives
				(gr_poly
					(pts
						(arc
							(start 0.1524 -0.127)
							(mid 0.137521 -0.162921)
							(end 0.1016 -0.1778)
						)
						(arc
							(start -0.1016 -0.1778)
							(mid -0.137521 -0.162921)
							(end -0.1524 -0.127)
						)
						(arc
							(start -0.1524 0.127)
							(mid -0.137521 0.162921)
							(end -0.1016 0.1778)
						)
						(arc
							(start 0.1016 0.1778)
							(mid 0.137521 0.162921)
							(end 0.1524 0.127)
						)
					)
					(width 0)
					(fill yes)
				)
			)
		)
		(pad "2" smd custom
			(at 0 0.2794 270)
			(size 0.0762 0.0762)
			(layers "F.Cu" "F.Mask" "F.Paste")
			(net "IOC_RAID_TX_P5")
			(options
				(clearance outline)
				(anchor circle)
			)
			(primitives
				(gr_poly
					(pts
						(arc
							(start 0.1524 -0.127)
							(mid 0.137521 -0.162921)
							(end 0.1016 -0.1778)
						)
						(arc
							(start -0.1016 -0.1778)
							(mid -0.137521 -0.162921)
							(end -0.1524 -0.127)
						)
						(arc
							(start -0.1524 0.127)
							(mid -0.137521 0.162921)
							(end -0.1016 0.1778)
						)
						(arc
							(start 0.1016 0.1778)
							(mid 0.137521 0.162921)
							(end 0.1524 0.127)
						)
					)
					(width 0)
					(fill yes)
				)
			)
		)
	)
	(footprint ""
		(layer "F.Cu")
		(at 85.730842 -122.118882 -90)
		(property "Reference" "SU65"
			(at 0 0 270)
			(layer "F.SilkS")
			(hide yes)
			(effects
				(font
					(size 1.27 1.27)
				)
			)
		)
		(property "Value" "PCA9306DCTT-GP"
			(at 0 -11.6332 270)
			(unlocked yes)
			(layer "F.Fab")
			(hide yes)
			(effects
				(font
					(size 1.016 1.016)
					(thickness 0.1524)
				)
			)
		)
		(property "Device Type" "SSOIC8H52"
			(at 0 -13.1572 270)
			(unlocked yes)
			(layer "F.Fab")
			(hide yes)
			(effects
				(font
					(size 1.016 1.016)
					(thickness 0.1524)
				)
			)
		)
		(duplicate_pad_numbers_are_jumpers no)
		(fp_line
			(start -1.524 0.5842)
			(end -1.524 2.286)
			(stroke
				(width 0.508)
				(type default)
			)
			(layer "F.SilkS")
		)
		(fp_line
			(start 1.0668 0.5842)
			(end -1.524 0.5842)
			(stroke
				(width 0.1524)
				(type default)
			)
			(layer "F.SilkS")
		)
		(fp_line
			(start -1.397 0)
			(end -1.7018 0.3048)
			(stroke
				(width 0.1524)
				(type default)
			)
			(layer "F.SilkS")
		)
		(fp_line
			(start -1.397 0)
			(end -1.7018 -0.3048)
			(stroke
				(width 0.1524)
				(type default)
			)
			(layer "F.SilkS")
		)
		(fp_line
			(start -1.7018 -0.5842)
			(end -1.7018 2.286)
			(stroke
				(width 0.1524)
				(type default)
			)
			(layer "F.SilkS")
		)
		(fp_line
			(start -1.7018 -0.5842)
			(end 1.0668 -0.5842)
			(stroke
				(width 0.1524)
				(type default)
			)
			(layer "F.SilkS")
		)
		(fp_line
			(start 1.0668 -0.5842)
			(end 1.0668 0.5842)
			(stroke
				(width 0.1524)
				(type default)
			)
			(layer "F.SilkS")
		)
		(fp_poly
			(pts
				(xy -1.1684 -0.5842) (xy 1.0668 -0.5842) (xy 1.0668 0.5842) (xy -1.1684 0.5842)
			)
			(stroke
				(width 0)
				(type default)
			)
			(fill yes)
			(layer "F.SilkS")
		)
		(fp_poly
			(pts
				(xy -1.778 2.54) (xy 1.778 2.54) (xy 1.778 -2.54) (xy -1.778 -2.54)
			)
			(stroke
				(width 0)
				(type default)
			)
			(fill no)
			(layer "F.CrtYd")
		)
		(fp_poly
			(pts
				(xy -1.778 -2.54) (xy 1.778 -2.54) (xy 1.778 2.54) (xy -1.778 2.54)
			)
			(stroke
				(width 0)
				(type default)
			)
			(fill no)
			(layer "F.Fab")
		)
		(pad "1" smd rect
			(at -0.97536 1.6256 270)
			(size 0.3556 1.524)
			(layers "F.Cu" "F.Mask" "F.Paste")
			(net "GND")
		)
		(pad "2" smd rect
			(at -0.32512 1.6256 270)
			(size 0.3556 1.524)
			(layers "F.Cu" "F.Mask" "F.Paste")
			(net "P1V8_E")
		)
		(pad "3" smd rect
			(at 0.32512 1.6256 270)
			(size 0.3556 1.524)
			(layers "F.Cu" "F.Mask" "F.Paste")
			(net "EXP_I2C_SCL_1")
		)
		(pad "4" smd rect
			(at 0.97536 1.6256 270)
			(size 0.3556 1.524)
			(layers "F.Cu" "F.Mask" "F.Paste")
			(net "EXP_I2C_SDA_1")
		)
		(pad "5" smd rect
			(at 0.97536 -1.6256 270)
			(size 0.3556 1.524)
			(layers "F.Cu" "F.Mask" "F.Paste")
			(net "BMC_I2C_F_SDA")
		)
		(pad "6" smd rect
			(at 0.32512 -1.6256 270)
			(size 0.3556 1.524)
			(layers "F.Cu" "F.Mask" "F.Paste")
			(net "BMC_I2C_F_SCL")
		)
		(pad "7" smd rect
			(at -0.32512 -1.6256 270)
			(size 0.3556 1.524)
			(layers "F.Cu" "F.Mask" "F.Paste")
			(net "EXP_I2C_VREF_0")
		)
		(pad "8" smd rect
			(at -0.97536 -1.6256 270)
			(size 0.3556 1.524)
			(layers "F.Cu" "F.Mask" "F.Paste")
			(net "EXP_I2C_VREF_0")
		)
	)
	(footprint ""
		(layer "F.Cu")
		(at 199.39 -140.589 90)
		(property "Reference" "SR766"
			(at 0 0 90)
			(layer "F.SilkS")
			(hide yes)
			(effects
				(font
					(size 1.27 1.27)
				)
			)
		)
		(property "Value" "4K7R2F-GP"
			(at 0.064008 -3.993896 90)
			(unlocked yes)
			(layer "F.Fab")
			(hide yes)
			(effects
				(font
					(size 1.016 1.016)
					(thickness 0.1524)
				)
			)
		)
		(property "Device Type" "R402H16"
			(at 0.064008 -5.517896 90)
			(unlocked yes)
			(layer "F.Fab")
			(hide yes)
			(effects
				(font
					(size 1.016 1.016)
					(thickness 0.1524)
				)
			)
		)
		(duplicate_pad_numbers_are_jumpers no)
		(fp_line
			(start 0.508 -0.9398)
			(end -0.508 -0.9398)
			(stroke
				(width 0.1524)
				(type default)
			)
			(layer "F.SilkS")
		)
		(fp_line
			(start -0.508 -0.9398)
			(end -0.508 0.9398)
			(stroke
				(width 0.1524)
				(type default)
			)
			(layer "F.SilkS")
		)
		(fp_rect
			(start -0.508 0.9398)
			(end 0.508 -0.9398)
			(stroke
				(width 0)
				(type default)
			)
			(fill no)
			(layer "F.CrtYd")
		)
		(fp_rect
			(start -0.508 0.9398)
			(end 0.508 -0.9398)
			(stroke
				(width 0)
				(type default)
			)
			(fill no)
			(layer "F.Fab")
		)
		(pad "1" smd custom
			(at 0 -0.4445 90)
			(size 0.1397 0.1397)
			(layers "F.Cu" "F.Mask" "F.Paste")
			(net "EXP_EEPROM_A1")
			(options
				(clearance outline)
				(anchor circle)
			)
			(primitives
				(gr_poly
					(pts
						(arc
							(start -0.1778 -0.2794)
							(mid -0.249642 -0.249642)
							(end -0.2794 -0.1778)
						)
						(arc
							(start -0.2794 0.1778)
							(mid -0.249642 0.249642)
							(end -0.1778 0.2794)
						)
						(arc
							(start 0.1778 0.2794)
							(mid 0.249642 0.249642)
							(end 0.2794 0.1778)
						)
						(arc
							(start 0.2794 -0.1778)
							(mid 0.249642 -0.249642)
							(end 0.1778 -0.2794)
						)
					)
					(width 0)
					(fill yes)
				)
			)
		)
		(pad "2" smd custom
			(at 0 0.4445 90)
			(size 0.1397 0.1397)
			(layers "F.Cu" "F.Mask" "F.Paste")
			(net "GND")
			(options
				(clearance outline)
				(anchor circle)
			)
			(primitives
				(gr_poly
					(pts
						(arc
							(start -0.1778 -0.2794)
							(mid -0.249642 -0.249642)
							(end -0.2794 -0.1778)
						)
						(arc
							(start -0.2794 0.1778)
							(mid -0.249642 0.249642)
							(end -0.1778 0.2794)
						)
						(arc
							(start 0.1778 0.2794)
							(mid 0.249642 0.249642)
							(end 0.2794 0.1778)
						)
						(arc
							(start 0.2794 -0.1778)
							(mid 0.249642 -0.249642)
							(end 0.1778 -0.2794)
						)
					)
					(width 0)
					(fill yes)
				)
			)
		)
	)
	(footprint ""
		(layer "F.Cu")
		(at 301.752 -91.186 -90)
		(property "Reference" "R162"
			(at 0 0 270)
			(layer "F.SilkS")
			(hide yes)
			(effects
				(font
					(size 1.27 1.27)
				)
			)
		)
		(property "Value" "0R2J-2-GP"
			(at 0.064008 -3.993896 270)
			(unlocked yes)
			(layer "F.Fab")
			(hide yes)
			(effects
				(font
					(size 1.016 1.016)
					(thickness 0.1524)
				)
			)
		)
		(property "Device Type" "R402H16"
			(at 0.064008 -5.517896 270)
			(unlocked yes)
			(layer "F.Fab")
			(hide yes)
			(effects
				(font
					(size 1.016 1.016)
					(thickness 0.1524)
				)
			)
		)
		(duplicate_pad_numbers_are_jumpers no)
		(fp_line
			(start -0.508 -0.9398)
			(end -0.508 0.9398)
			(stroke
				(width 0.1524)
				(type default)
			)
			(layer "F.SilkS")
		)
		(fp_line
			(start 0.508 -0.9398)
			(end -0.508 -0.9398)
			(stroke
				(width 0.1524)
				(type default)
			)
			(layer "F.SilkS")
		)
		(fp_rect
			(start -0.508 0.9398)
			(end 0.508 -0.9398)
			(stroke
				(width 0)
				(type default)
			)
			(fill no)
			(layer "F.CrtYd")
		)
		(fp_rect
			(start -0.508 0.9398)
			(end 0.508 -0.9398)
			(stroke
				(width 0)
				(type default)
			)
			(fill no)
			(layer "F.Fab")
		)
		(pad "1" smd custom
			(at 0 -0.4445 270)
			(size 0.1397 0.1397)
			(layers "F.Cu" "F.Mask" "F.Paste")
			(net "BMC_I2C_D_SCL")
			(options
				(clearance outline)
				(anchor circle)
			)
			(primitives
				(gr_poly
					(pts
						(arc
							(start -0.1778 -0.2794)
							(mid -0.249642 -0.249642)
							(end -0.2794 -0.1778)
						)
						(arc
							(start -0.2794 0.1778)
							(mid -0.249642 0.249642)
							(end -0.1778 0.2794)
						)
						(arc
							(start 0.1778 0.2794)
							(mid 0.249642 0.249642)
							(end 0.2794 0.1778)
						)
						(arc
							(start 0.2794 -0.1778)
							(mid 0.249642 -0.249642)
							(end 0.1778 -0.2794)
						)
					)
					(width 0)
					(fill yes)
				)
			)
		)
		(pad "2" smd custom
			(at 0 0.4445 270)
			(size 0.1397 0.1397)
			(layers "F.Cu" "F.Mask" "F.Paste")
			(net "TEMP_2_SCL")
			(options
				(clearance outline)
				(anchor circle)
			)
			(primitives
				(gr_poly
					(pts
						(arc
							(start -0.1778 -0.2794)
							(mid -0.249642 -0.249642)
							(end -0.2794 -0.1778)
						)
						(arc
							(start -0.2794 0.1778)
							(mid -0.249642 0.249642)
							(end -0.1778 0.2794)
						)
						(arc
							(start 0.1778 0.2794)
							(mid 0.249642 0.249642)
							(end 0.2794 0.1778)
						)
						(arc
							(start 0.2794 -0.1778)
							(mid 0.249642 -0.249642)
							(end 0.1778 -0.2794)
						)
					)
					(width 0)
					(fill yes)
				)
			)
		)
	)
	(footprint ""
		(layer "F.Cu")
		(at 83.420966 -84.074 180)
		(property "Reference" "SC1154"
			(at 0 0 180)
			(layer "F.SilkS")
			(hide yes)
			(effects
				(font
					(size 1.27 1.27)
				)
			)
		)
		(property "Value" "SC22U6D3V5MX-2GP"
			(at -0.0762 -6.1214 180)
			(unlocked yes)
			(layer "F.Fab")
			(hide yes)
			(effects
				(font
					(size 1.016 1.016)
					(thickness 0.1524)
				)
			)
		)
		(property "Device Type" "C805H58"
			(at -0.0762 -8.1534 180)
			(unlocked yes)
			(layer "F.Fab")
			(hide yes)
			(effects
				(font
					(size 1.016 1.016)
					(thickness 0.1524)
				)
			)
		)
		(duplicate_pad_numbers_are_jumpers no)
		(fp_line
			(start 0.635 0)
			(end -0.635 0)
			(stroke
				(width 0.508)
				(type default)
			)
			(layer "F.SilkS")
		)
		(fp_rect
			(start -0.9652 1.778)
			(end 0.9652 -1.778)
			(stroke
				(width 0)
				(type default)
			)
			(fill no)
			(layer "F.CrtYd")
		)
		(fp_poly
			(pts
				(xy -0.9652 -1.778) (xy 0.9652 -1.778) (xy 0.9652 1.778) (xy -0.9652 1.778)
			)
			(stroke
				(width 0)
				(type default)
			)
			(fill no)
			(layer "F.Fab")
		)
		(pad "1" smd rect
			(at 0 -0.9652 180)
			(size 1.397 1.143)
			(layers "F.Cu" "F.Mask" "F.Paste")
			(net "PLLDDR_VDDA18")
		)
		(pad "2" smd rect
			(at 0 0.9652 180)
			(size 1.397 1.143)
			(layers "F.Cu" "F.Mask" "F.Paste")
			(net "GND")
		)
	)
	(footprint ""
		(layer "F.Cu")
		(at 86.24697 -112.014 180)
		(property "Reference" "SC1230"
			(at 0 0 180)
			(layer "F.SilkS")
			(hide yes)
			(effects
				(font
					(size 1.27 1.27)
				)
			)
		)
		(property "Value" "SCD1U6D3V1KX-GP"
			(at -2.8321 -1.7399 180)
			(unlocked yes)
			(layer "F.Fab")
			(hide yes)
			(effects
				(font
					(size 1.016 1.016)
					(thickness 0.1524)
				)
			)
		)
		(property "Device Type" "C0201H13"
			(at -2.8321 -3.2639 180)
			(unlocked yes)
			(layer "F.Fab")
			(hide yes)
			(effects
				(font
					(size 1.016 1.016)
					(thickness 0.1524)
				)
			)
		)
		(duplicate_pad_numbers_are_jumpers no)
		(fp_rect
			(start -0.2794 0.6477)
			(end 0.2794 -0.6477)
			(stroke
				(width 0)
				(type default)
			)
			(fill no)
			(layer "F.CrtYd")
		)
		(fp_rect
			(start -0.2794 0.6477)
			(end 0.2794 -0.6477)
			(stroke
				(width 0)
				(type default)
			)
			(fill no)
			(layer "F.Fab")
		)
		(pad "1" smd custom
			(at 0 -0.2794 180)
			(size 0.0762 0.0762)
			(layers "F.Cu" "F.Mask" "F.Paste")
			(net "P1V8_E")
			(options
				(clearance outline)
				(anchor circle)
			)
			(primitives
				(gr_poly
					(pts
						(arc
							(start 0.1524 -0.127)
							(mid 0.137521 -0.162921)
							(end 0.1016 -0.1778)
						)
						(arc
							(start -0.1016 -0.1778)
							(mid -0.137521 -0.162921)
							(end -0.1524 -0.127)
						)
						(arc
							(start -0.1524 0.127)
							(mid -0.137521 0.162921)
							(end -0.1016 0.1778)
						)
						(arc
							(start 0.1016 0.1778)
							(mid 0.137521 0.162921)
							(end 0.1524 0.127)
						)
					)
					(width 0)
					(fill yes)
				)
			)
		)
		(pad "2" smd custom
			(at 0 0.2794 180)
			(size 0.0762 0.0762)
			(layers "F.Cu" "F.Mask" "F.Paste")
			(net "GND")
			(options
				(clearance outline)
				(anchor circle)
			)
			(primitives
				(gr_poly
					(pts
						(arc
							(start 0.1524 -0.127)
							(mid 0.137521 -0.162921)
							(end 0.1016 -0.1778)
						)
						(arc
							(start -0.1016 -0.1778)
							(mid -0.137521 -0.162921)
							(end -0.1524 -0.127)
						)
						(arc
							(start -0.1524 0.127)
							(mid -0.137521 0.162921)
							(end -0.1016 0.1778)
						)
						(arc
							(start 0.1016 0.1778)
							(mid 0.137521 0.162921)
							(end 0.1524 0.127)
						)
					)
					(width 0)
					(fill yes)
				)
			)
		)
	)
	(footprint ""
		(layer "F.Cu")
		(at 319.913 -166.878 -90)
		(property "Reference" "R475"
			(at 0 0 270)
			(layer "F.SilkS")
			(hide yes)
			(effects
				(font
					(size 1.27 1.27)
				)
			)
		)
		(property "Value" "10KR2F-2-GP"
			(at 0.064008 -3.993896 270)
			(unlocked yes)
			(layer "F.Fab")
			(hide yes)
			(effects
				(font
					(size 1.016 1.016)
					(thickness 0.1524)
				)
			)
		)
		(property "Device Type" "R402H16"
			(at 0.064008 -5.517896 270)
			(unlocked yes)
			(layer "F.Fab")
			(hide yes)
			(effects
				(font
					(size 1.016 1.016)
					(thickness 0.1524)
				)
			)
		)
		(duplicate_pad_numbers_are_jumpers no)
		(fp_line
			(start -0.508 -0.9398)
			(end -0.508 0.9398)
			(stroke
				(width 0.1524)
				(type default)
			)
			(layer "F.SilkS")
		)
		(fp_line
			(start 0.508 -0.9398)
			(end -0.508 -0.9398)
			(stroke
				(width 0.1524)
				(type default)
			)
			(layer "F.SilkS")
		)
		(fp_rect
			(start -0.508 0.9398)
			(end 0.508 -0.9398)
			(stroke
				(width 0)
				(type default)
			)
			(fill no)
			(layer "F.CrtYd")
		)
		(fp_rect
			(start -0.508 0.9398)
			(end 0.508 -0.9398)
			(stroke
				(width 0)
				(type default)
			)
			(fill no)
			(layer "F.Fab")
		)
		(pad "1" smd custom
			(at 0 -0.4445 270)
			(size 0.1397 0.1397)
			(layers "F.Cu" "F.Mask" "F.Paste")
			(net "P3V3_STBY")
			(options
				(clearance outline)
				(anchor circle)
			)
			(primitives
				(gr_poly
					(pts
						(arc
							(start -0.1778 -0.2794)
							(mid -0.249642 -0.249642)
							(end -0.2794 -0.1778)
						)
						(arc
							(start -0.2794 0.1778)
							(mid -0.249642 0.249642)
							(end -0.1778 0.2794)
						)
						(arc
							(start 0.1778 0.2794)
							(mid 0.249642 0.249642)
							(end 0.2794 0.1778)
						)
						(arc
							(start 0.2794 -0.1778)
							(mid 0.249642 -0.249642)
							(end 0.1778 -0.2794)
						)
					)
					(width 0)
					(fill yes)
				)
			)
		)
		(pad "2" smd custom
			(at 0 0.4445 270)
			(size 0.1397 0.1397)
			(layers "F.Cu" "F.Mask" "F.Paste")
			(net "BMC_I2C_C_SDA")
			(options
				(clearance outline)
				(anchor circle)
			)
			(primitives
				(gr_poly
					(pts
						(arc
							(start -0.1778 -0.2794)
							(mid -0.249642 -0.249642)
							(end -0.2794 -0.1778)
						)
						(arc
							(start -0.2794 0.1778)
							(mid -0.249642 0.249642)
							(end -0.1778 0.2794)
						)
						(arc
							(start 0.1778 0.2794)
							(mid 0.249642 0.249642)
							(end 0.2794 0.1778)
						)
						(arc
							(start 0.2794 -0.1778)
							(mid 0.249642 -0.249642)
							(end 0.1778 -0.2794)
						)
					)
					(width 0)
					(fill yes)
				)
			)
		)
	)
	(footprint ""
		(layer "F.Cu")
		(at 54.864 -224.917)
		(property "Reference" "R2098"
			(at 0 0 0)
			(layer "F.SilkS")
			(hide yes)
			(effects
				(font
					(size 1.27 1.27)
				)
			)
		)
		(property "Value" "10R2F-L-GP"
			(at 0.064008 -3.993896 0)
			(unlocked yes)
			(layer "F.Fab")
			(hide yes)
			(effects
				(font
					(size 1.016 1.016)
					(thickness 0.1524)
				)
			)
		)
		(property "Device Type" "R402H14"
			(at 0.064008 -5.517896 0)
			(unlocked yes)
			(layer "F.Fab")
			(hide yes)
			(effects
				(font
					(size 1.016 1.016)
					(thickness 0.1524)
				)
			)
		)
		(duplicate_pad_numbers_are_jumpers no)
		(fp_line
			(start -0.508 -0.9398)
			(end -0.508 0.9398)
			(stroke
				(width 0.1524)
				(type default)
			)
			(layer "F.SilkS")
		)
		(fp_line
			(start 0.508 -0.9398)
			(end -0.508 -0.9398)
			(stroke
				(width 0.1524)
				(type default)
			)
			(layer "F.SilkS")
		)
		(fp_rect
			(start -0.508 0.9398)
			(end 0.508 -0.9398)
			(stroke
				(width 0)
				(type default)
			)
			(fill no)
			(layer "F.CrtYd")
		)
		(fp_rect
			(start -0.508 0.9398)
			(end 0.508 -0.9398)
			(stroke
				(width 0)
				(type default)
			)
			(fill no)
			(layer "F.Fab")
		)
		(pad "1" smd custom
			(at 0 -0.4445)
			(size 0.1397 0.1397)
			(layers "F.Cu" "F.Mask" "F.Paste")
			(net "P12V_PCIE")
			(options
				(clearance outline)
				(anchor circle)
			)
			(primitives
				(gr_poly
					(pts
						(arc
							(start -0.1778 -0.2794)
							(mid -0.249642 -0.249642)
							(end -0.2794 -0.1778)
						)
						(arc
							(start -0.2794 0.1778)
							(mid -0.249642 0.249642)
							(end -0.1778 0.2794)
						)
						(arc
							(start 0.1778 0.2794)
							(mid 0.249642 0.249642)
							(end 0.2794 0.1778)
						)
						(arc
							(start 0.2794 -0.1778)
							(mid 0.249642 -0.249642)
							(end 0.1778 -0.2794)
						)
					)
					(width 0)
					(fill yes)
				)
			)
		)
		(pad "2" smd custom
			(at 0 0.4445)
			(size 0.1397 0.1397)
			(layers "F.Cu" "F.Mask" "F.Paste")
			(net "MB0_VCC")
			(options
				(clearance outline)
				(anchor circle)
			)
			(primitives
				(gr_poly
					(pts
						(arc
							(start -0.1778 -0.2794)
							(mid -0.249642 -0.249642)
							(end -0.2794 -0.1778)
						)
						(arc
							(start -0.2794 0.1778)
							(mid -0.249642 0.249642)
							(end -0.1778 0.2794)
						)
						(arc
							(start 0.1778 0.2794)
							(mid 0.249642 0.249642)
							(end 0.2794 0.1778)
						)
						(arc
							(start 0.2794 -0.1778)
							(mid 0.249642 -0.249642)
							(end 0.1778 -0.2794)
						)
					)
					(width 0)
					(fill yes)
				)
			)
		)
	)
	(footprint ""
		(layer "F.Cu")
		(at 81.915 -24.892 90)
		(property "Reference" "PR194"
			(at 0 0 90)
			(layer "F.SilkS")
			(hide yes)
			(effects
				(font
					(size 1.27 1.27)
				)
			)
		)
		(property "Value" "287R2F-GP"
			(at 0.064008 -3.993896 90)
			(unlocked yes)
			(layer "F.Fab")
			(hide yes)
			(effects
				(font
					(size 1.016 1.016)
					(thickness 0.1524)
				)
			)
		)
		(property "Device Type" "R402H16"
			(at 0.064008 -5.517896 90)
			(unlocked yes)
			(layer "F.Fab")
			(hide yes)
			(effects
				(font
					(size 1.016 1.016)
					(thickness 0.1524)
				)
			)
		)
		(duplicate_pad_numbers_are_jumpers no)
		(fp_line
			(start 0.508 -0.9398)
			(end -0.508 -0.9398)
			(stroke
				(width 0.1524)
				(type default)
			)
			(layer "F.SilkS")
		)
		(fp_line
			(start -0.508 -0.9398)
			(end -0.508 0.9398)
			(stroke
				(width 0.1524)
				(type default)
			)
			(layer "F.SilkS")
		)
		(fp_rect
			(start -0.508 0.9398)
			(end 0.508 -0.9398)
			(stroke
				(width 0)
				(type default)
			)
			(fill no)
			(layer "F.CrtYd")
		)
		(fp_rect
			(start -0.508 0.9398)
			(end 0.508 -0.9398)
			(stroke
				(width 0)
				(type default)
			)
			(fill no)
			(layer "F.Fab")
		)
		(pad "1" smd custom
			(at 0 -0.4445 90)
			(size 0.1397 0.1397)
			(layers "F.Cu" "F.Mask" "F.Paste")
			(net "VT235_VDES_RR")
			(options
				(clearance outline)
				(anchor circle)
			)
			(primitives
				(gr_poly
					(pts
						(arc
							(start -0.1778 -0.2794)
							(mid -0.249642 -0.249642)
							(end -0.2794 -0.1778)
						)
						(arc
							(start -0.2794 0.1778)
							(mid -0.249642 0.249642)
							(end -0.1778 0.2794)
						)
						(arc
							(start 0.1778 0.2794)
							(mid 0.249642 0.249642)
							(end 0.2794 0.1778)
						)
						(arc
							(start 0.2794 -0.1778)
							(mid 0.249642 -0.249642)
							(end 0.1778 -0.2794)
						)
					)
					(width 0)
					(fill yes)
				)
			)
		)
		(pad "2" smd custom
			(at 0 0.4445 90)
			(size 0.1397 0.1397)
			(layers "F.Cu" "F.Mask" "F.Paste")
			(net "VT235_VDES_RCC")
			(options
				(clearance outline)
				(anchor circle)
			)
			(primitives
				(gr_poly
					(pts
						(arc
							(start -0.1778 -0.2794)
							(mid -0.249642 -0.249642)
							(end -0.2794 -0.1778)
						)
						(arc
							(start -0.2794 0.1778)
							(mid -0.249642 0.249642)
							(end -0.1778 0.2794)
						)
						(arc
							(start 0.1778 0.2794)
							(mid 0.249642 0.249642)
							(end 0.2794 0.1778)
						)
						(arc
							(start 0.2794 -0.1778)
							(mid 0.249642 -0.249642)
							(end 0.1778 -0.2794)
						)
					)
					(width 0)
					(fill yes)
				)
			)
		)
	)
	(footprint ""
		(layer "F.Cu")
		(at 215.15197 -69.088)
		(property "Reference" "R18"
			(at 0 0 0)
			(layer "F.SilkS")
			(hide yes)
			(effects
				(font
					(size 1.27 1.27)
				)
			)
		)
		(property "Value" "100R2F-L1-GP-U"
			(at 0.064008 -3.993896 0)
			(unlocked yes)
			(layer "F.Fab")
			(hide yes)
			(effects
				(font
					(size 1.016 1.016)
					(thickness 0.1524)
				)
			)
		)
		(property "Device Type" "R402H14"
			(at 0.064008 -5.517896 0)
			(unlocked yes)
			(layer "F.Fab")
			(hide yes)
			(effects
				(font
					(size 1.016 1.016)
					(thickness 0.1524)
				)
			)
		)
		(duplicate_pad_numbers_are_jumpers no)
		(fp_line
			(start -0.508 -0.9398)
			(end -0.508 0.9398)
			(stroke
				(width 0.1524)
				(type default)
			)
			(layer "F.SilkS")
		)
		(fp_line
			(start 0.508 -0.9398)
			(end -0.508 -0.9398)
			(stroke
				(width 0.1524)
				(type default)
			)
			(layer "F.SilkS")
		)
		(fp_rect
			(start -0.508 0.9398)
			(end 0.508 -0.9398)
			(stroke
				(width 0)
				(type default)
			)
			(fill no)
			(layer "F.CrtYd")
		)
		(fp_rect
			(start -0.508 0.9398)
			(end 0.508 -0.9398)
			(stroke
				(width 0)
				(type default)
			)
			(fill no)
			(layer "F.Fab")
		)
		(pad "1" smd custom
			(at 0 -0.4445)
			(size 0.1397 0.1397)
			(layers "F.Cu" "F.Mask" "F.Paste")
			(net "SVR_ID3")
			(options
				(clearance outline)
				(anchor circle)
			)
			(primitives
				(gr_poly
					(pts
						(arc
							(start -0.1778 -0.2794)
							(mid -0.249642 -0.249642)
							(end -0.2794 -0.1778)
						)
						(arc
							(start -0.2794 0.1778)
							(mid -0.249642 0.249642)
							(end -0.1778 0.2794)
						)
						(arc
							(start 0.1778 0.2794)
							(mid 0.249642 0.249642)
							(end 0.2794 0.1778)
						)
						(arc
							(start 0.2794 -0.1778)
							(mid 0.249642 -0.249642)
							(end 0.1778 -0.2794)
						)
					)
					(width 0)
					(fill yes)
				)
			)
		)
		(pad "2" smd custom
			(at 0 0.4445)
			(size 0.1397 0.1397)
			(layers "F.Cu" "F.Mask" "F.Paste")
			(net "GND")
			(options
				(clearance outline)
				(anchor circle)
			)
			(primitives
				(gr_poly
					(pts
						(arc
							(start -0.1778 -0.2794)
							(mid -0.249642 -0.249642)
							(end -0.2794 -0.1778)
						)
						(arc
							(start -0.2794 0.1778)
							(mid -0.249642 0.249642)
							(end -0.1778 0.2794)
						)
						(arc
							(start 0.1778 0.2794)
							(mid 0.249642 0.249642)
							(end 0.2794 0.1778)
						)
						(arc
							(start 0.2794 -0.1778)
							(mid 0.249642 -0.249642)
							(end 0.1778 -0.2794)
						)
					)
					(width 0)
					(fill yes)
				)
			)
		)
	)
	(footprint ""
		(layer "F.Cu")
		(at 340.868 -20.193 180)
		(property "Reference" "R1582"
			(at 0 0 180)
			(layer "F.SilkS")
			(hide yes)
			(effects
				(font
					(size 1.27 1.27)
				)
			)
		)
		(property "Value" "33R2F-3-GP"
			(at 0.064008 -3.993896 180)
			(unlocked yes)
			(layer "F.Fab")
			(hide yes)
			(effects
				(font
					(size 1.016 1.016)
					(thickness 0.1524)
				)
			)
		)
		(property "Device Type" "R402H16"
			(at 0.064008 -5.517896 180)
			(unlocked yes)
			(layer "F.Fab")
			(hide yes)
			(effects
				(font
					(size 1.016 1.016)
					(thickness 0.1524)
				)
			)
		)
		(duplicate_pad_numbers_are_jumpers no)
		(fp_line
			(start 0.508 -0.9398)
			(end -0.508 -0.9398)
			(stroke
				(width 0.1524)
				(type default)
			)
			(layer "F.SilkS")
		)
		(fp_line
			(start -0.508 -0.9398)
			(end -0.508 0.9398)
			(stroke
				(width 0.1524)
				(type default)
			)
			(layer "F.SilkS")
		)
		(fp_rect
			(start -0.508 0.9398)
			(end 0.508 -0.9398)
			(stroke
				(width 0)
				(type default)
			)
			(fill no)
			(layer "F.CrtYd")
		)
		(fp_rect
			(start -0.508 0.9398)
			(end 0.508 -0.9398)
			(stroke
				(width 0)
				(type default)
			)
			(fill no)
			(layer "F.Fab")
		)
		(pad "1" smd custom
			(at 0 -0.4445 180)
			(size 0.1397 0.1397)
			(layers "F.Cu" "F.Mask" "F.Paste")
			(net "CPU_EXP_RST")
			(options
				(clearance outline)
				(anchor circle)
			)
			(primitives
				(gr_poly
					(pts
						(arc
							(start -0.1778 -0.2794)
							(mid -0.249642 -0.249642)
							(end -0.2794 -0.1778)
						)
						(arc
							(start -0.2794 0.1778)
							(mid -0.249642 0.249642)
							(end -0.1778 0.2794)
						)
						(arc
							(start 0.1778 0.2794)
							(mid 0.249642 0.249642)
							(end 0.2794 0.1778)
						)
						(arc
							(start 0.2794 -0.1778)
							(mid 0.249642 -0.249642)
							(end 0.1778 -0.2794)
						)
					)
					(width 0)
					(fill yes)
				)
			)
		)
		(pad "2" smd custom
			(at 0 0.4445 180)
			(size 0.1397 0.1397)
			(layers "F.Cu" "F.Mask" "F.Paste")
			(net "FP_RESET_RC_N")
			(options
				(clearance outline)
				(anchor circle)
			)
			(primitives
				(gr_poly
					(pts
						(arc
							(start -0.1778 -0.2794)
							(mid -0.249642 -0.249642)
							(end -0.2794 -0.1778)
						)
						(arc
							(start -0.2794 0.1778)
							(mid -0.249642 0.249642)
							(end -0.1778 0.2794)
						)
						(arc
							(start 0.1778 0.2794)
							(mid 0.249642 0.249642)
							(end 0.2794 0.1778)
						)
						(arc
							(start 0.2794 -0.1778)
							(mid 0.249642 -0.249642)
							(end 0.1778 -0.2794)
						)
					)
					(width 0)
					(fill yes)
				)
			)
		)
	)
	(footprint ""
		(layer "F.Cu")
		(at 179.324 -16.129 -90)
		(property "Reference" "R204"
			(at 0 0 270)
			(layer "F.SilkS")
			(hide yes)
			(effects
				(font
					(size 1.27 1.27)
				)
			)
		)
		(property "Value" "0R2J-2-GP"
			(at 0.064008 -3.993896 270)
			(unlocked yes)
			(layer "F.Fab")
			(hide yes)
			(effects
				(font
					(size 1.016 1.016)
					(thickness 0.1524)
				)
			)
		)
		(property "Device Type" "R402H16"
			(at 0.064008 -5.517896 270)
			(unlocked yes)
			(layer "F.Fab")
			(hide yes)
			(effects
				(font
					(size 1.016 1.016)
					(thickness 0.1524)
				)
			)
		)
		(duplicate_pad_numbers_are_jumpers no)
		(fp_line
			(start -0.508 -0.9398)
			(end -0.508 0.9398)
			(stroke
				(width 0.1524)
				(type default)
			)
			(layer "F.SilkS")
		)
		(fp_line
			(start 0.508 -0.9398)
			(end -0.508 -0.9398)
			(stroke
				(width 0.1524)
				(type default)
			)
			(layer "F.SilkS")
		)
		(fp_rect
			(start -0.508 0.9398)
			(end 0.508 -0.9398)
			(stroke
				(width 0)
				(type default)
			)
			(fill no)
			(layer "F.CrtYd")
		)
		(fp_rect
			(start -0.508 0.9398)
			(end 0.508 -0.9398)
			(stroke
				(width 0)
				(type default)
			)
			(fill no)
			(layer "F.Fab")
		)
		(pad "1" smd custom
			(at 0 -0.4445 270)
			(size 0.1397 0.1397)
			(layers "F.Cu" "F.Mask" "F.Paste")
			(net "TEMP_SENSOR_C")
			(options
				(clearance outline)
				(anchor circle)
			)
			(primitives
				(gr_poly
					(pts
						(arc
							(start -0.1778 -0.2794)
							(mid -0.249642 -0.249642)
							(end -0.2794 -0.1778)
						)
						(arc
							(start -0.2794 0.1778)
							(mid -0.249642 0.249642)
							(end -0.1778 0.2794)
						)
						(arc
							(start 0.1778 0.2794)
							(mid 0.249642 0.249642)
							(end 0.2794 0.1778)
						)
						(arc
							(start 0.2794 -0.1778)
							(mid 0.249642 -0.249642)
							(end 0.1778 -0.2794)
						)
					)
					(width 0)
					(fill yes)
				)
			)
		)
		(pad "2" smd custom
			(at 0 0.4445 270)
			(size 0.1397 0.1397)
			(layers "F.Cu" "F.Mask" "F.Paste")
			(net "TEMP_SENSOR_DXN_BJT")
			(options
				(clearance outline)
				(anchor circle)
			)
			(primitives
				(gr_poly
					(pts
						(arc
							(start -0.1778 -0.2794)
							(mid -0.249642 -0.249642)
							(end -0.2794 -0.1778)
						)
						(arc
							(start -0.2794 0.1778)
							(mid -0.249642 0.249642)
							(end -0.1778 0.2794)
						)
						(arc
							(start 0.1778 0.2794)
							(mid 0.249642 0.249642)
							(end 0.2794 0.1778)
						)
						(arc
							(start 0.2794 -0.1778)
							(mid 0.249642 -0.249642)
							(end 0.1778 -0.2794)
						)
					)
					(width 0)
					(fill yes)
				)
			)
		)
	)
	(footprint ""
		(layer "F.Cu")
		(at 267.335 -66.04 180)
		(property "Reference" "Q76"
			(at 0 0 180)
			(layer "F.SilkS")
			(hide yes)
			(effects
				(font
					(size 1.27 1.27)
				)
			)
		)
		(property "Value" "PSMN0R9-25YLC-GP"
			(at -4.2799 -0.4572 180)
			(unlocked yes)
			(layer "F.Fab")
			(hide yes)
			(effects
				(font
					(size 1.016 1.016)
					(thickness 0.1524)
				)
			)
		)
		(property "Device Type" "LFPAK-5PH48-U"
			(at -4.2799 -1.9812 180)
			(unlocked yes)
			(layer "F.Fab")
			(hide yes)
			(effects
				(font
					(size 1.016 1.016)
					(thickness 0.1524)
				)
			)
		)
		(duplicate_pad_numbers_are_jumpers no)
		(fp_line
			(start 2.7559 1.0668)
			(end 2.7559 -6.5532)
			(stroke
				(width 0.1524)
				(type default)
			)
			(layer "F.SilkS")
		)
		(fp_line
			(start 2.7559 -6.5532)
			(end -2.7559 -6.5532)
			(stroke
				(width 0.1524)
				(type default)
			)
			(layer "F.SilkS")
		)
		(fp_line
			(start -1.7272 1.1684)
			(end -2.1082 1.1684)
			(stroke
				(width 0.3302)
				(type default)
			)
			(layer "F.SilkS")
		)
		(fp_line
			(start -2.7559 1.0668)
			(end 2.7559 1.0668)
			(stroke
				(width 0.1524)
				(type default)
			)
			(layer "F.SilkS")
		)
		(fp_line
			(start -2.7559 -6.5532)
			(end -2.7559 1.0668)
			(stroke
				(width 0.1524)
				(type default)
			)
			(layer "F.SilkS")
		)
		(fp_poly
			(pts
				(xy -2.3368 1.5748) (xy -1.905 1.143) (xy -1.4732 1.5748)
			)
			(stroke
				(width 0)
				(type default)
			)
			(fill yes)
			(layer "F.SilkS")
		)
		(fp_poly
			(pts
				(xy 0.3302 -1.09601) (xy 2.5019 -1.09601) (xy 2.5019 -3.36931) (xy 0.3302 -3.36931)
			)
			(stroke
				(width 0)
				(type default)
			)
			(fill yes)
			(layer "F.Paste")
		)
		(fp_poly
			(pts
				(xy 0.3302 -4.02971) (xy 2.5019 -4.02971) (xy 2.5019 -6.30301) (xy 0.3302 -6.30301)
			)
			(stroke
				(width 0)
				(type default)
			)
			(fill yes)
			(layer "F.Paste")
		)
		(fp_poly
			(pts
				(xy -2.5019 -1.09601) (xy -0.3302 -1.09601) (xy -0.3302 -3.36931) (xy -2.5019 -3.36931)
			)
			(stroke
				(width 0)
				(type default)
			)
			(fill yes)
			(layer "F.Paste")
		)
		(fp_poly
			(pts
				(xy -2.5019 -4.02971) (xy -0.3302 -4.02971) (xy -0.3302 -6.30301) (xy -2.5019 -6.30301)
			)
			(stroke
				(width 0)
				(type default)
			)
			(fill yes)
			(layer "F.Paste")
		)
		(fp_rect
			(start -2.4511 0.3048)
			(end 2.4511 -5.6896)
			(stroke
				(width 0)
				(type default)
			)
			(fill no)
			(layer "F.CrtYd")
		)
		(fp_poly
			(pts
				(xy -3.0099 1.3208) (xy -3.0099 -6.8072) (xy 3.0099 -6.8072) (xy 3.0099 -1.016) (xy 2.4511 -1.016)
				(xy 2.4511 -5.6896) (xy -2.4511 -5.6896) (xy -2.4511 0.3048) (xy 2.4511 0.3048) (xy 2.4511 -1.0033)
				(xy 3.0099 -1.0033) (xy 3.0099 1.3208)
			)
			(stroke
				(width 0)
				(type default)
			)
			(fill no)
			(layer "F.CrtYd")
		)
		(fp_rect
			(start -3.0099 1.3208)
			(end 3.0099 -6.8072)
			(stroke
				(width 0)
				(type default)
			)
			(fill no)
			(layer "F.Fab")
		)
		(pad "1" smd rect
			(at -1.905 0 180)
			(size 0.762 1.6256)
			(layers "F.Cu" "F.Mask" "F.Paste")
			(net "P12V_MSB")
		)
		(pad "2" smd rect
			(at -0.635 0 180)
			(size 0.762 1.6256)
			(layers "F.Cu" "F.Mask" "F.Paste")
			(net "P12V_MSB")
		)
		(pad "3" smd rect
			(at 0.635 0 180)
			(size 0.762 1.6256)
			(layers "F.Cu" "F.Mask" "F.Paste")
			(net "P12V_MSB")
		)
		(pad "4" smd rect
			(at 1.905 0 180)
			(size 0.762 1.6256)
			(layers "F.Cu" "F.Mask" "F.Paste")
			(net "VR_HSC_GATE_R_MSB")
		)
		(pad "5" smd rect
			(at 0 -3.69951 180)
			(size 5.0038 5.207)
			(layers "F.Cu" "F.Mask" "F.Paste")
			(net "VSENSE_HSC_MSB")
		)
	)
	(footprint ""
		(layer "F.Cu")
		(at 289.678872 -72.716136 90)
		(property "Reference" "R522"
			(at 0 0 90)
			(layer "F.SilkS")
			(hide yes)
			(effects
				(font
					(size 1.27 1.27)
				)
			)
		)
		(property "Value" "10R2F-L-GP"
			(at 0.064008 -3.993896 90)
			(unlocked yes)
			(layer "F.Fab")
			(hide yes)
			(effects
				(font
					(size 1.016 1.016)
					(thickness 0.1524)
				)
			)
		)
		(property "Device Type" "R402H14"
			(at 0.064008 -5.517896 90)
			(unlocked yes)
			(layer "F.Fab")
			(hide yes)
			(effects
				(font
					(size 1.016 1.016)
					(thickness 0.1524)
				)
			)
		)
		(duplicate_pad_numbers_are_jumpers no)
		(fp_line
			(start 0.508 -0.9398)
			(end -0.508 -0.9398)
			(stroke
				(width 0.1524)
				(type default)
			)
			(layer "F.SilkS")
		)
		(fp_line
			(start -0.508 -0.9398)
			(end -0.508 0.9398)
			(stroke
				(width 0.1524)
				(type default)
			)
			(layer "F.SilkS")
		)
		(fp_rect
			(start -0.508 0.9398)
			(end 0.508 -0.9398)
			(stroke
				(width 0)
				(type default)
			)
			(fill no)
			(layer "F.CrtYd")
		)
		(fp_rect
			(start -0.508 0.9398)
			(end 0.508 -0.9398)
			(stroke
				(width 0)
				(type default)
			)
			(fill no)
			(layer "F.Fab")
		)
		(pad "1" smd custom
			(at 0 -0.4445 90)
			(size 0.1397 0.1397)
			(layers "F.Cu" "F.Mask" "F.Paste")
			(net "VR_HSC_GATE_MSB")
			(options
				(clearance outline)
				(anchor circle)
			)
			(primitives
				(gr_poly
					(pts
						(arc
							(start -0.1778 -0.2794)
							(mid -0.249642 -0.249642)
							(end -0.2794 -0.1778)
						)
						(arc
							(start -0.2794 0.1778)
							(mid -0.249642 0.249642)
							(end -0.1778 0.2794)
						)
						(arc
							(start 0.1778 0.2794)
							(mid 0.249642 0.249642)
							(end 0.2794 0.1778)
						)
						(arc
							(start 0.2794 -0.1778)
							(mid 0.249642 -0.249642)
							(end 0.1778 -0.2794)
						)
					)
					(width 0)
					(fill yes)
				)
			)
		)
		(pad "2" smd custom
			(at 0 0.4445 90)
			(size 0.1397 0.1397)
			(layers "F.Cu" "F.Mask" "F.Paste")
			(net "VR_HSC_GATE_R_MSB")
			(options
				(clearance outline)
				(anchor circle)
			)
			(primitives
				(gr_poly
					(pts
						(arc
							(start -0.1778 -0.2794)
							(mid -0.249642 -0.249642)
							(end -0.2794 -0.1778)
						)
						(arc
							(start -0.2794 0.1778)
							(mid -0.249642 0.249642)
							(end -0.1778 0.2794)
						)
						(arc
							(start 0.1778 0.2794)
							(mid 0.249642 0.249642)
							(end 0.2794 0.1778)
						)
						(arc
							(start 0.2794 -0.1778)
							(mid 0.249642 -0.249642)
							(end 0.1778 -0.2794)
						)
					)
					(width 0)
					(fill yes)
				)
			)
		)
	)
	(footprint ""
		(layer "F.Cu")
		(at 92.21597 -98.933 -90)
		(property "Reference" "SR778"
			(at 0 0 270)
			(layer "F.SilkS")
			(hide yes)
			(effects
				(font
					(size 1.27 1.27)
				)
			)
		)
		(property "Value" "4K7R2F-GP"
			(at 0.064008 -3.993896 270)
			(unlocked yes)
			(layer "F.Fab")
			(hide yes)
			(effects
				(font
					(size 1.016 1.016)
					(thickness 0.1524)
				)
			)
		)
		(property "Device Type" "R402H16"
			(at 0.064008 -5.517896 270)
			(unlocked yes)
			(layer "F.Fab")
			(hide yes)
			(effects
				(font
					(size 1.016 1.016)
					(thickness 0.1524)
				)
			)
		)
		(duplicate_pad_numbers_are_jumpers no)
		(fp_line
			(start -0.508 -0.9398)
			(end -0.508 0.9398)
			(stroke
				(width 0.1524)
				(type default)
			)
			(layer "F.SilkS")
		)
		(fp_line
			(start 0.508 -0.9398)
			(end -0.508 -0.9398)
			(stroke
				(width 0.1524)
				(type default)
			)
			(layer "F.SilkS")
		)
		(fp_rect
			(start -0.508 0.9398)
			(end 0.508 -0.9398)
			(stroke
				(width 0)
				(type default)
			)
			(fill no)
			(layer "F.CrtYd")
		)
		(fp_rect
			(start -0.508 0.9398)
			(end 0.508 -0.9398)
			(stroke
				(width 0)
				(type default)
			)
			(fill no)
			(layer "F.Fab")
		)
		(pad "1" smd custom
			(at 0 -0.4445 270)
			(size 0.1397 0.1397)
			(layers "F.Cu" "F.Mask" "F.Paste")
			(net "EXP_XM_ADDR_17")
			(options
				(clearance outline)
				(anchor circle)
			)
			(primitives
				(gr_poly
					(pts
						(arc
							(start -0.1778 -0.2794)
							(mid -0.249642 -0.249642)
							(end -0.2794 -0.1778)
						)
						(arc
							(start -0.2794 0.1778)
							(mid -0.249642 0.249642)
							(end -0.1778 0.2794)
						)
						(arc
							(start 0.1778 0.2794)
							(mid 0.249642 0.249642)
							(end 0.2794 0.1778)
						)
						(arc
							(start 0.2794 -0.1778)
							(mid 0.249642 -0.249642)
							(end 0.1778 -0.2794)
						)
					)
					(width 0)
					(fill yes)
				)
			)
		)
		(pad "2" smd custom
			(at 0 0.4445 270)
			(size 0.1397 0.1397)
			(layers "F.Cu" "F.Mask" "F.Paste")
			(net "GND")
			(options
				(clearance outline)
				(anchor circle)
			)
			(primitives
				(gr_poly
					(pts
						(arc
							(start -0.1778 -0.2794)
							(mid -0.249642 -0.249642)
							(end -0.2794 -0.1778)
						)
						(arc
							(start -0.2794 0.1778)
							(mid -0.249642 0.249642)
							(end -0.1778 0.2794)
						)
						(arc
							(start 0.1778 0.2794)
							(mid 0.249642 0.249642)
							(end 0.2794 0.1778)
						)
						(arc
							(start 0.2794 -0.1778)
							(mid 0.249642 -0.249642)
							(end 0.1778 -0.2794)
						)
					)
					(width 0)
					(fill yes)
				)
			)
		)
	)
	(footprint ""
		(layer "F.Cu")
		(at 332.359 -211.455 180)
		(property "Reference" "R5305"
			(at 0 0 180)
			(layer "F.SilkS")
			(hide yes)
			(effects
				(font
					(size 1.27 1.27)
				)
			)
		)
		(property "Value" "0R2J-2-GP"
			(at 0.064008 -3.993896 180)
			(unlocked yes)
			(layer "F.Fab")
			(hide yes)
			(effects
				(font
					(size 1.016 1.016)
					(thickness 0.1524)
				)
			)
		)
		(property "Device Type" "R402H16"
			(at 0.064008 -5.517896 180)
			(unlocked yes)
			(layer "F.Fab")
			(hide yes)
			(effects
				(font
					(size 1.016 1.016)
					(thickness 0.1524)
				)
			)
		)
		(duplicate_pad_numbers_are_jumpers no)
		(fp_line
			(start 0.508 -0.9398)
			(end -0.508 -0.9398)
			(stroke
				(width 0.1524)
				(type default)
			)
			(layer "F.SilkS")
		)
		(fp_line
			(start -0.508 -0.9398)
			(end -0.508 0.9398)
			(stroke
				(width 0.1524)
				(type default)
			)
			(layer "F.SilkS")
		)
		(fp_rect
			(start -0.508 0.9398)
			(end 0.508 -0.9398)
			(stroke
				(width 0)
				(type default)
			)
			(fill no)
			(layer "F.CrtYd")
		)
		(fp_rect
			(start -0.508 0.9398)
			(end 0.508 -0.9398)
			(stroke
				(width 0)
				(type default)
			)
			(fill no)
			(layer "F.Fab")
		)
		(pad "1" smd custom
			(at 0 -0.4445 180)
			(size 0.1397 0.1397)
			(layers "F.Cu" "F.Mask" "F.Paste")
			(net "EEPROM_SCL")
			(options
				(clearance outline)
				(anchor circle)
			)
			(primitives
				(gr_poly
					(pts
						(arc
							(start -0.1778 -0.2794)
							(mid -0.249642 -0.249642)
							(end -0.2794 -0.1778)
						)
						(arc
							(start -0.2794 0.1778)
							(mid -0.249642 0.249642)
							(end -0.1778 0.2794)
						)
						(arc
							(start 0.1778 0.2794)
							(mid 0.249642 0.249642)
							(end 0.2794 0.1778)
						)
						(arc
							(start 0.2794 -0.1778)
							(mid 0.249642 -0.249642)
							(end 0.1778 -0.2794)
						)
					)
					(width 0)
					(fill yes)
				)
			)
		)
		(pad "2" smd custom
			(at 0 0.4445 180)
			(size 0.1397 0.1397)
			(layers "F.Cu" "F.Mask" "F.Paste")
			(net "BMC_I2C_SCL_10")
			(options
				(clearance outline)
				(anchor circle)
			)
			(primitives
				(gr_poly
					(pts
						(arc
							(start -0.1778 -0.2794)
							(mid -0.249642 -0.249642)
							(end -0.2794 -0.1778)
						)
						(arc
							(start -0.2794 0.1778)
							(mid -0.249642 0.249642)
							(end -0.1778 0.2794)
						)
						(arc
							(start 0.1778 0.2794)
							(mid 0.249642 0.249642)
							(end 0.2794 0.1778)
						)
						(arc
							(start 0.2794 -0.1778)
							(mid 0.249642 -0.249642)
							(end 0.1778 -0.2794)
						)
					)
					(width 0)
					(fill yes)
				)
			)
		)
	)
	(footprint ""
		(layer "F.Cu")
		(at 185.284872 -206.497936 180)
		(property "Reference" "C242"
			(at 0 0 180)
			(layer "F.SilkS")
			(hide yes)
			(effects
				(font
					(size 1.27 1.27)
				)
			)
		)
		(property "Value" "SCD01U50V2KX-1GP"
			(at 1.1811 -2.7051 180)
			(unlocked yes)
			(layer "F.Fab")
			(hide yes)
			(effects
				(font
					(size 1.016 1.016)
					(thickness 0.1524)
				)
			)
		)
		(property "Device Type" "C402H22"
			(at 1.1811 -4.2291 180)
			(unlocked yes)
			(layer "F.Fab")
			(hide yes)
			(effects
				(font
					(size 1.016 1.016)
					(thickness 0.1524)
				)
			)
		)
		(duplicate_pad_numbers_are_jumpers no)
		(fp_rect
			(start -0.4318 0.9525)
			(end 0.4318 -0.9525)
			(stroke
				(width 0)
				(type default)
			)
			(fill no)
			(layer "F.CrtYd")
		)
		(fp_rect
			(start -0.4318 0.9525)
			(end 0.4318 -0.9525)
			(stroke
				(width 0)
				(type default)
			)
			(fill no)
			(layer "F.Fab")
		)
		(pad "1" smd custom
			(at 0 -0.4445 180)
			(size 0.1524 0.1524)
			(layers "F.Cu" "F.Mask" "F.Paste")
			(net "P3V3_STBY")
			(options
				(clearance outline)
				(anchor circle)
			)
			(primitives
				(gr_poly
					(pts
						(arc
							(start 0.3048 -0.2032)
							(mid 0.275042 -0.275042)
							(end 0.2032 -0.3048)
						)
						(arc
							(start -0.2032 -0.3048)
							(mid -0.275042 -0.275042)
							(end -0.3048 -0.2032)
						)
						(arc
							(start -0.3048 0.2032)
							(mid -0.275042 0.275042)
							(end -0.2032 0.3048)
						)
						(arc
							(start 0.2032 0.3048)
							(mid 0.275042 0.275042)
							(end 0.3048 0.2032)
						)
					)
					(width 0)
					(fill yes)
				)
			)
		)
		(pad "2" smd custom
			(at 0 0.4445 180)
			(size 0.1524 0.1524)
			(layers "F.Cu" "F.Mask" "F.Paste")
			(net "GND")
			(options
				(clearance outline)
				(anchor circle)
			)
			(primitives
				(gr_poly
					(pts
						(arc
							(start 0.3048 -0.2032)
							(mid 0.275042 -0.275042)
							(end 0.2032 -0.3048)
						)
						(arc
							(start -0.2032 -0.3048)
							(mid -0.275042 -0.275042)
							(end -0.3048 -0.2032)
						)
						(arc
							(start -0.3048 0.2032)
							(mid -0.275042 0.275042)
							(end -0.2032 0.3048)
						)
						(arc
							(start 0.2032 0.3048)
							(mid 0.275042 0.275042)
							(end 0.3048 0.2032)
						)
					)
					(width 0)
					(fill yes)
				)
			)
		)
	)
	(footprint ""
		(layer "F.Cu")
		(at 350.484948 -22.200108 180)
		(property "Reference" "SW2"
			(at 0 0 180)
			(layer "F.SilkS")
			(hide yes)
			(effects
				(font
					(size 1.27 1.27)
				)
			)
		)
		(property "Value" "SW-TACT-4P-196-GP"
			(at -5.5118 0.2032 180)
			(unlocked yes)
			(layer "F.Fab")
			(hide yes)
			(effects
				(font
					(size 1.016 1.016)
					(thickness 0.1524)
				)
			)
		)
		(property "Device Type" "DTS-63N-V"
			(at -5.5118 -1.3208 180)
			(unlocked yes)
			(layer "F.Fab")
			(hide yes)
			(effects
				(font
					(size 1.016 1.016)
					(thickness 0.1524)
				)
			)
		)
		(duplicate_pad_numbers_are_jumpers no)
		(fp_line
			(start 4.2164 3.3528)
			(end 4.2164 -3.3528)
			(stroke
				(width 0.1524)
				(type default)
			)
			(layer "F.SilkS")
		)
		(fp_line
			(start 4.2164 -3.3528)
			(end -4.2164 -3.3528)
			(stroke
				(width 0.1524)
				(type default)
			)
			(layer "F.SilkS")
		)
		(fp_line
			(start 0 0.762)
			(end 0 2.54)
			(stroke
				(width 0.1524)
				(type default)
			)
			(layer "F.SilkS")
		)
		(fp_line
			(start 0 -0.762)
			(end 0.508 0.508)
			(stroke
				(width 0.1524)
				(type default)
			)
			(layer "F.SilkS")
		)
		(fp_line
			(start 0 -2.54)
			(end 0 -0.762)
			(stroke
				(width 0.1524)
				(type default)
			)
			(layer "F.SilkS")
		)
		(fp_line
			(start -3.2258 -3.6322)
			(end -4.4958 -3.6322)
			(stroke
				(width 0.4064)
				(type default)
			)
			(layer "F.SilkS")
		)
		(fp_line
			(start -4.2164 3.3528)
			(end 4.2164 3.3528)
			(stroke
				(width 0.1524)
				(type default)
			)
			(layer "F.SilkS")
		)
		(fp_line
			(start -4.2164 -3.3528)
			(end -4.2164 3.3528)
			(stroke
				(width 0.1524)
				(type default)
			)
			(layer "F.SilkS")
		)
		(fp_line
			(start -4.4958 -3.6322)
			(end -4.4958 -2.3622)
			(stroke
				(width 0.4064)
				(type default)
			)
			(layer "F.SilkS")
		)
		(fp_circle
			(center 3.24993 2.249932)
			(end 2.18313 2.249932)
			(stroke
				(width 0.3048)
				(type default)
			)
			(fill no)
			(layer "F.SilkS")
		)
		(fp_circle
			(center 3.24993 -2.249932)
			(end 2.18313 -2.249932)
			(stroke
				(width 0.3048)
				(type default)
			)
			(fill no)
			(layer "F.SilkS")
		)
		(fp_circle
			(center 0 0.762)
			(end -0.0762 0.762)
			(stroke
				(width 0.1524)
				(type default)
			)
			(fill no)
			(layer "F.SilkS")
		)
		(fp_circle
			(center 0 -0.762)
			(end -0.0762 -0.762)
			(stroke
				(width 0.1524)
				(type default)
			)
			(fill no)
			(layer "F.SilkS")
		)
		(fp_circle
			(center -3.24993 2.249932)
			(end -4.31673 2.249932)
			(stroke
				(width 0.3048)
				(type default)
			)
			(fill no)
			(layer "F.SilkS")
		)
		(fp_circle
			(center -3.24993 -2.249932)
			(end -4.31673 -2.249932)
			(stroke
				(width 0.3048)
				(type default)
			)
			(fill no)
			(layer "F.SilkS")
		)
		(fp_poly
			(pts
				(xy -3.0988 3.0988) (xy -3.0988 2.605532) (xy -3.9497 2.605532) (xy -3.9497 1.894332) (xy -3.0988 1.894332)
				(xy -3.0988 -1.894332) (xy -3.9497 -1.894332) (xy -3.9497 -2.605532) (xy -3.0988 -2.605532) (xy -3.0988 -3.0988)
				(xy 3.0988 -3.0988) (xy 3.0988 -2.605532) (xy 3.9497 -2.605532) (xy 3.9497 -1.894332) (xy 3.0988 -1.894332)
				(xy 3.0988 1.894332) (xy 3.9497 1.894332) (xy 3.9497 2.605532) (xy 3.0988 2.605532) (xy 3.0988 3.0988)
			)
			(stroke
				(width 0)
				(type default)
			)
			(fill no)
			(layer "F.CrtYd")
		)
		(fp_poly
			(pts
				(xy -4.4704 3.6068) (xy -4.4704 -3.6068) (xy 4.4704 -3.6068) (xy 4.4704 3.6068) (xy 0.00254 3.6068)
				(xy 0.00254 3.0988) (xy 3.0988 3.0988) (xy 3.0988 2.605532) (xy 3.9497 2.605532) (xy 3.9497 1.894332)
				(xy 3.0988 1.894332) (xy 3.0988 -1.894332) (xy 3.9497 -1.894332) (xy 3.9497 -2.605532) (xy 3.0988 -2.605532)
				(xy 3.0988 -3.0988) (xy -3.0988 -3.0988) (xy -3.0988 -2.605532) (xy -3.9497 -2.605532) (xy -3.9497 -1.894332)
				(xy -3.0988 -1.894332) (xy -3.0988 1.894332) (xy -3.9497 1.894332) (xy -3.9497 2.605532) (xy -3.0988 2.605532)
				(xy -3.0988 3.0988) (xy -0.00254 3.0988) (xy -0.00254 3.6068)
			)
			(stroke
				(width 0)
				(type default)
			)
			(fill no)
			(layer "F.CrtYd")
		)
		(fp_rect
			(start -4.4704 3.6068)
			(end 4.4704 -3.6068)
			(stroke
				(width 0)
				(type default)
			)
			(fill no)
			(layer "F.Fab")
		)
		(pad "1" thru_hole circle
			(at -3.24993 -2.249932 180)
			(size 1.4224 1.4224)
			(drill 1.016)
			(layers "*.Cu" "*.Mask")
			(remove_unused_layers no)
			(net "CPU_EXP_RST")
			(clearance 0.1524)
			(thermal_gap 0.1524)
		)
		(pad "2" thru_hole circle
			(at 3.24993 -2.249932 180)
			(size 1.4224 1.4224)
			(drill 1.016)
			(layers "*.Cu" "*.Mask")
			(remove_unused_layers no)
			(net "CPU_EXP_RST")
			(clearance 0.1524)
			(thermal_gap 0.1524)
		)
		(pad "3" thru_hole circle
			(at -3.24993 2.249932 180)
			(size 1.4224 1.4224)
			(drill 1.016)
			(layers "*.Cu" "*.Mask")
			(remove_unused_layers no)
			(net "GND")
			(clearance 0.1524)
			(thermal_gap 0.1524)
		)
		(pad "4" thru_hole circle
			(at 3.24993 2.249932 180)
			(size 1.4224 1.4224)
			(drill 1.016)
			(layers "*.Cu" "*.Mask")
			(remove_unused_layers no)
			(net "GND")
			(clearance 0.1524)
			(thermal_gap 0.1524)
		)
	)
	(footprint ""
		(layer "F.Cu")
		(at 186.554872 -195.271136 -90)
		(property "Reference" "R432"
			(at 0 0 270)
			(layer "F.SilkS")
			(hide yes)
			(effects
				(font
					(size 1.27 1.27)
				)
			)
		)
		(property "Value" "0R2J-2-GP"
			(at 0.064008 -3.993896 270)
			(unlocked yes)
			(layer "F.Fab")
			(hide yes)
			(effects
				(font
					(size 1.016 1.016)
					(thickness 0.1524)
				)
			)
		)
		(property "Device Type" "R402H16"
			(at 0.064008 -5.517896 270)
			(unlocked yes)
			(layer "F.Fab")
			(hide yes)
			(effects
				(font
					(size 1.016 1.016)
					(thickness 0.1524)
				)
			)
		)
		(duplicate_pad_numbers_are_jumpers no)
		(fp_line
			(start -0.508 -0.9398)
			(end -0.508 0.9398)
			(stroke
				(width 0.1524)
				(type default)
			)
			(layer "F.SilkS")
		)
		(fp_line
			(start 0.508 -0.9398)
			(end -0.508 -0.9398)
			(stroke
				(width 0.1524)
				(type default)
			)
			(layer "F.SilkS")
		)
		(fp_rect
			(start -0.508 0.9398)
			(end 0.508 -0.9398)
			(stroke
				(width 0)
				(type default)
			)
			(fill no)
			(layer "F.CrtYd")
		)
		(fp_rect
			(start -0.508 0.9398)
			(end 0.508 -0.9398)
			(stroke
				(width 0)
				(type default)
			)
			(fill no)
			(layer "F.Fab")
		)
		(pad "1" smd custom
			(at 0 -0.4445 270)
			(size 0.1397 0.1397)
			(layers "F.Cu" "F.Mask" "F.Paste")
			(net "SAS_I2C_C_BUF_SDA")
			(options
				(clearance outline)
				(anchor circle)
			)
			(primitives
				(gr_poly
					(pts
						(arc
							(start -0.1778 -0.2794)
							(mid -0.249642 -0.249642)
							(end -0.2794 -0.1778)
						)
						(arc
							(start -0.2794 0.1778)
							(mid -0.249642 0.249642)
							(end -0.1778 0.2794)
						)
						(arc
							(start 0.1778 0.2794)
							(mid 0.249642 0.249642)
							(end 0.2794 0.1778)
						)
						(arc
							(start 0.2794 -0.1778)
							(mid 0.249642 -0.249642)
							(end 0.1778 -0.2794)
						)
					)
					(width 0)
					(fill yes)
				)
			)
		)
		(pad "2" smd custom
			(at 0 0.4445 270)
			(size 0.1397 0.1397)
			(layers "F.Cu" "F.Mask" "F.Paste")
			(net "BMC_I2C_C_SDA")
			(options
				(clearance outline)
				(anchor circle)
			)
			(primitives
				(gr_poly
					(pts
						(arc
							(start -0.1778 -0.2794)
							(mid -0.249642 -0.249642)
							(end -0.2794 -0.1778)
						)
						(arc
							(start -0.2794 0.1778)
							(mid -0.249642 0.249642)
							(end -0.1778 0.2794)
						)
						(arc
							(start 0.1778 0.2794)
							(mid 0.249642 0.249642)
							(end 0.2794 0.1778)
						)
						(arc
							(start 0.2794 -0.1778)
							(mid 0.249642 -0.249642)
							(end 0.1778 -0.2794)
						)
					)
					(width 0)
					(fill yes)
				)
			)
		)
	)
	(footprint ""
		(layer "F.Cu")
		(at 334.518 -217.3605)
		(property "Reference" "R5302"
			(at 0 0 0)
			(layer "F.SilkS")
			(hide yes)
			(effects
				(font
					(size 1.27 1.27)
				)
			)
		)
		(property "Value" "0R2J-2-GP"
			(at 0.064008 -3.993896 0)
			(unlocked yes)
			(layer "F.Fab")
			(hide yes)
			(effects
				(font
					(size 1.016 1.016)
					(thickness 0.1524)
				)
			)
		)
		(property "Device Type" "R402H16"
			(at 0.064008 -5.517896 0)
			(unlocked yes)
			(layer "F.Fab")
			(hide yes)
			(effects
				(font
					(size 1.016 1.016)
					(thickness 0.1524)
				)
			)
		)
		(duplicate_pad_numbers_are_jumpers no)
		(fp_line
			(start -0.508 -0.9398)
			(end -0.508 0.9398)
			(stroke
				(width 0.1524)
				(type default)
			)
			(layer "F.SilkS")
		)
		(fp_line
			(start 0.508 -0.9398)
			(end -0.508 -0.9398)
			(stroke
				(width 0.1524)
				(type default)
			)
			(layer "F.SilkS")
		)
		(fp_rect
			(start -0.508 0.9398)
			(end 0.508 -0.9398)
			(stroke
				(width 0)
				(type default)
			)
			(fill no)
			(layer "F.CrtYd")
		)
		(fp_rect
			(start -0.508 0.9398)
			(end 0.508 -0.9398)
			(stroke
				(width 0)
				(type default)
			)
			(fill no)
			(layer "F.Fab")
		)
		(pad "1" smd custom
			(at 0 -0.4445)
			(size 0.1397 0.1397)
			(layers "F.Cu" "F.Mask" "F.Paste")
			(net "VOL_SEN_SDA")
			(options
				(clearance outline)
				(anchor circle)
			)
			(primitives
				(gr_poly
					(pts
						(arc
							(start -0.1778 -0.2794)
							(mid -0.249642 -0.249642)
							(end -0.2794 -0.1778)
						)
						(arc
							(start -0.2794 0.1778)
							(mid -0.249642 0.249642)
							(end -0.1778 0.2794)
						)
						(arc
							(start 0.1778 0.2794)
							(mid 0.249642 0.249642)
							(end 0.2794 0.1778)
						)
						(arc
							(start 0.2794 -0.1778)
							(mid 0.249642 -0.249642)
							(end 0.1778 -0.2794)
						)
					)
					(width 0)
					(fill yes)
				)
			)
		)
		(pad "2" smd custom
			(at 0 0.4445)
			(size 0.1397 0.1397)
			(layers "F.Cu" "F.Mask" "F.Paste")
			(net "BMC_I2C_SDA_10")
			(options
				(clearance outline)
				(anchor circle)
			)
			(primitives
				(gr_poly
					(pts
						(arc
							(start -0.1778 -0.2794)
							(mid -0.249642 -0.249642)
							(end -0.2794 -0.1778)
						)
						(arc
							(start -0.2794 0.1778)
							(mid -0.249642 0.249642)
							(end -0.1778 0.2794)
						)
						(arc
							(start 0.1778 0.2794)
							(mid 0.249642 0.249642)
							(end 0.2794 0.1778)
						)
						(arc
							(start 0.2794 -0.1778)
							(mid 0.249642 -0.249642)
							(end 0.1778 -0.2794)
						)
					)
					(width 0)
					(fill yes)
				)
			)
		)
	)
	(footprint ""
		(layer "F.Cu")
		(at 329.429872 -164.029136 -90)
		(property "Reference" "U26"
			(at 0 0 270)
			(layer "F.SilkS")
			(hide yes)
			(effects
				(font
					(size 1.27 1.27)
				)
			)
		)
		(property "Value" "TS5A23157DGSR-GP"
			(at 0 -11.1252 270)
			(unlocked yes)
			(layer "F.Fab")
			(hide yes)
			(effects
				(font
					(size 1.016 1.016)
					(thickness 0.1524)
				)
			)
		)
		(property "Device Type" "MSOP10H44"
			(at 0 -12.6492 270)
			(unlocked yes)
			(layer "F.Fab")
			(hide yes)
			(effects
				(font
					(size 1.016 1.016)
					(thickness 0.1524)
				)
			)
		)
		(duplicate_pad_numbers_are_jumpers no)
		(fp_line
			(start -2.0066 1.016)
			(end -2.0066 -1.016)
			(stroke
				(width 0.1524)
				(type default)
			)
			(layer "F.SilkS")
		)
		(fp_line
			(start -1.8288 1.016)
			(end -1.8288 3.048)
			(stroke
				(width 0.508)
				(type default)
			)
			(layer "F.SilkS")
		)
		(fp_line
			(start 1.143 1.016)
			(end -2.0066 1.016)
			(stroke
				(width 0.1524)
				(type default)
			)
			(layer "F.SilkS")
		)
		(fp_line
			(start -1.5748 0)
			(end -1.9558 0.381)
			(stroke
				(width 0.1524)
				(type default)
			)
			(layer "F.SilkS")
		)
		(fp_line
			(start -1.5748 0)
			(end -1.9558 -0.381)
			(stroke
				(width 0.1524)
				(type default)
			)
			(layer "F.SilkS")
		)
		(fp_line
			(start -2.0066 -1.016)
			(end 1.143 -1.016)
			(stroke
				(width 0.1524)
				(type default)
			)
			(layer "F.SilkS")
		)
		(fp_line
			(start 1.143 -1.016)
			(end 1.143 1.016)
			(stroke
				(width 0.1524)
				(type default)
			)
			(layer "F.SilkS")
		)
		(fp_poly
			(pts
				(xy -2.0828 3.3401) (xy 2.0828 3.3401) (xy 2.0828 -3.3401) (xy -2.0828 -3.3401)
			)
			(stroke
				(width 0)
				(type default)
			)
			(fill no)
			(layer "F.CrtYd")
		)
		(fp_poly
			(pts
				(xy -2.0828 3.3401) (xy 2.0828 3.3401) (xy 2.0828 -3.3401) (xy -2.0828 -3.3401)
			)
			(stroke
				(width 0)
				(type default)
			)
			(fill no)
			(layer "F.Fab")
		)
		(pad "1" smd rect
			(at -0.99949 2.0701 270)
			(size 0.3048 1.524)
			(layers "F.Cu" "F.Mask" "F.Paste")
			(net "BMC_UART_SWITCH_1R")
		)
		(pad "2" smd rect
			(at -0.50038 2.0701 270)
			(size 0.3048 1.524)
			(layers "F.Cu" "F.Mask" "F.Paste")
			(net "IOC_UART_TX")
		)
		(pad "3" smd rect
			(at 0 2.0701 270)
			(size 0.3048 1.524)
			(layers "F.Cu" "F.Mask" "F.Paste")
			(net "GND")
		)
		(pad "4" smd rect
			(at 0.50038 2.0701 270)
			(size 0.3048 1.524)
			(layers "F.Cu" "F.Mask" "F.Paste")
			(net "IOC_UART_RX")
		)
		(pad "5" smd rect
			(at 0.99949 2.0701 270)
			(size 0.3048 1.524)
			(layers "F.Cu" "F.Mask" "F.Paste")
			(net "BMC_UART_SWITCH_1R")
		)
		(pad "6" smd rect
			(at 0.99949 -2.0701 270)
			(size 0.3048 1.524)
			(layers "F.Cu" "F.Mask" "F.Paste")
			(net "UART1_RX")
		)
		(pad "7" smd rect
			(at 0.50038 -2.0701 270)
			(size 0.3048 1.524)
			(layers "F.Cu" "F.Mask" "F.Paste")
			(net "CPU_UART_RX_R")
		)
		(pad "8" smd rect
			(at 0 -2.0701 270)
			(size 0.3048 1.524)
			(layers "F.Cu" "F.Mask" "F.Paste")
			(net "P3V3_STBY")
		)
		(pad "9" smd rect
			(at -0.50038 -2.0701 270)
			(size 0.3048 1.524)
			(layers "F.Cu" "F.Mask" "F.Paste")
			(net "CPU_UART_TX_R")
		)
		(pad "10" smd rect
			(at -0.99949 -2.0701 270)
			(size 0.3048 1.524)
			(layers "F.Cu" "F.Mask" "F.Paste")
			(net "UART1_TX")
		)
	)
	(footprint ""
		(layer "F.Cu")
		(at 86.995 -242.443 180)
		(property "Reference" "SR952"
			(at 0 0 180)
			(layer "F.SilkS")
			(hide yes)
			(effects
				(font
					(size 1.27 1.27)
				)
			)
		)
		(property "Value" "4K7R2F-GP"
			(at 0.064008 -3.993896 180)
			(unlocked yes)
			(layer "F.Fab")
			(hide yes)
			(effects
				(font
					(size 1.016 1.016)
					(thickness 0.1524)
				)
			)
		)
		(property "Device Type" "R402H16"
			(at 0.064008 -5.517896 180)
			(unlocked yes)
			(layer "F.Fab")
			(hide yes)
			(effects
				(font
					(size 1.016 1.016)
					(thickness 0.1524)
				)
			)
		)
		(duplicate_pad_numbers_are_jumpers no)
		(fp_line
			(start 0.508 -0.9398)
			(end -0.508 -0.9398)
			(stroke
				(width 0.1524)
				(type default)
			)
			(layer "F.SilkS")
		)
		(fp_line
			(start -0.508 -0.9398)
			(end -0.508 0.9398)
			(stroke
				(width 0.1524)
				(type default)
			)
			(layer "F.SilkS")
		)
		(fp_rect
			(start -0.508 0.9398)
			(end 0.508 -0.9398)
			(stroke
				(width 0)
				(type default)
			)
			(fill no)
			(layer "F.CrtYd")
		)
		(fp_rect
			(start -0.508 0.9398)
			(end 0.508 -0.9398)
			(stroke
				(width 0)
				(type default)
			)
			(fill no)
			(layer "F.Fab")
		)
		(pad "1" smd custom
			(at 0 -0.4445 180)
			(size 0.1397 0.1397)
			(layers "F.Cu" "F.Mask" "F.Paste")
			(net "SAS_FAULT_LED11")
			(options
				(clearance outline)
				(anchor circle)
			)
			(primitives
				(gr_poly
					(pts
						(arc
							(start -0.1778 -0.2794)
							(mid -0.249642 -0.249642)
							(end -0.2794 -0.1778)
						)
						(arc
							(start -0.2794 0.1778)
							(mid -0.249642 0.249642)
							(end -0.1778 0.2794)
						)
						(arc
							(start 0.1778 0.2794)
							(mid 0.249642 0.249642)
							(end 0.2794 0.1778)
						)
						(arc
							(start 0.2794 -0.1778)
							(mid 0.249642 -0.249642)
							(end 0.1778 -0.2794)
						)
					)
					(width 0)
					(fill yes)
				)
			)
		)
		(pad "2" smd custom
			(at 0 0.4445 180)
			(size 0.1397 0.1397)
			(layers "F.Cu" "F.Mask" "F.Paste")
			(net "P3V3_STBY")
			(options
				(clearance outline)
				(anchor circle)
			)
			(primitives
				(gr_poly
					(pts
						(arc
							(start -0.1778 -0.2794)
							(mid -0.249642 -0.249642)
							(end -0.2794 -0.1778)
						)
						(arc
							(start -0.2794 0.1778)
							(mid -0.249642 0.249642)
							(end -0.1778 0.2794)
						)
						(arc
							(start 0.1778 0.2794)
							(mid 0.249642 0.249642)
							(end 0.2794 0.1778)
						)
						(arc
							(start 0.2794 -0.1778)
							(mid 0.249642 -0.249642)
							(end 0.1778 -0.2794)
						)
					)
					(width 0)
					(fill yes)
				)
			)
		)
	)
	(footprint ""
		(layer "F.Cu")
		(at 131.318 -91.313 90)
		(property "Reference" "SC1104"
			(at 0 0 90)
			(layer "F.SilkS")
			(hide yes)
			(effects
				(font
					(size 1.27 1.27)
				)
			)
		)
		(property "Value" "SCD01U10V1KX-GP"
			(at -2.8321 -1.7399 90)
			(unlocked yes)
			(layer "F.Fab")
			(hide yes)
			(effects
				(font
					(size 1.016 1.016)
					(thickness 0.1524)
				)
			)
		)
		(property "Device Type" "C0201H13"
			(at -2.8321 -3.2639 90)
			(unlocked yes)
			(layer "F.Fab")
			(hide yes)
			(effects
				(font
					(size 1.016 1.016)
					(thickness 0.1524)
				)
			)
		)
		(duplicate_pad_numbers_are_jumpers no)
		(fp_rect
			(start -0.2794 0.6477)
			(end 0.2794 -0.6477)
			(stroke
				(width 0)
				(type default)
			)
			(fill no)
			(layer "F.CrtYd")
		)
		(fp_rect
			(start -0.2794 0.6477)
			(end 0.2794 -0.6477)
			(stroke
				(width 0)
				(type default)
			)
			(fill no)
			(layer "F.Fab")
		)
		(pad "1" smd custom
			(at 0 -0.2794 90)
			(size 0.0762 0.0762)
			(layers "F.Cu" "F.Mask" "F.Paste")
			(net "3X24_SAS_TX19_P")
			(options
				(clearance outline)
				(anchor circle)
			)
			(primitives
				(gr_poly
					(pts
						(arc
							(start 0.1524 -0.127)
							(mid 0.137521 -0.162921)
							(end 0.1016 -0.1778)
						)
						(arc
							(start -0.1016 -0.1778)
							(mid -0.137521 -0.162921)
							(end -0.1524 -0.127)
						)
						(arc
							(start -0.1524 0.127)
							(mid -0.137521 0.162921)
							(end -0.1016 0.1778)
						)
						(arc
							(start 0.1016 0.1778)
							(mid 0.137521 0.162921)
							(end 0.1524 0.127)
						)
					)
					(width 0)
					(fill yes)
				)
			)
		)
		(pad "2" smd custom
			(at 0 0.2794 90)
			(size 0.0762 0.0762)
			(layers "F.Cu" "F.Mask" "F.Paste")
			(net "SAS_EXP2CONN_TX_P_23")
			(options
				(clearance outline)
				(anchor circle)
			)
			(primitives
				(gr_poly
					(pts
						(arc
							(start 0.1524 -0.127)
							(mid 0.137521 -0.162921)
							(end 0.1016 -0.1778)
						)
						(arc
							(start -0.1016 -0.1778)
							(mid -0.137521 -0.162921)
							(end -0.1524 -0.127)
						)
						(arc
							(start -0.1524 0.127)
							(mid -0.137521 0.162921)
							(end -0.1016 0.1778)
						)
						(arc
							(start 0.1016 0.1778)
							(mid 0.137521 0.162921)
							(end 0.1524 0.127)
						)
					)
					(width 0)
					(fill yes)
				)
			)
		)
	)
	(footprint ""
		(layer "F.Cu")
		(at 120.847612 -205.867 180)
		(property "Reference" "SR871"
			(at 0 0 180)
			(layer "F.SilkS")
			(hide yes)
			(effects
				(font
					(size 1.27 1.27)
				)
			)
		)
		(property "Value" "0R2J-2-GP"
			(at 0.064008 -3.993896 180)
			(unlocked yes)
			(layer "F.Fab")
			(hide yes)
			(effects
				(font
					(size 1.016 1.016)
					(thickness 0.1524)
				)
			)
		)
		(property "Device Type" "R402H16"
			(at 0.064008 -5.517896 180)
			(unlocked yes)
			(layer "F.Fab")
			(hide yes)
			(effects
				(font
					(size 1.016 1.016)
					(thickness 0.1524)
				)
			)
		)
		(duplicate_pad_numbers_are_jumpers no)
		(fp_line
			(start 0.508 -0.9398)
			(end -0.508 -0.9398)
			(stroke
				(width 0.1524)
				(type default)
			)
			(layer "F.SilkS")
		)
		(fp_line
			(start -0.508 -0.9398)
			(end -0.508 0.9398)
			(stroke
				(width 0.1524)
				(type default)
			)
			(layer "F.SilkS")
		)
		(fp_rect
			(start -0.508 0.9398)
			(end 0.508 -0.9398)
			(stroke
				(width 0)
				(type default)
			)
			(fill no)
			(layer "F.CrtYd")
		)
		(fp_rect
			(start -0.508 0.9398)
			(end 0.508 -0.9398)
			(stroke
				(width 0)
				(type default)
			)
			(fill no)
			(layer "F.Fab")
		)
		(pad "1" smd custom
			(at 0 -0.4445 180)
			(size 0.1397 0.1397)
			(layers "F.Cu" "F.Mask" "F.Paste")
			(net "SAS_HDD_REDV_TX7_P")
			(options
				(clearance outline)
				(anchor circle)
			)
			(primitives
				(gr_poly
					(pts
						(arc
							(start -0.1778 -0.2794)
							(mid -0.249642 -0.249642)
							(end -0.2794 -0.1778)
						)
						(arc
							(start -0.2794 0.1778)
							(mid -0.249642 0.249642)
							(end -0.1778 0.2794)
						)
						(arc
							(start 0.1778 0.2794)
							(mid 0.249642 0.249642)
							(end 0.2794 0.1778)
						)
						(arc
							(start 0.2794 -0.1778)
							(mid 0.249642 -0.249642)
							(end 0.1778 -0.2794)
						)
					)
					(width 0)
					(fill yes)
				)
			)
		)
		(pad "2" smd custom
			(at 0 0.4445 180)
			(size 0.1397 0.1397)
			(layers "F.Cu" "F.Mask" "F.Paste")
			(net "REDV_TX7_P")
			(options
				(clearance outline)
				(anchor circle)
			)
			(primitives
				(gr_poly
					(pts
						(arc
							(start -0.1778 -0.2794)
							(mid -0.249642 -0.249642)
							(end -0.2794 -0.1778)
						)
						(arc
							(start -0.2794 0.1778)
							(mid -0.249642 0.249642)
							(end -0.1778 0.2794)
						)
						(arc
							(start 0.1778 0.2794)
							(mid 0.249642 0.249642)
							(end 0.2794 0.1778)
						)
						(arc
							(start 0.2794 -0.1778)
							(mid 0.249642 -0.249642)
							(end 0.1778 -0.2794)
						)
					)
					(width 0)
					(fill yes)
				)
			)
		)
	)
	(footprint ""
		(layer "F.Cu")
		(at 98.557842 -104.719882)
		(property "Reference" "STP89"
			(at 0 0 0)
			(layer "F.SilkS")
			(hide yes)
			(effects
				(font
					(size 1.27 1.27)
				)
			)
		)
		(property "Value" "TPAD28"
			(at 0.0127 -1.8034 0)
			(unlocked yes)
			(layer "F.Fab")
			(hide yes)
			(effects
				(font
					(size 1.016 1.016)
					(thickness 0.1524)
				)
			)
		)
		(property "Device Type" "TPAD28"
			(at 0.0127 -3.3274 0)
			(unlocked yes)
			(layer "F.Fab")
			(hide yes)
			(effects
				(font
					(size 1.016 1.016)
					(thickness 0.1524)
				)
			)
		)
		(duplicate_pad_numbers_are_jumpers no)
		(fp_poly
			(pts
				(arc
					(start 0.3556 0)
					(mid -0.3556 0)
					(end 0.3556 0)
				)
			)
			(stroke
				(width 0)
				(type default)
			)
			(fill no)
			(layer "F.CrtYd")
		)
		(fp_poly
			(pts
				(arc
					(start 0.6096 0)
					(mid -0.6096 0)
					(end 0.6096 0)
				)
			)
			(stroke
				(width 0)
				(type default)
			)
			(fill no)
			(layer "F.Fab")
		)
		(pad "1" smd circle
			(at 0 0)
			(size 0.7112 0.7112)
			(layers "F.Cu" "F.Mask" "F.Paste")
			(net "UART_RTS")
		)
	)
	(footprint ""
		(layer "F.Cu")
		(at 318.389 -44.704 90)
		(property "Reference" "TC14"
			(at 0 0 90)
			(layer "F.SilkS")
			(hide yes)
			(effects
				(font
					(size 1.27 1.27)
				)
			)
		)
		(property "Value" "SC47U16V0MX-GP"
			(at -0.00254 -4.78536 90)
			(unlocked yes)
			(layer "F.Fab")
			(hide yes)
			(effects
				(font
					(size 1.016 1.016)
					(thickness 0.1524)
				)
			)
		)
		(property "Device Type" "C1210H107"
			(at -0.00254 -6.38048 90)
			(unlocked yes)
			(layer "F.Fab")
			(hide yes)
			(effects
				(font
					(size 1.016 1.016)
					(thickness 0.1524)
				)
			)
		)
		(duplicate_pad_numbers_are_jumpers no)
		(fp_line
			(start 1.5748 -2.3368)
			(end -1.5748 -2.3368)
			(stroke
				(width 0.1524)
				(type default)
			)
			(layer "F.SilkS")
		)
		(fp_line
			(start -1.5748 -2.3368)
			(end -1.5748 -0.762)
			(stroke
				(width 0.1524)
				(type default)
			)
			(layer "F.SilkS")
		)
		(fp_line
			(start 1.5748 -0.762)
			(end 1.5748 -2.3368)
			(stroke
				(width 0.1524)
				(type default)
			)
			(layer "F.SilkS")
		)
		(fp_line
			(start -1.5748 0.762)
			(end -1.5748 2.3368)
			(stroke
				(width 0.1524)
				(type default)
			)
			(layer "F.SilkS")
		)
		(fp_line
			(start 1.5748 2.3368)
			(end 1.5748 0.762)
			(stroke
				(width 0.1524)
				(type default)
			)
			(layer "F.SilkS")
		)
		(fp_line
			(start -1.5748 2.3368)
			(end 1.5748 2.3368)
			(stroke
				(width 0.1524)
				(type default)
			)
			(layer "F.SilkS")
		)
		(fp_rect
			(start -1.651 2.413)
			(end 1.651 -2.413)
			(stroke
				(width 0)
				(type default)
			)
			(fill no)
			(layer "F.CrtYd")
		)
		(fp_poly
			(pts
				(xy 1.651 2.413) (xy 1.651 -2.413) (xy -1.651 -2.413) (xy -1.651 2.413)
			)
			(stroke
				(width 0)
				(type default)
			)
			(fill no)
			(layer "F.Fab")
		)
		(pad "1" smd rect
			(at 0 -1.4732 90)
			(size 2.794 1.397)
			(layers "F.Cu" "F.Mask" "F.Paste")
			(net "P5V_STBY")
		)
		(pad "2" smd rect
			(at 0 1.4732 90)
			(size 2.794 1.397)
			(layers "F.Cu" "F.Mask" "F.Paste")
			(net "GND")
		)
	)
	(footprint ""
		(layer "F.Cu")
		(at 35.383216 -204.14488 90)
		(property "Reference" "R5311"
			(at 0 0 90)
			(layer "F.SilkS")
			(hide yes)
			(effects
				(font
					(size 1.27 1.27)
				)
			)
		)
		(property "Value" "0R2J-2-GP"
			(at 0.064008 -3.993896 90)
			(unlocked yes)
			(layer "F.Fab")
			(hide yes)
			(effects
				(font
					(size 1.016 1.016)
					(thickness 0.1524)
				)
			)
		)
		(property "Device Type" "R402H16"
			(at 0.064008 -5.517896 90)
			(unlocked yes)
			(layer "F.Fab")
			(hide yes)
			(effects
				(font
					(size 1.016 1.016)
					(thickness 0.1524)
				)
			)
		)
		(duplicate_pad_numbers_are_jumpers no)
		(fp_line
			(start 0.508 -0.9398)
			(end -0.508 -0.9398)
			(stroke
				(width 0.1524)
				(type default)
			)
			(layer "F.SilkS")
		)
		(fp_line
			(start -0.508 -0.9398)
			(end -0.508 0.9398)
			(stroke
				(width 0.1524)
				(type default)
			)
			(layer "F.SilkS")
		)
		(fp_rect
			(start -0.508 0.9398)
			(end 0.508 -0.9398)
			(stroke
				(width 0)
				(type default)
			)
			(fill no)
			(layer "F.CrtYd")
		)
		(fp_rect
			(start -0.508 0.9398)
			(end 0.508 -0.9398)
			(stroke
				(width 0)
				(type default)
			)
			(fill no)
			(layer "F.Fab")
		)
		(pad "1" smd custom
			(at 0 -0.4445 90)
			(size 0.1397 0.1397)
			(layers "F.Cu" "F.Mask" "F.Paste")
			(net "VOL_SEN_SDA_U17")
			(options
				(clearance outline)
				(anchor circle)
			)
			(primitives
				(gr_poly
					(pts
						(arc
							(start -0.1778 -0.2794)
							(mid -0.249642 -0.249642)
							(end -0.2794 -0.1778)
						)
						(arc
							(start -0.2794 0.1778)
							(mid -0.249642 0.249642)
							(end -0.1778 0.2794)
						)
						(arc
							(start 0.1778 0.2794)
							(mid 0.249642 0.249642)
							(end 0.2794 0.1778)
						)
						(arc
							(start 0.2794 -0.1778)
							(mid 0.249642 -0.249642)
							(end 0.1778 -0.2794)
						)
					)
					(width 0)
					(fill yes)
				)
			)
		)
		(pad "2" smd custom
			(at 0 0.4445 90)
			(size 0.1397 0.1397)
			(layers "F.Cu" "F.Mask" "F.Paste")
			(net "BMC_I2C_SDA_10")
			(options
				(clearance outline)
				(anchor circle)
			)
			(primitives
				(gr_poly
					(pts
						(arc
							(start -0.1778 -0.2794)
							(mid -0.249642 -0.249642)
							(end -0.2794 -0.1778)
						)
						(arc
							(start -0.2794 0.1778)
							(mid -0.249642 0.249642)
							(end -0.1778 0.2794)
						)
						(arc
							(start 0.1778 0.2794)
							(mid 0.249642 0.249642)
							(end 0.2794 0.1778)
						)
						(arc
							(start 0.2794 -0.1778)
							(mid 0.249642 -0.249642)
							(end 0.1778 -0.2794)
						)
					)
					(width 0)
					(fill yes)
				)
			)
		)
	)
	(footprint ""
		(layer "F.Cu")
		(at 68.834 -45.847 -90)
		(property "Reference" "SC936"
			(at 0 0 270)
			(layer "F.SilkS")
			(hide yes)
			(effects
				(font
					(size 1.27 1.27)
				)
			)
		)
		(property "Value" "SC10U6D3V5KX-4GP"
			(at -0.0762 -6.1214 270)
			(unlocked yes)
			(layer "F.Fab")
			(hide yes)
			(effects
				(font
					(size 1.016 1.016)
					(thickness 0.1524)
				)
			)
		)
		(property "Device Type" "C805H58"
			(at -0.0762 -8.1534 270)
			(unlocked yes)
			(layer "F.Fab")
			(hide yes)
			(effects
				(font
					(size 1.016 1.016)
					(thickness 0.1524)
				)
			)
		)
		(duplicate_pad_numbers_are_jumpers no)
		(fp_line
			(start 0.635 0)
			(end -0.635 0)
			(stroke
				(width 0.508)
				(type default)
			)
			(layer "F.SilkS")
		)
		(fp_rect
			(start -0.9652 1.778)
			(end 0.9652 -1.778)
			(stroke
				(width 0)
				(type default)
			)
			(fill no)
			(layer "F.CrtYd")
		)
		(fp_poly
			(pts
				(xy -0.9652 -1.778) (xy 0.9652 -1.778) (xy 0.9652 1.778) (xy -0.9652 1.778)
			)
			(stroke
				(width 0)
				(type default)
			)
			(fill no)
			(layer "F.Fab")
		)
		(pad "1" smd rect
			(at 0 -0.9652 270)
			(size 1.397 1.143)
			(layers "F.Cu" "F.Mask" "F.Paste")
			(net "SAS0_VDDH")
		)
		(pad "2" smd rect
			(at 0 0.9652 270)
			(size 1.397 1.143)
			(layers "F.Cu" "F.Mask" "F.Paste")
			(net "GND")
		)
	)
	(footprint ""
		(layer "F.Cu")
		(at 261.562596 -50.692812 90)
		(property "Reference" "SR719"
			(at 0 0 90)
			(layer "F.SilkS")
			(hide yes)
			(effects
				(font
					(size 1.27 1.27)
				)
			)
		)
		(property "Value" "4K7R2F-GP"
			(at 0.064008 -3.993896 90)
			(unlocked yes)
			(layer "F.Fab")
			(hide yes)
			(effects
				(font
					(size 1.016 1.016)
					(thickness 0.1524)
				)
			)
		)
		(property "Device Type" "R402H16"
			(at 0.064008 -5.517896 90)
			(unlocked yes)
			(layer "F.Fab")
			(hide yes)
			(effects
				(font
					(size 1.016 1.016)
					(thickness 0.1524)
				)
			)
		)
		(duplicate_pad_numbers_are_jumpers no)
		(fp_line
			(start 0.508 -0.9398)
			(end -0.508 -0.9398)
			(stroke
				(width 0.1524)
				(type default)
			)
			(layer "F.SilkS")
		)
		(fp_line
			(start -0.508 -0.9398)
			(end -0.508 0.9398)
			(stroke
				(width 0.1524)
				(type default)
			)
			(layer "F.SilkS")
		)
		(fp_rect
			(start -0.508 0.9398)
			(end 0.508 -0.9398)
			(stroke
				(width 0)
				(type default)
			)
			(fill no)
			(layer "F.CrtYd")
		)
		(fp_rect
			(start -0.508 0.9398)
			(end 0.508 -0.9398)
			(stroke
				(width 0)
				(type default)
			)
			(fill no)
			(layer "F.Fab")
		)
		(pad "1" smd custom
			(at 0 -0.4445 90)
			(size 0.1397 0.1397)
			(layers "F.Cu" "F.Mask" "F.Paste")
			(net "IOC_EEPROM_A0")
			(options
				(clearance outline)
				(anchor circle)
			)
			(primitives
				(gr_poly
					(pts
						(arc
							(start -0.1778 -0.2794)
							(mid -0.249642 -0.249642)
							(end -0.2794 -0.1778)
						)
						(arc
							(start -0.2794 0.1778)
							(mid -0.249642 0.249642)
							(end -0.1778 0.2794)
						)
						(arc
							(start 0.1778 0.2794)
							(mid 0.249642 0.249642)
							(end 0.2794 0.1778)
						)
						(arc
							(start 0.2794 -0.1778)
							(mid 0.249642 -0.249642)
							(end 0.1778 -0.2794)
						)
					)
					(width 0)
					(fill yes)
				)
			)
		)
		(pad "2" smd custom
			(at 0 0.4445 90)
			(size 0.1397 0.1397)
			(layers "F.Cu" "F.Mask" "F.Paste")
			(net "GND")
			(options
				(clearance outline)
				(anchor circle)
			)
			(primitives
				(gr_poly
					(pts
						(arc
							(start -0.1778 -0.2794)
							(mid -0.249642 -0.249642)
							(end -0.2794 -0.1778)
						)
						(arc
							(start -0.2794 0.1778)
							(mid -0.249642 0.249642)
							(end -0.1778 0.2794)
						)
						(arc
							(start 0.1778 0.2794)
							(mid 0.249642 0.249642)
							(end 0.2794 0.1778)
						)
						(arc
							(start 0.2794 -0.1778)
							(mid 0.249642 -0.249642)
							(end 0.1778 -0.2794)
						)
					)
					(width 0)
					(fill yes)
				)
			)
		)
	)
	(footprint ""
		(layer "F.Cu")
		(at 96.120966 -61.468)
		(property "Reference" "STP33"
			(at 0 0 0)
			(layer "F.SilkS")
			(hide yes)
			(effects
				(font
					(size 1.27 1.27)
				)
			)
		)
		(property "Value" "TPAD28"
			(at 0.0127 -1.8034 0)
			(unlocked yes)
			(layer "F.Fab")
			(hide yes)
			(effects
				(font
					(size 1.016 1.016)
					(thickness 0.1524)
				)
			)
		)
		(property "Device Type" "TPAD28"
			(at 0.0127 -3.3274 0)
			(unlocked yes)
			(layer "F.Fab")
			(hide yes)
			(effects
				(font
					(size 1.016 1.016)
					(thickness 0.1524)
				)
			)
		)
		(duplicate_pad_numbers_are_jumpers no)
		(fp_poly
			(pts
				(arc
					(start 0.3556 0)
					(mid -0.3556 0)
					(end 0.3556 0)
				)
			)
			(stroke
				(width 0)
				(type default)
			)
			(fill no)
			(layer "F.CrtYd")
		)
		(fp_poly
			(pts
				(arc
					(start 0.6096 0)
					(mid -0.6096 0)
					(end 0.6096 0)
				)
			)
			(stroke
				(width 0)
				(type default)
			)
			(fill no)
			(layer "F.Fab")
		)
		(pad "1" smd circle
			(at 0 0)
			(size 0.7112 0.7112)
			(layers "F.Cu" "F.Mask" "F.Paste")
			(net "ICE0_TDO")
		)
	)
	(footprint ""
		(layer "F.Cu")
		(at 172.675804 -26.295096 90)
		(property "Reference" "R389"
			(at 0 0 90)
			(layer "F.SilkS")
			(hide yes)
			(effects
				(font
					(size 1.27 1.27)
				)
			)
		)
		(property "Value" "0R2J-2-GP"
			(at 0.064008 -3.993896 90)
			(unlocked yes)
			(layer "F.Fab")
			(hide yes)
			(effects
				(font
					(size 1.016 1.016)
					(thickness 0.1524)
				)
			)
		)
		(property "Device Type" "R402H16"
			(at 0.064008 -5.517896 90)
			(unlocked yes)
			(layer "F.Fab")
			(hide yes)
			(effects
				(font
					(size 1.016 1.016)
					(thickness 0.1524)
				)
			)
		)
		(duplicate_pad_numbers_are_jumpers no)
		(fp_line
			(start 0.508 -0.9398)
			(end -0.508 -0.9398)
			(stroke
				(width 0.1524)
				(type default)
			)
			(layer "F.SilkS")
		)
		(fp_line
			(start -0.508 -0.9398)
			(end -0.508 0.9398)
			(stroke
				(width 0.1524)
				(type default)
			)
			(layer "F.SilkS")
		)
		(fp_rect
			(start -0.508 0.9398)
			(end 0.508 -0.9398)
			(stroke
				(width 0)
				(type default)
			)
			(fill no)
			(layer "F.CrtYd")
		)
		(fp_rect
			(start -0.508 0.9398)
			(end 0.508 -0.9398)
			(stroke
				(width 0)
				(type default)
			)
			(fill no)
			(layer "F.Fab")
		)
		(pad "1" smd custom
			(at 0 -0.4445 90)
			(size 0.1397 0.1397)
			(layers "F.Cu" "F.Mask" "F.Paste")
			(net "BCM5221_MB_TX_DN")
			(options
				(clearance outline)
				(anchor circle)
			)
			(primitives
				(gr_poly
					(pts
						(arc
							(start -0.1778 -0.2794)
							(mid -0.249642 -0.249642)
							(end -0.2794 -0.1778)
						)
						(arc
							(start -0.2794 0.1778)
							(mid -0.249642 0.249642)
							(end -0.1778 0.2794)
						)
						(arc
							(start 0.1778 0.2794)
							(mid 0.249642 0.249642)
							(end 0.2794 0.1778)
						)
						(arc
							(start 0.2794 -0.1778)
							(mid 0.249642 -0.249642)
							(end 0.1778 -0.2794)
						)
					)
					(width 0)
					(fill yes)
				)
			)
		)
		(pad "2" smd custom
			(at 0 0.4445 90)
			(size 0.1397 0.1397)
			(layers "F.Cu" "F.Mask" "F.Paste")
			(net "BCM5221_TX_C_DN")
			(options
				(clearance outline)
				(anchor circle)
			)
			(primitives
				(gr_poly
					(pts
						(arc
							(start -0.1778 -0.2794)
							(mid -0.249642 -0.249642)
							(end -0.2794 -0.1778)
						)
						(arc
							(start -0.2794 0.1778)
							(mid -0.249642 0.249642)
							(end -0.1778 0.2794)
						)
						(arc
							(start 0.1778 0.2794)
							(mid 0.249642 0.249642)
							(end 0.2794 0.1778)
						)
						(arc
							(start 0.2794 -0.1778)
							(mid 0.249642 -0.249642)
							(end 0.1778 -0.2794)
						)
					)
					(width 0)
					(fill yes)
				)
			)
		)
	)
	(footprint ""
		(layer "F.Cu")
		(at 111.252 -76.327)
		(property "Reference" "STP65"
			(at 0 0 0)
			(layer "F.SilkS")
			(hide yes)
			(effects
				(font
					(size 1.27 1.27)
				)
			)
		)
		(property "Value" "TPAD28"
			(at 0.0127 -1.8034 0)
			(unlocked yes)
			(layer "F.Fab")
			(hide yes)
			(effects
				(font
					(size 1.016 1.016)
					(thickness 0.1524)
				)
			)
		)
		(property "Device Type" "TPAD28"
			(at 0.0127 -3.3274 0)
			(unlocked yes)
			(layer "F.Fab")
			(hide yes)
			(effects
				(font
					(size 1.016 1.016)
					(thickness 0.1524)
				)
			)
		)
		(duplicate_pad_numbers_are_jumpers no)
		(fp_poly
			(pts
				(arc
					(start 0.3556 0)
					(mid -0.3556 0)
					(end 0.3556 0)
				)
			)
			(stroke
				(width 0)
				(type default)
			)
			(fill no)
			(layer "F.CrtYd")
		)
		(fp_poly
			(pts
				(arc
					(start 0.6096 0)
					(mid -0.6096 0)
					(end 0.6096 0)
				)
			)
			(stroke
				(width 0)
				(type default)
			)
			(fill no)
			(layer "F.Fab")
		)
		(pad "1" smd circle
			(at 0 0)
			(size 0.7112 0.7112)
			(layers "F.Cu" "F.Mask" "F.Paste")
			(net "EXP_TEST_MUX27")
		)
	)
	(footprint ""
		(layer "F.Cu")
		(at 182.38597 -67.183)
		(property "Reference" "C291"
			(at 0 0 0)
			(layer "F.SilkS")
			(hide yes)
			(effects
				(font
					(size 1.27 1.27)
				)
			)
		)
		(property "Value" "SCD1U25V2KX-2-GP"
			(at 1.1811 -2.7051 0)
			(unlocked yes)
			(layer "F.Fab")
			(hide yes)
			(effects
				(font
					(size 1.016 1.016)
					(thickness 0.1524)
				)
			)
		)
		(property "Device Type" "C402H22"
			(at 1.1811 -4.2291 0)
			(unlocked yes)
			(layer "F.Fab")
			(hide yes)
			(effects
				(font
					(size 1.016 1.016)
					(thickness 0.1524)
				)
			)
		)
		(duplicate_pad_numbers_are_jumpers no)
		(fp_rect
			(start -0.4318 0.9525)
			(end 0.4318 -0.9525)
			(stroke
				(width 0)
				(type default)
			)
			(fill no)
			(layer "F.CrtYd")
		)
		(fp_rect
			(start -0.4318 0.9525)
			(end 0.4318 -0.9525)
			(stroke
				(width 0)
				(type default)
			)
			(fill no)
			(layer "F.Fab")
		)
		(pad "1" smd custom
			(at 0 -0.4445)
			(size 0.1524 0.1524)
			(layers "F.Cu" "F.Mask" "F.Paste")
			(net "TP_MSB_A34_CPU_SATA_RX_N")
			(options
				(clearance outline)
				(anchor circle)
			)
			(primitives
				(gr_poly
					(pts
						(arc
							(start 0.3048 -0.2032)
							(mid 0.275042 -0.275042)
							(end 0.2032 -0.3048)
						)
						(arc
							(start -0.2032 -0.3048)
							(mid -0.275042 -0.275042)
							(end -0.3048 -0.2032)
						)
						(arc
							(start -0.3048 0.2032)
							(mid -0.275042 0.275042)
							(end -0.2032 0.3048)
						)
						(arc
							(start 0.2032 0.3048)
							(mid 0.275042 0.275042)
							(end 0.3048 0.2032)
						)
					)
					(width 0)
					(fill yes)
				)
			)
		)
		(pad "2" smd custom
			(at 0 0.4445)
			(size 0.1524 0.1524)
			(layers "F.Cu" "F.Mask" "F.Paste")
			(net "GND")
			(options
				(clearance outline)
				(anchor circle)
			)
			(primitives
				(gr_poly
					(pts
						(arc
							(start 0.3048 -0.2032)
							(mid 0.275042 -0.275042)
							(end 0.2032 -0.3048)
						)
						(arc
							(start -0.2032 -0.3048)
							(mid -0.275042 -0.275042)
							(end -0.3048 -0.2032)
						)
						(arc
							(start -0.3048 0.2032)
							(mid -0.275042 0.275042)
							(end -0.2032 0.3048)
						)
						(arc
							(start 0.2032 0.3048)
							(mid 0.275042 0.275042)
							(end 0.3048 0.2032)
						)
					)
					(width 0)
					(fill yes)
				)
			)
		)
	)
	(footprint ""
		(layer "F.Cu")
		(at 185.792872 -198.496936 180)
		(property "Reference" "C244"
			(at 0 0 180)
			(layer "F.SilkS")
			(hide yes)
			(effects
				(font
					(size 1.27 1.27)
				)
			)
		)
		(property "Value" "SCD01U50V2KX-1GP"
			(at 1.1811 -2.7051 180)
			(unlocked yes)
			(layer "F.Fab")
			(hide yes)
			(effects
				(font
					(size 1.016 1.016)
					(thickness 0.1524)
				)
			)
		)
		(property "Device Type" "C402H22"
			(at 1.1811 -4.2291 180)
			(unlocked yes)
			(layer "F.Fab")
			(hide yes)
			(effects
				(font
					(size 1.016 1.016)
					(thickness 0.1524)
				)
			)
		)
		(duplicate_pad_numbers_are_jumpers no)
		(fp_rect
			(start -0.4318 0.9525)
			(end 0.4318 -0.9525)
			(stroke
				(width 0)
				(type default)
			)
			(fill no)
			(layer "F.CrtYd")
		)
		(fp_rect
			(start -0.4318 0.9525)
			(end 0.4318 -0.9525)
			(stroke
				(width 0)
				(type default)
			)
			(fill no)
			(layer "F.Fab")
		)
		(pad "1" smd custom
			(at 0 -0.4445 180)
			(size 0.1524 0.1524)
			(layers "F.Cu" "F.Mask" "F.Paste")
			(net "P3V3_STBY")
			(options
				(clearance outline)
				(anchor circle)
			)
			(primitives
				(gr_poly
					(pts
						(arc
							(start 0.3048 -0.2032)
							(mid 0.275042 -0.275042)
							(end 0.2032 -0.3048)
						)
						(arc
							(start -0.2032 -0.3048)
							(mid -0.275042 -0.275042)
							(end -0.3048 -0.2032)
						)
						(arc
							(start -0.3048 0.2032)
							(mid -0.275042 0.275042)
							(end -0.2032 0.3048)
						)
						(arc
							(start 0.2032 0.3048)
							(mid 0.275042 0.275042)
							(end 0.3048 0.2032)
						)
					)
					(width 0)
					(fill yes)
				)
			)
		)
		(pad "2" smd custom
			(at 0 0.4445 180)
			(size 0.1524 0.1524)
			(layers "F.Cu" "F.Mask" "F.Paste")
			(net "GND")
			(options
				(clearance outline)
				(anchor circle)
			)
			(primitives
				(gr_poly
					(pts
						(arc
							(start 0.3048 -0.2032)
							(mid 0.275042 -0.275042)
							(end 0.2032 -0.3048)
						)
						(arc
							(start -0.2032 -0.3048)
							(mid -0.275042 -0.275042)
							(end -0.3048 -0.2032)
						)
						(arc
							(start -0.3048 0.2032)
							(mid -0.275042 0.275042)
							(end -0.2032 0.3048)
						)
						(arc
							(start 0.2032 0.3048)
							(mid 0.275042 0.275042)
							(end 0.3048 0.2032)
						)
					)
					(width 0)
					(fill yes)
				)
			)
		)
	)
	(footprint ""
		(layer "F.Cu")
		(at 222.377 -118.745 -90)
		(property "Reference" "PR178"
			(at 0 0 270)
			(layer "F.SilkS")
			(hide yes)
			(effects
				(font
					(size 1.27 1.27)
				)
			)
		)
		(property "Value" "0R2J-2-GP"
			(at 0.064008 -3.993896 270)
			(unlocked yes)
			(layer "F.Fab")
			(hide yes)
			(effects
				(font
					(size 1.016 1.016)
					(thickness 0.1524)
				)
			)
		)
		(property "Device Type" "R402H16"
			(at 0.064008 -5.517896 270)
			(unlocked yes)
			(layer "F.Fab")
			(hide yes)
			(effects
				(font
					(size 1.016 1.016)
					(thickness 0.1524)
				)
			)
		)
		(duplicate_pad_numbers_are_jumpers no)
		(fp_line
			(start -0.508 -0.9398)
			(end -0.508 0.9398)
			(stroke
				(width 0.1524)
				(type default)
			)
			(layer "F.SilkS")
		)
		(fp_line
			(start 0.508 -0.9398)
			(end -0.508 -0.9398)
			(stroke
				(width 0.1524)
				(type default)
			)
			(layer "F.SilkS")
		)
		(fp_rect
			(start -0.508 0.9398)
			(end 0.508 -0.9398)
			(stroke
				(width 0)
				(type default)
			)
			(fill no)
			(layer "F.CrtYd")
		)
		(fp_rect
			(start -0.508 0.9398)
			(end 0.508 -0.9398)
			(stroke
				(width 0)
				(type default)
			)
			(fill no)
			(layer "F.Fab")
		)
		(pad "1" smd custom
			(at 0 -0.4445 270)
			(size 0.1397 0.1397)
			(layers "F.Cu" "F.Mask" "F.Paste")
			(net "P3V3_STBY_B3")
			(options
				(clearance outline)
				(anchor circle)
			)
			(primitives
				(gr_poly
					(pts
						(arc
							(start -0.1778 -0.2794)
							(mid -0.249642 -0.249642)
							(end -0.2794 -0.1778)
						)
						(arc
							(start -0.2794 0.1778)
							(mid -0.249642 0.249642)
							(end -0.1778 0.2794)
						)
						(arc
							(start 0.1778 0.2794)
							(mid 0.249642 0.249642)
							(end 0.2794 0.1778)
						)
						(arc
							(start 0.2794 -0.1778)
							(mid 0.249642 -0.249642)
							(end 0.1778 -0.2794)
						)
					)
					(width 0)
					(fill yes)
				)
			)
		)
		(pad "2" smd custom
			(at 0 0.4445 270)
			(size 0.1397 0.1397)
			(layers "F.Cu" "F.Mask" "F.Paste")
			(net "P3V3_STBY_R3")
			(options
				(clearance outline)
				(anchor circle)
			)
			(primitives
				(gr_poly
					(pts
						(arc
							(start -0.1778 -0.2794)
							(mid -0.249642 -0.249642)
							(end -0.2794 -0.1778)
						)
						(arc
							(start -0.2794 0.1778)
							(mid -0.249642 0.249642)
							(end -0.1778 0.2794)
						)
						(arc
							(start 0.1778 0.2794)
							(mid 0.249642 0.249642)
							(end 0.2794 0.1778)
						)
						(arc
							(start 0.2794 -0.1778)
							(mid 0.249642 -0.249642)
							(end 0.1778 -0.2794)
						)
					)
					(width 0)
					(fill yes)
				)
			)
		)
	)
	(footprint ""
		(layer "F.Cu")
		(at 318.008 -166.878 -90)
		(property "Reference" "R251"
			(at 0 0 270)
			(layer "F.SilkS")
			(hide yes)
			(effects
				(font
					(size 1.27 1.27)
				)
			)
		)
		(property "Value" "0R2J-2-GP"
			(at 0.064008 -3.993896 270)
			(unlocked yes)
			(layer "F.Fab")
			(hide yes)
			(effects
				(font
					(size 1.016 1.016)
					(thickness 0.1524)
				)
			)
		)
		(property "Device Type" "R402H16"
			(at 0.064008 -5.517896 270)
			(unlocked yes)
			(layer "F.Fab")
			(hide yes)
			(effects
				(font
					(size 1.016 1.016)
					(thickness 0.1524)
				)
			)
		)
		(duplicate_pad_numbers_are_jumpers no)
		(fp_line
			(start -0.508 -0.9398)
			(end -0.508 0.9398)
			(stroke
				(width 0.1524)
				(type default)
			)
			(layer "F.SilkS")
		)
		(fp_line
			(start 0.508 -0.9398)
			(end -0.508 -0.9398)
			(stroke
				(width 0.1524)
				(type default)
			)
			(layer "F.SilkS")
		)
		(fp_rect
			(start -0.508 0.9398)
			(end 0.508 -0.9398)
			(stroke
				(width 0)
				(type default)
			)
			(fill no)
			(layer "F.CrtYd")
		)
		(fp_rect
			(start -0.508 0.9398)
			(end 0.508 -0.9398)
			(stroke
				(width 0)
				(type default)
			)
			(fill no)
			(layer "F.Fab")
		)
		(pad "1" smd custom
			(at 0 -0.4445 270)
			(size 0.1397 0.1397)
			(layers "F.Cu" "F.Mask" "F.Paste")
			(net "BMC_I2C_C_SDA")
			(options
				(clearance outline)
				(anchor circle)
			)
			(primitives
				(gr_poly
					(pts
						(arc
							(start -0.1778 -0.2794)
							(mid -0.249642 -0.249642)
							(end -0.2794 -0.1778)
						)
						(arc
							(start -0.2794 0.1778)
							(mid -0.249642 0.249642)
							(end -0.1778 0.2794)
						)
						(arc
							(start 0.1778 0.2794)
							(mid 0.249642 0.249642)
							(end 0.2794 0.1778)
						)
						(arc
							(start 0.2794 -0.1778)
							(mid 0.249642 -0.249642)
							(end 0.1778 -0.2794)
						)
					)
					(width 0)
					(fill yes)
				)
			)
		)
		(pad "2" smd custom
			(at 0 0.4445 270)
			(size 0.1397 0.1397)
			(layers "F.Cu" "F.Mask" "F.Paste")
			(net "BMC0_SMB6_DAT")
			(options
				(clearance outline)
				(anchor circle)
			)
			(primitives
				(gr_poly
					(pts
						(arc
							(start -0.1778 -0.2794)
							(mid -0.249642 -0.249642)
							(end -0.2794 -0.1778)
						)
						(arc
							(start -0.2794 0.1778)
							(mid -0.249642 0.249642)
							(end -0.1778 0.2794)
						)
						(arc
							(start 0.1778 0.2794)
							(mid 0.249642 0.249642)
							(end 0.2794 0.1778)
						)
						(arc
							(start 0.2794 -0.1778)
							(mid 0.249642 -0.249642)
							(end 0.1778 -0.2794)
						)
					)
					(width 0)
					(fill yes)
				)
			)
		)
	)
	(footprint ""
		(layer "F.Cu")
		(at 99.568 -242.189 180)
		(property "Reference" "SR265"
			(at 0 0 180)
			(layer "F.SilkS")
			(hide yes)
			(effects
				(font
					(size 1.27 1.27)
				)
			)
		)
		(property "Value" "0R2J-2-GP"
			(at 0.064008 -3.993896 180)
			(unlocked yes)
			(layer "F.Fab")
			(hide yes)
			(effects
				(font
					(size 1.016 1.016)
					(thickness 0.1524)
				)
			)
		)
		(property "Device Type" "R402H16"
			(at 0.064008 -5.517896 180)
			(unlocked yes)
			(layer "F.Fab")
			(hide yes)
			(effects
				(font
					(size 1.016 1.016)
					(thickness 0.1524)
				)
			)
		)
		(duplicate_pad_numbers_are_jumpers no)
		(fp_line
			(start 0.508 -0.9398)
			(end -0.508 -0.9398)
			(stroke
				(width 0.1524)
				(type default)
			)
			(layer "F.SilkS")
		)
		(fp_line
			(start -0.508 -0.9398)
			(end -0.508 0.9398)
			(stroke
				(width 0.1524)
				(type default)
			)
			(layer "F.SilkS")
		)
		(fp_rect
			(start -0.508 0.9398)
			(end 0.508 -0.9398)
			(stroke
				(width 0)
				(type default)
			)
			(fill no)
			(layer "F.CrtYd")
		)
		(fp_rect
			(start -0.508 0.9398)
			(end 0.508 -0.9398)
			(stroke
				(width 0)
				(type default)
			)
			(fill no)
			(layer "F.Fab")
		)
		(pad "1" smd custom
			(at 0 -0.4445 180)
			(size 0.1397 0.1397)
			(layers "F.Cu" "F.Mask" "F.Paste")
			(net "PCIE_MATED#_LED_CD")
			(options
				(clearance outline)
				(anchor circle)
			)
			(primitives
				(gr_poly
					(pts
						(arc
							(start -0.1778 -0.2794)
							(mid -0.249642 -0.249642)
							(end -0.2794 -0.1778)
						)
						(arc
							(start -0.2794 0.1778)
							(mid -0.249642 0.249642)
							(end -0.1778 0.2794)
						)
						(arc
							(start 0.1778 0.2794)
							(mid 0.249642 0.249642)
							(end 0.2794 0.1778)
						)
						(arc
							(start 0.2794 -0.1778)
							(mid 0.249642 -0.249642)
							(end 0.1778 -0.2794)
						)
					)
					(width 0)
					(fill yes)
				)
			)
		)
		(pad "2" smd custom
			(at 0 0.4445 180)
			(size 0.1397 0.1397)
			(layers "F.Cu" "F.Mask" "F.Paste")
			(net "PCIE_MATED#")
			(options
				(clearance outline)
				(anchor circle)
			)
			(primitives
				(gr_poly
					(pts
						(arc
							(start -0.1778 -0.2794)
							(mid -0.249642 -0.249642)
							(end -0.2794 -0.1778)
						)
						(arc
							(start -0.2794 0.1778)
							(mid -0.249642 0.249642)
							(end -0.1778 0.2794)
						)
						(arc
							(start 0.1778 0.2794)
							(mid 0.249642 0.249642)
							(end 0.2794 0.1778)
						)
						(arc
							(start 0.2794 -0.1778)
							(mid 0.249642 -0.249642)
							(end 0.1778 -0.2794)
						)
					)
					(width 0)
					(fill yes)
				)
			)
		)
	)
	(footprint ""
		(layer "F.Cu")
		(at 179.505864 -22.551136 180)
		(property "Reference" "R383"
			(at 0 0 180)
			(layer "F.SilkS")
			(hide yes)
			(effects
				(font
					(size 1.27 1.27)
				)
			)
		)
		(property "Value" "4K75R2F-1-GP"
			(at 0.064008 -3.993896 180)
			(unlocked yes)
			(layer "F.Fab")
			(hide yes)
			(effects
				(font
					(size 1.016 1.016)
					(thickness 0.1524)
				)
			)
		)
		(property "Device Type" "R402H16"
			(at 0.064008 -5.517896 180)
			(unlocked yes)
			(layer "F.Fab")
			(hide yes)
			(effects
				(font
					(size 1.016 1.016)
					(thickness 0.1524)
				)
			)
		)
		(duplicate_pad_numbers_are_jumpers no)
		(fp_line
			(start 0.508 -0.9398)
			(end -0.508 -0.9398)
			(stroke
				(width 0.1524)
				(type default)
			)
			(layer "F.SilkS")
		)
		(fp_line
			(start -0.508 -0.9398)
			(end -0.508 0.9398)
			(stroke
				(width 0.1524)
				(type default)
			)
			(layer "F.SilkS")
		)
		(fp_rect
			(start -0.508 0.9398)
			(end 0.508 -0.9398)
			(stroke
				(width 0)
				(type default)
			)
			(fill no)
			(layer "F.CrtYd")
		)
		(fp_rect
			(start -0.508 0.9398)
			(end 0.508 -0.9398)
			(stroke
				(width 0)
				(type default)
			)
			(fill no)
			(layer "F.Fab")
		)
		(pad "1" smd custom
			(at 0 -0.4445 180)
			(size 0.1397 0.1397)
			(layers "F.Cu" "F.Mask" "F.Paste")
			(net "P3V3_STBY")
			(options
				(clearance outline)
				(anchor circle)
			)
			(primitives
				(gr_poly
					(pts
						(arc
							(start -0.1778 -0.2794)
							(mid -0.249642 -0.249642)
							(end -0.2794 -0.1778)
						)
						(arc
							(start -0.2794 0.1778)
							(mid -0.249642 0.249642)
							(end -0.1778 0.2794)
						)
						(arc
							(start 0.1778 0.2794)
							(mid 0.249642 0.249642)
							(end 0.2794 0.1778)
						)
						(arc
							(start 0.2794 -0.1778)
							(mid 0.249642 -0.249642)
							(end 0.1778 -0.2794)
						)
					)
					(width 0)
					(fill yes)
				)
			)
		)
		(pad "2" smd custom
			(at 0 0.4445 180)
			(size 0.1397 0.1397)
			(layers "F.Cu" "F.Mask" "F.Paste")
			(net "PHY_F100")
			(options
				(clearance outline)
				(anchor circle)
			)
			(primitives
				(gr_poly
					(pts
						(arc
							(start -0.1778 -0.2794)
							(mid -0.249642 -0.249642)
							(end -0.2794 -0.1778)
						)
						(arc
							(start -0.2794 0.1778)
							(mid -0.249642 0.249642)
							(end -0.1778 0.2794)
						)
						(arc
							(start 0.1778 0.2794)
							(mid 0.249642 0.249642)
							(end 0.2794 0.1778)
						)
						(arc
							(start 0.2794 -0.1778)
							(mid 0.249642 -0.249642)
							(end 0.1778 -0.2794)
						)
					)
					(width 0)
					(fill yes)
				)
			)
		)
	)
	(footprint ""
		(layer "F.Cu")
		(at 177.727864 -34.870136)
		(property "Reference" "TP128"
			(at 0 0 0)
			(layer "F.SilkS")
			(hide yes)
			(effects
				(font
					(size 1.27 1.27)
				)
			)
		)
		(property "Value" "TPAD28"
			(at 0.0127 -1.8034 0)
			(unlocked yes)
			(layer "F.Fab")
			(hide yes)
			(effects
				(font
					(size 1.016 1.016)
					(thickness 0.1524)
				)
			)
		)
		(property "Device Type" "TPAD28"
			(at 0.0127 -3.3274 0)
			(unlocked yes)
			(layer "F.Fab")
			(hide yes)
			(effects
				(font
					(size 1.016 1.016)
					(thickness 0.1524)
				)
			)
		)
		(duplicate_pad_numbers_are_jumpers no)
		(fp_poly
			(pts
				(arc
					(start 0.3556 0)
					(mid -0.3556 0)
					(end 0.3556 0)
				)
			)
			(stroke
				(width 0)
				(type default)
			)
			(fill no)
			(layer "F.CrtYd")
		)
		(fp_poly
			(pts
				(arc
					(start 0.6096 0)
					(mid -0.6096 0)
					(end 0.6096 0)
				)
			)
			(stroke
				(width 0)
				(type default)
			)
			(fill no)
			(layer "F.Fab")
		)
		(pad "1" smd circle
			(at 0 0)
			(size 0.7112 0.7112)
			(layers "F.Cu" "F.Mask" "F.Paste")
			(net "NC_PHY_ENGY_DET")
		)
	)
	(footprint ""
		(layer "F.Cu")
		(at 180.721 -146.431 -90)
		(property "Reference" "SR917"
			(at 0 0 270)
			(layer "F.SilkS")
			(hide yes)
			(effects
				(font
					(size 1.27 1.27)
				)
			)
		)
		(property "Value" "4K7R2F-GP"
			(at 0.064008 -3.993896 270)
			(unlocked yes)
			(layer "F.Fab")
			(hide yes)
			(effects
				(font
					(size 1.016 1.016)
					(thickness 0.1524)
				)
			)
		)
		(property "Device Type" "R402H16"
			(at 0.064008 -5.517896 270)
			(unlocked yes)
			(layer "F.Fab")
			(hide yes)
			(effects
				(font
					(size 1.016 1.016)
					(thickness 0.1524)
				)
			)
		)
		(duplicate_pad_numbers_are_jumpers no)
		(fp_line
			(start -0.508 -0.9398)
			(end -0.508 0.9398)
			(stroke
				(width 0.1524)
				(type default)
			)
			(layer "F.SilkS")
		)
		(fp_line
			(start 0.508 -0.9398)
			(end -0.508 -0.9398)
			(stroke
				(width 0.1524)
				(type default)
			)
			(layer "F.SilkS")
		)
		(fp_rect
			(start -0.508 0.9398)
			(end 0.508 -0.9398)
			(stroke
				(width 0)
				(type default)
			)
			(fill no)
			(layer "F.CrtYd")
		)
		(fp_rect
			(start -0.508 0.9398)
			(end 0.508 -0.9398)
			(stroke
				(width 0)
				(type default)
			)
			(fill no)
			(layer "F.Fab")
		)
		(pad "1" smd custom
			(at 0 -0.4445 270)
			(size 0.1397 0.1397)
			(layers "F.Cu" "F.Mask" "F.Paste")
			(net "BMC_I2C_C_SCL")
			(options
				(clearance outline)
				(anchor circle)
			)
			(primitives
				(gr_poly
					(pts
						(arc
							(start -0.1778 -0.2794)
							(mid -0.249642 -0.249642)
							(end -0.2794 -0.1778)
						)
						(arc
							(start -0.2794 0.1778)
							(mid -0.249642 0.249642)
							(end -0.1778 0.2794)
						)
						(arc
							(start 0.1778 0.2794)
							(mid 0.249642 0.249642)
							(end 0.2794 0.1778)
						)
						(arc
							(start 0.2794 -0.1778)
							(mid 0.249642 -0.249642)
							(end 0.1778 -0.2794)
						)
					)
					(width 0)
					(fill yes)
				)
			)
		)
		(pad "2" smd custom
			(at 0 0.4445 270)
			(size 0.1397 0.1397)
			(layers "F.Cu" "F.Mask" "F.Paste")
			(net "P3V3_STBY")
			(options
				(clearance outline)
				(anchor circle)
			)
			(primitives
				(gr_poly
					(pts
						(arc
							(start -0.1778 -0.2794)
							(mid -0.249642 -0.249642)
							(end -0.2794 -0.1778)
						)
						(arc
							(start -0.2794 0.1778)
							(mid -0.249642 0.249642)
							(end -0.1778 0.2794)
						)
						(arc
							(start 0.1778 0.2794)
							(mid 0.249642 0.249642)
							(end 0.2794 0.1778)
						)
						(arc
							(start 0.2794 -0.1778)
							(mid 0.249642 -0.249642)
							(end 0.1778 -0.2794)
						)
					)
					(width 0)
					(fill yes)
				)
			)
		)
	)
	(footprint ""
		(layer "F.Cu")
		(at 110.11916 -29.845 -90)
		(property "Reference" "SR647"
			(at 0 0 270)
			(layer "F.SilkS")
			(hide yes)
			(effects
				(font
					(size 1.27 1.27)
				)
			)
		)
		(property "Value" "4K7R2F-GP"
			(at 0.064008 -3.993896 270)
			(unlocked yes)
			(layer "F.Fab")
			(hide yes)
			(effects
				(font
					(size 1.016 1.016)
					(thickness 0.1524)
				)
			)
		)
		(property "Device Type" "R402H16"
			(at 0.064008 -5.517896 270)
			(unlocked yes)
			(layer "F.Fab")
			(hide yes)
			(effects
				(font
					(size 1.016 1.016)
					(thickness 0.1524)
				)
			)
		)
		(duplicate_pad_numbers_are_jumpers no)
		(fp_line
			(start -0.508 -0.9398)
			(end -0.508 0.9398)
			(stroke
				(width 0.1524)
				(type default)
			)
			(layer "F.SilkS")
		)
		(fp_line
			(start 0.508 -0.9398)
			(end -0.508 -0.9398)
			(stroke
				(width 0.1524)
				(type default)
			)
			(layer "F.SilkS")
		)
		(fp_rect
			(start -0.508 0.9398)
			(end 0.508 -0.9398)
			(stroke
				(width 0)
				(type default)
			)
			(fill no)
			(layer "F.CrtYd")
		)
		(fp_rect
			(start -0.508 0.9398)
			(end 0.508 -0.9398)
			(stroke
				(width 0)
				(type default)
			)
			(fill no)
			(layer "F.Fab")
		)
		(pad "1" smd custom
			(at 0 -0.4445 270)
			(size 0.1397 0.1397)
			(layers "F.Cu" "F.Mask" "F.Paste")
			(net "P1V8_C")
			(options
				(clearance outline)
				(anchor circle)
			)
			(primitives
				(gr_poly
					(pts
						(arc
							(start -0.1778 -0.2794)
							(mid -0.249642 -0.249642)
							(end -0.2794 -0.1778)
						)
						(arc
							(start -0.2794 0.1778)
							(mid -0.249642 0.249642)
							(end -0.1778 0.2794)
						)
						(arc
							(start 0.1778 0.2794)
							(mid 0.249642 0.249642)
							(end 0.2794 0.1778)
						)
						(arc
							(start 0.2794 -0.1778)
							(mid 0.249642 -0.249642)
							(end 0.1778 -0.2794)
						)
					)
					(width 0)
					(fill yes)
				)
			)
		)
		(pad "2" smd custom
			(at 0 0.4445 270)
			(size 0.1397 0.1397)
			(layers "F.Cu" "F.Mask" "F.Paste")
			(net "IOC_UART_0_RX")
			(options
				(clearance outline)
				(anchor circle)
			)
			(primitives
				(gr_poly
					(pts
						(arc
							(start -0.1778 -0.2794)
							(mid -0.249642 -0.249642)
							(end -0.2794 -0.1778)
						)
						(arc
							(start -0.2794 0.1778)
							(mid -0.249642 0.249642)
							(end -0.1778 0.2794)
						)
						(arc
							(start 0.1778 0.2794)
							(mid 0.249642 0.249642)
							(end 0.2794 0.1778)
						)
						(arc
							(start 0.2794 -0.1778)
							(mid 0.249642 -0.249642)
							(end 0.1778 -0.2794)
						)
					)
					(width 0)
					(fill yes)
				)
			)
		)
	)
	(footprint ""
		(layer "F.Cu")
		(at 279.899872 -205.304136)
		(property "Reference" "R491"
			(at 0 0 0)
			(layer "F.SilkS")
			(hide yes)
			(effects
				(font
					(size 1.27 1.27)
				)
			)
		)
		(property "Value" "0R2J-2-GP"
			(at 0.064008 -3.993896 0)
			(unlocked yes)
			(layer "F.Fab")
			(hide yes)
			(effects
				(font
					(size 1.016 1.016)
					(thickness 0.1524)
				)
			)
		)
		(property "Device Type" "R402H16"
			(at 0.064008 -5.517896 0)
			(unlocked yes)
			(layer "F.Fab")
			(hide yes)
			(effects
				(font
					(size 1.016 1.016)
					(thickness 0.1524)
				)
			)
		)
		(duplicate_pad_numbers_are_jumpers no)
		(fp_line
			(start -0.508 -0.9398)
			(end -0.508 0.9398)
			(stroke
				(width 0.1524)
				(type default)
			)
			(layer "F.SilkS")
		)
		(fp_line
			(start 0.508 -0.9398)
			(end -0.508 -0.9398)
			(stroke
				(width 0.1524)
				(type default)
			)
			(layer "F.SilkS")
		)
		(fp_rect
			(start -0.508 0.9398)
			(end 0.508 -0.9398)
			(stroke
				(width 0)
				(type default)
			)
			(fill no)
			(layer "F.CrtYd")
		)
		(fp_rect
			(start -0.508 0.9398)
			(end 0.508 -0.9398)
			(stroke
				(width 0)
				(type default)
			)
			(fill no)
			(layer "F.Fab")
		)
		(pad "1" smd custom
			(at 0 -0.4445)
			(size 0.1397 0.1397)
			(layers "F.Cu" "F.Mask" "F.Paste")
			(net "RST_BMC_DDR3_R_N")
			(options
				(clearance outline)
				(anchor circle)
			)
			(primitives
				(gr_poly
					(pts
						(arc
							(start -0.1778 -0.2794)
							(mid -0.249642 -0.249642)
							(end -0.2794 -0.1778)
						)
						(arc
							(start -0.2794 0.1778)
							(mid -0.249642 0.249642)
							(end -0.1778 0.2794)
						)
						(arc
							(start 0.1778 0.2794)
							(mid 0.249642 0.249642)
							(end 0.2794 0.1778)
						)
						(arc
							(start 0.2794 -0.1778)
							(mid 0.249642 -0.249642)
							(end 0.1778 -0.2794)
						)
					)
					(width 0)
					(fill yes)
				)
			)
		)
		(pad "2" smd custom
			(at 0 0.4445)
			(size 0.1397 0.1397)
			(layers "F.Cu" "F.Mask" "F.Paste")
			(net "BMC_DDR3_RST_N")
			(options
				(clearance outline)
				(anchor circle)
			)
			(primitives
				(gr_poly
					(pts
						(arc
							(start -0.1778 -0.2794)
							(mid -0.249642 -0.249642)
							(end -0.2794 -0.1778)
						)
						(arc
							(start -0.2794 0.1778)
							(mid -0.249642 0.249642)
							(end -0.1778 0.2794)
						)
						(arc
							(start 0.1778 0.2794)
							(mid 0.249642 0.249642)
							(end 0.2794 0.1778)
						)
						(arc
							(start 0.2794 -0.1778)
							(mid 0.249642 -0.249642)
							(end 0.1778 -0.2794)
						)
					)
					(width 0)
					(fill yes)
				)
			)
		)
	)
	(footprint ""
		(layer "F.Cu")
		(at 158.369 -106.934 90)
		(property "Reference" "SC1209"
			(at 0 0 90)
			(layer "F.SilkS")
			(hide yes)
			(effects
				(font
					(size 1.27 1.27)
				)
			)
		)
		(property "Value" "SC10U6D3V5KX-4GP"
			(at -0.0762 -6.1214 90)
			(unlocked yes)
			(layer "F.Fab")
			(hide yes)
			(effects
				(font
					(size 1.016 1.016)
					(thickness 0.1524)
				)
			)
		)
		(property "Device Type" "C805H58"
			(at -0.0762 -8.1534 90)
			(unlocked yes)
			(layer "F.Fab")
			(hide yes)
			(effects
				(font
					(size 1.016 1.016)
					(thickness 0.1524)
				)
			)
		)
		(duplicate_pad_numbers_are_jumpers no)
		(fp_line
			(start 0.635 0)
			(end -0.635 0)
			(stroke
				(width 0.508)
				(type default)
			)
			(layer "F.SilkS")
		)
		(fp_rect
			(start -0.9652 1.778)
			(end 0.9652 -1.778)
			(stroke
				(width 0)
				(type default)
			)
			(fill no)
			(layer "F.CrtYd")
		)
		(fp_poly
			(pts
				(xy -0.9652 -1.778) (xy 0.9652 -1.778) (xy 0.9652 1.778) (xy -0.9652 1.778)
			)
			(stroke
				(width 0)
				(type default)
			)
			(fill no)
			(layer "F.Fab")
		)
		(pad "1" smd rect
			(at 0 -0.9652 90)
			(size 1.397 1.143)
			(layers "F.Cu" "F.Mask" "F.Paste")
			(net "P0V9_E")
		)
		(pad "2" smd rect
			(at 0 0.9652 90)
			(size 1.397 1.143)
			(layers "F.Cu" "F.Mask" "F.Paste")
			(net "GND")
		)
	)
	(footprint ""
		(layer "F.Cu")
		(at 318.008 -162.306 -90)
		(property "Reference" "R307"
			(at 0 0 270)
			(layer "F.SilkS")
			(hide yes)
			(effects
				(font
					(size 1.27 1.27)
				)
			)
		)
		(property "Value" "10KR2F-2-GP"
			(at 0.064008 -3.993896 270)
			(unlocked yes)
			(layer "F.Fab")
			(hide yes)
			(effects
				(font
					(size 1.016 1.016)
					(thickness 0.1524)
				)
			)
		)
		(property "Device Type" "R402H16"
			(at 0.064008 -5.517896 270)
			(unlocked yes)
			(layer "F.Fab")
			(hide yes)
			(effects
				(font
					(size 1.016 1.016)
					(thickness 0.1524)
				)
			)
		)
		(duplicate_pad_numbers_are_jumpers no)
		(fp_line
			(start -0.508 -0.9398)
			(end -0.508 0.9398)
			(stroke
				(width 0.1524)
				(type default)
			)
			(layer "F.SilkS")
		)
		(fp_line
			(start 0.508 -0.9398)
			(end -0.508 -0.9398)
			(stroke
				(width 0.1524)
				(type default)
			)
			(layer "F.SilkS")
		)
		(fp_rect
			(start -0.508 0.9398)
			(end 0.508 -0.9398)
			(stroke
				(width 0)
				(type default)
			)
			(fill no)
			(layer "F.CrtYd")
		)
		(fp_rect
			(start -0.508 0.9398)
			(end 0.508 -0.9398)
			(stroke
				(width 0)
				(type default)
			)
			(fill no)
			(layer "F.Fab")
		)
		(pad "1" smd custom
			(at 0 -0.4445 270)
			(size 0.1397 0.1397)
			(layers "F.Cu" "F.Mask" "F.Paste")
			(net "P3V3_STBY")
			(options
				(clearance outline)
				(anchor circle)
			)
			(primitives
				(gr_poly
					(pts
						(arc
							(start -0.1778 -0.2794)
							(mid -0.249642 -0.249642)
							(end -0.2794 -0.1778)
						)
						(arc
							(start -0.2794 0.1778)
							(mid -0.249642 0.249642)
							(end -0.1778 0.2794)
						)
						(arc
							(start 0.1778 0.2794)
							(mid 0.249642 0.249642)
							(end 0.2794 0.1778)
						)
						(arc
							(start 0.2794 -0.1778)
							(mid 0.249642 -0.249642)
							(end 0.1778 -0.2794)
						)
					)
					(width 0)
					(fill yes)
				)
			)
		)
		(pad "2" smd custom
			(at 0 0.4445 270)
			(size 0.1397 0.1397)
			(layers "F.Cu" "F.Mask" "F.Paste")
			(net "PU_BMC0_SDA13")
			(options
				(clearance outline)
				(anchor circle)
			)
			(primitives
				(gr_poly
					(pts
						(arc
							(start -0.1778 -0.2794)
							(mid -0.249642 -0.249642)
							(end -0.2794 -0.1778)
						)
						(arc
							(start -0.2794 0.1778)
							(mid -0.249642 0.249642)
							(end -0.1778 0.2794)
						)
						(arc
							(start 0.1778 0.2794)
							(mid 0.249642 0.249642)
							(end 0.2794 0.1778)
						)
						(arc
							(start 0.2794 -0.1778)
							(mid 0.249642 -0.249642)
							(end 0.1778 -0.2794)
						)
					)
					(width 0)
					(fill yes)
				)
			)
		)
	)
	(footprint ""
		(layer "F.Cu")
		(at 278.003 -16.891 90)
		(property "Reference" "R446"
			(at 0 0 90)
			(layer "F.SilkS")
			(hide yes)
			(effects
				(font
					(size 1.27 1.27)
				)
			)
		)
		(property "Value" "0R3J-0-U-GP"
			(at -0.0254 -2.5146 90)
			(unlocked yes)
			(layer "F.Fab")
			(hide yes)
			(effects
				(font
					(size 1.016 1.016)
					(thickness 0.1524)
				)
			)
		)
		(property "Device Type" "R603H22"
			(at -0.0254 -4.0386 90)
			(unlocked yes)
			(layer "F.Fab")
			(hide yes)
			(effects
				(font
					(size 1.016 1.016)
					(thickness 0.1524)
				)
			)
		)
		(duplicate_pad_numbers_are_jumpers no)
		(fp_line
			(start 0.2032 0)
			(end 0.4826 0)
			(stroke
				(width 0.2032)
				(type default)
			)
			(layer "F.SilkS")
		)
		(fp_line
			(start -0.4826 0)
			(end -0.2032 0)
			(stroke
				(width 0.2032)
				(type default)
			)
			(layer "F.SilkS")
		)
		(fp_rect
			(start -0.5842 1.3335)
			(end 0.5842 -1.3335)
			(stroke
				(width 0)
				(type default)
			)
			(fill no)
			(layer "F.CrtYd")
		)
		(fp_rect
			(start -0.5842 1.3335)
			(end 0.5842 -1.3335)
			(stroke
				(width 0)
				(type default)
			)
			(fill no)
			(layer "F.Fab")
		)
		(pad "1" smd custom
			(at 0 -0.762 90)
			(size 0.2159 0.2159)
			(layers "F.Cu" "F.Mask" "F.Paste")
			(net "AGND_USB")
			(options
				(clearance outline)
				(anchor circle)
			)
			(primitives
				(gr_poly
					(pts
						(arc
							(start -0.3302 -0.4318)
							(mid -0.402042 -0.402042)
							(end -0.4318 -0.3302)
						)
						(arc
							(start -0.4318 0.3302)
							(mid -0.402042 0.402042)
							(end -0.3302 0.4318)
						)
						(arc
							(start 0.3302 0.4318)
							(mid 0.402042 0.402042)
							(end 0.4318 0.3302)
						)
						(arc
							(start 0.4318 -0.3302)
							(mid 0.402042 -0.402042)
							(end 0.3302 -0.4318)
						)
					)
					(width 0)
					(fill yes)
				)
			)
		)
		(pad "2" smd custom
			(at 0 0.762 90)
			(size 0.2159 0.2159)
			(layers "F.Cu" "F.Mask" "F.Paste")
			(net "GND")
			(options
				(clearance outline)
				(anchor circle)
			)
			(primitives
				(gr_poly
					(pts
						(arc
							(start -0.3302 -0.4318)
							(mid -0.402042 -0.402042)
							(end -0.4318 -0.3302)
						)
						(arc
							(start -0.4318 0.3302)
							(mid -0.402042 0.402042)
							(end -0.3302 0.4318)
						)
						(arc
							(start 0.3302 0.4318)
							(mid 0.402042 0.402042)
							(end 0.4318 0.3302)
						)
						(arc
							(start 0.4318 -0.3302)
							(mid 0.402042 -0.402042)
							(end 0.3302 -0.4318)
						)
					)
					(width 0)
					(fill yes)
				)
			)
		)
	)
	(footprint ""
		(layer "F.Cu")
		(at 86.976966 -84.328 180)
		(property "Reference" "SC1156"
			(at 0 0 180)
			(layer "F.SilkS")
			(hide yes)
			(effects
				(font
					(size 1.27 1.27)
				)
			)
		)
		(property "Value" "SC1U6D3V1MX-GP"
			(at 1.9177 2.0193 180)
			(unlocked yes)
			(layer "F.Fab")
			(hide yes)
			(effects
				(font
					(size 1.016 1.016)
					(thickness 0.1524)
				)
			)
		)
		(property "Device Type" "C0201H14"
			(at 1.9177 0.4953 180)
			(unlocked yes)
			(layer "F.Fab")
			(hide yes)
			(effects
				(font
					(size 1.016 1.016)
					(thickness 0.1524)
				)
			)
		)
		(duplicate_pad_numbers_are_jumpers no)
		(fp_rect
			(start -0.1524 0.3048)
			(end 0.1524 -0.3048)
			(stroke
				(width 0)
				(type default)
			)
			(fill no)
			(layer "F.CrtYd")
		)
		(fp_poly
			(pts
				(xy -0.2794 0.6477) (xy -0.2794 -0.6477) (xy 0.2794 -0.6477) (xy 0.2794 -0.1905) (xy 0.1524 -0.1905)
				(xy 0.1524 -0.3048) (xy -0.1524 -0.3048) (xy -0.1524 0.3048) (xy 0.1524 0.3048) (xy 0.1524 -0.1778)
				(xy 0.2794 -0.1778) (xy 0.2794 0.6477)
			)
			(stroke
				(width 0)
				(type default)
			)
			(fill no)
			(layer "F.CrtYd")
		)
		(fp_rect
			(start -0.2794 0.6477)
			(end 0.2794 -0.6477)
			(stroke
				(width 0)
				(type default)
			)
			(fill no)
			(layer "F.Fab")
		)
		(pad "1" smd custom
			(at 0 -0.2794 180)
			(size 0.0762 0.0762)
			(layers "F.Cu" "F.Mask" "F.Paste")
			(net "PLLDDR_VDDA18")
			(options
				(clearance outline)
				(anchor circle)
			)
			(primitives
				(gr_poly
					(pts
						(arc
							(start 0.1524 -0.127)
							(mid 0.137521 -0.162921)
							(end 0.1016 -0.1778)
						)
						(arc
							(start -0.1016 -0.1778)
							(mid -0.137521 -0.162921)
							(end -0.1524 -0.127)
						)
						(arc
							(start -0.1524 0.127)
							(mid -0.137521 0.162921)
							(end -0.1016 0.1778)
						)
						(arc
							(start 0.1016 0.1778)
							(mid 0.137521 0.162921)
							(end 0.1524 0.127)
						)
					)
					(width 0)
					(fill yes)
				)
			)
		)
		(pad "2" smd custom
			(at 0 0.2794 180)
			(size 0.0762 0.0762)
			(layers "F.Cu" "F.Mask" "F.Paste")
			(net "GND")
			(options
				(clearance outline)
				(anchor circle)
			)
			(primitives
				(gr_poly
					(pts
						(arc
							(start 0.1524 -0.127)
							(mid 0.137521 -0.162921)
							(end 0.1016 -0.1778)
						)
						(arc
							(start -0.1016 -0.1778)
							(mid -0.137521 -0.162921)
							(end -0.1524 -0.127)
						)
						(arc
							(start -0.1524 0.127)
							(mid -0.137521 0.162921)
							(end -0.1016 0.1778)
						)
						(arc
							(start 0.1016 0.1778)
							(mid 0.137521 0.162921)
							(end 0.1524 0.127)
						)
					)
					(width 0)
					(fill yes)
				)
			)
		)
	)
	(footprint ""
		(layer "F.Cu")
		(at 217.43797 -69.088)
		(property "Reference" "R12"
			(at 0 0 0)
			(layer "F.SilkS")
			(hide yes)
			(effects
				(font
					(size 1.27 1.27)
				)
			)
		)
		(property "Value" "10KR2F-2-GP"
			(at 0.064008 -3.993896 0)
			(unlocked yes)
			(layer "F.Fab")
			(hide yes)
			(effects
				(font
					(size 1.016 1.016)
					(thickness 0.1524)
				)
			)
		)
		(property "Device Type" "R402H16"
			(at 0.064008 -5.517896 0)
			(unlocked yes)
			(layer "F.Fab")
			(hide yes)
			(effects
				(font
					(size 1.016 1.016)
					(thickness 0.1524)
				)
			)
		)
		(duplicate_pad_numbers_are_jumpers no)
		(fp_line
			(start -0.508 -0.9398)
			(end -0.508 0.9398)
			(stroke
				(width 0.1524)
				(type default)
			)
			(layer "F.SilkS")
		)
		(fp_line
			(start 0.508 -0.9398)
			(end -0.508 -0.9398)
			(stroke
				(width 0.1524)
				(type default)
			)
			(layer "F.SilkS")
		)
		(fp_rect
			(start -0.508 0.9398)
			(end 0.508 -0.9398)
			(stroke
				(width 0)
				(type default)
			)
			(fill no)
			(layer "F.CrtYd")
		)
		(fp_rect
			(start -0.508 0.9398)
			(end 0.508 -0.9398)
			(stroke
				(width 0)
				(type default)
			)
			(fill no)
			(layer "F.Fab")
		)
		(pad "1" smd custom
			(at 0 -0.4445)
			(size 0.1397 0.1397)
			(layers "F.Cu" "F.Mask" "F.Paste")
			(net "SVR_ID1")
			(options
				(clearance outline)
				(anchor circle)
			)
			(primitives
				(gr_poly
					(pts
						(arc
							(start -0.1778 -0.2794)
							(mid -0.249642 -0.249642)
							(end -0.2794 -0.1778)
						)
						(arc
							(start -0.2794 0.1778)
							(mid -0.249642 0.249642)
							(end -0.1778 0.2794)
						)
						(arc
							(start 0.1778 0.2794)
							(mid 0.249642 0.249642)
							(end 0.2794 0.1778)
						)
						(arc
							(start 0.2794 -0.1778)
							(mid 0.249642 -0.249642)
							(end 0.1778 -0.2794)
						)
					)
					(width 0)
					(fill yes)
				)
			)
		)
		(pad "2" smd custom
			(at 0 0.4445)
			(size 0.1397 0.1397)
			(layers "F.Cu" "F.Mask" "F.Paste")
			(net "P3V3_STBY")
			(options
				(clearance outline)
				(anchor circle)
			)
			(primitives
				(gr_poly
					(pts
						(arc
							(start -0.1778 -0.2794)
							(mid -0.249642 -0.249642)
							(end -0.2794 -0.1778)
						)
						(arc
							(start -0.2794 0.1778)
							(mid -0.249642 0.249642)
							(end -0.1778 0.2794)
						)
						(arc
							(start 0.1778 0.2794)
							(mid 0.249642 0.249642)
							(end 0.2794 0.1778)
						)
						(arc
							(start 0.2794 -0.1778)
							(mid 0.249642 -0.249642)
							(end 0.1778 -0.2794)
						)
					)
					(width 0)
					(fill yes)
				)
			)
		)
	)
	(footprint ""
		(layer "F.Cu")
		(at 333.366872 -232.482136)
		(property "Reference" "R185"
			(at 0 0 0)
			(layer "F.SilkS")
			(hide yes)
			(effects
				(font
					(size 1.27 1.27)
				)
			)
		)
		(property "Value" "4K7R2F-GP"
			(at 0.064008 -3.993896 0)
			(unlocked yes)
			(layer "F.Fab")
			(hide yes)
			(effects
				(font
					(size 1.016 1.016)
					(thickness 0.1524)
				)
			)
		)
		(property "Device Type" "R402H16"
			(at 0.064008 -5.517896 0)
			(unlocked yes)
			(layer "F.Fab")
			(hide yes)
			(effects
				(font
					(size 1.016 1.016)
					(thickness 0.1524)
				)
			)
		)
		(duplicate_pad_numbers_are_jumpers no)
		(fp_line
			(start -0.508 -0.9398)
			(end -0.508 0.9398)
			(stroke
				(width 0.1524)
				(type default)
			)
			(layer "F.SilkS")
		)
		(fp_line
			(start 0.508 -0.9398)
			(end -0.508 -0.9398)
			(stroke
				(width 0.1524)
				(type default)
			)
			(layer "F.SilkS")
		)
		(fp_rect
			(start -0.508 0.9398)
			(end 0.508 -0.9398)
			(stroke
				(width 0)
				(type default)
			)
			(fill no)
			(layer "F.CrtYd")
		)
		(fp_rect
			(start -0.508 0.9398)
			(end 0.508 -0.9398)
			(stroke
				(width 0)
				(type default)
			)
			(fill no)
			(layer "F.Fab")
		)
		(pad "1" smd custom
			(at 0 -0.4445)
			(size 0.1397 0.1397)
			(layers "F.Cu" "F.Mask" "F.Paste")
			(net "P3V3_STBY")
			(options
				(clearance outline)
				(anchor circle)
			)
			(primitives
				(gr_poly
					(pts
						(arc
							(start -0.1778 -0.2794)
							(mid -0.249642 -0.249642)
							(end -0.2794 -0.1778)
						)
						(arc
							(start -0.2794 0.1778)
							(mid -0.249642 0.249642)
							(end -0.1778 0.2794)
						)
						(arc
							(start 0.1778 0.2794)
							(mid 0.249642 0.249642)
							(end 0.2794 0.1778)
						)
						(arc
							(start 0.2794 -0.1778)
							(mid 0.249642 -0.249642)
							(end 0.1778 -0.2794)
						)
					)
					(width 0)
					(fill yes)
				)
			)
		)
		(pad "2" smd custom
			(at 0 0.4445)
			(size 0.1397 0.1397)
			(layers "F.Cu" "F.Mask" "F.Paste")
			(net "VOL_SEN_ALERT")
			(options
				(clearance outline)
				(anchor circle)
			)
			(primitives
				(gr_poly
					(pts
						(arc
							(start -0.1778 -0.2794)
							(mid -0.249642 -0.249642)
							(end -0.2794 -0.1778)
						)
						(arc
							(start -0.2794 0.1778)
							(mid -0.249642 0.249642)
							(end -0.1778 0.2794)
						)
						(arc
							(start 0.1778 0.2794)
							(mid 0.249642 0.249642)
							(end 0.2794 0.1778)
						)
						(arc
							(start 0.2794 -0.1778)
							(mid 0.249642 -0.249642)
							(end 0.1778 -0.2794)
						)
					)
					(width 0)
					(fill yes)
				)
			)
		)
	)
	(footprint ""
		(layer "F.Cu")
		(at 24.842216 -204.17028)
		(property "Reference" "TP168"
			(at 0 0 0)
			(layer "F.SilkS")
			(hide yes)
			(effects
				(font
					(size 1.27 1.27)
				)
			)
		)
		(property "Value" "TPAD32-GP"
			(at 0 -3.166364 0)
			(unlocked yes)
			(layer "F.Fab")
			(hide yes)
			(effects
				(font
					(size 1.016 1.016)
					(thickness 0.1524)
				)
			)
		)
		(property "Device Type" "TPAD32"
			(at 0 -4.690618 0)
			(unlocked yes)
			(layer "F.Fab")
			(hide yes)
			(effects
				(font
					(size 1.016 1.016)
					(thickness 0.1524)
				)
			)
		)
		(duplicate_pad_numbers_are_jumpers no)
		(fp_poly
			(pts
				(arc
					(start 0.4064 0)
					(mid -0.4064 0)
					(end 0.4064 0)
				)
			)
			(stroke
				(width 0)
				(type default)
			)
			(fill no)
			(layer "F.CrtYd")
		)
		(fp_poly
			(pts
				(arc
					(start 0.7112 0)
					(mid -0.7112 0)
					(end 0.7112 0)
				)
			)
			(stroke
				(width 0)
				(type default)
			)
			(fill no)
			(layer "F.Fab")
		)
		(pad "1" smd circle
			(at 0 0)
			(size 0.8128 0.8128)
			(layers "F.Cu" "F.Mask" "F.Paste")
			(net "VOL_SEN_ALERT_U17")
		)
	)
	(footprint ""
		(layer "F.Cu")
		(at 43.5102 -119.4562 90)
		(property "Reference" "U186"
			(at 0 0 90)
			(layer "F.SilkS")
			(hide yes)
			(effects
				(font
					(size 1.27 1.27)
				)
			)
		)
		(property "Value" "TXS0102DCUR-1-GP"
			(at 0 -11.1252 90)
			(unlocked yes)
			(layer "F.Fab")
			(hide yes)
			(effects
				(font
					(size 1.016 1.016)
					(thickness 0.1524)
				)
			)
		)
		(property "Device Type" "SSOIC8-4H36"
			(at 0 -12.6492 90)
			(unlocked yes)
			(layer "F.Fab")
			(hide yes)
			(effects
				(font
					(size 1.016 1.016)
					(thickness 0.1524)
				)
			)
		)
		(duplicate_pad_numbers_are_jumpers no)
		(fp_line
			(start 1.2573 -2.1844)
			(end 1.2573 2.1844)
			(stroke
				(width 0.1524)
				(type default)
			)
			(layer "F.SilkS")
		)
		(fp_line
			(start -1.2573 -2.1844)
			(end 1.2573 -2.1844)
			(stroke
				(width 0.1524)
				(type default)
			)
			(layer "F.SilkS")
		)
		(fp_line
			(start -1.2192 -0.3556)
			(end -0.9017 -0.0381)
			(stroke
				(width 0.1524)
				(type default)
			)
			(layer "F.SilkS")
		)
		(fp_line
			(start -1.2573 -0.3556)
			(end -1.2192 -0.3556)
			(stroke
				(width 0.1524)
				(type default)
			)
			(layer "F.SilkS")
		)
		(fp_line
			(start -0.9017 -0.0381)
			(end -1.2065 0.2667)
			(stroke
				(width 0.1524)
				(type default)
			)
			(layer "F.SilkS")
		)
		(fp_line
			(start -1.2065 0.2667)
			(end -1.27 0.2667)
			(stroke
				(width 0.1524)
				(type default)
			)
			(layer "F.SilkS")
		)
		(fp_line
			(start -1.2954 0.4572)
			(end -1.2954 2.159)
			(stroke
				(width 0.4064)
				(type default)
			)
			(layer "F.SilkS")
		)
		(fp_line
			(start 1.2573 2.1844)
			(end -1.2573 2.1844)
			(stroke
				(width 0.1524)
				(type default)
			)
			(layer "F.SilkS")
		)
		(fp_line
			(start -1.2573 2.1844)
			(end -1.2573 -2.1844)
			(stroke
				(width 0.1524)
				(type default)
			)
			(layer "F.SilkS")
		)
		(fp_poly
			(pts
				(xy -1.5113 2.4384) (xy 1.5113 2.4384) (xy 1.5113 -2.4384) (xy -1.5113 -2.4384)
			)
			(stroke
				(width 0)
				(type default)
			)
			(fill no)
			(layer "F.CrtYd")
		)
		(fp_poly
			(pts
				(xy -1.5113 -2.4384) (xy 1.5113 -2.4384) (xy 1.5113 2.4384) (xy -1.5113 2.4384)
			)
			(stroke
				(width 0)
				(type default)
			)
			(fill no)
			(layer "F.Fab")
		)
		(pad "1" smd rect
			(at -0.75057 1.1684 90)
			(size 0.3048 1.524)
			(layers "F.Cu" "F.Mask" "F.Paste")
			(net "SAS_R_SDBRX")
		)
		(pad "2" smd rect
			(at -0.25019 1.1684 90)
			(size 0.3048 1.524)
			(layers "F.Cu" "F.Mask" "F.Paste")
			(net "GND")
		)
		(pad "3" smd rect
			(at 0.25019 1.1684 90)
			(size 0.3048 1.524)
			(layers "F.Cu" "F.Mask" "F.Paste")
			(net "P1V8_E")
		)
		(pad "4" smd rect
			(at 0.75057 1.1684 90)
			(size 0.3048 1.524)
			(layers "F.Cu" "F.Mask" "F.Paste")
			(net "SDB_RX_R")
		)
		(pad "5" smd rect
			(at 0.75057 -1.1684 90)
			(size 0.3048 1.524)
			(layers "F.Cu" "F.Mask" "F.Paste")
			(net "SDB_TX_R")
		)
		(pad "6" smd rect
			(at 0.25019 -1.1684 90)
			(size 0.3048 1.524)
			(layers "F.Cu" "F.Mask" "F.Paste")
			(net "SDB_UART_EN")
		)
		(pad "7" smd rect
			(at -0.25019 -1.1684 90)
			(size 0.3048 1.524)
			(layers "F.Cu" "F.Mask" "F.Paste")
			(net "P3V3_STBY")
		)
		(pad "8" smd rect
			(at -0.75057 -1.1684 90)
			(size 0.3048 1.524)
			(layers "F.Cu" "F.Mask" "F.Paste")
			(net "SAS_R_SDBTX")
		)
	)
	(footprint ""
		(layer "F.Cu")
		(at 221.359984 -175.618394)
		(property "Reference" "Q18"
			(at 0 0 0)
			(layer "F.SilkS")
			(hide yes)
			(effects
				(font
					(size 1.27 1.27)
				)
			)
		)
		(property "Value" "2N7002DW-7F-GP"
			(at -2.3622 -8.2042 0)
			(unlocked yes)
			(layer "F.Fab")
			(hide yes)
			(effects
				(font
					(size 1.016 1.016)
					(thickness 0.1524)
				)
			)
		)
		(property "Device Type" "SOT-363H44"
			(at -2.3622 -10.1092 0)
			(unlocked yes)
			(layer "F.Fab")
			(hide yes)
			(effects
				(font
					(size 1.016 1.016)
					(thickness 0.1524)
				)
			)
		)
		(duplicate_pad_numbers_are_jumpers no)
		(fp_line
			(start -1.4478 -1.7018)
			(end -1.4478 1.7018)
			(stroke
				(width 0.1524)
				(type default)
			)
			(layer "F.SilkS")
		)
		(fp_line
			(start -1.4478 1.7018)
			(end 1.4478 1.7018)
			(stroke
				(width 0.1524)
				(type default)
			)
			(layer "F.SilkS")
		)
		(fp_line
			(start -1.27 1.524)
			(end -1.27 0.6604)
			(stroke
				(width 0.4826)
				(type default)
			)
			(layer "F.SilkS")
		)
		(fp_line
			(start 1.4478 -1.7018)
			(end -1.4478 -1.7018)
			(stroke
				(width 0.1524)
				(type default)
			)
			(layer "F.SilkS")
		)
		(fp_line
			(start 1.4478 1.7018)
			(end 1.4478 -1.7018)
			(stroke
				(width 0.1524)
				(type default)
			)
			(layer "F.SilkS")
		)
		(fp_poly
			(pts
				(xy -1.524 -1.778) (xy 1.524 -1.778) (xy 1.524 1.778) (xy -1.524 1.778)
			)
			(stroke
				(width 0)
				(type default)
			)
			(fill no)
			(layer "F.CrtYd")
		)
		(fp_poly
			(pts
				(xy -1.524 -1.778) (xy 1.524 -1.778) (xy 1.524 1.778) (xy -1.524 1.778)
			)
			(stroke
				(width 0)
				(type default)
			)
			(fill no)
			(layer "F.Fab")
		)
		(pad "1" smd rect
			(at -0.65024 0.9398)
			(size 0.4064 1.016)
			(layers "F.Cu" "F.Mask" "F.Paste")
			(net "GND")
		)
		(pad "2" smd rect
			(at 0 0.9398)
			(size 0.4064 1.016)
			(layers "F.Cu" "F.Mask" "F.Paste")
			(net "INVERTER_G2_EXP")
		)
		(pad "3" smd rect
			(at 0.65024 0.9398)
			(size 0.4064 1.016)
			(layers "F.Cu" "F.Mask" "F.Paste")
			(net "INVERTER_G2_EXP")
		)
		(pad "4" smd rect
			(at 0.65024 -0.9398)
			(size 0.4064 1.016)
			(layers "F.Cu" "F.Mask" "F.Paste")
			(net "GND")
		)
		(pad "5" smd rect
			(at 0 -0.9398)
			(size 0.4064 1.016)
			(layers "F.Cu" "F.Mask" "F.Paste")
			(net "INVERTER_G1_EXP")
		)
		(pad "6" smd rect
			(at -0.65024 -0.9398)
			(size 0.4064 1.016)
			(layers "F.Cu" "F.Mask" "F.Paste")
			(net "HB_EXP_TO_BMC")
		)
	)
	(footprint ""
		(layer "F.Cu")
		(at 337.185 -110.49 180)
		(property "Reference" "PC20"
			(at 0 0 180)
			(layer "F.SilkS")
			(hide yes)
			(effects
				(font
					(size 1.27 1.27)
				)
			)
		)
		(property "Value" "SC1U10V2KX-1GP"
			(at 1.1811 -2.7051 180)
			(unlocked yes)
			(layer "F.Fab")
			(hide yes)
			(effects
				(font
					(size 1.016 1.016)
					(thickness 0.1524)
				)
			)
		)
		(property "Device Type" "C402H22"
			(at 1.1811 -4.2291 180)
			(unlocked yes)
			(layer "F.Fab")
			(hide yes)
			(effects
				(font
					(size 1.016 1.016)
					(thickness 0.1524)
				)
			)
		)
		(duplicate_pad_numbers_are_jumpers no)
		(fp_rect
			(start -0.4318 0.9525)
			(end 0.4318 -0.9525)
			(stroke
				(width 0)
				(type default)
			)
			(fill no)
			(layer "F.CrtYd")
		)
		(fp_rect
			(start -0.4318 0.9525)
			(end 0.4318 -0.9525)
			(stroke
				(width 0)
				(type default)
			)
			(fill no)
			(layer "F.Fab")
		)
		(pad "1" smd custom
			(at 0 -0.4445 180)
			(size 0.1524 0.1524)
			(layers "F.Cu" "F.Mask" "F.Paste")
			(net "GND")
			(options
				(clearance outline)
				(anchor circle)
			)
			(primitives
				(gr_poly
					(pts
						(arc
							(start 0.3048 -0.2032)
							(mid 0.275042 -0.275042)
							(end 0.2032 -0.3048)
						)
						(arc
							(start -0.2032 -0.3048)
							(mid -0.275042 -0.275042)
							(end -0.3048 -0.2032)
						)
						(arc
							(start -0.3048 0.2032)
							(mid -0.275042 0.275042)
							(end -0.2032 0.3048)
						)
						(arc
							(start 0.2032 0.3048)
							(mid 0.275042 0.275042)
							(end 0.3048 0.2032)
						)
					)
					(width 0)
					(fill yes)
				)
			)
		)
		(pad "2" smd custom
			(at 0 0.4445 180)
			(size 0.1524 0.1524)
			(layers "F.Cu" "F.Mask" "F.Paste")
			(net "P5V_STBY_EN_R")
			(options
				(clearance outline)
				(anchor circle)
			)
			(primitives
				(gr_poly
					(pts
						(arc
							(start 0.3048 -0.2032)
							(mid 0.275042 -0.275042)
							(end 0.2032 -0.3048)
						)
						(arc
							(start -0.2032 -0.3048)
							(mid -0.275042 -0.275042)
							(end -0.3048 -0.2032)
						)
						(arc
							(start -0.3048 0.2032)
							(mid -0.275042 0.275042)
							(end -0.2032 0.3048)
						)
						(arc
							(start 0.2032 0.3048)
							(mid 0.275042 0.275042)
							(end 0.3048 0.2032)
						)
					)
					(width 0)
					(fill yes)
				)
			)
		)
	)
	(footprint ""
		(layer "F.Cu")
		(at 308.737 -112.776 -90)
		(property "Reference" "PR21"
			(at 0 0 270)
			(layer "F.SilkS")
			(hide yes)
			(effects
				(font
					(size 1.27 1.27)
				)
			)
		)
		(property "Value" "0R2J-2-GP"
			(at 0.064008 -3.993896 270)
			(unlocked yes)
			(layer "F.Fab")
			(hide yes)
			(effects
				(font
					(size 1.016 1.016)
					(thickness 0.1524)
				)
			)
		)
		(property "Device Type" "R402H16"
			(at 0.064008 -5.517896 270)
			(unlocked yes)
			(layer "F.Fab")
			(hide yes)
			(effects
				(font
					(size 1.016 1.016)
					(thickness 0.1524)
				)
			)
		)
		(duplicate_pad_numbers_are_jumpers no)
		(fp_line
			(start -0.508 -0.9398)
			(end -0.508 0.9398)
			(stroke
				(width 0.1524)
				(type default)
			)
			(layer "F.SilkS")
		)
		(fp_line
			(start 0.508 -0.9398)
			(end -0.508 -0.9398)
			(stroke
				(width 0.1524)
				(type default)
			)
			(layer "F.SilkS")
		)
		(fp_rect
			(start -0.508 0.9398)
			(end 0.508 -0.9398)
			(stroke
				(width 0)
				(type default)
			)
			(fill no)
			(layer "F.CrtYd")
		)
		(fp_rect
			(start -0.508 0.9398)
			(end 0.508 -0.9398)
			(stroke
				(width 0)
				(type default)
			)
			(fill no)
			(layer "F.Fab")
		)
		(pad "1" smd custom
			(at 0 -0.4445 270)
			(size 0.1397 0.1397)
			(layers "F.Cu" "F.Mask" "F.Paste")
			(net "P3V3_STBY_EN")
			(options
				(clearance outline)
				(anchor circle)
			)
			(primitives
				(gr_poly
					(pts
						(arc
							(start -0.1778 -0.2794)
							(mid -0.249642 -0.249642)
							(end -0.2794 -0.1778)
						)
						(arc
							(start -0.2794 0.1778)
							(mid -0.249642 0.249642)
							(end -0.1778 0.2794)
						)
						(arc
							(start 0.1778 0.2794)
							(mid 0.249642 0.249642)
							(end 0.2794 0.1778)
						)
						(arc
							(start 0.2794 -0.1778)
							(mid 0.249642 -0.249642)
							(end 0.1778 -0.2794)
						)
					)
					(width 0)
					(fill yes)
				)
			)
		)
		(pad "2" smd custom
			(at 0 0.4445 270)
			(size 0.1397 0.1397)
			(layers "F.Cu" "F.Mask" "F.Paste")
			(net "P5V_STBY_PG")
			(options
				(clearance outline)
				(anchor circle)
			)
			(primitives
				(gr_poly
					(pts
						(arc
							(start -0.1778 -0.2794)
							(mid -0.249642 -0.249642)
							(end -0.2794 -0.1778)
						)
						(arc
							(start -0.2794 0.1778)
							(mid -0.249642 0.249642)
							(end -0.1778 0.2794)
						)
						(arc
							(start 0.1778 0.2794)
							(mid 0.249642 0.249642)
							(end 0.2794 0.1778)
						)
						(arc
							(start 0.2794 -0.1778)
							(mid 0.249642 -0.249642)
							(end 0.1778 -0.2794)
						)
					)
					(width 0)
					(fill yes)
				)
			)
		)
	)
	(footprint ""
		(layer "F.Cu")
		(at 47.9552 -120.5992 90)
		(property "Reference" "SR940"
			(at 0 0 90)
			(layer "F.SilkS")
			(hide yes)
			(effects
				(font
					(size 1.27 1.27)
				)
			)
		)
		(property "Value" "0R2J-2-GP"
			(at 0.064008 -3.993896 90)
			(unlocked yes)
			(layer "F.Fab")
			(hide yes)
			(effects
				(font
					(size 1.016 1.016)
					(thickness 0.1524)
				)
			)
		)
		(property "Device Type" "R402H16"
			(at 0.064008 -5.517896 90)
			(unlocked yes)
			(layer "F.Fab")
			(hide yes)
			(effects
				(font
					(size 1.016 1.016)
					(thickness 0.1524)
				)
			)
		)
		(duplicate_pad_numbers_are_jumpers no)
		(fp_line
			(start 0.508 -0.9398)
			(end -0.508 -0.9398)
			(stroke
				(width 0.1524)
				(type default)
			)
			(layer "F.SilkS")
		)
		(fp_line
			(start -0.508 -0.9398)
			(end -0.508 0.9398)
			(stroke
				(width 0.1524)
				(type default)
			)
			(layer "F.SilkS")
		)
		(fp_rect
			(start -0.508 0.9398)
			(end 0.508 -0.9398)
			(stroke
				(width 0)
				(type default)
			)
			(fill no)
			(layer "F.CrtYd")
		)
		(fp_rect
			(start -0.508 0.9398)
			(end 0.508 -0.9398)
			(stroke
				(width 0)
				(type default)
			)
			(fill no)
			(layer "F.Fab")
		)
		(pad "1" smd custom
			(at 0 -0.4445 90)
			(size 0.1397 0.1397)
			(layers "F.Cu" "F.Mask" "F.Paste")
			(net "SDB_RX_R")
			(options
				(clearance outline)
				(anchor circle)
			)
			(primitives
				(gr_poly
					(pts
						(arc
							(start -0.1778 -0.2794)
							(mid -0.249642 -0.249642)
							(end -0.2794 -0.1778)
						)
						(arc
							(start -0.2794 0.1778)
							(mid -0.249642 0.249642)
							(end -0.1778 0.2794)
						)
						(arc
							(start 0.1778 0.2794)
							(mid 0.249642 0.249642)
							(end 0.2794 0.1778)
						)
						(arc
							(start 0.2794 -0.1778)
							(mid 0.249642 -0.249642)
							(end 0.1778 -0.2794)
						)
					)
					(width 0)
					(fill yes)
				)
			)
		)
		(pad "2" smd custom
			(at 0 0.4445 90)
			(size 0.1397 0.1397)
			(layers "F.Cu" "F.Mask" "F.Paste")
			(net "SDB_RX")
			(options
				(clearance outline)
				(anchor circle)
			)
			(primitives
				(gr_poly
					(pts
						(arc
							(start -0.1778 -0.2794)
							(mid -0.249642 -0.249642)
							(end -0.2794 -0.1778)
						)
						(arc
							(start -0.2794 0.1778)
							(mid -0.249642 0.249642)
							(end -0.1778 0.2794)
						)
						(arc
							(start 0.1778 0.2794)
							(mid 0.249642 0.249642)
							(end 0.2794 0.1778)
						)
						(arc
							(start 0.2794 -0.1778)
							(mid 0.249642 -0.249642)
							(end 0.1778 -0.2794)
						)
					)
					(width 0)
					(fill yes)
				)
			)
		)
	)
	(footprint ""
		(layer "F.Cu")
		(at 321.31 -149.987 90)
		(property "Reference" "U43"
			(at 0 0 90)
			(layer "F.SilkS")
			(hide yes)
			(effects
				(font
					(size 1.27 1.27)
				)
			)
		)
		(property "Value" "PCF8563T-1-GP"
			(at -3.707384 -1.5367 90)
			(unlocked yes)
			(layer "F.Fab")
			(hide yes)
			(effects
				(font
					(size 1.016 1.016)
					(thickness 0.1524)
				)
			)
		)
		(property "Device Type" "SOIC8H69"
			(at -3.707384 -3.0607 90)
			(unlocked yes)
			(layer "F.Fab")
			(hide yes)
			(effects
				(font
					(size 1.016 1.016)
					(thickness 0.1524)
				)
			)
		)
		(duplicate_pad_numbers_are_jumpers no)
		(fp_line
			(start 2.1336 -1.4224)
			(end -2.7432 -1.4224)
			(stroke
				(width 0.1524)
				(type default)
			)
			(layer "F.SilkS")
		)
		(fp_line
			(start -2.7432 -1.4224)
			(end -2.7432 1.4224)
			(stroke
				(width 0.1524)
				(type default)
			)
			(layer "F.SilkS")
		)
		(fp_line
			(start -2.7178 -0.508)
			(end -2.1844 -0.0508)
			(stroke
				(width 0.1524)
				(type default)
			)
			(layer "F.SilkS")
		)
		(fp_line
			(start -2.1844 -0.0508)
			(end -2.7178 0.508)
			(stroke
				(width 0.1524)
				(type default)
			)
			(layer "F.SilkS")
		)
		(fp_line
			(start 2.1336 1.4224)
			(end 2.1336 -1.4224)
			(stroke
				(width 0.1524)
				(type default)
			)
			(layer "F.SilkS")
		)
		(fp_line
			(start -2.7432 1.4224)
			(end 2.1336 1.4224)
			(stroke
				(width 0.1524)
				(type default)
			)
			(layer "F.SilkS")
		)
		(fp_line
			(start -2.7432 1.4224)
			(end -2.6416 1.4224)
			(stroke
				(width 0.1524)
				(type default)
			)
			(layer "F.SilkS")
		)
		(fp_line
			(start -2.6289 3.4417)
			(end -2.6289 1.4732)
			(stroke
				(width 0.381)
				(type default)
			)
			(layer "F.SilkS")
		)
		(fp_poly
			(pts
				(xy -2.2098 -1.4224) (xy -2.2098 1.4224) (xy 2.2098 1.4224) (xy 2.2098 -1.4224)
			)
			(stroke
				(width 0)
				(type default)
			)
			(fill yes)
			(layer "F.SilkS")
		)
		(fp_rect
			(start -2.450084 2.999994)
			(end 2.450084 -2.999994)
			(stroke
				(width 0)
				(type default)
			)
			(fill no)
			(layer "F.CrtYd")
		)
		(fp_poly
			(pts
				(xy -2.8194 3.6322) (xy -2.8194 -3.6322) (xy 2.8194 -3.6322) (xy 2.8194 1.18364) (xy 2.450084 1.18364)
				(xy 2.450084 -2.999994) (xy -2.450084 -2.999994) (xy -2.450084 2.999994) (xy 2.450084 2.999994)
				(xy 2.450084 1.18618) (xy 2.8194 1.18618) (xy 2.8194 3.6322)
			)
			(stroke
				(width 0)
				(type default)
			)
			(fill no)
			(layer "F.CrtYd")
		)
		(fp_rect
			(start -2.8194 3.6322)
			(end 2.8194 -3.6322)
			(stroke
				(width 0)
				(type default)
			)
			(fill no)
			(layer "F.Fab")
		)
		(pad "1" smd rect
			(at -1.905 2.54 90)
			(size 0.635 1.651)
			(layers "F.Cu" "F.Mask" "F.Paste")
			(net "RTC_OSCI")
		)
		(pad "2" smd rect
			(at -0.635 2.54 90)
			(size 0.635 1.651)
			(layers "F.Cu" "F.Mask" "F.Paste")
			(net "RTC_OSCO")
		)
		(pad "3" smd rect
			(at 0.635 2.54 90)
			(size 0.635 1.651)
			(layers "F.Cu" "F.Mask" "F.Paste")
			(net "RTC_INT_N")
		)
		(pad "4" smd rect
			(at 1.905 2.54 90)
			(size 0.635 1.651)
			(layers "F.Cu" "F.Mask" "F.Paste")
			(net "GND")
		)
		(pad "5" smd rect
			(at 1.905 -2.54 90)
			(size 0.635 1.651)
			(layers "F.Cu" "F.Mask" "F.Paste")
			(net "RTC_I2C_SDA")
		)
		(pad "6" smd rect
			(at 0.635 -2.54 90)
			(size 0.635 1.651)
			(layers "F.Cu" "F.Mask" "F.Paste")
			(net "RTC_I2C_SCL")
		)
		(pad "7" smd rect
			(at -0.635 -2.54 90)
			(size 0.635 1.651)
			(layers "F.Cu" "F.Mask" "F.Paste")
			(net "RTC_CLK_OUT")
		)
		(pad "8" smd rect
			(at -1.905 -2.54 90)
			(size 0.635 1.651)
			(layers "F.Cu" "F.Mask" "F.Paste")
			(net "P3V3_RTC")
		)
	)
	(footprint ""
		(layer "F.Cu")
		(at 291.973 -206.756 90)
		(property "Reference" "C174"
			(at 0 0 90)
			(layer "F.SilkS")
			(hide yes)
			(effects
				(font
					(size 1.27 1.27)
				)
			)
		)
		(property "Value" "SCD1U16V2KX-3GP"
			(at 1.1811 -2.7051 90)
			(unlocked yes)
			(layer "F.Fab")
			(hide yes)
			(effects
				(font
					(size 1.016 1.016)
					(thickness 0.1524)
				)
			)
		)
		(property "Device Type" "C402H22"
			(at 1.1811 -4.2291 90)
			(unlocked yes)
			(layer "F.Fab")
			(hide yes)
			(effects
				(font
					(size 1.016 1.016)
					(thickness 0.1524)
				)
			)
		)
		(duplicate_pad_numbers_are_jumpers no)
		(fp_rect
			(start -0.4318 0.9525)
			(end 0.4318 -0.9525)
			(stroke
				(width 0)
				(type default)
			)
			(fill no)
			(layer "F.CrtYd")
		)
		(fp_rect
			(start -0.4318 0.9525)
			(end 0.4318 -0.9525)
			(stroke
				(width 0)
				(type default)
			)
			(fill no)
			(layer "F.Fab")
		)
		(pad "1" smd custom
			(at 0 -0.4445 90)
			(size 0.1524 0.1524)
			(layers "F.Cu" "F.Mask" "F.Paste")
			(net "DDR_VREF")
			(options
				(clearance outline)
				(anchor circle)
			)
			(primitives
				(gr_poly
					(pts
						(arc
							(start 0.3048 -0.2032)
							(mid 0.275042 -0.275042)
							(end 0.2032 -0.3048)
						)
						(arc
							(start -0.2032 -0.3048)
							(mid -0.275042 -0.275042)
							(end -0.3048 -0.2032)
						)
						(arc
							(start -0.3048 0.2032)
							(mid -0.275042 0.275042)
							(end -0.2032 0.3048)
						)
						(arc
							(start 0.2032 0.3048)
							(mid 0.275042 0.275042)
							(end 0.3048 0.2032)
						)
					)
					(width 0)
					(fill yes)
				)
			)
		)
		(pad "2" smd custom
			(at 0 0.4445 90)
			(size 0.1524 0.1524)
			(layers "F.Cu" "F.Mask" "F.Paste")
			(net "GND")
			(options
				(clearance outline)
				(anchor circle)
			)
			(primitives
				(gr_poly
					(pts
						(arc
							(start 0.3048 -0.2032)
							(mid 0.275042 -0.275042)
							(end 0.2032 -0.3048)
						)
						(arc
							(start -0.2032 -0.3048)
							(mid -0.275042 -0.275042)
							(end -0.3048 -0.2032)
						)
						(arc
							(start -0.3048 0.2032)
							(mid -0.275042 0.275042)
							(end -0.2032 0.3048)
						)
						(arc
							(start 0.2032 0.3048)
							(mid 0.275042 0.275042)
							(end 0.3048 0.2032)
						)
					)
					(width 0)
					(fill yes)
				)
			)
		)
	)
	(footprint ""
		(layer "F.Cu")
		(at 312.547 -191.262 90)
		(property "Reference" "R804"
			(at 0 0 90)
			(layer "F.SilkS")
			(hide yes)
			(effects
				(font
					(size 1.27 1.27)
				)
			)
		)
		(property "Value" "4K7R2F-GP"
			(at 0.064008 -3.993896 90)
			(unlocked yes)
			(layer "F.Fab")
			(hide yes)
			(effects
				(font
					(size 1.016 1.016)
					(thickness 0.1524)
				)
			)
		)
		(property "Device Type" "R402H16"
			(at 0.064008 -5.517896 90)
			(unlocked yes)
			(layer "F.Fab")
			(hide yes)
			(effects
				(font
					(size 1.016 1.016)
					(thickness 0.1524)
				)
			)
		)
		(duplicate_pad_numbers_are_jumpers no)
		(fp_line
			(start 0.508 -0.9398)
			(end -0.508 -0.9398)
			(stroke
				(width 0.1524)
				(type default)
			)
			(layer "F.SilkS")
		)
		(fp_line
			(start -0.508 -0.9398)
			(end -0.508 0.9398)
			(stroke
				(width 0.1524)
				(type default)
			)
			(layer "F.SilkS")
		)
		(fp_rect
			(start -0.508 0.9398)
			(end 0.508 -0.9398)
			(stroke
				(width 0)
				(type default)
			)
			(fill no)
			(layer "F.CrtYd")
		)
		(fp_rect
			(start -0.508 0.9398)
			(end 0.508 -0.9398)
			(stroke
				(width 0)
				(type default)
			)
			(fill no)
			(layer "F.Fab")
		)
		(pad "1" smd custom
			(at 0 -0.4445 90)
			(size 0.1397 0.1397)
			(layers "F.Cu" "F.Mask" "F.Paste")
			(net "P3V3_STBY")
			(options
				(clearance outline)
				(anchor circle)
			)
			(primitives
				(gr_poly
					(pts
						(arc
							(start -0.1778 -0.2794)
							(mid -0.249642 -0.249642)
							(end -0.2794 -0.1778)
						)
						(arc
							(start -0.2794 0.1778)
							(mid -0.249642 0.249642)
							(end -0.1778 0.2794)
						)
						(arc
							(start 0.1778 0.2794)
							(mid 0.249642 0.249642)
							(end 0.2794 0.1778)
						)
						(arc
							(start 0.2794 -0.1778)
							(mid 0.249642 -0.249642)
							(end 0.1778 -0.2794)
						)
					)
					(width 0)
					(fill yes)
				)
			)
		)
		(pad "2" smd custom
			(at 0 0.4445 90)
			(size 0.1397 0.1397)
			(layers "F.Cu" "F.Mask" "F.Paste")
			(net "JTAG_BMC_TCK")
			(options
				(clearance outline)
				(anchor circle)
			)
			(primitives
				(gr_poly
					(pts
						(arc
							(start -0.1778 -0.2794)
							(mid -0.249642 -0.249642)
							(end -0.2794 -0.1778)
						)
						(arc
							(start -0.2794 0.1778)
							(mid -0.249642 0.249642)
							(end -0.1778 0.2794)
						)
						(arc
							(start 0.1778 0.2794)
							(mid 0.249642 0.249642)
							(end 0.2794 0.1778)
						)
						(arc
							(start 0.2794 -0.1778)
							(mid 0.249642 -0.249642)
							(end 0.1778 -0.2794)
						)
					)
					(width 0)
					(fill yes)
				)
			)
		)
	)
	(footprint ""
		(layer "F.Cu")
		(at 192.151 -222.123 90)
		(property "Reference" "R1586"
			(at 0 0 90)
			(layer "F.SilkS")
			(hide yes)
			(effects
				(font
					(size 1.27 1.27)
				)
			)
		)
		(property "Value" "33R2F-3-GP"
			(at 0.064008 -3.993896 90)
			(unlocked yes)
			(layer "F.Fab")
			(hide yes)
			(effects
				(font
					(size 1.016 1.016)
					(thickness 0.1524)
				)
			)
		)
		(property "Device Type" "R402H16"
			(at 0.064008 -5.517896 90)
			(unlocked yes)
			(layer "F.Fab")
			(hide yes)
			(effects
				(font
					(size 1.016 1.016)
					(thickness 0.1524)
				)
			)
		)
		(duplicate_pad_numbers_are_jumpers no)
		(fp_line
			(start 0.508 -0.9398)
			(end -0.508 -0.9398)
			(stroke
				(width 0.1524)
				(type default)
			)
			(layer "F.SilkS")
		)
		(fp_line
			(start -0.508 -0.9398)
			(end -0.508 0.9398)
			(stroke
				(width 0.1524)
				(type default)
			)
			(layer "F.SilkS")
		)
		(fp_rect
			(start -0.508 0.9398)
			(end 0.508 -0.9398)
			(stroke
				(width 0)
				(type default)
			)
			(fill no)
			(layer "F.CrtYd")
		)
		(fp_rect
			(start -0.508 0.9398)
			(end 0.508 -0.9398)
			(stroke
				(width 0)
				(type default)
			)
			(fill no)
			(layer "F.Fab")
		)
		(pad "1" smd custom
			(at 0 -0.4445 90)
			(size 0.1397 0.1397)
			(layers "F.Cu" "F.Mask" "F.Paste")
			(net "FP_RETBTN")
			(options
				(clearance outline)
				(anchor circle)
			)
			(primitives
				(gr_poly
					(pts
						(arc
							(start -0.1778 -0.2794)
							(mid -0.249642 -0.249642)
							(end -0.2794 -0.1778)
						)
						(arc
							(start -0.2794 0.1778)
							(mid -0.249642 0.249642)
							(end -0.1778 0.2794)
						)
						(arc
							(start 0.1778 0.2794)
							(mid 0.249642 0.249642)
							(end 0.2794 0.1778)
						)
						(arc
							(start 0.2794 -0.1778)
							(mid 0.249642 -0.249642)
							(end 0.1778 -0.2794)
						)
					)
					(width 0)
					(fill yes)
				)
			)
		)
		(pad "2" smd custom
			(at 0 0.4445 90)
			(size 0.1397 0.1397)
			(layers "F.Cu" "F.Mask" "F.Paste")
			(net "FP_RETBTN_R")
			(options
				(clearance outline)
				(anchor circle)
			)
			(primitives
				(gr_poly
					(pts
						(arc
							(start -0.1778 -0.2794)
							(mid -0.249642 -0.249642)
							(end -0.2794 -0.1778)
						)
						(arc
							(start -0.2794 0.1778)
							(mid -0.249642 0.249642)
							(end -0.1778 0.2794)
						)
						(arc
							(start 0.1778 0.2794)
							(mid 0.249642 0.249642)
							(end 0.2794 0.1778)
						)
						(arc
							(start 0.2794 -0.1778)
							(mid 0.249642 -0.249642)
							(end 0.1778 -0.2794)
						)
					)
					(width 0)
					(fill yes)
				)
			)
		)
	)
	(footprint ""
		(layer "F.Cu")
		(at 139.45997 -83.566)
		(property "Reference" "R166"
			(at 0 0 0)
			(layer "F.SilkS")
			(hide yes)
			(effects
				(font
					(size 1.27 1.27)
				)
			)
		)
		(property "Value" "4K7R2F-GP"
			(at 0.064008 -3.993896 0)
			(unlocked yes)
			(layer "F.Fab")
			(hide yes)
			(effects
				(font
					(size 1.016 1.016)
					(thickness 0.1524)
				)
			)
		)
		(property "Device Type" "R402H16"
			(at 0.064008 -5.517896 0)
			(unlocked yes)
			(layer "F.Fab")
			(hide yes)
			(effects
				(font
					(size 1.016 1.016)
					(thickness 0.1524)
				)
			)
		)
		(duplicate_pad_numbers_are_jumpers no)
		(fp_line
			(start -0.508 -0.9398)
			(end -0.508 0.9398)
			(stroke
				(width 0.1524)
				(type default)
			)
			(layer "F.SilkS")
		)
		(fp_line
			(start 0.508 -0.9398)
			(end -0.508 -0.9398)
			(stroke
				(width 0.1524)
				(type default)
			)
			(layer "F.SilkS")
		)
		(fp_rect
			(start -0.508 0.9398)
			(end 0.508 -0.9398)
			(stroke
				(width 0)
				(type default)
			)
			(fill no)
			(layer "F.CrtYd")
		)
		(fp_rect
			(start -0.508 0.9398)
			(end 0.508 -0.9398)
			(stroke
				(width 0)
				(type default)
			)
			(fill no)
			(layer "F.Fab")
		)
		(pad "1" smd custom
			(at 0 -0.4445)
			(size 0.1397 0.1397)
			(layers "F.Cu" "F.Mask" "F.Paste")
			(net "TEMP_3_A2")
			(options
				(clearance outline)
				(anchor circle)
			)
			(primitives
				(gr_poly
					(pts
						(arc
							(start -0.1778 -0.2794)
							(mid -0.249642 -0.249642)
							(end -0.2794 -0.1778)
						)
						(arc
							(start -0.2794 0.1778)
							(mid -0.249642 0.249642)
							(end -0.1778 0.2794)
						)
						(arc
							(start 0.1778 0.2794)
							(mid 0.249642 0.249642)
							(end 0.2794 0.1778)
						)
						(arc
							(start 0.2794 -0.1778)
							(mid 0.249642 -0.249642)
							(end 0.1778 -0.2794)
						)
					)
					(width 0)
					(fill yes)
				)
			)
		)
		(pad "2" smd custom
			(at 0 0.4445)
			(size 0.1397 0.1397)
			(layers "F.Cu" "F.Mask" "F.Paste")
			(net "GND")
			(options
				(clearance outline)
				(anchor circle)
			)
			(primitives
				(gr_poly
					(pts
						(arc
							(start -0.1778 -0.2794)
							(mid -0.249642 -0.249642)
							(end -0.2794 -0.1778)
						)
						(arc
							(start -0.2794 0.1778)
							(mid -0.249642 0.249642)
							(end -0.1778 0.2794)
						)
						(arc
							(start 0.1778 0.2794)
							(mid 0.249642 0.249642)
							(end 0.2794 0.1778)
						)
						(arc
							(start 0.2794 -0.1778)
							(mid 0.249642 -0.249642)
							(end 0.1778 -0.2794)
						)
					)
					(width 0)
					(fill yes)
				)
			)
		)
	)
	(footprint ""
		(layer "F.Cu")
		(at 85.579966 -64.897 90)
		(property "Reference" "SX1"
			(at 0 0 90)
			(layer "F.SilkS")
			(hide yes)
			(effects
				(font
					(size 1.27 1.27)
				)
			)
		)
		(property "Value" "XTAL-25MHZ-105-GP"
			(at 0.1016 -10.5918 90)
			(unlocked yes)
			(layer "F.Fab")
			(hide yes)
			(effects
				(font
					(size 1.016 1.016)
					(thickness 0.1524)
				)
			)
		)
		(property "Device Type" "SG8002CAPC-4H40"
			(at 0.1016 -12.6238 90)
			(unlocked yes)
			(layer "F.Fab")
			(hide yes)
			(effects
				(font
					(size 1.016 1.016)
					(thickness 0.1524)
				)
			)
		)
		(duplicate_pad_numbers_are_jumpers no)
		(fp_line
			(start 2.8575 -1.9558)
			(end 2.8575 1.9558)
			(stroke
				(width 0.1524)
				(type default)
			)
			(layer "F.SilkS")
		)
		(fp_line
			(start -2.8575 -1.9558)
			(end 2.8575 -1.9558)
			(stroke
				(width 0.1524)
				(type default)
			)
			(layer "F.SilkS")
		)
		(fp_line
			(start 2.8575 1.9558)
			(end -2.8575 1.9558)
			(stroke
				(width 0.1524)
				(type default)
			)
			(layer "F.SilkS")
		)
		(fp_line
			(start -2.8575 1.9558)
			(end -2.8575 -1.9558)
			(stroke
				(width 0.1524)
				(type default)
			)
			(layer "F.SilkS")
		)
		(fp_poly
			(pts
				(xy -2.3114 2.3876) (xy -1.9558 2.032) (xy -1.6002 2.3876)
			)
			(stroke
				(width 0)
				(type default)
			)
			(fill yes)
			(layer "F.SilkS")
		)
		(fp_rect
			(start -2.99974 2.10058)
			(end 2.99974 -2.09931)
			(stroke
				(width 0)
				(type default)
			)
			(fill no)
			(layer "F.CrtYd")
		)
		(fp_rect
			(start -2.3114 2.3876)
			(end -1.6002 2.10058)
			(stroke
				(width 0)
				(type default)
			)
			(fill no)
			(layer "F.CrtYd")
		)
		(fp_poly
			(pts
				(xy -2.3114 2.3876) (xy -2.3114 2.10058) (xy -2.99974 2.10058) (xy -2.99974 -2.09931) (xy 2.99974 -2.09931)
				(xy 2.99974 2.09931) (xy -1.6002 2.09931) (xy -1.6002 2.3876)
			)
			(stroke
				(width 0)
				(type default)
			)
			(fill no)
			(layer "F.Fab")
		)
		(pad "1" smd rect
			(at -1.8034 1.0414 90)
			(size 1.6002 1.3462)
			(layers "F.Cu" "F.Mask" "F.Paste")
			(net "REF_CLK")
		)
		(pad "2" smd rect
			(at 1.8034 1.0414 90)
			(size 1.6002 1.3462)
			(layers "F.Cu" "F.Mask" "F.Paste")
			(net "GND")
		)
		(pad "3" smd rect
			(at 1.8034 -1.0414 90)
			(size 1.6002 1.3462)
			(layers "F.Cu" "F.Mask" "F.Paste")
			(net "IOC_REF_CLK_P")
		)
		(pad "4" smd rect
			(at -1.8034 -1.0414 90)
			(size 1.6002 1.3462)
			(layers "F.Cu" "F.Mask" "F.Paste")
			(net "GND")
		)
		(zone
			(layer "F.Cu")
			(hatch none 0.5)
			(connect_pads
				(clearance 0)
			)
			(min_thickness 0.25)
			(keepout
				(tracks not_allowed)
				(vias allowed)
				(pads allowed)
				(copperpour not_allowed)
				(footprints allowed)
			)
			(placement
				(enabled no)
				(sheetname "")
			)
			(fill
				(thermal_gap 0.5)
				(thermal_bridge_width 0.5)
				(island_removal_mode 0)
			)
			(polygon
				(pts
					(xy 85.198966 -64.389) (xy 85.198966 -65.405) (xy 85.960966 -65.405) (xy 85.960966 -64.389)
				)
			)
		)
		(zone
			(layer "F.Cu")
			(hatch none 0.5)
			(connect_pads
				(clearance 0)
			)
			(min_thickness 0.25)
			(keepout
				(tracks allowed)
				(vias not_allowed)
				(pads allowed)
				(copperpour not_allowed)
				(footprints allowed)
			)
			(placement
				(enabled no)
				(sheetname "")
			)
			(fill
				(thermal_gap 0.5)
				(thermal_bridge_width 0.5)
				(island_removal_mode 0)
			)
			(polygon
				(pts
					(xy 83.928966 -63.881) (xy 83.928966 -65.913) (xy 85.325966 -65.913) (xy 85.325966 -67.437) (xy 85.833966 -67.437)
					(xy 85.833966 -65.913) (xy 87.230966 -65.913) (xy 87.230966 -63.881) (xy 85.833966 -63.881) (xy 85.833966 -62.357)
					(xy 85.325966 -62.357) (xy 85.325966 -63.881)
				)
			)
		)
	)
	(footprint ""
		(layer "F.Cu")
		(at 86.614 -29.09316 180)
		(property "Reference" "SR582"
			(at 0 0 180)
			(layer "F.SilkS")
			(hide yes)
			(effects
				(font
					(size 1.27 1.27)
				)
			)
		)
		(property "Value" "51R2F-2-GP"
			(at 0.064008 -3.993896 180)
			(unlocked yes)
			(layer "F.Fab")
			(hide yes)
			(effects
				(font
					(size 1.016 1.016)
					(thickness 0.1524)
				)
			)
		)
		(property "Device Type" "R402H16"
			(at 0.064008 -5.517896 180)
			(unlocked yes)
			(layer "F.Fab")
			(hide yes)
			(effects
				(font
					(size 1.016 1.016)
					(thickness 0.1524)
				)
			)
		)
		(duplicate_pad_numbers_are_jumpers no)
		(fp_line
			(start 0.508 -0.9398)
			(end -0.508 -0.9398)
			(stroke
				(width 0.1524)
				(type default)
			)
			(layer "F.SilkS")
		)
		(fp_line
			(start -0.508 -0.9398)
			(end -0.508 0.9398)
			(stroke
				(width 0.1524)
				(type default)
			)
			(layer "F.SilkS")
		)
		(fp_rect
			(start -0.508 0.9398)
			(end 0.508 -0.9398)
			(stroke
				(width 0)
				(type default)
			)
			(fill no)
			(layer "F.CrtYd")
		)
		(fp_rect
			(start -0.508 0.9398)
			(end 0.508 -0.9398)
			(stroke
				(width 0)
				(type default)
			)
			(fill no)
			(layer "F.Fab")
		)
		(pad "1" smd custom
			(at 0 -0.4445 180)
			(size 0.1397 0.1397)
			(layers "F.Cu" "F.Mask" "F.Paste")
			(net "CLK_100M_PCIE_P")
			(options
				(clearance outline)
				(anchor circle)
			)
			(primitives
				(gr_poly
					(pts
						(arc
							(start -0.1778 -0.2794)
							(mid -0.249642 -0.249642)
							(end -0.2794 -0.1778)
						)
						(arc
							(start -0.2794 0.1778)
							(mid -0.249642 0.249642)
							(end -0.1778 0.2794)
						)
						(arc
							(start 0.1778 0.2794)
							(mid 0.249642 0.249642)
							(end 0.2794 0.1778)
						)
						(arc
							(start 0.2794 -0.1778)
							(mid 0.249642 -0.249642)
							(end 0.1778 -0.2794)
						)
					)
					(width 0)
					(fill yes)
				)
			)
		)
		(pad "2" smd custom
			(at 0 0.4445 180)
			(size 0.1397 0.1397)
			(layers "F.Cu" "F.Mask" "F.Paste")
			(net "CK_100M_EXP_SAS")
			(options
				(clearance outline)
				(anchor circle)
			)
			(primitives
				(gr_poly
					(pts
						(arc
							(start -0.1778 -0.2794)
							(mid -0.249642 -0.249642)
							(end -0.2794 -0.1778)
						)
						(arc
							(start -0.2794 0.1778)
							(mid -0.249642 0.249642)
							(end -0.1778 0.2794)
						)
						(arc
							(start 0.1778 0.2794)
							(mid 0.249642 0.249642)
							(end 0.2794 0.1778)
						)
						(arc
							(start 0.2794 -0.1778)
							(mid 0.249642 -0.249642)
							(end 0.1778 -0.2794)
						)
					)
					(width 0)
					(fill yes)
				)
			)
		)
	)
	(footprint ""
		(layer "F.Cu")
		(at 73.827386 -109.392212 90)
		(property "Reference" "PQ3"
			(at 0 0 90)
			(layer "F.SilkS")
			(hide yes)
			(effects
				(font
					(size 1.27 1.27)
				)
			)
		)
		(property "Value" "FDN359BN-GP-U"
			(at -3.175 0.254 90)
			(unlocked yes)
			(layer "F.Fab")
			(hide yes)
			(effects
				(font
					(size 1.016 1.016)
					(thickness 0.1524)
				)
			)
		)
		(property "Device Type" "SOT23DGS2D6H45"
			(at -3.175 -1.27 90)
			(unlocked yes)
			(layer "F.Fab")
			(hide yes)
			(effects
				(font
					(size 1.016 1.016)
					(thickness 0.1524)
				)
			)
		)
		(duplicate_pad_numbers_are_jumpers no)
		(fp_line
			(start 1.7018 -1.905)
			(end 1.7018 1.905)
			(stroke
				(width 0.1524)
				(type default)
			)
			(layer "F.SilkS")
		)
		(fp_line
			(start -1.7018 -1.905)
			(end 1.7018 -1.905)
			(stroke
				(width 0.1524)
				(type default)
			)
			(layer "F.SilkS")
		)
		(fp_line
			(start 1.7018 1.905)
			(end -1.7018 1.905)
			(stroke
				(width 0.1524)
				(type default)
			)
			(layer "F.SilkS")
		)
		(fp_line
			(start -1.7018 1.905)
			(end -1.7018 -1.905)
			(stroke
				(width 0.1524)
				(type default)
			)
			(layer "F.SilkS")
		)
		(fp_rect
			(start -2.0066 1.9812)
			(end 2.0066 -1.9812)
			(stroke
				(width 0)
				(type default)
			)
			(fill no)
			(layer "F.CrtYd")
		)
		(fp_rect
			(start -2.0066 1.9812)
			(end 2.0066 -1.9812)
			(stroke
				(width 0)
				(type default)
			)
			(fill no)
			(layer "F.Fab")
		)
		(pad "D" smd custom
			(at 0 -1.0922 90)
			(size 0.1651 0.1651)
			(layers "F.Cu" "F.Mask" "F.Paste")
			(net "P1V8_STBY")
			(options
				(clearance outline)
				(anchor circle)
			)
			(primitives
				(gr_poly
					(pts
						(arc
							(start 0.3302 -0.381)
							(mid 0.270684 -0.524684)
							(end 0.127 -0.5842)
						)
						(arc
							(start -0.127 -0.5842)
							(mid -0.270684 -0.524684)
							(end -0.3302 -0.381)
						)
						(arc
							(start -0.3302 0.381)
							(mid -0.270684 0.524684)
							(end -0.127 0.5842)
						)
						(arc
							(start 0.127 0.5842)
							(mid 0.270684 0.524684)
							(end 0.3302 0.381)
						)
					)
					(width 0)
					(fill yes)
				)
			)
		)
		(pad "G" smd custom
			(at -0.94996 1.0922 90)
			(size 0.1651 0.1651)
			(layers "F.Cu" "F.Mask" "F.Paste")
			(net "P1V8_EN_LV")
			(options
				(clearance outline)
				(anchor circle)
			)
			(primitives
				(gr_poly
					(pts
						(arc
							(start 0.3302 -0.381)
							(mid 0.270684 -0.524684)
							(end 0.127 -0.5842)
						)
						(arc
							(start -0.127 -0.5842)
							(mid -0.270684 -0.524684)
							(end -0.3302 -0.381)
						)
						(arc
							(start -0.3302 0.381)
							(mid -0.270684 0.524684)
							(end -0.127 0.5842)
						)
						(arc
							(start 0.127 0.5842)
							(mid 0.270684 0.524684)
							(end 0.3302 0.381)
						)
					)
					(width 0)
					(fill yes)
				)
			)
		)
		(pad "S" smd custom
			(at 0.94996 1.0922 90)
			(size 0.1651 0.1651)
			(layers "F.Cu" "F.Mask" "F.Paste")
			(net "P1V8_E")
			(options
				(clearance outline)
				(anchor circle)
			)
			(primitives
				(gr_poly
					(pts
						(arc
							(start 0.3302 -0.381)
							(mid 0.270684 -0.524684)
							(end 0.127 -0.5842)
						)
						(arc
							(start -0.127 -0.5842)
							(mid -0.270684 -0.524684)
							(end -0.3302 -0.381)
						)
						(arc
							(start -0.3302 0.381)
							(mid -0.270684 0.524684)
							(end -0.127 0.5842)
						)
						(arc
							(start 0.127 0.5842)
							(mid 0.270684 0.524684)
							(end 0.3302 0.381)
						)
					)
					(width 0)
					(fill yes)
				)
			)
		)
	)
	(footprint ""
		(layer "F.Cu")
		(at 311.531 -194.945)
		(property "Reference" "TP172"
			(at 0 0 0)
			(layer "F.SilkS")
			(hide yes)
			(effects
				(font
					(size 1.27 1.27)
				)
			)
		)
		(property "Value" "TPAD28"
			(at -0.0127 -1.6637 0)
			(unlocked yes)
			(layer "F.Fab")
			(hide yes)
			(effects
				(font
					(size 1.016 1.016)
					(thickness 0.1524)
				)
			)
		)
		(property "Device Type" "TPAD28"
			(at -0.0127 -3.1877 0)
			(unlocked yes)
			(layer "F.Fab")
			(hide yes)
			(effects
				(font
					(size 1.016 1.016)
					(thickness 0.1524)
				)
			)
		)
		(duplicate_pad_numbers_are_jumpers no)
		(fp_poly
			(pts
				(arc
					(start 0.3556 0)
					(mid -0.3556 0)
					(end 0.3556 0)
				)
			)
			(stroke
				(width 0)
				(type default)
			)
			(fill no)
			(layer "F.CrtYd")
		)
		(fp_poly
			(pts
				(arc
					(start 0.6096 0)
					(mid -0.6096 0)
					(end 0.6096 0)
				)
			)
			(stroke
				(width 0)
				(type default)
			)
			(fill no)
			(layer "F.Fab")
		)
		(pad "1" smd circle
			(at 0 0)
			(size 0.7112 0.7112)
			(layers "F.Cu" "F.Mask" "F.Paste")
			(net "JTAG_BMC_TRST_N")
		)
	)
	(footprint ""
		(layer "F.Cu")
		(at 257.175 -132.08)
		(property "Reference" "U192"
			(at 0 0 0)
			(layer "F.SilkS")
			(hide yes)
			(effects
				(font
					(size 1.27 1.27)
				)
			)
		)
		(property "Value" "74HC2G125DP-GP"
			(at 0 -9.0932 0)
			(unlocked yes)
			(layer "F.Fab")
			(hide yes)
			(effects
				(font
					(size 1.016 1.016)
					(thickness 0.1524)
				)
			)
		)
		(property "Device Type" "SSOIC8H44"
			(at 0 -10.6172 0)
			(unlocked yes)
			(layer "F.Fab")
			(hide yes)
			(effects
				(font
					(size 1.016 1.016)
					(thickness 0.1524)
				)
			)
		)
		(duplicate_pad_numbers_are_jumpers no)
		(fp_line
			(start -1.7018 -0.5842)
			(end -1.7018 0.5842)
			(stroke
				(width 0.1524)
				(type default)
			)
			(layer "F.SilkS")
		)
		(fp_line
			(start -1.7018 -0.5842)
			(end 1.0668 -0.5842)
			(stroke
				(width 0.1524)
				(type default)
			)
			(layer "F.SilkS")
		)
		(fp_line
			(start -1.524 0.5842)
			(end -1.524 2.286)
			(stroke
				(width 0.508)
				(type default)
			)
			(layer "F.SilkS")
		)
		(fp_line
			(start -1.397 0)
			(end -1.7018 -0.3048)
			(stroke
				(width 0.1524)
				(type default)
			)
			(layer "F.SilkS")
		)
		(fp_line
			(start -1.397 0)
			(end -1.7018 0.3048)
			(stroke
				(width 0.1524)
				(type default)
			)
			(layer "F.SilkS")
		)
		(fp_line
			(start 1.0668 -0.5842)
			(end 1.0668 0.5842)
			(stroke
				(width 0.1524)
				(type default)
			)
			(layer "F.SilkS")
		)
		(fp_line
			(start 1.0668 0.5842)
			(end -1.7018 0.5842)
			(stroke
				(width 0.1524)
				(type default)
			)
			(layer "F.SilkS")
		)
		(fp_poly
			(pts
				(xy -1.1684 0.5842) (xy 1.0668 0.5842) (xy 1.0668 -0.5842) (xy -1.1684 -0.5842)
			)
			(stroke
				(width 0)
				(type default)
			)
			(fill yes)
			(layer "F.SilkS")
		)
		(fp_rect
			(start -1.778 2.54)
			(end 1.778 -2.54)
			(stroke
				(width 0)
				(type default)
			)
			(fill no)
			(layer "F.CrtYd")
		)
		(fp_poly
			(pts
				(xy -1.778 -2.54) (xy 1.778 -2.54) (xy 1.778 2.54) (xy -1.778 2.54)
			)
			(stroke
				(width 0)
				(type default)
			)
			(fill no)
			(layer "F.Fab")
		)
		(pad "1" smd rect
			(at -0.97536 1.6256)
			(size 0.3556 1.524)
			(layers "F.Cu" "F.Mask" "F.Paste")
			(net "DEBUG_OE_1_N")
		)
		(pad "2" smd rect
			(at -0.32512 1.6256)
			(size 0.3556 1.524)
			(layers "F.Cu" "F.Mask" "F.Paste")
			(net "CPU_U192_PIN2_TX")
		)
		(pad "3" smd rect
			(at 0.32512 1.6256)
			(size 0.3556 1.524)
			(layers "F.Cu" "F.Mask" "F.Paste")
			(net "CPU_U192_PIN3_RX")
		)
		(pad "4" smd rect
			(at 0.97536 1.6256)
			(size 0.3556 1.524)
			(layers "F.Cu" "F.Mask" "F.Paste")
			(net "GND")
		)
		(pad "5" smd rect
			(at 0.97536 -1.6256)
			(size 0.3556 1.524)
			(layers "F.Cu" "F.Mask" "F.Paste")
			(net "CPU_U192_PIN5_RX")
		)
		(pad "6" smd rect
			(at 0.32512 -1.6256)
			(size 0.3556 1.524)
			(layers "F.Cu" "F.Mask" "F.Paste")
			(net "CPU_U192_PIN6_TX")
		)
		(pad "7" smd rect
			(at -0.32512 -1.6256)
			(size 0.3556 1.524)
			(layers "F.Cu" "F.Mask" "F.Paste")
			(net "DEBUG_OE_1_N")
		)
		(pad "8" smd rect
			(at -0.97536 -1.6256)
			(size 0.3556 1.524)
			(layers "F.Cu" "F.Mask" "F.Paste")
			(net "P3V3_STBY")
		)
	)
	(footprint ""
		(layer "F.Cu")
		(at 35.383216 -203.12888 90)
		(property "Reference" "R566"
			(at 0 0 90)
			(layer "F.SilkS")
			(hide yes)
			(effects
				(font
					(size 1.27 1.27)
				)
			)
		)
		(property "Value" "0R2J-2-GP"
			(at 0.064008 -3.993896 90)
			(unlocked yes)
			(layer "F.Fab")
			(hide yes)
			(effects
				(font
					(size 1.016 1.016)
					(thickness 0.1524)
				)
			)
		)
		(property "Device Type" "R402H16"
			(at 0.064008 -5.517896 90)
			(unlocked yes)
			(layer "F.Fab")
			(hide yes)
			(effects
				(font
					(size 1.016 1.016)
					(thickness 0.1524)
				)
			)
		)
		(duplicate_pad_numbers_are_jumpers no)
		(fp_line
			(start 0.508 -0.9398)
			(end -0.508 -0.9398)
			(stroke
				(width 0.1524)
				(type default)
			)
			(layer "F.SilkS")
		)
		(fp_line
			(start -0.508 -0.9398)
			(end -0.508 0.9398)
			(stroke
				(width 0.1524)
				(type default)
			)
			(layer "F.SilkS")
		)
		(fp_rect
			(start -0.508 0.9398)
			(end 0.508 -0.9398)
			(stroke
				(width 0)
				(type default)
			)
			(fill no)
			(layer "F.CrtYd")
		)
		(fp_rect
			(start -0.508 0.9398)
			(end 0.508 -0.9398)
			(stroke
				(width 0)
				(type default)
			)
			(fill no)
			(layer "F.Fab")
		)
		(pad "1" smd custom
			(at 0 -0.4445 90)
			(size 0.1397 0.1397)
			(layers "F.Cu" "F.Mask" "F.Paste")
			(net "VOL_SEN_SDA_U17")
			(options
				(clearance outline)
				(anchor circle)
			)
			(primitives
				(gr_poly
					(pts
						(arc
							(start -0.1778 -0.2794)
							(mid -0.249642 -0.249642)
							(end -0.2794 -0.1778)
						)
						(arc
							(start -0.2794 0.1778)
							(mid -0.249642 0.249642)
							(end -0.1778 0.2794)
						)
						(arc
							(start 0.1778 0.2794)
							(mid 0.249642 0.249642)
							(end 0.2794 0.1778)
						)
						(arc
							(start 0.2794 -0.1778)
							(mid 0.249642 -0.249642)
							(end 0.1778 -0.2794)
						)
					)
					(width 0)
					(fill yes)
				)
			)
		)
		(pad "2" smd custom
			(at 0 0.4445 90)
			(size 0.1397 0.1397)
			(layers "F.Cu" "F.Mask" "F.Paste")
			(net "BMC_I2C_A_SDA")
			(options
				(clearance outline)
				(anchor circle)
			)
			(primitives
				(gr_poly
					(pts
						(arc
							(start -0.1778 -0.2794)
							(mid -0.249642 -0.249642)
							(end -0.2794 -0.1778)
						)
						(arc
							(start -0.2794 0.1778)
							(mid -0.249642 0.249642)
							(end -0.1778 0.2794)
						)
						(arc
							(start 0.1778 0.2794)
							(mid 0.249642 0.249642)
							(end 0.2794 0.1778)
						)
						(arc
							(start 0.2794 -0.1778)
							(mid 0.249642 -0.249642)
							(end 0.1778 -0.2794)
						)
					)
					(width 0)
					(fill yes)
				)
			)
		)
	)
	(footprint ""
		(layer "F.Cu")
		(at 328.549 -118.491 180)
		(property "Reference" "PC22"
			(at 0 0 180)
			(layer "F.SilkS")
			(hide yes)
			(effects
				(font
					(size 1.27 1.27)
				)
			)
		)
		(property "Value" "SC22U25V5MX-GP"
			(at -0.0762 -6.1214 180)
			(unlocked yes)
			(layer "F.Fab")
			(hide yes)
			(effects
				(font
					(size 1.016 1.016)
					(thickness 0.1524)
				)
			)
		)
		(property "Device Type" "C805H58"
			(at -0.0762 -8.1534 180)
			(unlocked yes)
			(layer "F.Fab")
			(hide yes)
			(effects
				(font
					(size 1.016 1.016)
					(thickness 0.1524)
				)
			)
		)
		(duplicate_pad_numbers_are_jumpers no)
		(fp_line
			(start 0.635 0)
			(end -0.635 0)
			(stroke
				(width 0.508)
				(type default)
			)
			(layer "F.SilkS")
		)
		(fp_rect
			(start -0.9652 1.778)
			(end 0.9652 -1.778)
			(stroke
				(width 0)
				(type default)
			)
			(fill no)
			(layer "F.CrtYd")
		)
		(fp_poly
			(pts
				(xy -0.9652 -1.778) (xy 0.9652 -1.778) (xy 0.9652 1.778) (xy -0.9652 1.778)
			)
			(stroke
				(width 0)
				(type default)
			)
			(fill no)
			(layer "F.Fab")
		)
		(pad "1" smd rect
			(at 0 -0.9652 180)
			(size 1.397 1.143)
			(layers "F.Cu" "F.Mask" "F.Paste")
			(net "P3V3_STBY_VIN")
		)
		(pad "2" smd rect
			(at 0 0.9652 180)
			(size 1.397 1.143)
			(layers "F.Cu" "F.Mask" "F.Paste")
			(net "GND")
		)
	)
	(footprint ""
		(layer "F.Cu")
		(at 12.650216 -215.82888 90)
		(property "Reference" "SC564"
			(at 0 0 90)
			(layer "F.SilkS")
			(hide yes)
			(effects
				(font
					(size 1.27 1.27)
				)
			)
		)
		(property "Value" "SCD1U16V2KX-3GP"
			(at 1.1811 -2.7051 90)
			(unlocked yes)
			(layer "F.Fab")
			(hide yes)
			(effects
				(font
					(size 1.016 1.016)
					(thickness 0.1524)
				)
			)
		)
		(property "Device Type" "C402H22"
			(at 1.1811 -4.2291 90)
			(unlocked yes)
			(layer "F.Fab")
			(hide yes)
			(effects
				(font
					(size 1.016 1.016)
					(thickness 0.1524)
				)
			)
		)
		(duplicate_pad_numbers_are_jumpers no)
		(fp_rect
			(start -0.4318 0.9525)
			(end 0.4318 -0.9525)
			(stroke
				(width 0)
				(type default)
			)
			(fill no)
			(layer "F.CrtYd")
		)
		(fp_rect
			(start -0.4318 0.9525)
			(end 0.4318 -0.9525)
			(stroke
				(width 0)
				(type default)
			)
			(fill no)
			(layer "F.Fab")
		)
		(pad "1" smd custom
			(at 0 -0.4445 90)
			(size 0.1524 0.1524)
			(layers "F.Cu" "F.Mask" "F.Paste")
			(net "P3V3_STBY")
			(options
				(clearance outline)
				(anchor circle)
			)
			(primitives
				(gr_poly
					(pts
						(arc
							(start 0.3048 -0.2032)
							(mid 0.275042 -0.275042)
							(end 0.2032 -0.3048)
						)
						(arc
							(start -0.2032 -0.3048)
							(mid -0.275042 -0.275042)
							(end -0.3048 -0.2032)
						)
						(arc
							(start -0.3048 0.2032)
							(mid -0.275042 0.275042)
							(end -0.2032 0.3048)
						)
						(arc
							(start 0.2032 0.3048)
							(mid 0.275042 0.275042)
							(end 0.3048 0.2032)
						)
					)
					(width 0)
					(fill yes)
				)
			)
		)
		(pad "2" smd custom
			(at 0 0.4445 90)
			(size 0.1524 0.1524)
			(layers "F.Cu" "F.Mask" "F.Paste")
			(net "GND")
			(options
				(clearance outline)
				(anchor circle)
			)
			(primitives
				(gr_poly
					(pts
						(arc
							(start 0.3048 -0.2032)
							(mid 0.275042 -0.275042)
							(end 0.2032 -0.3048)
						)
						(arc
							(start -0.2032 -0.3048)
							(mid -0.275042 -0.275042)
							(end -0.3048 -0.2032)
						)
						(arc
							(start -0.3048 0.2032)
							(mid -0.275042 0.275042)
							(end -0.2032 0.3048)
						)
						(arc
							(start 0.2032 0.3048)
							(mid 0.275042 0.275042)
							(end 0.3048 0.2032)
						)
					)
					(width 0)
					(fill yes)
				)
			)
		)
	)
	(footprint ""
		(layer "F.Cu")
		(at 14.682216 -222.94088 -90)
		(property "Reference" "SR297"
			(at 0 0 270)
			(layer "F.SilkS")
			(hide yes)
			(effects
				(font
					(size 1.27 1.27)
				)
			)
		)
		(property "Value" "0R2J-2-GP"
			(at 0.064008 -3.993896 270)
			(unlocked yes)
			(layer "F.Fab")
			(hide yes)
			(effects
				(font
					(size 1.016 1.016)
					(thickness 0.1524)
				)
			)
		)
		(property "Device Type" "R402H16"
			(at 0.064008 -5.517896 270)
			(unlocked yes)
			(layer "F.Fab")
			(hide yes)
			(effects
				(font
					(size 1.016 1.016)
					(thickness 0.1524)
				)
			)
		)
		(duplicate_pad_numbers_are_jumpers no)
		(fp_line
			(start -0.508 -0.9398)
			(end -0.508 0.9398)
			(stroke
				(width 0.1524)
				(type default)
			)
			(layer "F.SilkS")
		)
		(fp_line
			(start 0.508 -0.9398)
			(end -0.508 -0.9398)
			(stroke
				(width 0.1524)
				(type default)
			)
			(layer "F.SilkS")
		)
		(fp_rect
			(start -0.508 0.9398)
			(end 0.508 -0.9398)
			(stroke
				(width 0)
				(type default)
			)
			(fill no)
			(layer "F.CrtYd")
		)
		(fp_rect
			(start -0.508 0.9398)
			(end 0.508 -0.9398)
			(stroke
				(width 0)
				(type default)
			)
			(fill no)
			(layer "F.Fab")
		)
		(pad "1" smd custom
			(at 0 -0.4445 270)
			(size 0.1397 0.1397)
			(layers "F.Cu" "F.Mask" "F.Paste")
			(net "PWR_SCL")
			(options
				(clearance outline)
				(anchor circle)
			)
			(primitives
				(gr_poly
					(pts
						(arc
							(start -0.1778 -0.2794)
							(mid -0.249642 -0.249642)
							(end -0.2794 -0.1778)
						)
						(arc
							(start -0.2794 0.1778)
							(mid -0.249642 0.249642)
							(end -0.1778 0.2794)
						)
						(arc
							(start 0.1778 0.2794)
							(mid 0.249642 0.249642)
							(end 0.2794 0.1778)
						)
						(arc
							(start 0.2794 -0.1778)
							(mid 0.249642 -0.249642)
							(end 0.1778 -0.2794)
						)
					)
					(width 0)
					(fill yes)
				)
			)
		)
		(pad "2" smd custom
			(at 0 0.4445 270)
			(size 0.1397 0.1397)
			(layers "F.Cu" "F.Mask" "F.Paste")
			(net "EXP_SCL_0")
			(options
				(clearance outline)
				(anchor circle)
			)
			(primitives
				(gr_poly
					(pts
						(arc
							(start -0.1778 -0.2794)
							(mid -0.249642 -0.249642)
							(end -0.2794 -0.1778)
						)
						(arc
							(start -0.2794 0.1778)
							(mid -0.249642 0.249642)
							(end -0.1778 0.2794)
						)
						(arc
							(start 0.1778 0.2794)
							(mid 0.249642 0.249642)
							(end 0.2794 0.1778)
						)
						(arc
							(start 0.2794 -0.1778)
							(mid 0.249642 -0.249642)
							(end 0.1778 -0.2794)
						)
					)
					(width 0)
					(fill yes)
				)
			)
		)
	)
	(footprint ""
		(layer "F.Cu")
		(at 264.541 -28.194 -90)
		(property "Reference" "PC56"
			(at 0 0 270)
			(layer "F.SilkS")
			(hide yes)
			(effects
				(font
					(size 1.27 1.27)
				)
			)
		)
		(property "Value" "SC22U6D3V3MX-1-GP"
			(at 0 -2.8194 270)
			(unlocked yes)
			(layer "F.Fab")
			(hide yes)
			(effects
				(font
					(size 1.016 1.016)
					(thickness 0.1524)
				)
			)
		)
		(property "Device Type" "C603H40"
			(at 0 -4.3434 270)
			(unlocked yes)
			(layer "F.Fab")
			(hide yes)
			(effects
				(font
					(size 1.016 1.016)
					(thickness 0.1524)
				)
			)
		)
		(duplicate_pad_numbers_are_jumpers no)
		(fp_line
			(start 0.508 0)
			(end -0.508 0)
			(stroke
				(width 0.2032)
				(type default)
			)
			(layer "F.SilkS")
		)
		(fp_rect
			(start -0.5842 1.3335)
			(end 0.5842 -1.3335)
			(stroke
				(width 0)
				(type default)
			)
			(fill no)
			(layer "F.CrtYd")
		)
		(fp_rect
			(start -0.5842 1.3335)
			(end 0.5842 -1.3335)
			(stroke
				(width 0)
				(type default)
			)
			(fill no)
			(layer "F.Fab")
		)
		(pad "1" smd custom
			(at 0 -0.762 270)
			(size 0.2159 0.2159)
			(layers "F.Cu" "F.Mask" "F.Paste")
			(net "P1V8_STBY")
			(options
				(clearance outline)
				(anchor circle)
			)
			(primitives
				(gr_poly
					(pts
						(arc
							(start -0.3302 -0.4318)
							(mid -0.402042 -0.402042)
							(end -0.4318 -0.3302)
						)
						(arc
							(start -0.4318 0.3302)
							(mid -0.402042 0.402042)
							(end -0.3302 0.4318)
						)
						(arc
							(start 0.3302 0.4318)
							(mid 0.402042 0.402042)
							(end 0.4318 0.3302)
						)
						(arc
							(start 0.4318 -0.3302)
							(mid 0.402042 -0.402042)
							(end 0.3302 -0.4318)
						)
					)
					(width 0)
					(fill yes)
				)
			)
		)
		(pad "2" smd custom
			(at 0 0.762 270)
			(size 0.2159 0.2159)
			(layers "F.Cu" "F.Mask" "F.Paste")
			(net "GND")
			(options
				(clearance outline)
				(anchor circle)
			)
			(primitives
				(gr_poly
					(pts
						(arc
							(start -0.3302 -0.4318)
							(mid -0.402042 -0.402042)
							(end -0.4318 -0.3302)
						)
						(arc
							(start -0.4318 0.3302)
							(mid -0.402042 0.402042)
							(end -0.3302 0.4318)
						)
						(arc
							(start 0.3302 0.4318)
							(mid 0.402042 0.402042)
							(end 0.4318 0.3302)
						)
						(arc
							(start 0.4318 -0.3302)
							(mid 0.402042 -0.402042)
							(end 0.3302 -0.4318)
						)
					)
					(width 0)
					(fill yes)
				)
			)
		)
	)
	(footprint ""
		(layer "F.Cu")
		(at 341.786718 -139.804648 -90)
		(property "Reference" "X11"
			(at 0 0 270)
			(layer "F.SilkS")
			(hide yes)
			(effects
				(font
					(size 1.27 1.27)
				)
			)
		)
		(property "Value" "XTAL-24MHZ-87-GP"
			(at -0.0889 -3.0988 270)
			(unlocked yes)
			(layer "F.Fab")
			(hide yes)
			(effects
				(font
					(size 1.016 1.016)
					(thickness 0.1524)
				)
			)
		)
		(property "Device Type" "OSC-3225-4P-4H30"
			(at -0.0889 -4.6228 270)
			(unlocked yes)
			(layer "F.Fab")
			(hide yes)
			(effects
				(font
					(size 1.016 1.016)
					(thickness 0.1524)
				)
			)
		)
		(duplicate_pad_numbers_are_jumpers no)
		(fp_line
			(start -2.2098 1.651)
			(end -2.2098 0.6604)
			(stroke
				(width 0.3302)
				(type default)
			)
			(layer "F.SilkS")
		)
		(fp_line
			(start -1.143 1.651)
			(end -2.2098 1.651)
			(stroke
				(width 0.3302)
				(type default)
			)
			(layer "F.SilkS")
		)
		(fp_line
			(start -2.1209 1.5494)
			(end 2.1209 1.5494)
			(stroke
				(width 0.1524)
				(type default)
			)
			(layer "F.SilkS")
		)
		(fp_line
			(start 2.1209 1.5494)
			(end 2.1209 -1.5494)
			(stroke
				(width 0.1524)
				(type default)
			)
			(layer "F.SilkS")
		)
		(fp_line
			(start -2.1209 -1.5494)
			(end -2.1209 1.5494)
			(stroke
				(width 0.1524)
				(type default)
			)
			(layer "F.SilkS")
		)
		(fp_line
			(start 2.1209 -1.5494)
			(end -2.1209 -1.5494)
			(stroke
				(width 0.1524)
				(type default)
			)
			(layer "F.SilkS")
		)
		(fp_poly
			(pts
				(xy -2.6289 1.1938) (xy -2.6289 0.3302) (xy -2.1971 0.762)
			)
			(stroke
				(width 0)
				(type default)
			)
			(fill yes)
			(layer "F.SilkS")
		)
		(fp_rect
			(start -1.6002 1.2446)
			(end 1.6002 -1.2446)
			(stroke
				(width 0)
				(type default)
			)
			(fill no)
			(layer "F.CrtYd")
		)
		(fp_poly
			(pts
				(xy -2.3749 1.8034) (xy -2.3749 -1.8034) (xy 2.3749 -1.8034) (xy 2.3749 1.8034) (xy 0.00254 1.8034)
				(xy 0.00254 1.2446) (xy 1.6002 1.2446) (xy 1.6002 -1.2446) (xy -1.6002 -1.2446) (xy -1.6002 1.2446)
				(xy -0.00254 1.2446) (xy -0.00254 1.8034)
			)
			(stroke
				(width 0)
				(type default)
			)
			(fill no)
			(layer "F.CrtYd")
		)
		(fp_rect
			(start -2.3749 1.8034)
			(end 2.3749 -1.8034)
			(stroke
				(width 0)
				(type default)
			)
			(fill no)
			(layer "F.Fab")
		)
		(pad "1" smd rect
			(at -1.171448 0.756412 270)
			(size 1.397 1.0668)
			(layers "F.Cu" "F.Mask" "F.Paste")
			(net "USB_HUB_XTAL_OUT")
		)
		(pad "2" smd rect
			(at 1.171448 0.756412 270)
			(size 1.397 1.0668)
			(layers "F.Cu" "F.Mask" "F.Paste")
			(net "GND")
		)
		(pad "3" smd rect
			(at 1.171448 -0.756412 270)
			(size 1.397 1.0668)
			(layers "F.Cu" "F.Mask" "F.Paste")
			(net "USB_HUB_XTAL_IN")
		)
		(pad "4" smd rect
			(at -1.171448 -0.756412 270)
			(size 1.397 1.0668)
			(layers "F.Cu" "F.Mask" "F.Paste")
			(net "GND")
		)
		(zone
			(layer "F.Cu")
			(hatch none 0.5)
			(connect_pads
				(clearance 0)
			)
			(min_thickness 0.25)
			(keepout
				(tracks not_allowed)
				(vias allowed)
				(pads allowed)
				(copperpour not_allowed)
				(footprints allowed)
			)
			(placement
				(enabled no)
				(sheetname "")
			)
			(fill
				(thermal_gap 0.5)
				(thermal_bridge_width 0.5)
				(island_removal_mode 0)
			)
			(polygon
				(pts
					(xy 341.735918 -139.855448) (xy 341.735918 -139.753848) (xy 341.837518 -139.753848) (xy 341.837518 -139.855448)
				)
			)
		)
		(zone
			(layer "F.Cu")
			(hatch none 0.5)
			(connect_pads
				(clearance 0)
			)
			(min_thickness 0.25)
			(keepout
				(tracks allowed)
				(vias not_allowed)
				(pads allowed)
				(copperpour not_allowed)
				(footprints allowed)
			)
			(placement
				(enabled no)
				(sheetname "")
			)
			(fill
				(thermal_gap 0.5)
				(thermal_bridge_width 0.5)
				(island_removal_mode 0)
			)
			(polygon
				(pts
					(xy 343.07653 -140.277596) (xy 343.07653 -139.3317) (xy 342.00973 -139.3317) (xy 342.00973 -137.9347)
					(xy 341.563706 -137.9347) (xy 341.563706 -139.3317) (xy 340.496906 -139.3317) (xy 340.496906 -140.277596)
					(xy 341.563706 -140.277596) (xy 341.563706 -141.674596) (xy 342.00973 -141.674596) (xy 342.00973 -140.277596)
				)
			)
		)
	)
	(footprint ""
		(layer "F.Cu")
		(at 306.07 -160.655)
		(property "Reference" "R806"
			(at 0 0 0)
			(layer "F.SilkS")
			(hide yes)
			(effects
				(font
					(size 1.27 1.27)
				)
			)
		)
		(property "Value" "0R2J-2-GP"
			(at 0.064008 -3.993896 0)
			(unlocked yes)
			(layer "F.Fab")
			(hide yes)
			(effects
				(font
					(size 1.016 1.016)
					(thickness 0.1524)
				)
			)
		)
		(property "Device Type" "R402H16"
			(at 0.064008 -5.517896 0)
			(unlocked yes)
			(layer "F.Fab")
			(hide yes)
			(effects
				(font
					(size 1.016 1.016)
					(thickness 0.1524)
				)
			)
		)
		(duplicate_pad_numbers_are_jumpers no)
		(fp_line
			(start -0.508 -0.9398)
			(end -0.508 0.9398)
			(stroke
				(width 0.1524)
				(type default)
			)
			(layer "F.SilkS")
		)
		(fp_line
			(start 0.508 -0.9398)
			(end -0.508 -0.9398)
			(stroke
				(width 0.1524)
				(type default)
			)
			(layer "F.SilkS")
		)
		(fp_rect
			(start -0.508 0.9398)
			(end 0.508 -0.9398)
			(stroke
				(width 0)
				(type default)
			)
			(fill no)
			(layer "F.CrtYd")
		)
		(fp_rect
			(start -0.508 0.9398)
			(end 0.508 -0.9398)
			(stroke
				(width 0)
				(type default)
			)
			(fill no)
			(layer "F.Fab")
		)
		(pad "1" smd custom
			(at 0 -0.4445)
			(size 0.1397 0.1397)
			(layers "F.Cu" "F.Mask" "F.Paste")
			(net "DP_BMC_CPU_RST_N_R")
			(options
				(clearance outline)
				(anchor circle)
			)
			(primitives
				(gr_poly
					(pts
						(arc
							(start -0.1778 -0.2794)
							(mid -0.249642 -0.249642)
							(end -0.2794 -0.1778)
						)
						(arc
							(start -0.2794 0.1778)
							(mid -0.249642 0.249642)
							(end -0.1778 0.2794)
						)
						(arc
							(start 0.1778 0.2794)
							(mid 0.249642 0.249642)
							(end 0.2794 0.1778)
						)
						(arc
							(start 0.2794 -0.1778)
							(mid 0.249642 -0.249642)
							(end 0.1778 -0.2794)
						)
					)
					(width 0)
					(fill yes)
				)
			)
		)
		(pad "2" smd custom
			(at 0 0.4445)
			(size 0.1397 0.1397)
			(layers "F.Cu" "F.Mask" "F.Paste")
			(net "DP_BMC_CPU_RST_N")
			(options
				(clearance outline)
				(anchor circle)
			)
			(primitives
				(gr_poly
					(pts
						(arc
							(start -0.1778 -0.2794)
							(mid -0.249642 -0.249642)
							(end -0.2794 -0.1778)
						)
						(arc
							(start -0.2794 0.1778)
							(mid -0.249642 0.249642)
							(end -0.1778 0.2794)
						)
						(arc
							(start 0.1778 0.2794)
							(mid 0.249642 0.249642)
							(end 0.2794 0.1778)
						)
						(arc
							(start 0.2794 -0.1778)
							(mid 0.249642 -0.249642)
							(end 0.1778 -0.2794)
						)
					)
					(width 0)
					(fill yes)
				)
			)
		)
	)
	(footprint ""
		(layer "F.Cu")
		(at 175.390048 -32.499808)
		(property "Reference" "R402"
			(at 0 0 0)
			(layer "F.SilkS")
			(hide yes)
			(effects
				(font
					(size 1.27 1.27)
				)
			)
		)
		(property "Value" "49D9R2F-GP"
			(at 0.064008 -3.993896 0)
			(unlocked yes)
			(layer "F.Fab")
			(hide yes)
			(effects
				(font
					(size 1.016 1.016)
					(thickness 0.1524)
				)
			)
		)
		(property "Device Type" "R402H16"
			(at 0.064008 -5.517896 0)
			(unlocked yes)
			(layer "F.Fab")
			(hide yes)
			(effects
				(font
					(size 1.016 1.016)
					(thickness 0.1524)
				)
			)
		)
		(duplicate_pad_numbers_are_jumpers no)
		(fp_line
			(start -0.508 -0.9398)
			(end -0.508 0.9398)
			(stroke
				(width 0.1524)
				(type default)
			)
			(layer "F.SilkS")
		)
		(fp_line
			(start 0.508 -0.9398)
			(end -0.508 -0.9398)
			(stroke
				(width 0.1524)
				(type default)
			)
			(layer "F.SilkS")
		)
		(fp_rect
			(start -0.508 0.9398)
			(end 0.508 -0.9398)
			(stroke
				(width 0)
				(type default)
			)
			(fill no)
			(layer "F.CrtYd")
		)
		(fp_rect
			(start -0.508 0.9398)
			(end 0.508 -0.9398)
			(stroke
				(width 0)
				(type default)
			)
			(fill no)
			(layer "F.Fab")
		)
		(pad "1" smd custom
			(at 0 -0.4445)
			(size 0.1397 0.1397)
			(layers "F.Cu" "F.Mask" "F.Paste")
			(net "MOD_IMC_FAB_D_COP")
			(options
				(clearance outline)
				(anchor circle)
			)
			(primitives
				(gr_poly
					(pts
						(arc
							(start -0.1778 -0.2794)
							(mid -0.249642 -0.249642)
							(end -0.2794 -0.1778)
						)
						(arc
							(start -0.2794 0.1778)
							(mid -0.249642 0.249642)
							(end -0.1778 0.2794)
						)
						(arc
							(start 0.1778 0.2794)
							(mid 0.249642 0.249642)
							(end 0.2794 0.1778)
						)
						(arc
							(start 0.2794 -0.1778)
							(mid 0.249642 -0.249642)
							(end 0.1778 -0.2794)
						)
					)
					(width 0)
					(fill yes)
				)
			)
		)
		(pad "2" smd custom
			(at 0 0.4445)
			(size 0.1397 0.1397)
			(layers "F.Cu" "F.Mask" "F.Paste")
			(net "BCM5221_RX_C_DN")
			(options
				(clearance outline)
				(anchor circle)
			)
			(primitives
				(gr_poly
					(pts
						(arc
							(start -0.1778 -0.2794)
							(mid -0.249642 -0.249642)
							(end -0.2794 -0.1778)
						)
						(arc
							(start -0.2794 0.1778)
							(mid -0.249642 0.249642)
							(end -0.1778 0.2794)
						)
						(arc
							(start 0.1778 0.2794)
							(mid 0.249642 0.249642)
							(end 0.2794 0.1778)
						)
						(arc
							(start 0.2794 -0.1778)
							(mid 0.249642 -0.249642)
							(end 0.1778 -0.2794)
						)
					)
					(width 0)
					(fill yes)
				)
			)
		)
	)
	(footprint ""
		(layer "F.Cu")
		(at 317.5 -108.585 -90)
		(property "Reference" "PR33"
			(at 0 0 270)
			(layer "F.SilkS")
			(hide yes)
			(effects
				(font
					(size 1.27 1.27)
				)
			)
		)
		(property "Value" "44K2R2F-1-GP"
			(at 0.064008 -3.993896 270)
			(unlocked yes)
			(layer "F.Fab")
			(hide yes)
			(effects
				(font
					(size 1.016 1.016)
					(thickness 0.1524)
				)
			)
		)
		(property "Device Type" "R402H16"
			(at 0.064008 -5.517896 270)
			(unlocked yes)
			(layer "F.Fab")
			(hide yes)
			(effects
				(font
					(size 1.016 1.016)
					(thickness 0.1524)
				)
			)
		)
		(duplicate_pad_numbers_are_jumpers no)
		(fp_line
			(start -0.508 -0.9398)
			(end -0.508 0.9398)
			(stroke
				(width 0.1524)
				(type default)
			)
			(layer "F.SilkS")
		)
		(fp_line
			(start 0.508 -0.9398)
			(end -0.508 -0.9398)
			(stroke
				(width 0.1524)
				(type default)
			)
			(layer "F.SilkS")
		)
		(fp_rect
			(start -0.508 0.9398)
			(end 0.508 -0.9398)
			(stroke
				(width 0)
				(type default)
			)
			(fill no)
			(layer "F.CrtYd")
		)
		(fp_rect
			(start -0.508 0.9398)
			(end 0.508 -0.9398)
			(stroke
				(width 0)
				(type default)
			)
			(fill no)
			(layer "F.Fab")
		)
		(pad "1" smd custom
			(at 0 -0.4445 270)
			(size 0.1397 0.1397)
			(layers "F.Cu" "F.Mask" "F.Paste")
			(net "P3V3_STBY_VFB")
			(options
				(clearance outline)
				(anchor circle)
			)
			(primitives
				(gr_poly
					(pts
						(arc
							(start -0.1778 -0.2794)
							(mid -0.249642 -0.249642)
							(end -0.2794 -0.1778)
						)
						(arc
							(start -0.2794 0.1778)
							(mid -0.249642 0.249642)
							(end -0.1778 0.2794)
						)
						(arc
							(start 0.1778 0.2794)
							(mid 0.249642 0.249642)
							(end 0.2794 0.1778)
						)
						(arc
							(start 0.2794 -0.1778)
							(mid 0.249642 -0.249642)
							(end 0.1778 -0.2794)
						)
					)
					(width 0)
					(fill yes)
				)
			)
		)
		(pad "2" smd custom
			(at 0 0.4445 270)
			(size 0.1397 0.1397)
			(layers "F.Cu" "F.Mask" "F.Paste")
			(net "P3V3_STBY_VFB_R")
			(options
				(clearance outline)
				(anchor circle)
			)
			(primitives
				(gr_poly
					(pts
						(arc
							(start -0.1778 -0.2794)
							(mid -0.249642 -0.249642)
							(end -0.2794 -0.1778)
						)
						(arc
							(start -0.2794 0.1778)
							(mid -0.249642 0.249642)
							(end -0.1778 0.2794)
						)
						(arc
							(start 0.1778 0.2794)
							(mid 0.249642 0.249642)
							(end 0.2794 0.1778)
						)
						(arc
							(start 0.2794 -0.1778)
							(mid 0.249642 -0.249642)
							(end 0.1778 -0.2794)
						)
					)
					(width 0)
					(fill yes)
				)
			)
		)
	)
	(footprint ""
		(layer "F.Cu")
		(at 324.104 -168.148)
		(property "Reference" "R275"
			(at 0 0 0)
			(layer "F.SilkS")
			(hide yes)
			(effects
				(font
					(size 1.27 1.27)
				)
			)
		)
		(property "Value" "0R2J-2-GP"
			(at 0.064008 -3.993896 0)
			(unlocked yes)
			(layer "F.Fab")
			(hide yes)
			(effects
				(font
					(size 1.016 1.016)
					(thickness 0.1524)
				)
			)
		)
		(property "Device Type" "R402H16"
			(at 0.064008 -5.517896 0)
			(unlocked yes)
			(layer "F.Fab")
			(hide yes)
			(effects
				(font
					(size 1.016 1.016)
					(thickness 0.1524)
				)
			)
		)
		(duplicate_pad_numbers_are_jumpers no)
		(fp_line
			(start -0.508 -0.9398)
			(end -0.508 0.9398)
			(stroke
				(width 0.1524)
				(type default)
			)
			(layer "F.SilkS")
		)
		(fp_line
			(start 0.508 -0.9398)
			(end -0.508 -0.9398)
			(stroke
				(width 0.1524)
				(type default)
			)
			(layer "F.SilkS")
		)
		(fp_rect
			(start -0.508 0.9398)
			(end 0.508 -0.9398)
			(stroke
				(width 0)
				(type default)
			)
			(fill no)
			(layer "F.CrtYd")
		)
		(fp_rect
			(start -0.508 0.9398)
			(end 0.508 -0.9398)
			(stroke
				(width 0)
				(type default)
			)
			(fill no)
			(layer "F.Fab")
		)
		(pad "1" smd custom
			(at 0 -0.4445)
			(size 0.1397 0.1397)
			(layers "F.Cu" "F.Mask" "F.Paste")
			(net "BMC_UART_SWITCH_1R")
			(options
				(clearance outline)
				(anchor circle)
			)
			(primitives
				(gr_poly
					(pts
						(arc
							(start -0.1778 -0.2794)
							(mid -0.249642 -0.249642)
							(end -0.2794 -0.1778)
						)
						(arc
							(start -0.2794 0.1778)
							(mid -0.249642 0.249642)
							(end -0.1778 0.2794)
						)
						(arc
							(start 0.1778 0.2794)
							(mid 0.249642 0.249642)
							(end 0.2794 0.1778)
						)
						(arc
							(start 0.2794 -0.1778)
							(mid 0.249642 -0.249642)
							(end 0.1778 -0.2794)
						)
					)
					(width 0)
					(fill yes)
				)
			)
		)
		(pad "2" smd custom
			(at 0 0.4445)
			(size 0.1397 0.1397)
			(layers "F.Cu" "F.Mask" "F.Paste")
			(net "BMC_UART_SWITCH_1")
			(options
				(clearance outline)
				(anchor circle)
			)
			(primitives
				(gr_poly
					(pts
						(arc
							(start -0.1778 -0.2794)
							(mid -0.249642 -0.249642)
							(end -0.2794 -0.1778)
						)
						(arc
							(start -0.2794 0.1778)
							(mid -0.249642 0.249642)
							(end -0.1778 0.2794)
						)
						(arc
							(start 0.1778 0.2794)
							(mid 0.249642 0.249642)
							(end 0.2794 0.1778)
						)
						(arc
							(start 0.2794 -0.1778)
							(mid 0.249642 -0.249642)
							(end 0.1778 -0.2794)
						)
					)
					(width 0)
					(fill yes)
				)
			)
		)
	)
	(footprint ""
		(layer "F.Cu")
		(at 38.9128 -168.5036)
		(property "Reference" "C371"
			(at 0 0 0)
			(layer "F.SilkS")
			(hide yes)
			(effects
				(font
					(size 1.27 1.27)
				)
			)
		)
		(property "Value" "SC1U6D3V3KX-2GP"
			(at 0 -2.8194 0)
			(unlocked yes)
			(layer "F.Fab")
			(hide yes)
			(effects
				(font
					(size 1.016 1.016)
					(thickness 0.1524)
				)
			)
		)
		(property "Device Type" "C603H36"
			(at 0 -4.3434 0)
			(unlocked yes)
			(layer "F.Fab")
			(hide yes)
			(effects
				(font
					(size 1.016 1.016)
					(thickness 0.1524)
				)
			)
		)
		(duplicate_pad_numbers_are_jumpers no)
		(fp_line
			(start 0.508 0)
			(end -0.508 0)
			(stroke
				(width 0.2032)
				(type default)
			)
			(layer "F.SilkS")
		)
		(fp_rect
			(start -0.5842 1.3335)
			(end 0.5842 -1.3335)
			(stroke
				(width 0)
				(type default)
			)
			(fill no)
			(layer "F.CrtYd")
		)
		(fp_rect
			(start -0.5842 1.3335)
			(end 0.5842 -1.3335)
			(stroke
				(width 0)
				(type default)
			)
			(fill no)
			(layer "F.Fab")
		)
		(pad "1" smd custom
			(at 0 -0.762)
			(size 0.2159 0.2159)
			(layers "F.Cu" "F.Mask" "F.Paste")
			(net "P3V3_STBY")
			(options
				(clearance outline)
				(anchor circle)
			)
			(primitives
				(gr_poly
					(pts
						(arc
							(start -0.3302 -0.4318)
							(mid -0.402042 -0.402042)
							(end -0.4318 -0.3302)
						)
						(arc
							(start -0.4318 0.3302)
							(mid -0.402042 0.402042)
							(end -0.3302 0.4318)
						)
						(arc
							(start 0.3302 0.4318)
							(mid 0.402042 0.402042)
							(end 0.4318 0.3302)
						)
						(arc
							(start 0.4318 -0.3302)
							(mid 0.402042 -0.402042)
							(end 0.3302 -0.4318)
						)
					)
					(width 0)
					(fill yes)
				)
			)
		)
		(pad "2" smd custom
			(at 0 0.762)
			(size 0.2159 0.2159)
			(layers "F.Cu" "F.Mask" "F.Paste")
			(net "GND")
			(options
				(clearance outline)
				(anchor circle)
			)
			(primitives
				(gr_poly
					(pts
						(arc
							(start -0.3302 -0.4318)
							(mid -0.402042 -0.402042)
							(end -0.4318 -0.3302)
						)
						(arc
							(start -0.4318 0.3302)
							(mid -0.402042 0.402042)
							(end -0.3302 0.4318)
						)
						(arc
							(start 0.3302 0.4318)
							(mid 0.402042 0.402042)
							(end 0.4318 0.3302)
						)
						(arc
							(start 0.4318 -0.3302)
							(mid 0.402042 -0.402042)
							(end 0.3302 -0.4318)
						)
					)
					(width 0)
					(fill yes)
				)
			)
		)
	)
	(footprint ""
		(layer "F.Cu")
		(at 96.247966 -69.342 180)
		(property "Reference" "SC970"
			(at 0 0 180)
			(layer "F.SilkS")
			(hide yes)
			(effects
				(font
					(size 1.27 1.27)
				)
			)
		)
		(property "Value" "SC1U10V2KX-4-GP"
			(at 1.1811 -2.7051 180)
			(unlocked yes)
			(layer "F.Fab")
			(hide yes)
			(effects
				(font
					(size 1.016 1.016)
					(thickness 0.1524)
				)
			)
		)
		(property "Device Type" "C402H22"
			(at 1.1811 -4.2291 180)
			(unlocked yes)
			(layer "F.Fab")
			(hide yes)
			(effects
				(font
					(size 1.016 1.016)
					(thickness 0.1524)
				)
			)
		)
		(duplicate_pad_numbers_are_jumpers no)
		(fp_rect
			(start -0.4318 0.9525)
			(end 0.4318 -0.9525)
			(stroke
				(width 0)
				(type default)
			)
			(fill no)
			(layer "F.CrtYd")
		)
		(fp_rect
			(start -0.4318 0.9525)
			(end 0.4318 -0.9525)
			(stroke
				(width 0)
				(type default)
			)
			(fill no)
			(layer "F.Fab")
		)
		(pad "1" smd custom
			(at 0 -0.4445 180)
			(size 0.1524 0.1524)
			(layers "F.Cu" "F.Mask" "F.Paste")
			(net "P1V8_C")
			(options
				(clearance outline)
				(anchor circle)
			)
			(primitives
				(gr_poly
					(pts
						(arc
							(start 0.3048 -0.2032)
							(mid 0.275042 -0.275042)
							(end 0.2032 -0.3048)
						)
						(arc
							(start -0.2032 -0.3048)
							(mid -0.275042 -0.275042)
							(end -0.3048 -0.2032)
						)
						(arc
							(start -0.3048 0.2032)
							(mid -0.275042 0.275042)
							(end -0.2032 0.3048)
						)
						(arc
							(start 0.2032 0.3048)
							(mid 0.275042 0.275042)
							(end 0.3048 0.2032)
						)
					)
					(width 0)
					(fill yes)
				)
			)
		)
		(pad "2" smd custom
			(at 0 0.4445 180)
			(size 0.1524 0.1524)
			(layers "F.Cu" "F.Mask" "F.Paste")
			(net "GND")
			(options
				(clearance outline)
				(anchor circle)
			)
			(primitives
				(gr_poly
					(pts
						(arc
							(start 0.3048 -0.2032)
							(mid 0.275042 -0.275042)
							(end 0.2032 -0.3048)
						)
						(arc
							(start -0.2032 -0.3048)
							(mid -0.275042 -0.275042)
							(end -0.3048 -0.2032)
						)
						(arc
							(start -0.3048 0.2032)
							(mid -0.275042 0.275042)
							(end -0.2032 0.3048)
						)
						(arc
							(start 0.2032 0.3048)
							(mid 0.275042 0.275042)
							(end 0.3048 0.2032)
						)
					)
					(width 0)
					(fill yes)
				)
			)
		)
	)
	(footprint ""
		(layer "F.Cu")
		(at 98.18497 -76.454)
		(property "Reference" "SR862"
			(at 0 0 0)
			(layer "F.SilkS")
			(hide yes)
			(effects
				(font
					(size 1.27 1.27)
				)
			)
		)
		(property "Value" "0R2J-2-GP"
			(at 0.064008 -3.993896 0)
			(unlocked yes)
			(layer "F.Fab")
			(hide yes)
			(effects
				(font
					(size 1.016 1.016)
					(thickness 0.1524)
				)
			)
		)
		(property "Device Type" "R402H16"
			(at 0.064008 -5.517896 0)
			(unlocked yes)
			(layer "F.Fab")
			(hide yes)
			(effects
				(font
					(size 1.016 1.016)
					(thickness 0.1524)
				)
			)
		)
		(duplicate_pad_numbers_are_jumpers no)
		(fp_line
			(start -0.508 -0.9398)
			(end -0.508 0.9398)
			(stroke
				(width 0.1524)
				(type default)
			)
			(layer "F.SilkS")
		)
		(fp_line
			(start 0.508 -0.9398)
			(end -0.508 -0.9398)
			(stroke
				(width 0.1524)
				(type default)
			)
			(layer "F.SilkS")
		)
		(fp_rect
			(start -0.508 0.9398)
			(end 0.508 -0.9398)
			(stroke
				(width 0)
				(type default)
			)
			(fill no)
			(layer "F.CrtYd")
		)
		(fp_rect
			(start -0.508 0.9398)
			(end 0.508 -0.9398)
			(stroke
				(width 0)
				(type default)
			)
			(fill no)
			(layer "F.Fab")
		)
		(pad "1" smd custom
			(at 0 -0.4445)
			(size 0.1397 0.1397)
			(layers "F.Cu" "F.Mask" "F.Paste")
			(net "JTAG_EXP_TCK")
			(options
				(clearance outline)
				(anchor circle)
			)
			(primitives
				(gr_poly
					(pts
						(arc
							(start -0.1778 -0.2794)
							(mid -0.249642 -0.249642)
							(end -0.2794 -0.1778)
						)
						(arc
							(start -0.2794 0.1778)
							(mid -0.249642 0.249642)
							(end -0.1778 0.2794)
						)
						(arc
							(start 0.1778 0.2794)
							(mid 0.249642 0.249642)
							(end 0.2794 0.1778)
						)
						(arc
							(start 0.2794 -0.1778)
							(mid 0.249642 -0.249642)
							(end 0.1778 -0.2794)
						)
					)
					(width 0)
					(fill yes)
				)
			)
		)
		(pad "2" smd custom
			(at 0 0.4445)
			(size 0.1397 0.1397)
			(layers "F.Cu" "F.Mask" "F.Paste")
			(net "JTAG_EXP_IOC_TCK")
			(options
				(clearance outline)
				(anchor circle)
			)
			(primitives
				(gr_poly
					(pts
						(arc
							(start -0.1778 -0.2794)
							(mid -0.249642 -0.249642)
							(end -0.2794 -0.1778)
						)
						(arc
							(start -0.2794 0.1778)
							(mid -0.249642 0.249642)
							(end -0.1778 0.2794)
						)
						(arc
							(start 0.1778 0.2794)
							(mid 0.249642 0.249642)
							(end 0.2794 0.1778)
						)
						(arc
							(start 0.2794 -0.1778)
							(mid 0.249642 -0.249642)
							(end 0.1778 -0.2794)
						)
					)
					(width 0)
					(fill yes)
				)
			)
		)
	)
	(footprint ""
		(layer "F.Cu")
		(at 332.096872 -224.227136 180)
		(property "Reference" "U14"
			(at 0 0 180)
			(layer "F.SilkS")
			(hide yes)
			(effects
				(font
					(size 1.27 1.27)
				)
			)
		)
		(property "Value" "ADS1015IDGSR-GP"
			(at 0 -11.1252 180)
			(unlocked yes)
			(layer "F.Fab")
			(hide yes)
			(effects
				(font
					(size 1.016 1.016)
					(thickness 0.1524)
				)
			)
		)
		(property "Device Type" "MSOP10H44"
			(at 0 -12.6492 180)
			(unlocked yes)
			(layer "F.Fab")
			(hide yes)
			(effects
				(font
					(size 1.016 1.016)
					(thickness 0.1524)
				)
			)
		)
		(duplicate_pad_numbers_are_jumpers no)
		(fp_line
			(start 1.143 1.016)
			(end -2.0066 1.016)
			(stroke
				(width 0.1524)
				(type default)
			)
			(layer "F.SilkS")
		)
		(fp_line
			(start 1.143 -1.016)
			(end 1.143 1.016)
			(stroke
				(width 0.1524)
				(type default)
			)
			(layer "F.SilkS")
		)
		(fp_line
			(start -1.5748 0)
			(end -1.9558 0.381)
			(stroke
				(width 0.1524)
				(type default)
			)
			(layer "F.SilkS")
		)
		(fp_line
			(start -1.5748 0)
			(end -1.9558 -0.381)
			(stroke
				(width 0.1524)
				(type default)
			)
			(layer "F.SilkS")
		)
		(fp_line
			(start -1.8288 1.016)
			(end -1.8288 3.048)
			(stroke
				(width 0.508)
				(type default)
			)
			(layer "F.SilkS")
		)
		(fp_line
			(start -2.0066 1.016)
			(end -2.0066 -1.016)
			(stroke
				(width 0.1524)
				(type default)
			)
			(layer "F.SilkS")
		)
		(fp_line
			(start -2.0066 -1.016)
			(end 1.143 -1.016)
			(stroke
				(width 0.1524)
				(type default)
			)
			(layer "F.SilkS")
		)
		(fp_poly
			(pts
				(xy -2.0828 3.3401) (xy 2.0828 3.3401) (xy 2.0828 -3.3401) (xy -2.0828 -3.3401)
			)
			(stroke
				(width 0)
				(type default)
			)
			(fill no)
			(layer "F.CrtYd")
		)
		(fp_poly
			(pts
				(xy -2.0828 3.3401) (xy 2.0828 3.3401) (xy 2.0828 -3.3401) (xy -2.0828 -3.3401)
			)
			(stroke
				(width 0)
				(type default)
			)
			(fill no)
			(layer "F.Fab")
		)
		(pad "1" smd rect
			(at -0.99949 2.0701 180)
			(size 0.3048 1.524)
			(layers "F.Cu" "F.Mask" "F.Paste")
			(net "VOL_SEN_ADDR")
		)
		(pad "2" smd rect
			(at -0.50038 2.0701 180)
			(size 0.3048 1.524)
			(layers "F.Cu" "F.Mask" "F.Paste")
			(net "VOL_SEN_ALERT")
		)
		(pad "3" smd rect
			(at 0 2.0701 180)
			(size 0.3048 1.524)
			(layers "F.Cu" "F.Mask" "F.Paste")
			(net "GND")
		)
		(pad "4" smd rect
			(at 0.50038 2.0701 180)
			(size 0.3048 1.524)
			(layers "F.Cu" "F.Mask" "F.Paste")
			(net "12V_SENSE")
		)
		(pad "5" smd rect
			(at 0.99949 2.0701 180)
			(size 0.3048 1.524)
			(layers "F.Cu" "F.Mask" "F.Paste")
			(net "5V_STBY_SENSE")
		)
		(pad "6" smd rect
			(at 0.99949 -2.0701 180)
			(size 0.3048 1.524)
			(layers "F.Cu" "F.Mask" "F.Paste")
			(net "3V3_STBY_SENSE")
		)
		(pad "7" smd rect
			(at 0.50038 -2.0701 180)
			(size 0.3048 1.524)
			(layers "F.Cu" "F.Mask" "F.Paste")
			(net "1V8_STBY_SENSE")
		)
		(pad "8" smd rect
			(at 0 -2.0701 180)
			(size 0.3048 1.524)
			(layers "F.Cu" "F.Mask" "F.Paste")
			(net "P3V3_STBY")
		)
		(pad "9" smd rect
			(at -0.50038 -2.0701 180)
			(size 0.3048 1.524)
			(layers "F.Cu" "F.Mask" "F.Paste")
			(net "VOL_SEN_SDA")
		)
		(pad "10" smd rect
			(at -0.99949 -2.0701 180)
			(size 0.3048 1.524)
			(layers "F.Cu" "F.Mask" "F.Paste")
			(net "VOL_SEN_SCL")
		)
	)
	(footprint ""
		(layer "F.Cu")
		(at 267.772896 -74.106024 90)
		(property "Reference" "C259"
			(at 0 0 90)
			(layer "F.SilkS")
			(hide yes)
			(effects
				(font
					(size 1.27 1.27)
				)
			)
		)
		(property "Value" "SCD1U25V2KX-2-GP"
			(at 1.1811 -2.7051 90)
			(unlocked yes)
			(layer "F.Fab")
			(hide yes)
			(effects
				(font
					(size 1.016 1.016)
					(thickness 0.1524)
				)
			)
		)
		(property "Device Type" "C402H22"
			(at 1.1811 -4.2291 90)
			(unlocked yes)
			(layer "F.Fab")
			(hide yes)
			(effects
				(font
					(size 1.016 1.016)
					(thickness 0.1524)
				)
			)
		)
		(duplicate_pad_numbers_are_jumpers no)
		(fp_rect
			(start -0.4318 0.9525)
			(end 0.4318 -0.9525)
			(stroke
				(width 0)
				(type default)
			)
			(fill no)
			(layer "F.CrtYd")
		)
		(fp_rect
			(start -0.4318 0.9525)
			(end 0.4318 -0.9525)
			(stroke
				(width 0)
				(type default)
			)
			(fill no)
			(layer "F.Fab")
		)
		(pad "1" smd custom
			(at 0 -0.4445 90)
			(size 0.1524 0.1524)
			(layers "F.Cu" "F.Mask" "F.Paste")
			(net "P12V_MSB")
			(options
				(clearance outline)
				(anchor circle)
			)
			(primitives
				(gr_poly
					(pts
						(arc
							(start 0.3048 -0.2032)
							(mid 0.275042 -0.275042)
							(end 0.2032 -0.3048)
						)
						(arc
							(start -0.2032 -0.3048)
							(mid -0.275042 -0.275042)
							(end -0.3048 -0.2032)
						)
						(arc
							(start -0.3048 0.2032)
							(mid -0.275042 0.275042)
							(end -0.2032 0.3048)
						)
						(arc
							(start 0.2032 0.3048)
							(mid 0.275042 0.275042)
							(end 0.3048 0.2032)
						)
					)
					(width 0)
					(fill yes)
				)
			)
		)
		(pad "2" smd custom
			(at 0 0.4445 90)
			(size 0.1524 0.1524)
			(layers "F.Cu" "F.Mask" "F.Paste")
			(net "GND")
			(options
				(clearance outline)
				(anchor circle)
			)
			(primitives
				(gr_poly
					(pts
						(arc
							(start 0.3048 -0.2032)
							(mid 0.275042 -0.275042)
							(end 0.2032 -0.3048)
						)
						(arc
							(start -0.2032 -0.3048)
							(mid -0.275042 -0.275042)
							(end -0.3048 -0.2032)
						)
						(arc
							(start -0.3048 0.2032)
							(mid -0.275042 0.275042)
							(end -0.2032 0.3048)
						)
						(arc
							(start 0.2032 0.3048)
							(mid 0.275042 0.275042)
							(end 0.3048 0.2032)
						)
					)
					(width 0)
					(fill yes)
				)
			)
		)
	)
	(footprint ""
		(layer "F.Cu")
		(at 92.71 -3.683)
		(property "Reference" "PC199"
			(at 0 0 0)
			(layer "F.SilkS")
			(hide yes)
			(effects
				(font
					(size 1.27 1.27)
				)
			)
		)
		(property "Value" "SC22U6D3V6KX-2-GP"
			(at -0.0762 -5.1308 0)
			(unlocked yes)
			(layer "F.Fab")
			(hide yes)
			(effects
				(font
					(size 1.016 1.016)
					(thickness 0.1524)
				)
			)
		)
		(property "Device Type" "C1206H71"
			(at -0.127 -6.6548 0)
			(unlocked yes)
			(layer "F.Fab")
			(hide yes)
			(effects
				(font
					(size 1.016 1.016)
					(thickness 0.1524)
				)
			)
		)
		(duplicate_pad_numbers_are_jumpers no)
		(fp_line
			(start -1.016 -2.2352)
			(end 1.016 -2.2352)
			(stroke
				(width 0.1524)
				(type default)
			)
			(layer "F.SilkS")
		)
		(fp_line
			(start -1.016 -0.8382)
			(end -1.016 -2.2352)
			(stroke
				(width 0.1524)
				(type default)
			)
			(layer "F.SilkS")
		)
		(fp_line
			(start -1.016 2.2352)
			(end -1.016 0.8382)
			(stroke
				(width 0.1524)
				(type default)
			)
			(layer "F.SilkS")
		)
		(fp_line
			(start 1.016 -2.2352)
			(end 1.016 -0.8382)
			(stroke
				(width 0.1524)
				(type default)
			)
			(layer "F.SilkS")
		)
		(fp_line
			(start 1.016 0.8382)
			(end 1.016 2.2352)
			(stroke
				(width 0.1524)
				(type default)
			)
			(layer "F.SilkS")
		)
		(fp_line
			(start 1.016 2.2352)
			(end -1.016 2.2352)
			(stroke
				(width 0.1524)
				(type default)
			)
			(layer "F.SilkS")
		)
		(fp_rect
			(start -1.0922 2.3114)
			(end 1.0922 -2.3114)
			(stroke
				(width 0)
				(type default)
			)
			(fill no)
			(layer "F.CrtYd")
		)
		(fp_poly
			(pts
				(xy 1.0922 -2.3114) (xy 1.0922 2.3114) (xy -1.0922 2.3114) (xy -1.0922 -2.3114)
			)
			(stroke
				(width 0)
				(type default)
			)
			(fill no)
			(layer "F.Fab")
		)
		(pad "1" smd rect
			(at 0 -1.397)
			(size 1.651 1.27)
			(layers "F.Cu" "F.Mask" "F.Paste")
			(net "P0V955_C")
		)
		(pad "2" smd rect
			(at 0 1.397)
			(size 1.651 1.27)
			(layers "F.Cu" "F.Mask" "F.Paste")
			(net "GND")
		)
	)
	(footprint ""
		(layer "F.Cu")
		(at 326.517 -118.491 180)
		(property "Reference" "PC24"
			(at 0 0 180)
			(layer "F.SilkS")
			(hide yes)
			(effects
				(font
					(size 1.27 1.27)
				)
			)
		)
		(property "Value" "SC22U25V5MX-GP"
			(at -0.0762 -6.1214 180)
			(unlocked yes)
			(layer "F.Fab")
			(hide yes)
			(effects
				(font
					(size 1.016 1.016)
					(thickness 0.1524)
				)
			)
		)
		(property "Device Type" "C805H58"
			(at -0.0762 -8.1534 180)
			(unlocked yes)
			(layer "F.Fab")
			(hide yes)
			(effects
				(font
					(size 1.016 1.016)
					(thickness 0.1524)
				)
			)
		)
		(duplicate_pad_numbers_are_jumpers no)
		(fp_line
			(start 0.635 0)
			(end -0.635 0)
			(stroke
				(width 0.508)
				(type default)
			)
			(layer "F.SilkS")
		)
		(fp_rect
			(start -0.9652 1.778)
			(end 0.9652 -1.778)
			(stroke
				(width 0)
				(type default)
			)
			(fill no)
			(layer "F.CrtYd")
		)
		(fp_poly
			(pts
				(xy -0.9652 -1.778) (xy 0.9652 -1.778) (xy 0.9652 1.778) (xy -0.9652 1.778)
			)
			(stroke
				(width 0)
				(type default)
			)
			(fill no)
			(layer "F.Fab")
		)
		(pad "1" smd rect
			(at 0 -0.9652 180)
			(size 1.397 1.143)
			(layers "F.Cu" "F.Mask" "F.Paste")
			(net "P3V3_STBY_VIN")
		)
		(pad "2" smd rect
			(at 0 0.9652 180)
			(size 1.397 1.143)
			(layers "F.Cu" "F.Mask" "F.Paste")
			(net "GND")
		)
	)
	(footprint ""
		(layer "F.Cu")
		(at 196.111876 -146.549872 -90)
		(property "Reference" "SU68"
			(at 0 0 270)
			(layer "F.SilkS")
			(hide yes)
			(effects
				(font
					(size 1.27 1.27)
				)
			)
		)
		(property "Value" "PCA9306DCTT-GP"
			(at 0 -11.6332 270)
			(unlocked yes)
			(layer "F.Fab")
			(hide yes)
			(effects
				(font
					(size 1.016 1.016)
					(thickness 0.1524)
				)
			)
		)
		(property "Device Type" "SSOIC8H52"
			(at 0 -13.1572 270)
			(unlocked yes)
			(layer "F.Fab")
			(hide yes)
			(effects
				(font
					(size 1.016 1.016)
					(thickness 0.1524)
				)
			)
		)
		(duplicate_pad_numbers_are_jumpers no)
		(fp_line
			(start -1.524 0.5842)
			(end -1.524 2.286)
			(stroke
				(width 0.508)
				(type default)
			)
			(layer "F.SilkS")
		)
		(fp_line
			(start 1.0668 0.5842)
			(end -1.524 0.5842)
			(stroke
				(width 0.1524)
				(type default)
			)
			(layer "F.SilkS")
		)
		(fp_line
			(start -1.397 0)
			(end -1.7018 0.3048)
			(stroke
				(width 0.1524)
				(type default)
			)
			(layer "F.SilkS")
		)
		(fp_line
			(start -1.397 0)
			(end -1.7018 -0.3048)
			(stroke
				(width 0.1524)
				(type default)
			)
			(layer "F.SilkS")
		)
		(fp_line
			(start -1.7018 -0.5842)
			(end -1.7018 2.286)
			(stroke
				(width 0.1524)
				(type default)
			)
			(layer "F.SilkS")
		)
		(fp_line
			(start -1.7018 -0.5842)
			(end 1.0668 -0.5842)
			(stroke
				(width 0.1524)
				(type default)
			)
			(layer "F.SilkS")
		)
		(fp_line
			(start 1.0668 -0.5842)
			(end 1.0668 0.5842)
			(stroke
				(width 0.1524)
				(type default)
			)
			(layer "F.SilkS")
		)
		(fp_poly
			(pts
				(xy -1.1684 -0.5842) (xy 1.0668 -0.5842) (xy 1.0668 0.5842) (xy -1.1684 0.5842)
			)
			(stroke
				(width 0)
				(type default)
			)
			(fill yes)
			(layer "F.SilkS")
		)
		(fp_poly
			(pts
				(xy -1.778 2.54) (xy 1.778 2.54) (xy 1.778 -2.54) (xy -1.778 -2.54)
			)
			(stroke
				(width 0)
				(type default)
			)
			(fill no)
			(layer "F.CrtYd")
		)
		(fp_poly
			(pts
				(xy -1.778 -2.54) (xy 1.778 -2.54) (xy 1.778 2.54) (xy -1.778 2.54)
			)
			(stroke
				(width 0)
				(type default)
			)
			(fill no)
			(layer "F.Fab")
		)
		(pad "1" smd rect
			(at -0.97536 1.6256 270)
			(size 0.3556 1.524)
			(layers "F.Cu" "F.Mask" "F.Paste")
			(net "GND")
		)
		(pad "2" smd rect
			(at -0.32512 1.6256 270)
			(size 0.3556 1.524)
			(layers "F.Cu" "F.Mask" "F.Paste")
			(net "P1V8_E")
		)
		(pad "3" smd rect
			(at 0.32512 1.6256 270)
			(size 0.3556 1.524)
			(layers "F.Cu" "F.Mask" "F.Paste")
			(net "EXP_I2C_SCL_3")
		)
		(pad "4" smd rect
			(at 0.97536 1.6256 270)
			(size 0.3556 1.524)
			(layers "F.Cu" "F.Mask" "F.Paste")
			(net "EXP_I2C_SDA_3")
		)
		(pad "5" smd rect
			(at 0.97536 -1.6256 270)
			(size 0.3556 1.524)
			(layers "F.Cu" "F.Mask" "F.Paste")
			(net "BMC_I2C_SDA_9")
		)
		(pad "6" smd rect
			(at 0.32512 -1.6256 270)
			(size 0.3556 1.524)
			(layers "F.Cu" "F.Mask" "F.Paste")
			(net "BMC_I2C_SCL_9")
		)
		(pad "7" smd rect
			(at -0.32512 -1.6256 270)
			(size 0.3556 1.524)
			(layers "F.Cu" "F.Mask" "F.Paste")
			(net "EXP_I2C_VREF_2")
		)
		(pad "8" smd rect
			(at -0.97536 -1.6256 270)
			(size 0.3556 1.524)
			(layers "F.Cu" "F.Mask" "F.Paste")
			(net "EXP_I2C_VREF_2")
		)
	)
	(footprint ""
		(layer "F.Cu")
		(at 258.699 -126.746 180)
		(property "Reference" "R9025"
			(at 0 0 180)
			(layer "F.SilkS")
			(hide yes)
			(effects
				(font
					(size 1.27 1.27)
				)
			)
		)
		(property "Value" "4K7R3F-GP"
			(at -0.0254 -2.5146 180)
			(unlocked yes)
			(layer "F.Fab")
			(hide yes)
			(effects
				(font
					(size 1.016 1.016)
					(thickness 0.1524)
				)
			)
		)
		(property "Device Type" "R603H22"
			(at -0.0254 -4.0386 180)
			(unlocked yes)
			(layer "F.Fab")
			(hide yes)
			(effects
				(font
					(size 1.016 1.016)
					(thickness 0.1524)
				)
			)
		)
		(duplicate_pad_numbers_are_jumpers no)
		(fp_line
			(start 0.2032 0)
			(end 0.4826 0)
			(stroke
				(width 0.2032)
				(type default)
			)
			(layer "F.SilkS")
		)
		(fp_line
			(start -0.4826 0)
			(end -0.2032 0)
			(stroke
				(width 0.2032)
				(type default)
			)
			(layer "F.SilkS")
		)
		(fp_rect
			(start -0.5842 1.3335)
			(end 0.5842 -1.3335)
			(stroke
				(width 0)
				(type default)
			)
			(fill no)
			(layer "F.CrtYd")
		)
		(fp_rect
			(start -0.5842 1.3335)
			(end 0.5842 -1.3335)
			(stroke
				(width 0)
				(type default)
			)
			(fill no)
			(layer "F.Fab")
		)
		(pad "1" smd custom
			(at 0 -0.762 180)
			(size 0.2159 0.2159)
			(layers "F.Cu" "F.Mask" "F.Paste")
			(net "P3V3_STBY")
			(options
				(clearance outline)
				(anchor circle)
			)
			(primitives
				(gr_poly
					(pts
						(arc
							(start -0.3302 -0.4318)
							(mid -0.402042 -0.402042)
							(end -0.4318 -0.3302)
						)
						(arc
							(start -0.4318 0.3302)
							(mid -0.402042 0.402042)
							(end -0.3302 0.4318)
						)
						(arc
							(start 0.3302 0.4318)
							(mid 0.402042 0.402042)
							(end 0.4318 0.3302)
						)
						(arc
							(start 0.4318 -0.3302)
							(mid 0.402042 -0.402042)
							(end 0.3302 -0.4318)
						)
					)
					(width 0)
					(fill yes)
				)
			)
		)
		(pad "2" smd custom
			(at 0 0.762 180)
			(size 0.2159 0.2159)
			(layers "F.Cu" "F.Mask" "F.Paste")
			(net "CPU_U192_PIN5_RX")
			(options
				(clearance outline)
				(anchor circle)
			)
			(primitives
				(gr_poly
					(pts
						(arc
							(start -0.3302 -0.4318)
							(mid -0.402042 -0.402042)
							(end -0.4318 -0.3302)
						)
						(arc
							(start -0.4318 0.3302)
							(mid -0.402042 0.402042)
							(end -0.3302 0.4318)
						)
						(arc
							(start 0.3302 0.4318)
							(mid 0.402042 0.402042)
							(end 0.4318 0.3302)
						)
						(arc
							(start 0.4318 -0.3302)
							(mid 0.402042 -0.402042)
							(end 0.3302 -0.4318)
						)
					)
					(width 0)
					(fill yes)
				)
			)
		)
	)
	(footprint ""
		(layer "F.Cu")
		(at 142.348966 -52.324)
		(property "Reference" "SU58"
			(at 0 0 0)
			(layer "F.SilkS")
			(hide yes)
			(effects
				(font
					(size 1.27 1.27)
				)
			)
		)
		(property "Value" "S29GL128S10TFIV20-GP"
			(at -0.1778 -20.32 0)
			(unlocked yes)
			(layer "F.Fab")
			(hide yes)
			(effects
				(font
					(size 1.016 1.016)
					(thickness 0.1524)
				)
			)
		)
		(property "Device Type" "TSOP56-1H48"
			(at -0.1778 -22.225 0)
			(unlocked yes)
			(layer "F.Fab")
			(hide yes)
			(effects
				(font
					(size 1.016 1.016)
					(thickness 0.1524)
				)
			)
		)
		(duplicate_pad_numbers_are_jumpers no)
		(fp_line
			(start -7.5438 -8.5598)
			(end -7.5438 8.5598)
			(stroke
				(width 0.1524)
				(type default)
			)
			(layer "F.SilkS")
		)
		(fp_line
			(start -7.5438 -0.4318)
			(end -7.112 0)
			(stroke
				(width 0.1524)
				(type default)
			)
			(layer "F.SilkS")
		)
		(fp_line
			(start -7.5438 8.5598)
			(end 6.8326 8.5598)
			(stroke
				(width 0.1524)
				(type default)
			)
			(layer "F.SilkS")
		)
		(fp_line
			(start -7.366 8.5598)
			(end -7.366 10.795)
			(stroke
				(width 0.508)
				(type default)
			)
			(layer "F.SilkS")
		)
		(fp_line
			(start -7.112 0)
			(end -7.5438 0.4318)
			(stroke
				(width 0.1524)
				(type default)
			)
			(layer "F.SilkS")
		)
		(fp_line
			(start 6.8326 -8.5598)
			(end -7.5438 -8.5598)
			(stroke
				(width 0.1524)
				(type default)
			)
			(layer "F.SilkS")
		)
		(fp_line
			(start 6.8326 8.5598)
			(end 6.8326 -8.5598)
			(stroke
				(width 0.1524)
				(type default)
			)
			(layer "F.SilkS")
		)
		(fp_poly
			(pts
				(xy -7.62 11.049) (xy 7.62 11.049) (xy 7.62 -11.049) (xy -7.62 -11.049)
			)
			(stroke
				(width 0)
				(type default)
			)
			(fill no)
			(layer "F.CrtYd")
		)
		(fp_poly
			(pts
				(xy -7.62 -11.049) (xy 7.62 -11.049) (xy 7.62 11.049) (xy -7.62 11.049)
			)
			(stroke
				(width 0)
				(type default)
			)
			(fill no)
			(layer "F.Fab")
		)
		(pad "1" smd rect
			(at -6.75005 9.6139)
			(size 0.3048 1.524)
			(layers "F.Cu" "F.Mask" "F.Paste")
			(net "Net_176")
		)
		(pad "2" smd rect
			(at -6.24967 9.6139)
			(size 0.3048 1.524)
			(layers "F.Cu" "F.Mask" "F.Paste")
			(net "XM_ADDR_23")
		)
		(pad "3" smd rect
			(at -5.75056 9.6139)
			(size 0.3048 1.524)
			(layers "F.Cu" "F.Mask" "F.Paste")
			(net "XM_ADDR_16")
		)
		(pad "4" smd rect
			(at -5.25018 9.6139)
			(size 0.3048 1.524)
			(layers "F.Cu" "F.Mask" "F.Paste")
			(net "XM_ADDR_15")
		)
		(pad "5" smd rect
			(at -4.7498 9.6139)
			(size 0.3048 1.524)
			(layers "F.Cu" "F.Mask" "F.Paste")
			(net "XM_ADDR_14")
		)
		(pad "6" smd rect
			(at -4.24942 9.6139)
			(size 0.3048 1.524)
			(layers "F.Cu" "F.Mask" "F.Paste")
			(net "XM_ADDR_13")
		)
		(pad "7" smd rect
			(at -3.75031 9.6139)
			(size 0.3048 1.524)
			(layers "F.Cu" "F.Mask" "F.Paste")
			(net "XM_ADDR_12")
		)
		(pad "8" smd rect
			(at -3.24993 9.6139)
			(size 0.3048 1.524)
			(layers "F.Cu" "F.Mask" "F.Paste")
			(net "XM_ADDR_11")
		)
		(pad "9" smd rect
			(at -2.74955 9.6139)
			(size 0.3048 1.524)
			(layers "F.Cu" "F.Mask" "F.Paste")
			(net "XM_ADDR_10")
		)
		(pad "10" smd rect
			(at -2.25044 9.6139)
			(size 0.3048 1.524)
			(layers "F.Cu" "F.Mask" "F.Paste")
			(net "XM_ADDR_9")
		)
		(pad "11" smd rect
			(at -1.75006 9.6139)
			(size 0.3048 1.524)
			(layers "F.Cu" "F.Mask" "F.Paste")
			(net "XM_ADDR_20")
		)
		(pad "12" smd rect
			(at -1.24968 9.6139)
			(size 0.3048 1.524)
			(layers "F.Cu" "F.Mask" "F.Paste")
			(net "XM_ADDR_21")
		)
		(pad "13" smd rect
			(at -0.75057 9.6139)
			(size 0.3048 1.524)
			(layers "F.Cu" "F.Mask" "F.Paste")
			(net "XM_WE_N")
		)
		(pad "14" smd rect
			(at -0.25019 9.6139)
			(size 0.3048 1.524)
			(layers "F.Cu" "F.Mask" "F.Paste")
			(net "XM_F_RST_N")
		)
		(pad "15" smd rect
			(at 0.25019 9.6139)
			(size 0.3048 1.524)
			(layers "F.Cu" "F.Mask" "F.Paste")
			(net "XM_ADDR_22")
		)
		(pad "16" smd rect
			(at 0.75057 9.6139)
			(size 0.3048 1.524)
			(layers "F.Cu" "F.Mask" "F.Paste")
			(net "IOC_WP_N")
		)
		(pad "17" smd rect
			(at 1.24968 9.6139)
			(size 0.3048 1.524)
			(layers "F.Cu" "F.Mask" "F.Paste")
			(net "Net_1019")
		)
		(pad "18" smd rect
			(at 1.75006 9.6139)
			(size 0.3048 1.524)
			(layers "F.Cu" "F.Mask" "F.Paste")
			(net "XM_ADDR_19")
		)
		(pad "19" smd rect
			(at 2.25044 9.6139)
			(size 0.3048 1.524)
			(layers "F.Cu" "F.Mask" "F.Paste")
			(net "XM_ADDR_18")
		)
		(pad "20" smd rect
			(at 2.74955 9.6139)
			(size 0.3048 1.524)
			(layers "F.Cu" "F.Mask" "F.Paste")
			(net "XM_ADDR_8")
		)
		(pad "21" smd rect
			(at 3.24993 9.6139)
			(size 0.3048 1.524)
			(layers "F.Cu" "F.Mask" "F.Paste")
			(net "XM_ADDR_7")
		)
		(pad "22" smd rect
			(at 3.75031 9.6139)
			(size 0.3048 1.524)
			(layers "F.Cu" "F.Mask" "F.Paste")
			(net "XM_ADDR_6")
		)
		(pad "23" smd rect
			(at 4.24942 9.6139)
			(size 0.3048 1.524)
			(layers "F.Cu" "F.Mask" "F.Paste")
			(net "XM_ADDR_5")
		)
		(pad "24" smd rect
			(at 4.7498 9.6139)
			(size 0.3048 1.524)
			(layers "F.Cu" "F.Mask" "F.Paste")
			(net "XM_ADDR_4")
		)
		(pad "25" smd rect
			(at 5.25018 9.6139)
			(size 0.3048 1.524)
			(layers "F.Cu" "F.Mask" "F.Paste")
			(net "XM_ADDR_3")
		)
		(pad "26" smd rect
			(at 5.75056 9.6139)
			(size 0.3048 1.524)
			(layers "F.Cu" "F.Mask" "F.Paste")
			(net "XM_ADDR_2")
		)
		(pad "27" smd rect
			(at 6.24967 9.6139)
			(size 0.3048 1.524)
			(layers "F.Cu" "F.Mask" "F.Paste")
			(net "Net_1020")
		)
		(pad "28" smd rect
			(at 6.75005 9.6139)
			(size 0.3048 1.524)
			(layers "F.Cu" "F.Mask" "F.Paste")
			(net "Net_1021")
		)
		(pad "29" smd rect
			(at 6.75005 -9.6139)
			(size 0.3048 1.524)
			(layers "F.Cu" "F.Mask" "F.Paste")
			(net "P1V8_C")
		)
		(pad "30" smd rect
			(at 6.24967 -9.6139)
			(size 0.3048 1.524)
			(layers "F.Cu" "F.Mask" "F.Paste")
			(net "Net_1018")
		)
		(pad "31" smd rect
			(at 5.75056 -9.6139)
			(size 0.3048 1.524)
			(layers "F.Cu" "F.Mask" "F.Paste")
			(net "XM_ADDR_1")
		)
		(pad "32" smd rect
			(at 5.25018 -9.6139)
			(size 0.3048 1.524)
			(layers "F.Cu" "F.Mask" "F.Paste")
			(net "XM_NOR_CS_N")
		)
		(pad "33" smd rect
			(at 4.7498 -9.6139)
			(size 0.3048 1.524)
			(layers "F.Cu" "F.Mask" "F.Paste")
			(net "GND")
		)
		(pad "34" smd rect
			(at 4.24942 -9.6139)
			(size 0.3048 1.524)
			(layers "F.Cu" "F.Mask" "F.Paste")
			(net "XM_OE_N")
		)
		(pad "35" smd rect
			(at 3.75031 -9.6139)
			(size 0.3048 1.524)
			(layers "F.Cu" "F.Mask" "F.Paste")
			(net "XM_DATA_0")
		)
		(pad "36" smd rect
			(at 3.24993 -9.6139)
			(size 0.3048 1.524)
			(layers "F.Cu" "F.Mask" "F.Paste")
			(net "XM_DATA_8")
		)
		(pad "37" smd rect
			(at 2.74955 -9.6139)
			(size 0.3048 1.524)
			(layers "F.Cu" "F.Mask" "F.Paste")
			(net "XM_DATA_1")
		)
		(pad "38" smd rect
			(at 2.25044 -9.6139)
			(size 0.3048 1.524)
			(layers "F.Cu" "F.Mask" "F.Paste")
			(net "XM_DATA_9")
		)
		(pad "39" smd rect
			(at 1.75006 -9.6139)
			(size 0.3048 1.524)
			(layers "F.Cu" "F.Mask" "F.Paste")
			(net "XM_DATA_2")
		)
		(pad "40" smd rect
			(at 1.24968 -9.6139)
			(size 0.3048 1.524)
			(layers "F.Cu" "F.Mask" "F.Paste")
			(net "XM_DATA_10")
		)
		(pad "41" smd rect
			(at 0.75057 -9.6139)
			(size 0.3048 1.524)
			(layers "F.Cu" "F.Mask" "F.Paste")
			(net "XM_DATA_3")
		)
		(pad "42" smd rect
			(at 0.25019 -9.6139)
			(size 0.3048 1.524)
			(layers "F.Cu" "F.Mask" "F.Paste")
			(net "XM_DATA_11")
		)
		(pad "43" smd rect
			(at -0.25019 -9.6139)
			(size 0.3048 1.524)
			(layers "F.Cu" "F.Mask" "F.Paste")
			(net "P3V3")
		)
		(pad "44" smd rect
			(at -0.75057 -9.6139)
			(size 0.3048 1.524)
			(layers "F.Cu" "F.Mask" "F.Paste")
			(net "XM_DATA_4")
		)
		(pad "45" smd rect
			(at -1.24968 -9.6139)
			(size 0.3048 1.524)
			(layers "F.Cu" "F.Mask" "F.Paste")
			(net "XM_DATA_12")
		)
		(pad "46" smd rect
			(at -1.75006 -9.6139)
			(size 0.3048 1.524)
			(layers "F.Cu" "F.Mask" "F.Paste")
			(net "XM_DATA_5")
		)
		(pad "47" smd rect
			(at -2.25044 -9.6139)
			(size 0.3048 1.524)
			(layers "F.Cu" "F.Mask" "F.Paste")
			(net "XM_DATA_13")
		)
		(pad "48" smd rect
			(at -2.74955 -9.6139)
			(size 0.3048 1.524)
			(layers "F.Cu" "F.Mask" "F.Paste")
			(net "XM_DATA_6")
		)
		(pad "49" smd rect
			(at -3.24993 -9.6139)
			(size 0.3048 1.524)
			(layers "F.Cu" "F.Mask" "F.Paste")
			(net "XM_DATA_14")
		)
		(pad "50" smd rect
			(at -3.75031 -9.6139)
			(size 0.3048 1.524)
			(layers "F.Cu" "F.Mask" "F.Paste")
			(net "XM_DATA_7")
		)
		(pad "51" smd rect
			(at -4.24942 -9.6139)
			(size 0.3048 1.524)
			(layers "F.Cu" "F.Mask" "F.Paste")
			(net "XM_DATA_15")
		)
		(pad "52" smd rect
			(at -4.7498 -9.6139)
			(size 0.3048 1.524)
			(layers "F.Cu" "F.Mask" "F.Paste")
			(net "GND")
		)
		(pad "53" smd rect
			(at -5.25018 -9.6139)
			(size 0.3048 1.524)
			(layers "F.Cu" "F.Mask" "F.Paste")
			(net "Net_260")
		)
		(pad "54" smd rect
			(at -5.75056 -9.6139)
			(size 0.3048 1.524)
			(layers "F.Cu" "F.Mask" "F.Paste")
			(net "XM_ADDR_17")
		)
		(pad "55" smd rect
			(at -6.24967 -9.6139)
			(size 0.3048 1.524)
			(layers "F.Cu" "F.Mask" "F.Paste")
			(net "Net_1022")
		)
		(pad "56" smd rect
			(at -6.75005 -9.6139)
			(size 0.3048 1.524)
			(layers "F.Cu" "F.Mask" "F.Paste")
			(net "Net_175")
		)
	)
	(footprint ""
		(layer "F.Cu")
		(at 179.061872 -204.211936 -90)
		(property "Reference" "U23"
			(at 0 0 270)
			(layer "F.SilkS")
			(hide yes)
			(effects
				(font
					(size 1.27 1.27)
				)
			)
		)
		(property "Value" "PCA9511ADP-T-GP"
			(at 0 -13.1572 270)
			(unlocked yes)
			(layer "F.Fab")
			(hide yes)
			(effects
				(font
					(size 1.016 1.016)
					(thickness 0.1524)
				)
			)
		)
		(property "Device Type" "SSOIC8-2H44"
			(at 0 -15.1892 270)
			(unlocked yes)
			(layer "F.Fab")
			(hide yes)
			(effects
				(font
					(size 1.016 1.016)
					(thickness 0.1524)
				)
			)
		)
		(duplicate_pad_numbers_are_jumpers no)
		(fp_line
			(start -1.7018 1.0414)
			(end -1.7018 2.9718)
			(stroke
				(width 0.635)
				(type default)
			)
			(layer "F.SilkS")
		)
		(fp_line
			(start -1.9304 1.016)
			(end -1.9304 -1.016)
			(stroke
				(width 0.1524)
				(type default)
			)
			(layer "F.SilkS")
		)
		(fp_line
			(start 1.0922 1.016)
			(end -1.9304 1.016)
			(stroke
				(width 0.1524)
				(type default)
			)
			(layer "F.SilkS")
		)
		(fp_line
			(start -1.524 0)
			(end -1.9304 0.4064)
			(stroke
				(width 0.1524)
				(type default)
			)
			(layer "F.SilkS")
		)
		(fp_line
			(start -1.524 0)
			(end -1.9304 -0.4064)
			(stroke
				(width 0.1524)
				(type default)
			)
			(layer "F.SilkS")
		)
		(fp_line
			(start -1.9304 -1.016)
			(end 1.0922 -1.016)
			(stroke
				(width 0.1524)
				(type default)
			)
			(layer "F.SilkS")
		)
		(fp_line
			(start 1.0922 -1.016)
			(end 1.0922 1.016)
			(stroke
				(width 0.1524)
				(type default)
			)
			(layer "F.SilkS")
		)
		(fp_poly
			(pts
				(xy -1.1938 -1.016) (xy 1.0922 -1.016) (xy 1.0922 1.016) (xy -1.1938 1.016)
			)
			(stroke
				(width 0)
				(type default)
			)
			(fill yes)
			(layer "F.SilkS")
		)
		(fp_rect
			(start -2.0066 3.3401)
			(end 2.0066 -3.3401)
			(stroke
				(width 0)
				(type default)
			)
			(fill no)
			(layer "F.CrtYd")
		)
		(fp_poly
			(pts
				(xy -2.0066 -3.3401) (xy 2.0066 -3.3401) (xy 2.0066 3.3401) (xy -2.0066 3.3401)
			)
			(stroke
				(width 0)
				(type default)
			)
			(fill no)
			(layer "F.Fab")
		)
		(pad "1" smd rect
			(at -0.97536 2.0701 270)
			(size 0.4064 1.524)
			(layers "F.Cu" "F.Mask" "F.Paste")
			(net "I2C_B_BUFF_EN")
		)
		(pad "2" smd rect
			(at -0.32512 2.0701 270)
			(size 0.4064 1.524)
			(layers "F.Cu" "F.Mask" "F.Paste")
			(net "BMC_I2C_B_SCL")
		)
		(pad "3" smd rect
			(at 0.32512 2.0701 270)
			(size 0.4064 1.524)
			(layers "F.Cu" "F.Mask" "F.Paste")
			(net "SAS_I2C_B_BUF_SCL")
		)
		(pad "4" smd rect
			(at 0.97536 2.0701 270)
			(size 0.4064 1.524)
			(layers "F.Cu" "F.Mask" "F.Paste")
			(net "GND")
		)
		(pad "5" smd rect
			(at 0.97536 -2.0701 270)
			(size 0.4064 1.524)
			(layers "F.Cu" "F.Mask" "F.Paste")
			(net "I2C_B_BUF_READY")
		)
		(pad "6" smd rect
			(at 0.32512 -2.0701 270)
			(size 0.4064 1.524)
			(layers "F.Cu" "F.Mask" "F.Paste")
			(net "SAS_I2C_B_BUF_SDA")
		)
		(pad "7" smd rect
			(at -0.32512 -2.0701 270)
			(size 0.4064 1.524)
			(layers "F.Cu" "F.Mask" "F.Paste")
			(net "BMC_I2C_B_SDA")
		)
		(pad "8" smd rect
			(at -0.97536 -2.0701 270)
			(size 0.4064 1.524)
			(layers "F.Cu" "F.Mask" "F.Paste")
			(net "P3V3_STBY")
		)
	)
	(footprint ""
		(layer "F.Cu")
		(at 17.730216 -213.79688)
		(property "Reference" "R631"
			(at 0 0 0)
			(layer "F.SilkS")
			(hide yes)
			(effects
				(font
					(size 1.27 1.27)
				)
			)
		)
		(property "Value" "4K7R2F-GP"
			(at 0.064008 -3.993896 0)
			(unlocked yes)
			(layer "F.Fab")
			(hide yes)
			(effects
				(font
					(size 1.016 1.016)
					(thickness 0.1524)
				)
			)
		)
		(property "Device Type" "R402H16"
			(at 0.064008 -5.517896 0)
			(unlocked yes)
			(layer "F.Fab")
			(hide yes)
			(effects
				(font
					(size 1.016 1.016)
					(thickness 0.1524)
				)
			)
		)
		(duplicate_pad_numbers_are_jumpers no)
		(fp_line
			(start -0.508 -0.9398)
			(end -0.508 0.9398)
			(stroke
				(width 0.1524)
				(type default)
			)
			(layer "F.SilkS")
		)
		(fp_line
			(start 0.508 -0.9398)
			(end -0.508 -0.9398)
			(stroke
				(width 0.1524)
				(type default)
			)
			(layer "F.SilkS")
		)
		(fp_rect
			(start -0.508 0.9398)
			(end 0.508 -0.9398)
			(stroke
				(width 0)
				(type default)
			)
			(fill no)
			(layer "F.CrtYd")
		)
		(fp_rect
			(start -0.508 0.9398)
			(end 0.508 -0.9398)
			(stroke
				(width 0)
				(type default)
			)
			(fill no)
			(layer "F.Fab")
		)
		(pad "1" smd custom
			(at 0 -0.4445)
			(size 0.1397 0.1397)
			(layers "F.Cu" "F.Mask" "F.Paste")
			(net "IO_EXP_HDD_PWR_A0")
			(options
				(clearance outline)
				(anchor circle)
			)
			(primitives
				(gr_poly
					(pts
						(arc
							(start -0.1778 -0.2794)
							(mid -0.249642 -0.249642)
							(end -0.2794 -0.1778)
						)
						(arc
							(start -0.2794 0.1778)
							(mid -0.249642 0.249642)
							(end -0.1778 0.2794)
						)
						(arc
							(start 0.1778 0.2794)
							(mid 0.249642 0.249642)
							(end 0.2794 0.1778)
						)
						(arc
							(start 0.2794 -0.1778)
							(mid 0.249642 -0.249642)
							(end 0.1778 -0.2794)
						)
					)
					(width 0)
					(fill yes)
				)
			)
		)
		(pad "2" smd custom
			(at 0 0.4445)
			(size 0.1397 0.1397)
			(layers "F.Cu" "F.Mask" "F.Paste")
			(net "GND")
			(options
				(clearance outline)
				(anchor circle)
			)
			(primitives
				(gr_poly
					(pts
						(arc
							(start -0.1778 -0.2794)
							(mid -0.249642 -0.249642)
							(end -0.2794 -0.1778)
						)
						(arc
							(start -0.2794 0.1778)
							(mid -0.249642 0.249642)
							(end -0.1778 0.2794)
						)
						(arc
							(start 0.1778 0.2794)
							(mid 0.249642 0.249642)
							(end 0.2794 0.1778)
						)
						(arc
							(start 0.2794 -0.1778)
							(mid 0.249642 -0.249642)
							(end 0.1778 -0.2794)
						)
					)
					(width 0)
					(fill yes)
				)
			)
		)
	)
	(footprint ""
		(layer "F.Cu")
		(at 341.786718 -144.122648 -90)
		(property "Reference" "R701"
			(at 0 0 270)
			(layer "F.SilkS")
			(hide yes)
			(effects
				(font
					(size 1.27 1.27)
				)
			)
		)
		(property "Value" "1MR2F-GP"
			(at 0.064008 -3.993896 270)
			(unlocked yes)
			(layer "F.Fab")
			(hide yes)
			(effects
				(font
					(size 1.016 1.016)
					(thickness 0.1524)
				)
			)
		)
		(property "Device Type" "R402H16"
			(at 0.064008 -5.517896 270)
			(unlocked yes)
			(layer "F.Fab")
			(hide yes)
			(effects
				(font
					(size 1.016 1.016)
					(thickness 0.1524)
				)
			)
		)
		(duplicate_pad_numbers_are_jumpers no)
		(fp_line
			(start -0.508 -0.9398)
			(end -0.508 0.9398)
			(stroke
				(width 0.1524)
				(type default)
			)
			(layer "F.SilkS")
		)
		(fp_line
			(start 0.508 -0.9398)
			(end -0.508 -0.9398)
			(stroke
				(width 0.1524)
				(type default)
			)
			(layer "F.SilkS")
		)
		(fp_rect
			(start -0.508 0.9398)
			(end 0.508 -0.9398)
			(stroke
				(width 0)
				(type default)
			)
			(fill no)
			(layer "F.CrtYd")
		)
		(fp_rect
			(start -0.508 0.9398)
			(end 0.508 -0.9398)
			(stroke
				(width 0)
				(type default)
			)
			(fill no)
			(layer "F.Fab")
		)
		(pad "1" smd custom
			(at 0 -0.4445 270)
			(size 0.1397 0.1397)
			(layers "F.Cu" "F.Mask" "F.Paste")
			(net "USB_HUB_XTAL_IN")
			(options
				(clearance outline)
				(anchor circle)
			)
			(primitives
				(gr_poly
					(pts
						(arc
							(start -0.1778 -0.2794)
							(mid -0.249642 -0.249642)
							(end -0.2794 -0.1778)
						)
						(arc
							(start -0.2794 0.1778)
							(mid -0.249642 0.249642)
							(end -0.1778 0.2794)
						)
						(arc
							(start 0.1778 0.2794)
							(mid 0.249642 0.249642)
							(end 0.2794 0.1778)
						)
						(arc
							(start 0.2794 -0.1778)
							(mid 0.249642 -0.249642)
							(end 0.1778 -0.2794)
						)
					)
					(width 0)
					(fill yes)
				)
			)
		)
		(pad "2" smd custom
			(at 0 0.4445 270)
			(size 0.1397 0.1397)
			(layers "F.Cu" "F.Mask" "F.Paste")
			(net "USB_HUB_XTAL_OUT")
			(options
				(clearance outline)
				(anchor circle)
			)
			(primitives
				(gr_poly
					(pts
						(arc
							(start -0.1778 -0.2794)
							(mid -0.249642 -0.249642)
							(end -0.2794 -0.1778)
						)
						(arc
							(start -0.2794 0.1778)
							(mid -0.249642 0.249642)
							(end -0.1778 0.2794)
						)
						(arc
							(start 0.1778 0.2794)
							(mid 0.249642 0.249642)
							(end 0.2794 0.1778)
						)
						(arc
							(start 0.2794 -0.1778)
							(mid 0.249642 -0.249642)
							(end 0.1778 -0.2794)
						)
					)
					(width 0)
					(fill yes)
				)
			)
		)
	)
	(footprint ""
		(layer "F.Cu")
		(at 303.320958 -64.135 -90)
		(property "Reference" "R220"
			(at 0 0 270)
			(layer "F.SilkS")
			(hide yes)
			(effects
				(font
					(size 1.27 1.27)
				)
			)
		)
		(property "Value" "0R2J-2-GP"
			(at 0.064008 -3.993896 270)
			(unlocked yes)
			(layer "F.Fab")
			(hide yes)
			(effects
				(font
					(size 1.016 1.016)
					(thickness 0.1524)
				)
			)
		)
		(property "Device Type" "R402H16"
			(at 0.064008 -5.517896 270)
			(unlocked yes)
			(layer "F.Fab")
			(hide yes)
			(effects
				(font
					(size 1.016 1.016)
					(thickness 0.1524)
				)
			)
		)
		(duplicate_pad_numbers_are_jumpers no)
		(fp_line
			(start -0.508 -0.9398)
			(end -0.508 0.9398)
			(stroke
				(width 0.1524)
				(type default)
			)
			(layer "F.SilkS")
		)
		(fp_line
			(start 0.508 -0.9398)
			(end -0.508 -0.9398)
			(stroke
				(width 0.1524)
				(type default)
			)
			(layer "F.SilkS")
		)
		(fp_rect
			(start -0.508 0.9398)
			(end 0.508 -0.9398)
			(stroke
				(width 0)
				(type default)
			)
			(fill no)
			(layer "F.CrtYd")
		)
		(fp_rect
			(start -0.508 0.9398)
			(end 0.508 -0.9398)
			(stroke
				(width 0)
				(type default)
			)
			(fill no)
			(layer "F.Fab")
		)
		(pad "1" smd custom
			(at 0 -0.4445 270)
			(size 0.1397 0.1397)
			(layers "F.Cu" "F.Mask" "F.Paste")
			(net "NCSI_10G_TXD1_R")
			(options
				(clearance outline)
				(anchor circle)
			)
			(primitives
				(gr_poly
					(pts
						(arc
							(start -0.1778 -0.2794)
							(mid -0.249642 -0.249642)
							(end -0.2794 -0.1778)
						)
						(arc
							(start -0.2794 0.1778)
							(mid -0.249642 0.249642)
							(end -0.1778 0.2794)
						)
						(arc
							(start 0.1778 0.2794)
							(mid 0.249642 0.249642)
							(end 0.2794 0.1778)
						)
						(arc
							(start 0.2794 -0.1778)
							(mid 0.249642 -0.249642)
							(end 0.1778 -0.2794)
						)
					)
					(width 0)
					(fill yes)
				)
			)
		)
		(pad "2" smd custom
			(at 0 0.4445 270)
			(size 0.1397 0.1397)
			(layers "F.Cu" "F.Mask" "F.Paste")
			(net "NCSI_10G_TXD1")
			(options
				(clearance outline)
				(anchor circle)
			)
			(primitives
				(gr_poly
					(pts
						(arc
							(start -0.1778 -0.2794)
							(mid -0.249642 -0.249642)
							(end -0.2794 -0.1778)
						)
						(arc
							(start -0.2794 0.1778)
							(mid -0.249642 0.249642)
							(end -0.1778 0.2794)
						)
						(arc
							(start 0.1778 0.2794)
							(mid 0.249642 0.249642)
							(end 0.2794 0.1778)
						)
						(arc
							(start 0.2794 -0.1778)
							(mid 0.249642 -0.249642)
							(end 0.1778 -0.2794)
						)
					)
					(width 0)
					(fill yes)
				)
			)
		)
	)
	(footprint ""
		(layer "F.Cu")
		(at 42.7482 -114.7572 180)
		(property "Reference" "SR848"
			(at 0 0 180)
			(layer "F.SilkS")
			(hide yes)
			(effects
				(font
					(size 1.27 1.27)
				)
			)
		)
		(property "Value" "0R2J-2-GP"
			(at 0.064008 -3.993896 180)
			(unlocked yes)
			(layer "F.Fab")
			(hide yes)
			(effects
				(font
					(size 1.016 1.016)
					(thickness 0.1524)
				)
			)
		)
		(property "Device Type" "R402H16"
			(at 0.064008 -5.517896 180)
			(unlocked yes)
			(layer "F.Fab")
			(hide yes)
			(effects
				(font
					(size 1.016 1.016)
					(thickness 0.1524)
				)
			)
		)
		(duplicate_pad_numbers_are_jumpers no)
		(fp_line
			(start 0.508 -0.9398)
			(end -0.508 -0.9398)
			(stroke
				(width 0.1524)
				(type default)
			)
			(layer "F.SilkS")
		)
		(fp_line
			(start -0.508 -0.9398)
			(end -0.508 0.9398)
			(stroke
				(width 0.1524)
				(type default)
			)
			(layer "F.SilkS")
		)
		(fp_rect
			(start -0.508 0.9398)
			(end 0.508 -0.9398)
			(stroke
				(width 0)
				(type default)
			)
			(fill no)
			(layer "F.CrtYd")
		)
		(fp_rect
			(start -0.508 0.9398)
			(end 0.508 -0.9398)
			(stroke
				(width 0)
				(type default)
			)
			(fill no)
			(layer "F.Fab")
		)
		(pad "1" smd custom
			(at 0 -0.4445 180)
			(size 0.1397 0.1397)
			(layers "F.Cu" "F.Mask" "F.Paste")
			(net "SAS_SDBTX_R")
			(options
				(clearance outline)
				(anchor circle)
			)
			(primitives
				(gr_poly
					(pts
						(arc
							(start -0.1778 -0.2794)
							(mid -0.249642 -0.249642)
							(end -0.2794 -0.1778)
						)
						(arc
							(start -0.2794 0.1778)
							(mid -0.249642 0.249642)
							(end -0.1778 0.2794)
						)
						(arc
							(start 0.1778 0.2794)
							(mid 0.249642 0.249642)
							(end 0.2794 0.1778)
						)
						(arc
							(start 0.2794 -0.1778)
							(mid 0.249642 -0.249642)
							(end 0.1778 -0.2794)
						)
					)
					(width 0)
					(fill yes)
				)
			)
		)
		(pad "2" smd custom
			(at 0 0.4445 180)
			(size 0.1397 0.1397)
			(layers "F.Cu" "F.Mask" "F.Paste")
			(net "SAS_SDBTX")
			(options
				(clearance outline)
				(anchor circle)
			)
			(primitives
				(gr_poly
					(pts
						(arc
							(start -0.1778 -0.2794)
							(mid -0.249642 -0.249642)
							(end -0.2794 -0.1778)
						)
						(arc
							(start -0.2794 0.1778)
							(mid -0.249642 0.249642)
							(end -0.1778 0.2794)
						)
						(arc
							(start 0.1778 0.2794)
							(mid 0.249642 0.249642)
							(end 0.2794 0.1778)
						)
						(arc
							(start 0.2794 -0.1778)
							(mid 0.249642 -0.249642)
							(end 0.1778 -0.2794)
						)
					)
					(width 0)
					(fill yes)
				)
			)
		)
	)
	(footprint ""
		(layer "F.Cu")
		(at 348.390718 -153.012648 -90)
		(property "Reference" "R451"
			(at 0 0 270)
			(layer "F.SilkS")
			(hide yes)
			(effects
				(font
					(size 1.27 1.27)
				)
			)
		)
		(property "Value" "0R2J-2-GP"
			(at 0.064008 -3.993896 270)
			(unlocked yes)
			(layer "F.Fab")
			(hide yes)
			(effects
				(font
					(size 1.016 1.016)
					(thickness 0.1524)
				)
			)
		)
		(property "Device Type" "R402H16"
			(at 0.064008 -5.517896 270)
			(unlocked yes)
			(layer "F.Fab")
			(hide yes)
			(effects
				(font
					(size 1.016 1.016)
					(thickness 0.1524)
				)
			)
		)
		(duplicate_pad_numbers_are_jumpers no)
		(fp_line
			(start -0.508 -0.9398)
			(end -0.508 0.9398)
			(stroke
				(width 0.1524)
				(type default)
			)
			(layer "F.SilkS")
		)
		(fp_line
			(start 0.508 -0.9398)
			(end -0.508 -0.9398)
			(stroke
				(width 0.1524)
				(type default)
			)
			(layer "F.SilkS")
		)
		(fp_rect
			(start -0.508 0.9398)
			(end 0.508 -0.9398)
			(stroke
				(width 0)
				(type default)
			)
			(fill no)
			(layer "F.CrtYd")
		)
		(fp_rect
			(start -0.508 0.9398)
			(end 0.508 -0.9398)
			(stroke
				(width 0)
				(type default)
			)
			(fill no)
			(layer "F.Fab")
		)
		(pad "1" smd custom
			(at 0 -0.4445 270)
			(size 0.1397 0.1397)
			(layers "F.Cu" "F.Mask" "F.Paste")
			(net "BMC_USB1_HDP")
			(options
				(clearance outline)
				(anchor circle)
			)
			(primitives
				(gr_poly
					(pts
						(arc
							(start -0.1778 -0.2794)
							(mid -0.249642 -0.249642)
							(end -0.2794 -0.1778)
						)
						(arc
							(start -0.2794 0.1778)
							(mid -0.249642 0.249642)
							(end -0.1778 0.2794)
						)
						(arc
							(start 0.1778 0.2794)
							(mid 0.249642 0.249642)
							(end 0.2794 0.1778)
						)
						(arc
							(start 0.2794 -0.1778)
							(mid 0.249642 -0.249642)
							(end 0.1778 -0.2794)
						)
					)
					(width 0)
					(fill yes)
				)
			)
		)
		(pad "2" smd custom
			(at 0 0.4445 270)
			(size 0.1397 0.1397)
			(layers "F.Cu" "F.Mask" "F.Paste")
			(net "USB_P3_DP")
			(options
				(clearance outline)
				(anchor circle)
			)
			(primitives
				(gr_poly
					(pts
						(arc
							(start -0.1778 -0.2794)
							(mid -0.249642 -0.249642)
							(end -0.2794 -0.1778)
						)
						(arc
							(start -0.2794 0.1778)
							(mid -0.249642 0.249642)
							(end -0.1778 0.2794)
						)
						(arc
							(start 0.1778 0.2794)
							(mid 0.249642 0.249642)
							(end 0.2794 0.1778)
						)
						(arc
							(start 0.2794 -0.1778)
							(mid 0.249642 -0.249642)
							(end 0.1778 -0.2794)
						)
					)
					(width 0)
					(fill yes)
				)
			)
		)
	)
	(footprint ""
		(layer "F.Cu")
		(at 136.779 -40.64)
		(property "Reference" "STP116"
			(at 0 0 0)
			(layer "F.SilkS")
			(hide yes)
			(effects
				(font
					(size 1.27 1.27)
				)
			)
		)
		(property "Value" "TPAD28"
			(at 0.0127 -1.8034 0)
			(unlocked yes)
			(layer "F.Fab")
			(hide yes)
			(effects
				(font
					(size 1.016 1.016)
					(thickness 0.1524)
				)
			)
		)
		(property "Device Type" "TPAD28"
			(at 0.0127 -3.3274 0)
			(unlocked yes)
			(layer "F.Fab")
			(hide yes)
			(effects
				(font
					(size 1.016 1.016)
					(thickness 0.1524)
				)
			)
		)
		(duplicate_pad_numbers_are_jumpers no)
		(fp_poly
			(pts
				(arc
					(start 0.3556 0)
					(mid -0.3556 0)
					(end 0.3556 0)
				)
			)
			(stroke
				(width 0)
				(type default)
			)
			(fill no)
			(layer "F.CrtYd")
		)
		(fp_poly
			(pts
				(arc
					(start 0.6096 0)
					(mid -0.6096 0)
					(end 0.6096 0)
				)
			)
			(stroke
				(width 0)
				(type default)
			)
			(fill no)
			(layer "F.Fab")
		)
		(pad "1" smd circle
			(at 0 0)
			(size 0.7112 0.7112)
			(layers "F.Cu" "F.Mask" "F.Paste")
			(net "XM_ADDR_16")
		)
	)
	(footprint ""
		(layer "F.Cu")
		(at 81.915 -23.749 -90)
		(property "Reference" "PR190"
			(at 0 0 270)
			(layer "F.SilkS")
			(hide yes)
			(effects
				(font
					(size 1.27 1.27)
				)
			)
		)
		(property "Value" "7K32R2F-GP"
			(at 0.064008 -3.993896 270)
			(unlocked yes)
			(layer "F.Fab")
			(hide yes)
			(effects
				(font
					(size 1.016 1.016)
					(thickness 0.1524)
				)
			)
		)
		(property "Device Type" "R402H16"
			(at 0.064008 -5.517896 270)
			(unlocked yes)
			(layer "F.Fab")
			(hide yes)
			(effects
				(font
					(size 1.016 1.016)
					(thickness 0.1524)
				)
			)
		)
		(duplicate_pad_numbers_are_jumpers no)
		(fp_line
			(start -0.508 -0.9398)
			(end -0.508 0.9398)
			(stroke
				(width 0.1524)
				(type default)
			)
			(layer "F.SilkS")
		)
		(fp_line
			(start 0.508 -0.9398)
			(end -0.508 -0.9398)
			(stroke
				(width 0.1524)
				(type default)
			)
			(layer "F.SilkS")
		)
		(fp_rect
			(start -0.508 0.9398)
			(end 0.508 -0.9398)
			(stroke
				(width 0)
				(type default)
			)
			(fill no)
			(layer "F.CrtYd")
		)
		(fp_rect
			(start -0.508 0.9398)
			(end 0.508 -0.9398)
			(stroke
				(width 0)
				(type default)
			)
			(fill no)
			(layer "F.Fab")
		)
		(pad "1" smd custom
			(at 0 -0.4445 270)
			(size 0.1397 0.1397)
			(layers "F.Cu" "F.Mask" "F.Paste")
			(net "VT235_VREF")
			(options
				(clearance outline)
				(anchor circle)
			)
			(primitives
				(gr_poly
					(pts
						(arc
							(start -0.1778 -0.2794)
							(mid -0.249642 -0.249642)
							(end -0.2794 -0.1778)
						)
						(arc
							(start -0.2794 0.1778)
							(mid -0.249642 0.249642)
							(end -0.1778 0.2794)
						)
						(arc
							(start 0.1778 0.2794)
							(mid 0.249642 0.249642)
							(end 0.2794 0.1778)
						)
						(arc
							(start 0.2794 -0.1778)
							(mid 0.249642 -0.249642)
							(end 0.1778 -0.2794)
						)
					)
					(width 0)
					(fill yes)
				)
			)
		)
		(pad "2" smd custom
			(at 0 0.4445 270)
			(size 0.1397 0.1397)
			(layers "F.Cu" "F.Mask" "F.Paste")
			(net "VT235_VDES_RR")
			(options
				(clearance outline)
				(anchor circle)
			)
			(primitives
				(gr_poly
					(pts
						(arc
							(start -0.1778 -0.2794)
							(mid -0.249642 -0.249642)
							(end -0.2794 -0.1778)
						)
						(arc
							(start -0.2794 0.1778)
							(mid -0.249642 0.249642)
							(end -0.1778 0.2794)
						)
						(arc
							(start 0.1778 0.2794)
							(mid 0.249642 0.249642)
							(end 0.2794 0.1778)
						)
						(arc
							(start 0.2794 -0.1778)
							(mid 0.249642 -0.249642)
							(end 0.1778 -0.2794)
						)
					)
					(width 0)
					(fill yes)
				)
			)
		)
	)
	(footprint ""
		(layer "F.Cu")
		(at 323.342 -182.372)
		(property "Reference" "C8085"
			(at 0 0 0)
			(layer "F.SilkS")
			(hide yes)
			(effects
				(font
					(size 1.27 1.27)
				)
			)
		)
		(property "Value" "SCD1U25V2KX-2-GP"
			(at 1.1811 -2.7051 0)
			(unlocked yes)
			(layer "F.Fab")
			(hide yes)
			(effects
				(font
					(size 1.016 1.016)
					(thickness 0.1524)
				)
			)
		)
		(property "Device Type" "C402H22"
			(at 1.1811 -4.2291 0)
			(unlocked yes)
			(layer "F.Fab")
			(hide yes)
			(effects
				(font
					(size 1.016 1.016)
					(thickness 0.1524)
				)
			)
		)
		(duplicate_pad_numbers_are_jumpers no)
		(fp_rect
			(start -0.4318 0.9525)
			(end 0.4318 -0.9525)
			(stroke
				(width 0)
				(type default)
			)
			(fill no)
			(layer "F.CrtYd")
		)
		(fp_rect
			(start -0.4318 0.9525)
			(end 0.4318 -0.9525)
			(stroke
				(width 0)
				(type default)
			)
			(fill no)
			(layer "F.Fab")
		)
		(pad "1" smd custom
			(at 0 -0.4445)
			(size 0.1524 0.1524)
			(layers "F.Cu" "F.Mask" "F.Paste")
			(net "ADC_P1V8_STBY")
			(options
				(clearance outline)
				(anchor circle)
			)
			(primitives
				(gr_poly
					(pts
						(arc
							(start 0.3048 -0.2032)
							(mid 0.275042 -0.275042)
							(end 0.2032 -0.3048)
						)
						(arc
							(start -0.2032 -0.3048)
							(mid -0.275042 -0.275042)
							(end -0.3048 -0.2032)
						)
						(arc
							(start -0.3048 0.2032)
							(mid -0.275042 0.275042)
							(end -0.2032 0.3048)
						)
						(arc
							(start 0.2032 0.3048)
							(mid 0.275042 0.275042)
							(end 0.3048 0.2032)
						)
					)
					(width 0)
					(fill yes)
				)
			)
		)
		(pad "2" smd custom
			(at 0 0.4445)
			(size 0.1524 0.1524)
			(layers "F.Cu" "F.Mask" "F.Paste")
			(net "GND")
			(options
				(clearance outline)
				(anchor circle)
			)
			(primitives
				(gr_poly
					(pts
						(arc
							(start 0.3048 -0.2032)
							(mid 0.275042 -0.275042)
							(end 0.2032 -0.3048)
						)
						(arc
							(start -0.2032 -0.3048)
							(mid -0.275042 -0.275042)
							(end -0.3048 -0.2032)
						)
						(arc
							(start -0.3048 0.2032)
							(mid -0.275042 0.275042)
							(end -0.2032 0.3048)
						)
						(arc
							(start 0.2032 0.3048)
							(mid 0.275042 0.275042)
							(end 0.3048 0.2032)
						)
					)
					(width 0)
					(fill yes)
				)
			)
		)
	)
	(footprint ""
		(layer "F.Cu")
		(at 338.700872 -171.395136 180)
		(property "Reference" "R278"
			(at 0 0 180)
			(layer "F.SilkS")
			(hide yes)
			(effects
				(font
					(size 1.27 1.27)
				)
			)
		)
		(property "Value" "0R2J-2-GP"
			(at 0.064008 -3.993896 180)
			(unlocked yes)
			(layer "F.Fab")
			(hide yes)
			(effects
				(font
					(size 1.016 1.016)
					(thickness 0.1524)
				)
			)
		)
		(property "Device Type" "R402H16"
			(at 0.064008 -5.517896 180)
			(unlocked yes)
			(layer "F.Fab")
			(hide yes)
			(effects
				(font
					(size 1.016 1.016)
					(thickness 0.1524)
				)
			)
		)
		(duplicate_pad_numbers_are_jumpers no)
		(fp_line
			(start 0.508 -0.9398)
			(end -0.508 -0.9398)
			(stroke
				(width 0.1524)
				(type default)
			)
			(layer "F.SilkS")
		)
		(fp_line
			(start -0.508 -0.9398)
			(end -0.508 0.9398)
			(stroke
				(width 0.1524)
				(type default)
			)
			(layer "F.SilkS")
		)
		(fp_rect
			(start -0.508 0.9398)
			(end 0.508 -0.9398)
			(stroke
				(width 0)
				(type default)
			)
			(fill no)
			(layer "F.CrtYd")
		)
		(fp_rect
			(start -0.508 0.9398)
			(end 0.508 -0.9398)
			(stroke
				(width 0)
				(type default)
			)
			(fill no)
			(layer "F.Fab")
		)
		(pad "1" smd custom
			(at 0 -0.4445 180)
			(size 0.1397 0.1397)
			(layers "F.Cu" "F.Mask" "F.Paste")
			(net "BMC_UART_SWITCH_R")
			(options
				(clearance outline)
				(anchor circle)
			)
			(primitives
				(gr_poly
					(pts
						(arc
							(start -0.1778 -0.2794)
							(mid -0.249642 -0.249642)
							(end -0.2794 -0.1778)
						)
						(arc
							(start -0.2794 0.1778)
							(mid -0.249642 0.249642)
							(end -0.1778 0.2794)
						)
						(arc
							(start 0.1778 0.2794)
							(mid 0.249642 0.249642)
							(end 0.2794 0.1778)
						)
						(arc
							(start 0.2794 -0.1778)
							(mid 0.249642 -0.249642)
							(end 0.1778 -0.2794)
						)
					)
					(width 0)
					(fill yes)
				)
			)
		)
		(pad "2" smd custom
			(at 0 0.4445 180)
			(size 0.1397 0.1397)
			(layers "F.Cu" "F.Mask" "F.Paste")
			(net "GND")
			(options
				(clearance outline)
				(anchor circle)
			)
			(primitives
				(gr_poly
					(pts
						(arc
							(start -0.1778 -0.2794)
							(mid -0.249642 -0.249642)
							(end -0.2794 -0.1778)
						)
						(arc
							(start -0.2794 0.1778)
							(mid -0.249642 0.249642)
							(end -0.1778 0.2794)
						)
						(arc
							(start 0.1778 0.2794)
							(mid 0.249642 0.249642)
							(end 0.2794 0.1778)
						)
						(arc
							(start 0.2794 -0.1778)
							(mid 0.249642 -0.249642)
							(end 0.1778 -0.2794)
						)
					)
					(width 0)
					(fill yes)
				)
			)
		)
	)
	(footprint ""
		(layer "F.Cu")
		(at 280.915872 -215.591136 180)
		(property "Reference" "PR83"
			(at 0 0 180)
			(layer "F.SilkS")
			(hide yes)
			(effects
				(font
					(size 1.27 1.27)
				)
			)
		)
		(property "Value" "0R2J-2-GP"
			(at 0.064008 -3.993896 180)
			(unlocked yes)
			(layer "F.Fab")
			(hide yes)
			(effects
				(font
					(size 1.016 1.016)
					(thickness 0.1524)
				)
			)
		)
		(property "Device Type" "R402H16"
			(at 0.064008 -5.517896 180)
			(unlocked yes)
			(layer "F.Fab")
			(hide yes)
			(effects
				(font
					(size 1.016 1.016)
					(thickness 0.1524)
				)
			)
		)
		(duplicate_pad_numbers_are_jumpers no)
		(fp_line
			(start 0.508 -0.9398)
			(end -0.508 -0.9398)
			(stroke
				(width 0.1524)
				(type default)
			)
			(layer "F.SilkS")
		)
		(fp_line
			(start -0.508 -0.9398)
			(end -0.508 0.9398)
			(stroke
				(width 0.1524)
				(type default)
			)
			(layer "F.SilkS")
		)
		(fp_rect
			(start -0.508 0.9398)
			(end 0.508 -0.9398)
			(stroke
				(width 0)
				(type default)
			)
			(fill no)
			(layer "F.CrtYd")
		)
		(fp_rect
			(start -0.508 0.9398)
			(end 0.508 -0.9398)
			(stroke
				(width 0)
				(type default)
			)
			(fill no)
			(layer "F.Fab")
		)
		(pad "1" smd custom
			(at 0 -0.4445 180)
			(size 0.1397 0.1397)
			(layers "F.Cu" "F.Mask" "F.Paste")
			(net "P1V8_STBY_PG")
			(options
				(clearance outline)
				(anchor circle)
			)
			(primitives
				(gr_poly
					(pts
						(arc
							(start -0.1778 -0.2794)
							(mid -0.249642 -0.249642)
							(end -0.2794 -0.1778)
						)
						(arc
							(start -0.2794 0.1778)
							(mid -0.249642 0.249642)
							(end -0.1778 0.2794)
						)
						(arc
							(start 0.1778 0.2794)
							(mid 0.249642 0.249642)
							(end 0.2794 0.1778)
						)
						(arc
							(start 0.2794 -0.1778)
							(mid 0.249642 -0.249642)
							(end 0.1778 -0.2794)
						)
					)
					(width 0)
					(fill yes)
				)
			)
		)
		(pad "2" smd custom
			(at 0 0.4445 180)
			(size 0.1397 0.1397)
			(layers "F.Cu" "F.Mask" "F.Paste")
			(net "TPS74801_1V53_STBY_EN")
			(options
				(clearance outline)
				(anchor circle)
			)
			(primitives
				(gr_poly
					(pts
						(arc
							(start -0.1778 -0.2794)
							(mid -0.249642 -0.249642)
							(end -0.2794 -0.1778)
						)
						(arc
							(start -0.2794 0.1778)
							(mid -0.249642 0.249642)
							(end -0.1778 0.2794)
						)
						(arc
							(start 0.1778 0.2794)
							(mid 0.249642 0.249642)
							(end 0.2794 0.1778)
						)
						(arc
							(start 0.2794 -0.1778)
							(mid 0.249642 -0.249642)
							(end 0.1778 -0.2794)
						)
					)
					(width 0)
					(fill yes)
				)
			)
		)
	)
	(footprint ""
		(layer "F.Cu")
		(at 284.090872 -68.017136 -90)
		(property "Reference" "U34"
			(at 0 0 270)
			(layer "F.SilkS")
			(hide yes)
			(effects
				(font
					(size 1.27 1.27)
				)
			)
		)
		(property "Value" "ADM1178-2ARMZ-R7-GP"
			(at 0 -11.1252 270)
			(unlocked yes)
			(layer "F.Fab")
			(hide yes)
			(effects
				(font
					(size 1.016 1.016)
					(thickness 0.1524)
				)
			)
		)
		(property "Device Type" "MSOP10H44"
			(at 0 -12.6492 270)
			(unlocked yes)
			(layer "F.Fab")
			(hide yes)
			(effects
				(font
					(size 1.016 1.016)
					(thickness 0.1524)
				)
			)
		)
		(duplicate_pad_numbers_are_jumpers no)
		(fp_line
			(start -2.0066 1.016)
			(end -2.0066 -1.016)
			(stroke
				(width 0.1524)
				(type default)
			)
			(layer "F.SilkS")
		)
		(fp_line
			(start -1.8288 1.016)
			(end -1.8288 3.048)
			(stroke
				(width 0.508)
				(type default)
			)
			(layer "F.SilkS")
		)
		(fp_line
			(start 1.143 1.016)
			(end -2.0066 1.016)
			(stroke
				(width 0.1524)
				(type default)
			)
			(layer "F.SilkS")
		)
		(fp_line
			(start -1.5748 0)
			(end -1.9558 0.381)
			(stroke
				(width 0.1524)
				(type default)
			)
			(layer "F.SilkS")
		)
		(fp_line
			(start -1.5748 0)
			(end -1.9558 -0.381)
			(stroke
				(width 0.1524)
				(type default)
			)
			(layer "F.SilkS")
		)
		(fp_line
			(start -2.0066 -1.016)
			(end 1.143 -1.016)
			(stroke
				(width 0.1524)
				(type default)
			)
			(layer "F.SilkS")
		)
		(fp_line
			(start 1.143 -1.016)
			(end 1.143 1.016)
			(stroke
				(width 0.1524)
				(type default)
			)
			(layer "F.SilkS")
		)
		(fp_poly
			(pts
				(xy -2.0828 3.3401) (xy 2.0828 3.3401) (xy 2.0828 -3.3401) (xy -2.0828 -3.3401)
			)
			(stroke
				(width 0)
				(type default)
			)
			(fill no)
			(layer "F.CrtYd")
		)
		(fp_poly
			(pts
				(xy -2.0828 3.3401) (xy 2.0828 3.3401) (xy 2.0828 -3.3401) (xy -2.0828 -3.3401)
			)
			(stroke
				(width 0)
				(type default)
			)
			(fill no)
			(layer "F.Fab")
		)
		(pad "1" smd rect
			(at -0.99949 2.0701 270)
			(size 0.3048 1.524)
			(layers "F.Cu" "F.Mask" "F.Paste")
			(net "P12V_PCIE")
		)
		(pad "2" smd rect
			(at -0.50038 2.0701 270)
			(size 0.3048 1.524)
			(layers "F.Cu" "F.Mask" "F.Paste")
			(net "VSENSE_HSC_MSB")
		)
		(pad "3" smd rect
			(at 0 2.0701 270)
			(size 0.3048 1.524)
			(layers "F.Cu" "F.Mask" "F.Paste")
			(net "PRSNT_EN_HPIC")
		)
		(pad "4" smd rect
			(at 0.50038 2.0701 270)
			(size 0.3048 1.524)
			(layers "F.Cu" "F.Mask" "F.Paste")
			(net "GND")
		)
		(pad "5" smd rect
			(at 0.99949 2.0701 270)
			(size 0.3048 1.524)
			(layers "F.Cu" "F.Mask" "F.Paste")
			(net "VR_HSC_TIMER_MSB")
		)
		(pad "6" smd rect
			(at 0.99949 -2.0701 270)
			(size 0.3048 1.524)
			(layers "F.Cu" "F.Mask" "F.Paste")
			(net "HSW_SCL1")
		)
		(pad "7" smd rect
			(at 0.50038 -2.0701 270)
			(size 0.3048 1.524)
			(layers "F.Cu" "F.Mask" "F.Paste")
			(net "HSW_SDA1")
		)
		(pad "8" smd rect
			(at 0 -2.0701 270)
			(size 0.3048 1.524)
			(layers "F.Cu" "F.Mask" "F.Paste")
			(net "HS_ADR")
		)
		(pad "9" smd rect
			(at -0.50038 -2.0701 270)
			(size 0.3048 1.524)
			(layers "F.Cu" "F.Mask" "F.Paste")
			(net "VR_HSC_GATE_MSB")
		)
		(pad "10" smd rect
			(at -0.99949 -2.0701 270)
			(size 0.3048 1.524)
			(layers "F.Cu" "F.Mask" "F.Paste")
			(net "HSC_MSB_ALERT_N")
		)
	)
	(footprint ""
		(layer "F.Cu")
		(at 276.352 -115.824)
		(property "Reference" "PR176"
			(at 0 0 0)
			(layer "F.SilkS")
			(hide yes)
			(effects
				(font
					(size 1.27 1.27)
				)
			)
		)
		(property "Value" "0R2J-2-GP"
			(at 0.064008 -3.993896 0)
			(unlocked yes)
			(layer "F.Fab")
			(hide yes)
			(effects
				(font
					(size 1.016 1.016)
					(thickness 0.1524)
				)
			)
		)
		(property "Device Type" "R402H16"
			(at 0.064008 -5.517896 0)
			(unlocked yes)
			(layer "F.Fab")
			(hide yes)
			(effects
				(font
					(size 1.016 1.016)
					(thickness 0.1524)
				)
			)
		)
		(duplicate_pad_numbers_are_jumpers no)
		(fp_line
			(start -0.508 -0.9398)
			(end -0.508 0.9398)
			(stroke
				(width 0.1524)
				(type default)
			)
			(layer "F.SilkS")
		)
		(fp_line
			(start 0.508 -0.9398)
			(end -0.508 -0.9398)
			(stroke
				(width 0.1524)
				(type default)
			)
			(layer "F.SilkS")
		)
		(fp_rect
			(start -0.508 0.9398)
			(end 0.508 -0.9398)
			(stroke
				(width 0)
				(type default)
			)
			(fill no)
			(layer "F.CrtYd")
		)
		(fp_rect
			(start -0.508 0.9398)
			(end 0.508 -0.9398)
			(stroke
				(width 0)
				(type default)
			)
			(fill no)
			(layer "F.Fab")
		)
		(pad "1" smd custom
			(at 0 -0.4445)
			(size 0.1397 0.1397)
			(layers "F.Cu" "F.Mask" "F.Paste")
			(net "P3V3_PG")
			(options
				(clearance outline)
				(anchor circle)
			)
			(primitives
				(gr_poly
					(pts
						(arc
							(start -0.1778 -0.2794)
							(mid -0.249642 -0.249642)
							(end -0.2794 -0.1778)
						)
						(arc
							(start -0.2794 0.1778)
							(mid -0.249642 0.249642)
							(end -0.1778 0.2794)
						)
						(arc
							(start 0.1778 0.2794)
							(mid 0.249642 0.249642)
							(end 0.2794 0.1778)
						)
						(arc
							(start 0.2794 -0.1778)
							(mid 0.249642 -0.249642)
							(end 0.1778 -0.2794)
						)
					)
					(width 0)
					(fill yes)
				)
			)
		)
		(pad "2" smd custom
			(at 0 0.4445)
			(size 0.1397 0.1397)
			(layers "F.Cu" "F.Mask" "F.Paste")
			(net "P1V8_C_EN_B")
			(options
				(clearance outline)
				(anchor circle)
			)
			(primitives
				(gr_poly
					(pts
						(arc
							(start -0.1778 -0.2794)
							(mid -0.249642 -0.249642)
							(end -0.2794 -0.1778)
						)
						(arc
							(start -0.2794 0.1778)
							(mid -0.249642 0.249642)
							(end -0.1778 0.2794)
						)
						(arc
							(start 0.1778 0.2794)
							(mid 0.249642 0.249642)
							(end 0.2794 0.1778)
						)
						(arc
							(start 0.2794 -0.1778)
							(mid 0.249642 -0.249642)
							(end 0.1778 -0.2794)
						)
					)
					(width 0)
					(fill yes)
				)
			)
		)
	)
	(footprint ""
		(layer "F.Cu")
		(at 189.865 -20.955 90)
		(property "Reference" "R380"
			(at 0 0 90)
			(layer "F.SilkS")
			(hide yes)
			(effects
				(font
					(size 1.27 1.27)
				)
			)
		)
		(property "Value" "0R2J-2-GP"
			(at 0.064008 -3.993896 90)
			(unlocked yes)
			(layer "F.Fab")
			(hide yes)
			(effects
				(font
					(size 1.016 1.016)
					(thickness 0.1524)
				)
			)
		)
		(property "Device Type" "R402H16"
			(at 0.064008 -5.517896 90)
			(unlocked yes)
			(layer "F.Fab")
			(hide yes)
			(effects
				(font
					(size 1.016 1.016)
					(thickness 0.1524)
				)
			)
		)
		(duplicate_pad_numbers_are_jumpers no)
		(fp_line
			(start 0.508 -0.9398)
			(end -0.508 -0.9398)
			(stroke
				(width 0.1524)
				(type default)
			)
			(layer "F.SilkS")
		)
		(fp_line
			(start -0.508 -0.9398)
			(end -0.508 0.9398)
			(stroke
				(width 0.1524)
				(type default)
			)
			(layer "F.SilkS")
		)
		(fp_rect
			(start -0.508 0.9398)
			(end 0.508 -0.9398)
			(stroke
				(width 0)
				(type default)
			)
			(fill no)
			(layer "F.CrtYd")
		)
		(fp_rect
			(start -0.508 0.9398)
			(end 0.508 -0.9398)
			(stroke
				(width 0)
				(type default)
			)
			(fill no)
			(layer "F.Fab")
		)
		(pad "1" smd custom
			(at 0 -0.4445 90)
			(size 0.1397 0.1397)
			(layers "F.Cu" "F.Mask" "F.Paste")
			(net "RMII_BMC_MDIO_R")
			(options
				(clearance outline)
				(anchor circle)
			)
			(primitives
				(gr_poly
					(pts
						(arc
							(start -0.1778 -0.2794)
							(mid -0.249642 -0.249642)
							(end -0.2794 -0.1778)
						)
						(arc
							(start -0.2794 0.1778)
							(mid -0.249642 0.249642)
							(end -0.1778 0.2794)
						)
						(arc
							(start 0.1778 0.2794)
							(mid 0.249642 0.249642)
							(end 0.2794 0.1778)
						)
						(arc
							(start 0.2794 -0.1778)
							(mid 0.249642 -0.249642)
							(end 0.1778 -0.2794)
						)
					)
					(width 0)
					(fill yes)
				)
			)
		)
		(pad "2" smd custom
			(at 0 0.4445 90)
			(size 0.1397 0.1397)
			(layers "F.Cu" "F.Mask" "F.Paste")
			(net "RMII_BMC_MDIO")
			(options
				(clearance outline)
				(anchor circle)
			)
			(primitives
				(gr_poly
					(pts
						(arc
							(start -0.1778 -0.2794)
							(mid -0.249642 -0.249642)
							(end -0.2794 -0.1778)
						)
						(arc
							(start -0.2794 0.1778)
							(mid -0.249642 0.249642)
							(end -0.1778 0.2794)
						)
						(arc
							(start 0.1778 0.2794)
							(mid 0.249642 0.249642)
							(end 0.2794 0.1778)
						)
						(arc
							(start 0.2794 -0.1778)
							(mid 0.249642 -0.249642)
							(end 0.1778 -0.2794)
						)
					)
					(width 0)
					(fill yes)
				)
			)
		)
	)
	(footprint ""
		(layer "F.Cu")
		(at 80.91297 -111.76 180)
		(property "Reference" "SC1205"
			(at 0 0 180)
			(layer "F.SilkS")
			(hide yes)
			(effects
				(font
					(size 1.27 1.27)
				)
			)
		)
		(property "Value" "SC10U6D3V5KX-4GP"
			(at -0.0762 -6.1214 180)
			(unlocked yes)
			(layer "F.Fab")
			(hide yes)
			(effects
				(font
					(size 1.016 1.016)
					(thickness 0.1524)
				)
			)
		)
		(property "Device Type" "C805H58"
			(at -0.0762 -8.1534 180)
			(unlocked yes)
			(layer "F.Fab")
			(hide yes)
			(effects
				(font
					(size 1.016 1.016)
					(thickness 0.1524)
				)
			)
		)
		(duplicate_pad_numbers_are_jumpers no)
		(fp_line
			(start 0.635 0)
			(end -0.635 0)
			(stroke
				(width 0.508)
				(type default)
			)
			(layer "F.SilkS")
		)
		(fp_rect
			(start -0.9652 1.778)
			(end 0.9652 -1.778)
			(stroke
				(width 0)
				(type default)
			)
			(fill no)
			(layer "F.CrtYd")
		)
		(fp_poly
			(pts
				(xy -0.9652 -1.778) (xy 0.9652 -1.778) (xy 0.9652 1.778) (xy -0.9652 1.778)
			)
			(stroke
				(width 0)
				(type default)
			)
			(fill no)
			(layer "F.Fab")
		)
		(pad "1" smd rect
			(at 0 -0.9652 180)
			(size 1.397 1.143)
			(layers "F.Cu" "F.Mask" "F.Paste")
			(net "P1V8_E")
		)
		(pad "2" smd rect
			(at 0 0.9652 180)
			(size 1.397 1.143)
			(layers "F.Cu" "F.Mask" "F.Paste")
			(net "GND")
		)
	)
	(footprint ""
		(layer "F.Cu")
		(at 212.598 -217.932 -90)
		(property "Reference" "R685"
			(at 0 0 270)
			(layer "F.SilkS")
			(hide yes)
			(effects
				(font
					(size 1.27 1.27)
				)
			)
		)
		(property "Value" "0R2J-2-GP"
			(at 0.064008 -3.993896 270)
			(unlocked yes)
			(layer "F.Fab")
			(hide yes)
			(effects
				(font
					(size 1.016 1.016)
					(thickness 0.1524)
				)
			)
		)
		(property "Device Type" "R402H16"
			(at 0.064008 -5.517896 270)
			(unlocked yes)
			(layer "F.Fab")
			(hide yes)
			(effects
				(font
					(size 1.016 1.016)
					(thickness 0.1524)
				)
			)
		)
		(duplicate_pad_numbers_are_jumpers no)
		(fp_line
			(start -0.508 -0.9398)
			(end -0.508 0.9398)
			(stroke
				(width 0.1524)
				(type default)
			)
			(layer "F.SilkS")
		)
		(fp_line
			(start 0.508 -0.9398)
			(end -0.508 -0.9398)
			(stroke
				(width 0.1524)
				(type default)
			)
			(layer "F.SilkS")
		)
		(fp_rect
			(start -0.508 0.9398)
			(end 0.508 -0.9398)
			(stroke
				(width 0)
				(type default)
			)
			(fill no)
			(layer "F.CrtYd")
		)
		(fp_rect
			(start -0.508 0.9398)
			(end 0.508 -0.9398)
			(stroke
				(width 0)
				(type default)
			)
			(fill no)
			(layer "F.Fab")
		)
		(pad "1" smd custom
			(at 0 -0.4445 270)
			(size 0.1397 0.1397)
			(layers "F.Cu" "F.Mask" "F.Paste")
			(net "CPU_RESET_N")
			(options
				(clearance outline)
				(anchor circle)
			)
			(primitives
				(gr_poly
					(pts
						(arc
							(start -0.1778 -0.2794)
							(mid -0.249642 -0.249642)
							(end -0.2794 -0.1778)
						)
						(arc
							(start -0.2794 0.1778)
							(mid -0.249642 0.249642)
							(end -0.1778 0.2794)
						)
						(arc
							(start 0.1778 0.2794)
							(mid 0.249642 0.249642)
							(end 0.2794 0.1778)
						)
						(arc
							(start 0.2794 -0.1778)
							(mid 0.249642 -0.249642)
							(end 0.1778 -0.2794)
						)
					)
					(width 0)
					(fill yes)
				)
			)
		)
		(pad "2" smd custom
			(at 0 0.4445 270)
			(size 0.1397 0.1397)
			(layers "F.Cu" "F.Mask" "F.Paste")
			(net "DP_BMC_CPU_RST_N_U177_OUT")
			(options
				(clearance outline)
				(anchor circle)
			)
			(primitives
				(gr_poly
					(pts
						(arc
							(start -0.1778 -0.2794)
							(mid -0.249642 -0.249642)
							(end -0.2794 -0.1778)
						)
						(arc
							(start -0.2794 0.1778)
							(mid -0.249642 0.249642)
							(end -0.1778 0.2794)
						)
						(arc
							(start 0.1778 0.2794)
							(mid 0.249642 0.249642)
							(end 0.2794 0.1778)
						)
						(arc
							(start 0.2794 -0.1778)
							(mid 0.249642 -0.249642)
							(end 0.1778 -0.2794)
						)
					)
					(width 0)
					(fill yes)
				)
			)
		)
	)
	(footprint ""
		(layer "F.Cu")
		(at 60.56757 -144.1704)
		(property "Reference" "SC1285"
			(at 0 0 0)
			(layer "F.SilkS")
			(hide yes)
			(effects
				(font
					(size 1.27 1.27)
				)
			)
		)
		(property "Value" "SCD1U16V2KX-3GP"
			(at 1.1811 -2.7051 0)
			(unlocked yes)
			(layer "F.Fab")
			(hide yes)
			(effects
				(font
					(size 1.016 1.016)
					(thickness 0.1524)
				)
			)
		)
		(property "Device Type" "C402H22"
			(at 1.1811 -4.2291 0)
			(unlocked yes)
			(layer "F.Fab")
			(hide yes)
			(effects
				(font
					(size 1.016 1.016)
					(thickness 0.1524)
				)
			)
		)
		(duplicate_pad_numbers_are_jumpers no)
		(fp_rect
			(start -0.4318 0.9525)
			(end 0.4318 -0.9525)
			(stroke
				(width 0)
				(type default)
			)
			(fill no)
			(layer "F.CrtYd")
		)
		(fp_rect
			(start -0.4318 0.9525)
			(end 0.4318 -0.9525)
			(stroke
				(width 0)
				(type default)
			)
			(fill no)
			(layer "F.Fab")
		)
		(pad "1" smd custom
			(at 0 -0.4445)
			(size 0.1524 0.1524)
			(layers "F.Cu" "F.Mask" "F.Paste")
			(net "P1V8_E")
			(options
				(clearance outline)
				(anchor circle)
			)
			(primitives
				(gr_poly
					(pts
						(arc
							(start 0.3048 -0.2032)
							(mid 0.275042 -0.275042)
							(end 0.2032 -0.3048)
						)
						(arc
							(start -0.2032 -0.3048)
							(mid -0.275042 -0.275042)
							(end -0.3048 -0.2032)
						)
						(arc
							(start -0.3048 0.2032)
							(mid -0.275042 0.275042)
							(end -0.2032 0.3048)
						)
						(arc
							(start 0.2032 0.3048)
							(mid 0.275042 0.275042)
							(end 0.3048 0.2032)
						)
					)
					(width 0)
					(fill yes)
				)
			)
		)
		(pad "2" smd custom
			(at 0 0.4445)
			(size 0.1524 0.1524)
			(layers "F.Cu" "F.Mask" "F.Paste")
			(net "GND")
			(options
				(clearance outline)
				(anchor circle)
			)
			(primitives
				(gr_poly
					(pts
						(arc
							(start 0.3048 -0.2032)
							(mid 0.275042 -0.275042)
							(end 0.2032 -0.3048)
						)
						(arc
							(start -0.2032 -0.3048)
							(mid -0.275042 -0.275042)
							(end -0.3048 -0.2032)
						)
						(arc
							(start -0.3048 0.2032)
							(mid -0.275042 0.275042)
							(end -0.2032 0.3048)
						)
						(arc
							(start 0.2032 0.3048)
							(mid 0.275042 0.275042)
							(end 0.3048 0.2032)
						)
					)
					(width 0)
					(fill yes)
				)
			)
		)
	)
	(footprint ""
		(layer "F.Cu")
		(at 191.135 -122.682 90)
		(property "Reference" "Q77"
			(at 0 0 90)
			(layer "F.SilkS")
			(hide yes)
			(effects
				(font
					(size 1.27 1.27)
				)
			)
		)
		(property "Value" "MMBT3904TT1G-GP"
			(at 0 -9.7282 90)
			(unlocked yes)
			(layer "F.Fab")
			(hide yes)
			(effects
				(font
					(size 1.016 1.016)
					(thickness 0.1524)
				)
			)
		)
		(property "Device Type" "SC75CBE1D6H36"
			(at 0 -11.6332 90)
			(unlocked yes)
			(layer "F.Fab")
			(hide yes)
			(effects
				(font
					(size 1.016 1.016)
					(thickness 0.1524)
				)
			)
		)
		(duplicate_pad_numbers_are_jumpers no)
		(fp_line
			(start 0.9652 -1.3716)
			(end -0.9652 -1.3716)
			(stroke
				(width 0.1524)
				(type default)
			)
			(layer "F.SilkS")
		)
		(fp_line
			(start -0.9652 -1.3716)
			(end -0.9652 1.3716)
			(stroke
				(width 0.1524)
				(type default)
			)
			(layer "F.SilkS")
		)
		(fp_line
			(start 0.9652 1.3716)
			(end 0.9652 -1.3716)
			(stroke
				(width 0.1524)
				(type default)
			)
			(layer "F.SilkS")
		)
		(fp_line
			(start -0.9652 1.3716)
			(end 0.9652 1.3716)
			(stroke
				(width 0.1524)
				(type default)
			)
			(layer "F.SilkS")
		)
		(fp_rect
			(start -1.0414 1.4478)
			(end 1.0414 -1.4478)
			(stroke
				(width 0)
				(type default)
			)
			(fill no)
			(layer "F.CrtYd")
		)
		(fp_poly
			(pts
				(xy -1.0414 -1.4478) (xy 1.0414 -1.4478) (xy 1.0414 1.4478) (xy -1.0414 1.4478)
			)
			(stroke
				(width 0)
				(type default)
			)
			(fill no)
			(layer "F.Fab")
		)
		(pad "B" smd custom
			(at -0.508 0.7112 90)
			(size 0.127 0.127)
			(layers "F.Cu" "F.Mask" "F.Paste")
			(net "P1V8_E_B")
			(options
				(clearance outline)
				(anchor circle)
			)
			(primitives
				(gr_poly
					(pts
						(arc
							(start -0.044958 0.4572)
							(mid -0.192463 0.399794)
							(end -0.254 0.254)
						)
						(xy -0.254 -0.254)
						(arc
							(start -0.253746 -0.254)
							(mid -0.192968 -0.398936)
							(end -0.04699 -0.4572)
						)
						(arc
							(start 0.04699 -0.4572)
							(mid 0.192989 -0.398958)
							(end 0.253746 -0.254)
						)
						(xy 0.254 -0.254)
						(arc
							(start 0.254 0.254)
							(mid 0.192404 0.399734)
							(end 0.044958 0.4572)
						)
					)
					(width 0)
					(fill yes)
				)
			)
		)
		(pad "C" smd custom
			(at 0 -0.7112 90)
			(size 0.127 0.127)
			(layers "F.Cu" "F.Mask" "F.Paste")
			(net "P3V3_STBY_R2")
			(options
				(clearance outline)
				(anchor circle)
			)
			(primitives
				(gr_poly
					(pts
						(arc
							(start -0.044958 0.4572)
							(mid -0.192463 0.399794)
							(end -0.254 0.254)
						)
						(xy -0.254 -0.254)
						(arc
							(start -0.253746 -0.254)
							(mid -0.192968 -0.398936)
							(end -0.04699 -0.4572)
						)
						(arc
							(start 0.04699 -0.4572)
							(mid 0.192989 -0.398958)
							(end 0.253746 -0.254)
						)
						(xy 0.254 -0.254)
						(arc
							(start 0.254 0.254)
							(mid 0.192404 0.399734)
							(end 0.044958 0.4572)
						)
					)
					(width 0)
					(fill yes)
				)
			)
		)
		(pad "E" smd custom
			(at 0.508 0.7112 90)
			(size 0.127 0.127)
			(layers "F.Cu" "F.Mask" "F.Paste")
			(net "GND")
			(options
				(clearance outline)
				(anchor circle)
			)
			(primitives
				(gr_poly
					(pts
						(arc
							(start -0.044958 0.4572)
							(mid -0.192463 0.399794)
							(end -0.254 0.254)
						)
						(xy -0.254 -0.254)
						(arc
							(start -0.253746 -0.254)
							(mid -0.192968 -0.398936)
							(end -0.04699 -0.4572)
						)
						(arc
							(start 0.04699 -0.4572)
							(mid 0.192989 -0.398958)
							(end 0.253746 -0.254)
						)
						(xy 0.254 -0.254)
						(arc
							(start 0.254 0.254)
							(mid 0.192404 0.399734)
							(end 0.044958 0.4572)
						)
					)
					(width 0)
					(fill yes)
				)
			)
		)
	)
	(footprint ""
		(layer "F.Cu")
		(at 9.856216 -226.62388 180)
		(property "Reference" "R518"
			(at 0 0 180)
			(layer "F.SilkS")
			(hide yes)
			(effects
				(font
					(size 1.27 1.27)
				)
			)
		)
		(property "Value" "27KR2F-L-GP"
			(at 0.064008 -3.993896 180)
			(unlocked yes)
			(layer "F.Fab")
			(hide yes)
			(effects
				(font
					(size 1.016 1.016)
					(thickness 0.1524)
				)
			)
		)
		(property "Device Type" "R402H16"
			(at 0.064008 -5.517896 180)
			(unlocked yes)
			(layer "F.Fab")
			(hide yes)
			(effects
				(font
					(size 1.016 1.016)
					(thickness 0.1524)
				)
			)
		)
		(duplicate_pad_numbers_are_jumpers no)
		(fp_line
			(start 0.508 -0.9398)
			(end -0.508 -0.9398)
			(stroke
				(width 0.1524)
				(type default)
			)
			(layer "F.SilkS")
		)
		(fp_line
			(start -0.508 -0.9398)
			(end -0.508 0.9398)
			(stroke
				(width 0.1524)
				(type default)
			)
			(layer "F.SilkS")
		)
		(fp_rect
			(start -0.508 0.9398)
			(end 0.508 -0.9398)
			(stroke
				(width 0)
				(type default)
			)
			(fill no)
			(layer "F.CrtYd")
		)
		(fp_rect
			(start -0.508 0.9398)
			(end 0.508 -0.9398)
			(stroke
				(width 0)
				(type default)
			)
			(fill no)
			(layer "F.Fab")
		)
		(pad "1" smd custom
			(at 0 -0.4445 180)
			(size 0.1397 0.1397)
			(layers "F.Cu" "F.Mask" "F.Paste")
			(net "P12V_PCIE")
			(options
				(clearance outline)
				(anchor circle)
			)
			(primitives
				(gr_poly
					(pts
						(arc
							(start -0.1778 -0.2794)
							(mid -0.249642 -0.249642)
							(end -0.2794 -0.1778)
						)
						(arc
							(start -0.2794 0.1778)
							(mid -0.249642 0.249642)
							(end -0.1778 0.2794)
						)
						(arc
							(start 0.1778 0.2794)
							(mid 0.249642 0.249642)
							(end 0.2794 0.1778)
						)
						(arc
							(start 0.2794 -0.1778)
							(mid 0.249642 -0.249642)
							(end 0.1778 -0.2794)
						)
					)
					(width 0)
					(fill yes)
				)
			)
		)
		(pad "2" smd custom
			(at 0 0.4445 180)
			(size 0.1397 0.1397)
			(layers "F.Cu" "F.Mask" "F.Paste")
			(net "PCIE_MATED#_A")
			(options
				(clearance outline)
				(anchor circle)
			)
			(primitives
				(gr_poly
					(pts
						(arc
							(start -0.1778 -0.2794)
							(mid -0.249642 -0.249642)
							(end -0.2794 -0.1778)
						)
						(arc
							(start -0.2794 0.1778)
							(mid -0.249642 0.249642)
							(end -0.1778 0.2794)
						)
						(arc
							(start 0.1778 0.2794)
							(mid 0.249642 0.249642)
							(end 0.2794 0.1778)
						)
						(arc
							(start 0.2794 -0.1778)
							(mid 0.249642 -0.249642)
							(end 0.1778 -0.2794)
						)
					)
					(width 0)
					(fill yes)
				)
			)
		)
	)
	(footprint ""
		(layer "F.Cu")
		(at 45.654722 -139.546584 180)
		(property "Reference" "SU76"
			(at 0 0 180)
			(layer "F.SilkS")
			(hide yes)
			(effects
				(font
					(size 1.27 1.27)
				)
			)
		)
		(property "Value" "SOLVC2G07DBVR-GP"
			(at -0.0254 -11.9634 180)
			(unlocked yes)
			(layer "F.Fab")
			(hide yes)
			(effects
				(font
					(size 1.016 1.016)
					(thickness 0.1524)
				)
			)
		)
		(property "Device Type" "SOT-6H58"
			(at -0.0254 -13.5636 180)
			(unlocked yes)
			(layer "F.Fab")
			(hide yes)
			(effects
				(font
					(size 1.016 1.016)
					(thickness 0.1524)
				)
			)
		)
		(duplicate_pad_numbers_are_jumpers no)
		(fp_line
			(start 1.7145 0.5842)
			(end 1.7145 -0.5842)
			(stroke
				(width 0.1524)
				(type default)
			)
			(layer "F.SilkS")
		)
		(fp_line
			(start 1.7145 -0.5842)
			(end -1.9685 -0.5842)
			(stroke
				(width 0.1524)
				(type default)
			)
			(layer "F.SilkS")
		)
		(fp_line
			(start -1.5621 0)
			(end -1.9685 0.4064)
			(stroke
				(width 0.1524)
				(type default)
			)
			(layer "F.SilkS")
		)
		(fp_line
			(start -1.9685 0.5842)
			(end 1.7145 0.5842)
			(stroke
				(width 0.1524)
				(type default)
			)
			(layer "F.SilkS")
		)
		(fp_line
			(start -1.9685 0.5842)
			(end -1.9685 2.3622)
			(stroke
				(width 0.508)
				(type default)
			)
			(layer "F.SilkS")
		)
		(fp_line
			(start -1.9685 -0.4064)
			(end -1.5621 0)
			(stroke
				(width 0.1524)
				(type default)
			)
			(layer "F.SilkS")
		)
		(fp_line
			(start -1.9685 -0.5842)
			(end -1.9685 0.5842)
			(stroke
				(width 0.1524)
				(type default)
			)
			(layer "F.SilkS")
		)
		(fp_poly
			(pts
				(xy -1.27 -0.635) (xy 1.27 -0.635) (xy 1.27 0.635) (xy -1.27 0.635)
			)
			(stroke
				(width 0)
				(type default)
			)
			(fill yes)
			(layer "F.SilkS")
		)
		(fp_rect
			(start -1.9685 2.3622)
			(end 1.9685 -2.3622)
			(stroke
				(width 0)
				(type default)
			)
			(fill no)
			(layer "F.CrtYd")
		)
		(fp_poly
			(pts
				(xy -1.9685 -2.3622) (xy 1.9685 -2.3622) (xy 1.9685 2.3622) (xy -1.9685 2.3622)
			)
			(stroke
				(width 0)
				(type default)
			)
			(fill no)
			(layer "F.Fab")
		)
		(pad "1" smd rect
			(at -0.9525 1.3462 180)
			(size 0.5842 1.016)
			(layers "F.Cu" "F.Mask" "F.Paste")
			(net "EXP_RESET_N")
		)
		(pad "2" smd rect
			(at 0 1.3462 180)
			(size 0.5842 1.016)
			(layers "F.Cu" "F.Mask" "F.Paste")
			(net "GND")
		)
		(pad "3" smd rect
			(at 0.9525 1.3462 180)
			(size 0.5842 1.016)
			(layers "F.Cu" "F.Mask" "F.Paste")
			(net "ICE_RESET_N")
		)
		(pad "4" smd rect
			(at 0.9525 -1.3462 180)
			(size 0.5842 1.016)
			(layers "F.Cu" "F.Mask" "F.Paste")
			(net "RESET_AND_N")
		)
		(pad "5" smd rect
			(at 0 -1.3462 180)
			(size 0.5842 1.016)
			(layers "F.Cu" "F.Mask" "F.Paste")
			(net "P1V8_STBY")
		)
		(pad "6" smd rect
			(at -0.9525 -1.3462 180)
			(size 0.5842 1.016)
			(layers "F.Cu" "F.Mask" "F.Paste")
			(net "RESET_AND_N")
		)
	)
	(footprint ""
		(layer "F.Cu")
		(at 99.32797 -76.454 180)
		(property "Reference" "SR771"
			(at 0 0 180)
			(layer "F.SilkS")
			(hide yes)
			(effects
				(font
					(size 1.27 1.27)
				)
			)
		)
		(property "Value" "4K75R2F-1-GP"
			(at 0.064008 -3.993896 180)
			(unlocked yes)
			(layer "F.Fab")
			(hide yes)
			(effects
				(font
					(size 1.016 1.016)
					(thickness 0.1524)
				)
			)
		)
		(property "Device Type" "R402H16"
			(at 0.064008 -5.517896 180)
			(unlocked yes)
			(layer "F.Fab")
			(hide yes)
			(effects
				(font
					(size 1.016 1.016)
					(thickness 0.1524)
				)
			)
		)
		(duplicate_pad_numbers_are_jumpers no)
		(fp_line
			(start 0.508 -0.9398)
			(end -0.508 -0.9398)
			(stroke
				(width 0.1524)
				(type default)
			)
			(layer "F.SilkS")
		)
		(fp_line
			(start -0.508 -0.9398)
			(end -0.508 0.9398)
			(stroke
				(width 0.1524)
				(type default)
			)
			(layer "F.SilkS")
		)
		(fp_rect
			(start -0.508 0.9398)
			(end 0.508 -0.9398)
			(stroke
				(width 0)
				(type default)
			)
			(fill no)
			(layer "F.CrtYd")
		)
		(fp_rect
			(start -0.508 0.9398)
			(end 0.508 -0.9398)
			(stroke
				(width 0)
				(type default)
			)
			(fill no)
			(layer "F.Fab")
		)
		(pad "1" smd custom
			(at 0 -0.4445 180)
			(size 0.1397 0.1397)
			(layers "F.Cu" "F.Mask" "F.Paste")
			(net "P1V8_E")
			(options
				(clearance outline)
				(anchor circle)
			)
			(primitives
				(gr_poly
					(pts
						(arc
							(start -0.1778 -0.2794)
							(mid -0.249642 -0.249642)
							(end -0.2794 -0.1778)
						)
						(arc
							(start -0.2794 0.1778)
							(mid -0.249642 0.249642)
							(end -0.1778 0.2794)
						)
						(arc
							(start 0.1778 0.2794)
							(mid 0.249642 0.249642)
							(end 0.2794 0.1778)
						)
						(arc
							(start 0.2794 -0.1778)
							(mid 0.249642 -0.249642)
							(end 0.1778 -0.2794)
						)
					)
					(width 0)
					(fill yes)
				)
			)
		)
		(pad "2" smd custom
			(at 0 0.4445 180)
			(size 0.1397 0.1397)
			(layers "F.Cu" "F.Mask" "F.Paste")
			(net "SXP_ACTIVE_0")
			(options
				(clearance outline)
				(anchor circle)
			)
			(primitives
				(gr_poly
					(pts
						(arc
							(start -0.1778 -0.2794)
							(mid -0.249642 -0.249642)
							(end -0.2794 -0.1778)
						)
						(arc
							(start -0.2794 0.1778)
							(mid -0.249642 0.249642)
							(end -0.1778 0.2794)
						)
						(arc
							(start 0.1778 0.2794)
							(mid 0.249642 0.249642)
							(end 0.2794 0.1778)
						)
						(arc
							(start 0.2794 -0.1778)
							(mid 0.249642 -0.249642)
							(end 0.1778 -0.2794)
						)
					)
					(width 0)
					(fill yes)
				)
			)
		)
	)
	(footprint ""
		(layer "F.Cu")
		(at 220.599 -121.158 90)
		(property "Reference" "Q80"
			(at 0 0 90)
			(layer "F.SilkS")
			(hide yes)
			(effects
				(font
					(size 1.27 1.27)
				)
			)
		)
		(property "Value" "MMBT3904TT1G-GP"
			(at 0 -9.7282 90)
			(unlocked yes)
			(layer "F.Fab")
			(hide yes)
			(effects
				(font
					(size 1.016 1.016)
					(thickness 0.1524)
				)
			)
		)
		(property "Device Type" "SC75CBE1D6H36"
			(at 0 -11.6332 90)
			(unlocked yes)
			(layer "F.Fab")
			(hide yes)
			(effects
				(font
					(size 1.016 1.016)
					(thickness 0.1524)
				)
			)
		)
		(duplicate_pad_numbers_are_jumpers no)
		(fp_line
			(start 0.9652 -1.3716)
			(end -0.9652 -1.3716)
			(stroke
				(width 0.1524)
				(type default)
			)
			(layer "F.SilkS")
		)
		(fp_line
			(start -0.9652 -1.3716)
			(end -0.9652 1.3716)
			(stroke
				(width 0.1524)
				(type default)
			)
			(layer "F.SilkS")
		)
		(fp_line
			(start 0.9652 1.3716)
			(end 0.9652 -1.3716)
			(stroke
				(width 0.1524)
				(type default)
			)
			(layer "F.SilkS")
		)
		(fp_line
			(start -0.9652 1.3716)
			(end 0.9652 1.3716)
			(stroke
				(width 0.1524)
				(type default)
			)
			(layer "F.SilkS")
		)
		(fp_rect
			(start -1.0414 1.4478)
			(end 1.0414 -1.4478)
			(stroke
				(width 0)
				(type default)
			)
			(fill no)
			(layer "F.CrtYd")
		)
		(fp_poly
			(pts
				(xy -1.0414 -1.4478) (xy 1.0414 -1.4478) (xy 1.0414 1.4478) (xy -1.0414 1.4478)
			)
			(stroke
				(width 0)
				(type default)
			)
			(fill no)
			(layer "F.Fab")
		)
		(pad "B" smd custom
			(at -0.508 0.7112 90)
			(size 0.127 0.127)
			(layers "F.Cu" "F.Mask" "F.Paste")
			(net "P1V8_C_B")
			(options
				(clearance outline)
				(anchor circle)
			)
			(primitives
				(gr_poly
					(pts
						(arc
							(start -0.044958 0.4572)
							(mid -0.192463 0.399794)
							(end -0.254 0.254)
						)
						(xy -0.254 -0.254)
						(arc
							(start -0.253746 -0.254)
							(mid -0.192968 -0.398936)
							(end -0.04699 -0.4572)
						)
						(arc
							(start 0.04699 -0.4572)
							(mid 0.192989 -0.398958)
							(end 0.253746 -0.254)
						)
						(xy 0.254 -0.254)
						(arc
							(start 0.254 0.254)
							(mid 0.192404 0.399734)
							(end 0.044958 0.4572)
						)
					)
					(width 0)
					(fill yes)
				)
			)
		)
		(pad "C" smd custom
			(at 0 -0.7112 90)
			(size 0.127 0.127)
			(layers "F.Cu" "F.Mask" "F.Paste")
			(net "P3V3_STBY_R3")
			(options
				(clearance outline)
				(anchor circle)
			)
			(primitives
				(gr_poly
					(pts
						(arc
							(start -0.044958 0.4572)
							(mid -0.192463 0.399794)
							(end -0.254 0.254)
						)
						(xy -0.254 -0.254)
						(arc
							(start -0.253746 -0.254)
							(mid -0.192968 -0.398936)
							(end -0.04699 -0.4572)
						)
						(arc
							(start 0.04699 -0.4572)
							(mid 0.192989 -0.398958)
							(end 0.253746 -0.254)
						)
						(xy 0.254 -0.254)
						(arc
							(start 0.254 0.254)
							(mid 0.192404 0.399734)
							(end 0.044958 0.4572)
						)
					)
					(width 0)
					(fill yes)
				)
			)
		)
		(pad "E" smd custom
			(at 0.508 0.7112 90)
			(size 0.127 0.127)
			(layers "F.Cu" "F.Mask" "F.Paste")
			(net "GND")
			(options
				(clearance outline)
				(anchor circle)
			)
			(primitives
				(gr_poly
					(pts
						(arc
							(start -0.044958 0.4572)
							(mid -0.192463 0.399794)
							(end -0.254 0.254)
						)
						(xy -0.254 -0.254)
						(arc
							(start -0.253746 -0.254)
							(mid -0.192968 -0.398936)
							(end -0.04699 -0.4572)
						)
						(arc
							(start 0.04699 -0.4572)
							(mid 0.192989 -0.398958)
							(end 0.253746 -0.254)
						)
						(xy 0.254 -0.254)
						(arc
							(start 0.254 0.254)
							(mid 0.192404 0.399734)
							(end 0.044958 0.4572)
						)
					)
					(width 0)
					(fill yes)
				)
			)
		)
	)
	(footprint ""
		(layer "F.Cu")
		(at 257.302 -136.779)
		(property "Reference" "R7902"
			(at 0 0 0)
			(layer "F.SilkS")
			(hide yes)
			(effects
				(font
					(size 1.27 1.27)
				)
			)
		)
		(property "Value" "0R2J-2-GP"
			(at 0.064008 -3.993896 0)
			(unlocked yes)
			(layer "F.Fab")
			(hide yes)
			(effects
				(font
					(size 1.016 1.016)
					(thickness 0.1524)
				)
			)
		)
		(property "Device Type" "R402H16"
			(at 0.064008 -5.517896 0)
			(unlocked yes)
			(layer "F.Fab")
			(hide yes)
			(effects
				(font
					(size 1.016 1.016)
					(thickness 0.1524)
				)
			)
		)
		(duplicate_pad_numbers_are_jumpers no)
		(fp_line
			(start -0.508 -0.9398)
			(end -0.508 0.9398)
			(stroke
				(width 0.1524)
				(type default)
			)
			(layer "F.SilkS")
		)
		(fp_line
			(start 0.508 -0.9398)
			(end -0.508 -0.9398)
			(stroke
				(width 0.1524)
				(type default)
			)
			(layer "F.SilkS")
		)
		(fp_rect
			(start -0.508 0.9398)
			(end 0.508 -0.9398)
			(stroke
				(width 0)
				(type default)
			)
			(fill no)
			(layer "F.CrtYd")
		)
		(fp_rect
			(start -0.508 0.9398)
			(end 0.508 -0.9398)
			(stroke
				(width 0)
				(type default)
			)
			(fill no)
			(layer "F.Fab")
		)
		(pad "1" smd custom
			(at 0 -0.4445)
			(size 0.1397 0.1397)
			(layers "F.Cu" "F.Mask" "F.Paste")
			(net "CPU_S_TXD")
			(options
				(clearance outline)
				(anchor circle)
			)
			(primitives
				(gr_poly
					(pts
						(arc
							(start -0.1778 -0.2794)
							(mid -0.249642 -0.249642)
							(end -0.2794 -0.1778)
						)
						(arc
							(start -0.2794 0.1778)
							(mid -0.249642 0.249642)
							(end -0.1778 0.2794)
						)
						(arc
							(start 0.1778 0.2794)
							(mid 0.249642 0.249642)
							(end 0.2794 0.1778)
						)
						(arc
							(start 0.2794 -0.1778)
							(mid 0.249642 -0.249642)
							(end 0.1778 -0.2794)
						)
					)
					(width 0)
					(fill yes)
				)
			)
		)
		(pad "2" smd custom
			(at 0 0.4445)
			(size 0.1397 0.1397)
			(layers "F.Cu" "F.Mask" "F.Paste")
			(net "CPU_U192_PIN6_TX")
			(options
				(clearance outline)
				(anchor circle)
			)
			(primitives
				(gr_poly
					(pts
						(arc
							(start -0.1778 -0.2794)
							(mid -0.249642 -0.249642)
							(end -0.2794 -0.1778)
						)
						(arc
							(start -0.2794 0.1778)
							(mid -0.249642 0.249642)
							(end -0.1778 0.2794)
						)
						(arc
							(start 0.1778 0.2794)
							(mid 0.249642 0.249642)
							(end 0.2794 0.1778)
						)
						(arc
							(start 0.2794 -0.1778)
							(mid 0.249642 -0.249642)
							(end 0.1778 -0.2794)
						)
					)
					(width 0)
					(fill yes)
				)
			)
		)
	)
	(footprint ""
		(layer "F.Cu")
		(at 294.513 -161.544 180)
		(property "Reference" "R283"
			(at 0 0 180)
			(layer "F.SilkS")
			(hide yes)
			(effects
				(font
					(size 1.27 1.27)
				)
			)
		)
		(property "Value" "0R2J-2-GP"
			(at 0.064008 -3.993896 180)
			(unlocked yes)
			(layer "F.Fab")
			(hide yes)
			(effects
				(font
					(size 1.016 1.016)
					(thickness 0.1524)
				)
			)
		)
		(property "Device Type" "R402H16"
			(at 0.064008 -5.517896 180)
			(unlocked yes)
			(layer "F.Fab")
			(hide yes)
			(effects
				(font
					(size 1.016 1.016)
					(thickness 0.1524)
				)
			)
		)
		(duplicate_pad_numbers_are_jumpers no)
		(fp_line
			(start 0.508 -0.9398)
			(end -0.508 -0.9398)
			(stroke
				(width 0.1524)
				(type default)
			)
			(layer "F.SilkS")
		)
		(fp_line
			(start -0.508 -0.9398)
			(end -0.508 0.9398)
			(stroke
				(width 0.1524)
				(type default)
			)
			(layer "F.SilkS")
		)
		(fp_rect
			(start -0.508 0.9398)
			(end 0.508 -0.9398)
			(stroke
				(width 0)
				(type default)
			)
			(fill no)
			(layer "F.CrtYd")
		)
		(fp_rect
			(start -0.508 0.9398)
			(end 0.508 -0.9398)
			(stroke
				(width 0)
				(type default)
			)
			(fill no)
			(layer "F.Fab")
		)
		(pad "1" smd custom
			(at 0 -0.4445 180)
			(size 0.1397 0.1397)
			(layers "F.Cu" "F.Mask" "F.Paste")
			(net "RMII_BMC_PHY_TXD0")
			(options
				(clearance outline)
				(anchor circle)
			)
			(primitives
				(gr_poly
					(pts
						(arc
							(start -0.1778 -0.2794)
							(mid -0.249642 -0.249642)
							(end -0.2794 -0.1778)
						)
						(arc
							(start -0.2794 0.1778)
							(mid -0.249642 0.249642)
							(end -0.1778 0.2794)
						)
						(arc
							(start 0.1778 0.2794)
							(mid 0.249642 0.249642)
							(end 0.2794 0.1778)
						)
						(arc
							(start 0.2794 -0.1778)
							(mid 0.249642 -0.249642)
							(end 0.1778 -0.2794)
						)
					)
					(width 0)
					(fill yes)
				)
			)
		)
		(pad "2" smd custom
			(at 0 0.4445 180)
			(size 0.1397 0.1397)
			(layers "F.Cu" "F.Mask" "F.Paste")
			(net "RMII0_BMC_C_PHY_TXD0")
			(options
				(clearance outline)
				(anchor circle)
			)
			(primitives
				(gr_poly
					(pts
						(arc
							(start -0.1778 -0.2794)
							(mid -0.249642 -0.249642)
							(end -0.2794 -0.1778)
						)
						(arc
							(start -0.2794 0.1778)
							(mid -0.249642 0.249642)
							(end -0.1778 0.2794)
						)
						(arc
							(start 0.1778 0.2794)
							(mid 0.249642 0.249642)
							(end 0.2794 0.1778)
						)
						(arc
							(start 0.2794 -0.1778)
							(mid 0.249642 -0.249642)
							(end 0.1778 -0.2794)
						)
					)
					(width 0)
					(fill yes)
				)
			)
		)
	)
	(footprint ""
		(layer "F.Cu")
		(at 111.76 -60.452)
		(property "Reference" "SR689"
			(at 0 0 0)
			(layer "F.SilkS")
			(hide yes)
			(effects
				(font
					(size 1.27 1.27)
				)
			)
		)
		(property "Value" "10KR2F-2-GP"
			(at 0.064008 -3.993896 0)
			(unlocked yes)
			(layer "F.Fab")
			(hide yes)
			(effects
				(font
					(size 1.016 1.016)
					(thickness 0.1524)
				)
			)
		)
		(property "Device Type" "R402H16"
			(at 0.064008 -5.517896 0)
			(unlocked yes)
			(layer "F.Fab")
			(hide yes)
			(effects
				(font
					(size 1.016 1.016)
					(thickness 0.1524)
				)
			)
		)
		(duplicate_pad_numbers_are_jumpers no)
		(fp_line
			(start -0.508 -0.9398)
			(end -0.508 0.9398)
			(stroke
				(width 0.1524)
				(type default)
			)
			(layer "F.SilkS")
		)
		(fp_line
			(start 0.508 -0.9398)
			(end -0.508 -0.9398)
			(stroke
				(width 0.1524)
				(type default)
			)
			(layer "F.SilkS")
		)
		(fp_rect
			(start -0.508 0.9398)
			(end 0.508 -0.9398)
			(stroke
				(width 0)
				(type default)
			)
			(fill no)
			(layer "F.CrtYd")
		)
		(fp_rect
			(start -0.508 0.9398)
			(end 0.508 -0.9398)
			(stroke
				(width 0)
				(type default)
			)
			(fill no)
			(layer "F.Fab")
		)
		(pad "1" smd custom
			(at 0 -0.4445)
			(size 0.1397 0.1397)
			(layers "F.Cu" "F.Mask" "F.Paste")
			(net "P1V8_C")
			(options
				(clearance outline)
				(anchor circle)
			)
			(primitives
				(gr_poly
					(pts
						(arc
							(start -0.1778 -0.2794)
							(mid -0.249642 -0.249642)
							(end -0.2794 -0.1778)
						)
						(arc
							(start -0.2794 0.1778)
							(mid -0.249642 0.249642)
							(end -0.1778 0.2794)
						)
						(arc
							(start 0.1778 0.2794)
							(mid 0.249642 0.249642)
							(end 0.2794 0.1778)
						)
						(arc
							(start 0.2794 -0.1778)
							(mid 0.249642 -0.249642)
							(end 0.1778 -0.2794)
						)
					)
					(width 0)
					(fill yes)
				)
			)
		)
		(pad "2" smd custom
			(at 0 0.4445)
			(size 0.1397 0.1397)
			(layers "F.Cu" "F.Mask" "F.Paste")
			(net "XM_ADDR_0")
			(options
				(clearance outline)
				(anchor circle)
			)
			(primitives
				(gr_poly
					(pts
						(arc
							(start -0.1778 -0.2794)
							(mid -0.249642 -0.249642)
							(end -0.2794 -0.1778)
						)
						(arc
							(start -0.2794 0.1778)
							(mid -0.249642 0.249642)
							(end -0.1778 0.2794)
						)
						(arc
							(start 0.1778 0.2794)
							(mid 0.249642 0.249642)
							(end 0.2794 0.1778)
						)
						(arc
							(start 0.2794 -0.1778)
							(mid 0.249642 -0.249642)
							(end 0.1778 -0.2794)
						)
					)
					(width 0)
					(fill yes)
				)
			)
		)
	)
	(footprint ""
		(layer "F.Cu")
		(at 94.01937 -117.602)
		(property "Reference" "TP266"
			(at 0 0 0)
			(layer "F.SilkS")
			(hide yes)
			(effects
				(font
					(size 1.27 1.27)
				)
			)
		)
		(property "Value" "TPAD28"
			(at 0.0127 -1.8034 0)
			(unlocked yes)
			(layer "F.Fab")
			(hide yes)
			(effects
				(font
					(size 1.016 1.016)
					(thickness 0.1524)
				)
			)
		)
		(property "Device Type" "TPAD28"
			(at 0.0127 -3.3274 0)
			(unlocked yes)
			(layer "F.Fab")
			(hide yes)
			(effects
				(font
					(size 1.016 1.016)
					(thickness 0.1524)
				)
			)
		)
		(duplicate_pad_numbers_are_jumpers no)
		(fp_poly
			(pts
				(arc
					(start 0.3556 0)
					(mid -0.3556 0)
					(end 0.3556 0)
				)
			)
			(stroke
				(width 0)
				(type default)
			)
			(fill no)
			(layer "F.CrtYd")
		)
		(fp_poly
			(pts
				(arc
					(start 0.6096 0)
					(mid -0.6096 0)
					(end 0.6096 0)
				)
			)
			(stroke
				(width 0)
				(type default)
			)
			(fill no)
			(layer "F.Fab")
		)
		(pad "1" smd circle
			(at 0 0)
			(size 0.7112 0.7112)
			(layers "F.Cu" "F.Mask" "F.Paste")
			(net "SIO_LOAD_OUT")
		)
	)
	(footprint ""
		(layer "F.Cu")
		(at 184.404 -225.298 90)
		(property "Reference" "R1583"
			(at 0 0 90)
			(layer "F.SilkS")
			(hide yes)
			(effects
				(font
					(size 1.27 1.27)
				)
			)
		)
		(property "Value" "0R2J-2-GP"
			(at 0.064008 -3.993896 90)
			(unlocked yes)
			(layer "F.Fab")
			(hide yes)
			(effects
				(font
					(size 1.016 1.016)
					(thickness 0.1524)
				)
			)
		)
		(property "Device Type" "R402H16"
			(at 0.064008 -5.517896 90)
			(unlocked yes)
			(layer "F.Fab")
			(hide yes)
			(effects
				(font
					(size 1.016 1.016)
					(thickness 0.1524)
				)
			)
		)
		(duplicate_pad_numbers_are_jumpers no)
		(fp_line
			(start 0.508 -0.9398)
			(end -0.508 -0.9398)
			(stroke
				(width 0.1524)
				(type default)
			)
			(layer "F.SilkS")
		)
		(fp_line
			(start -0.508 -0.9398)
			(end -0.508 0.9398)
			(stroke
				(width 0.1524)
				(type default)
			)
			(layer "F.SilkS")
		)
		(fp_rect
			(start -0.508 0.9398)
			(end 0.508 -0.9398)
			(stroke
				(width 0)
				(type default)
			)
			(fill no)
			(layer "F.CrtYd")
		)
		(fp_rect
			(start -0.508 0.9398)
			(end 0.508 -0.9398)
			(stroke
				(width 0)
				(type default)
			)
			(fill no)
			(layer "F.Fab")
		)
		(pad "1" smd custom
			(at 0 -0.4445 90)
			(size 0.1397 0.1397)
			(layers "F.Cu" "F.Mask" "F.Paste")
			(net "SYS_PWRBTN_N")
			(options
				(clearance outline)
				(anchor circle)
			)
			(primitives
				(gr_poly
					(pts
						(arc
							(start -0.1778 -0.2794)
							(mid -0.249642 -0.249642)
							(end -0.2794 -0.1778)
						)
						(arc
							(start -0.2794 0.1778)
							(mid -0.249642 0.249642)
							(end -0.1778 0.2794)
						)
						(arc
							(start 0.1778 0.2794)
							(mid 0.249642 0.249642)
							(end 0.2794 0.1778)
						)
						(arc
							(start 0.2794 -0.1778)
							(mid 0.249642 -0.249642)
							(end 0.1778 -0.2794)
						)
					)
					(width 0)
					(fill yes)
				)
			)
		)
		(pad "2" smd custom
			(at 0 0.4445 90)
			(size 0.1397 0.1397)
			(layers "F.Cu" "F.Mask" "F.Paste")
			(net "PWRBTN_FP_N")
			(options
				(clearance outline)
				(anchor circle)
			)
			(primitives
				(gr_poly
					(pts
						(arc
							(start -0.1778 -0.2794)
							(mid -0.249642 -0.249642)
							(end -0.2794 -0.1778)
						)
						(arc
							(start -0.2794 0.1778)
							(mid -0.249642 0.249642)
							(end -0.1778 0.2794)
						)
						(arc
							(start 0.1778 0.2794)
							(mid 0.249642 0.249642)
							(end 0.2794 0.1778)
						)
						(arc
							(start 0.2794 -0.1778)
							(mid 0.249642 -0.249642)
							(end 0.1778 -0.2794)
						)
					)
					(width 0)
					(fill yes)
				)
			)
		)
	)
	(footprint ""
		(layer "F.Cu")
		(at 274.193 -169.545 90)
		(property "Reference" "R472"
			(at 0 0 90)
			(layer "F.SilkS")
			(hide yes)
			(effects
				(font
					(size 1.27 1.27)
				)
			)
		)
		(property "Value" "10KR2F-2-GP"
			(at 0.064008 -3.993896 90)
			(unlocked yes)
			(layer "F.Fab")
			(hide yes)
			(effects
				(font
					(size 1.016 1.016)
					(thickness 0.1524)
				)
			)
		)
		(property "Device Type" "R402H16"
			(at 0.064008 -5.517896 90)
			(unlocked yes)
			(layer "F.Fab")
			(hide yes)
			(effects
				(font
					(size 1.016 1.016)
					(thickness 0.1524)
				)
			)
		)
		(duplicate_pad_numbers_are_jumpers no)
		(fp_line
			(start 0.508 -0.9398)
			(end -0.508 -0.9398)
			(stroke
				(width 0.1524)
				(type default)
			)
			(layer "F.SilkS")
		)
		(fp_line
			(start -0.508 -0.9398)
			(end -0.508 0.9398)
			(stroke
				(width 0.1524)
				(type default)
			)
			(layer "F.SilkS")
		)
		(fp_rect
			(start -0.508 0.9398)
			(end 0.508 -0.9398)
			(stroke
				(width 0)
				(type default)
			)
			(fill no)
			(layer "F.CrtYd")
		)
		(fp_rect
			(start -0.508 0.9398)
			(end 0.508 -0.9398)
			(stroke
				(width 0)
				(type default)
			)
			(fill no)
			(layer "F.Fab")
		)
		(pad "1" smd custom
			(at 0 -0.4445 90)
			(size 0.1397 0.1397)
			(layers "F.Cu" "F.Mask" "F.Paste")
			(net "P3V3_STBY")
			(options
				(clearance outline)
				(anchor circle)
			)
			(primitives
				(gr_poly
					(pts
						(arc
							(start -0.1778 -0.2794)
							(mid -0.249642 -0.249642)
							(end -0.2794 -0.1778)
						)
						(arc
							(start -0.2794 0.1778)
							(mid -0.249642 0.249642)
							(end -0.1778 0.2794)
						)
						(arc
							(start 0.1778 0.2794)
							(mid 0.249642 0.249642)
							(end 0.2794 0.1778)
						)
						(arc
							(start 0.2794 -0.1778)
							(mid 0.249642 -0.249642)
							(end 0.1778 -0.2794)
						)
					)
					(width 0)
					(fill yes)
				)
			)
		)
		(pad "2" smd custom
			(at 0 0.4445 90)
			(size 0.1397 0.1397)
			(layers "F.Cu" "F.Mask" "F.Paste")
			(net "BMC_MSB_I2C_E_ALERT_#")
			(options
				(clearance outline)
				(anchor circle)
			)
			(primitives
				(gr_poly
					(pts
						(arc
							(start -0.1778 -0.2794)
							(mid -0.249642 -0.249642)
							(end -0.2794 -0.1778)
						)
						(arc
							(start -0.2794 0.1778)
							(mid -0.249642 0.249642)
							(end -0.1778 0.2794)
						)
						(arc
							(start 0.1778 0.2794)
							(mid 0.249642 0.249642)
							(end 0.2794 0.1778)
						)
						(arc
							(start 0.2794 -0.1778)
							(mid 0.249642 -0.249642)
							(end 0.1778 -0.2794)
						)
					)
					(width 0)
					(fill yes)
				)
			)
		)
	)
	(footprint ""
		(layer "F.Cu")
		(at 348.390718 -149.837648 -90)
		(property "Reference" "R449"
			(at 0 0 270)
			(layer "F.SilkS")
			(hide yes)
			(effects
				(font
					(size 1.27 1.27)
				)
			)
		)
		(property "Value" "0R2J-2-GP"
			(at 0.064008 -3.993896 270)
			(unlocked yes)
			(layer "F.Fab")
			(hide yes)
			(effects
				(font
					(size 1.016 1.016)
					(thickness 0.1524)
				)
			)
		)
		(property "Device Type" "R402H16"
			(at 0.064008 -5.517896 270)
			(unlocked yes)
			(layer "F.Fab")
			(hide yes)
			(effects
				(font
					(size 1.016 1.016)
					(thickness 0.1524)
				)
			)
		)
		(duplicate_pad_numbers_are_jumpers no)
		(fp_line
			(start -0.508 -0.9398)
			(end -0.508 0.9398)
			(stroke
				(width 0.1524)
				(type default)
			)
			(layer "F.SilkS")
		)
		(fp_line
			(start 0.508 -0.9398)
			(end -0.508 -0.9398)
			(stroke
				(width 0.1524)
				(type default)
			)
			(layer "F.SilkS")
		)
		(fp_rect
			(start -0.508 0.9398)
			(end 0.508 -0.9398)
			(stroke
				(width 0)
				(type default)
			)
			(fill no)
			(layer "F.CrtYd")
		)
		(fp_rect
			(start -0.508 0.9398)
			(end 0.508 -0.9398)
			(stroke
				(width 0)
				(type default)
			)
			(fill no)
			(layer "F.Fab")
		)
		(pad "1" smd custom
			(at 0 -0.4445 270)
			(size 0.1397 0.1397)
			(layers "F.Cu" "F.Mask" "F.Paste")
			(net "BMC_USB2_HDP")
			(options
				(clearance outline)
				(anchor circle)
			)
			(primitives
				(gr_poly
					(pts
						(arc
							(start -0.1778 -0.2794)
							(mid -0.249642 -0.249642)
							(end -0.2794 -0.1778)
						)
						(arc
							(start -0.2794 0.1778)
							(mid -0.249642 0.249642)
							(end -0.1778 0.2794)
						)
						(arc
							(start 0.1778 0.2794)
							(mid 0.249642 0.249642)
							(end 0.2794 0.1778)
						)
						(arc
							(start 0.2794 -0.1778)
							(mid 0.249642 -0.249642)
							(end 0.1778 -0.2794)
						)
					)
					(width 0)
					(fill yes)
				)
			)
		)
		(pad "2" smd custom
			(at 0 0.4445 270)
			(size 0.1397 0.1397)
			(layers "F.Cu" "F.Mask" "F.Paste")
			(net "USB_P2_DP")
			(options
				(clearance outline)
				(anchor circle)
			)
			(primitives
				(gr_poly
					(pts
						(arc
							(start -0.1778 -0.2794)
							(mid -0.249642 -0.249642)
							(end -0.2794 -0.1778)
						)
						(arc
							(start -0.2794 0.1778)
							(mid -0.249642 0.249642)
							(end -0.1778 0.2794)
						)
						(arc
							(start 0.1778 0.2794)
							(mid 0.249642 0.249642)
							(end 0.2794 0.1778)
						)
						(arc
							(start 0.2794 -0.1778)
							(mid 0.249642 -0.249642)
							(end 0.1778 -0.2794)
						)
					)
					(width 0)
					(fill yes)
				)
			)
		)
	)
	(footprint ""
		(layer "F.Cu")
		(at 300.526958 -58.293 180)
		(property "Reference" "C283"
			(at 0 0 180)
			(layer "F.SilkS")
			(hide yes)
			(effects
				(font
					(size 1.27 1.27)
				)
			)
		)
		(property "Value" "SCD1U25V2KX-2-GP"
			(at 1.1811 -2.7051 180)
			(unlocked yes)
			(layer "F.Fab")
			(hide yes)
			(effects
				(font
					(size 1.016 1.016)
					(thickness 0.1524)
				)
			)
		)
		(property "Device Type" "C402H22"
			(at 1.1811 -4.2291 180)
			(unlocked yes)
			(layer "F.Fab")
			(hide yes)
			(effects
				(font
					(size 1.016 1.016)
					(thickness 0.1524)
				)
			)
		)
		(duplicate_pad_numbers_are_jumpers no)
		(fp_rect
			(start -0.4318 0.9525)
			(end 0.4318 -0.9525)
			(stroke
				(width 0)
				(type default)
			)
			(fill no)
			(layer "F.CrtYd")
		)
		(fp_rect
			(start -0.4318 0.9525)
			(end 0.4318 -0.9525)
			(stroke
				(width 0)
				(type default)
			)
			(fill no)
			(layer "F.Fab")
		)
		(pad "1" smd custom
			(at 0 -0.4445 180)
			(size 0.1524 0.1524)
			(layers "F.Cu" "F.Mask" "F.Paste")
			(net "P3V3_STBY")
			(options
				(clearance outline)
				(anchor circle)
			)
			(primitives
				(gr_poly
					(pts
						(arc
							(start 0.3048 -0.2032)
							(mid 0.275042 -0.275042)
							(end 0.2032 -0.3048)
						)
						(arc
							(start -0.2032 -0.3048)
							(mid -0.275042 -0.275042)
							(end -0.3048 -0.2032)
						)
						(arc
							(start -0.3048 0.2032)
							(mid -0.275042 0.275042)
							(end -0.2032 0.3048)
						)
						(arc
							(start 0.2032 0.3048)
							(mid 0.275042 0.275042)
							(end 0.3048 0.2032)
						)
					)
					(width 0)
					(fill yes)
				)
			)
		)
		(pad "2" smd custom
			(at 0 0.4445 180)
			(size 0.1524 0.1524)
			(layers "F.Cu" "F.Mask" "F.Paste")
			(net "GND")
			(options
				(clearance outline)
				(anchor circle)
			)
			(primitives
				(gr_poly
					(pts
						(arc
							(start 0.3048 -0.2032)
							(mid 0.275042 -0.275042)
							(end 0.2032 -0.3048)
						)
						(arc
							(start -0.2032 -0.3048)
							(mid -0.275042 -0.275042)
							(end -0.3048 -0.2032)
						)
						(arc
							(start -0.3048 0.2032)
							(mid -0.275042 0.275042)
							(end -0.2032 0.3048)
						)
						(arc
							(start 0.2032 0.3048)
							(mid 0.275042 0.275042)
							(end 0.3048 0.2032)
						)
					)
					(width 0)
					(fill yes)
				)
			)
		)
	)
	(footprint ""
		(layer "F.Cu")
		(at 111.03737 -77.5462)
		(property "Reference" "STP71"
			(at 0 0 0)
			(layer "F.SilkS")
			(hide yes)
			(effects
				(font
					(size 1.27 1.27)
				)
			)
		)
		(property "Value" "TPAD28"
			(at 0.0127 -1.8034 0)
			(unlocked yes)
			(layer "F.Fab")
			(hide yes)
			(effects
				(font
					(size 1.016 1.016)
					(thickness 0.1524)
				)
			)
		)
		(property "Device Type" "TPAD28"
			(at 0.0127 -3.3274 0)
			(unlocked yes)
			(layer "F.Fab")
			(hide yes)
			(effects
				(font
					(size 1.016 1.016)
					(thickness 0.1524)
				)
			)
		)
		(duplicate_pad_numbers_are_jumpers no)
		(fp_poly
			(pts
				(arc
					(start 0.3556 0)
					(mid -0.3556 0)
					(end 0.3556 0)
				)
			)
			(stroke
				(width 0)
				(type default)
			)
			(fill no)
			(layer "F.CrtYd")
		)
		(fp_poly
			(pts
				(arc
					(start 0.6096 0)
					(mid -0.6096 0)
					(end 0.6096 0)
				)
			)
			(stroke
				(width 0)
				(type default)
			)
			(fill no)
			(layer "F.Fab")
		)
		(pad "1" smd circle
			(at 0 0)
			(size 0.7112 0.7112)
			(layers "F.Cu" "F.Mask" "F.Paste")
			(net "EXP_TEST_MUX33")
		)
	)
	(footprint ""
		(layer "F.Cu")
		(at 98.05797 -118.3005 180)
		(property "Reference" "SR749"
			(at 0 0 180)
			(layer "F.SilkS")
			(hide yes)
			(effects
				(font
					(size 1.27 1.27)
				)
			)
		)
		(property "Value" "4K7R2F-GP"
			(at 0.064008 -3.993896 180)
			(unlocked yes)
			(layer "F.Fab")
			(hide yes)
			(effects
				(font
					(size 1.016 1.016)
					(thickness 0.1524)
				)
			)
		)
		(property "Device Type" "R402H16"
			(at 0.064008 -5.517896 180)
			(unlocked yes)
			(layer "F.Fab")
			(hide yes)
			(effects
				(font
					(size 1.016 1.016)
					(thickness 0.1524)
				)
			)
		)
		(duplicate_pad_numbers_are_jumpers no)
		(fp_line
			(start 0.508 -0.9398)
			(end -0.508 -0.9398)
			(stroke
				(width 0.1524)
				(type default)
			)
			(layer "F.SilkS")
		)
		(fp_line
			(start -0.508 -0.9398)
			(end -0.508 0.9398)
			(stroke
				(width 0.1524)
				(type default)
			)
			(layer "F.SilkS")
		)
		(fp_rect
			(start -0.508 0.9398)
			(end 0.508 -0.9398)
			(stroke
				(width 0)
				(type default)
			)
			(fill no)
			(layer "F.CrtYd")
		)
		(fp_rect
			(start -0.508 0.9398)
			(end 0.508 -0.9398)
			(stroke
				(width 0)
				(type default)
			)
			(fill no)
			(layer "F.Fab")
		)
		(pad "1" smd custom
			(at 0 -0.4445 180)
			(size 0.1397 0.1397)
			(layers "F.Cu" "F.Mask" "F.Paste")
			(net "SIO_LOAD_IN")
			(options
				(clearance outline)
				(anchor circle)
			)
			(primitives
				(gr_poly
					(pts
						(arc
							(start -0.1778 -0.2794)
							(mid -0.249642 -0.249642)
							(end -0.2794 -0.1778)
						)
						(arc
							(start -0.2794 0.1778)
							(mid -0.249642 0.249642)
							(end -0.1778 0.2794)
						)
						(arc
							(start 0.1778 0.2794)
							(mid 0.249642 0.249642)
							(end 0.2794 0.1778)
						)
						(arc
							(start 0.2794 -0.1778)
							(mid 0.249642 -0.249642)
							(end 0.1778 -0.2794)
						)
					)
					(width 0)
					(fill yes)
				)
			)
		)
		(pad "2" smd custom
			(at 0 0.4445 180)
			(size 0.1397 0.1397)
			(layers "F.Cu" "F.Mask" "F.Paste")
			(net "P1V8_E")
			(options
				(clearance outline)
				(anchor circle)
			)
			(primitives
				(gr_poly
					(pts
						(arc
							(start -0.1778 -0.2794)
							(mid -0.249642 -0.249642)
							(end -0.2794 -0.1778)
						)
						(arc
							(start -0.2794 0.1778)
							(mid -0.249642 0.249642)
							(end -0.1778 0.2794)
						)
						(arc
							(start 0.1778 0.2794)
							(mid 0.249642 0.249642)
							(end 0.2794 0.1778)
						)
						(arc
							(start 0.2794 -0.1778)
							(mid 0.249642 -0.249642)
							(end 0.1778 -0.2794)
						)
					)
					(width 0)
					(fill yes)
				)
			)
		)
	)
	(footprint ""
		(layer "F.Cu")
		(at 166.233856 -109.864652 -90)
		(property "Reference" "PR160"
			(at 0 0 270)
			(layer "F.SilkS")
			(hide yes)
			(effects
				(font
					(size 1.27 1.27)
				)
			)
		)
		(property "Value" "475KR2F-GP"
			(at 0.064008 -3.993896 270)
			(unlocked yes)
			(layer "F.Fab")
			(hide yes)
			(effects
				(font
					(size 1.016 1.016)
					(thickness 0.1524)
				)
			)
		)
		(property "Device Type" "R402H16"
			(at 0.064008 -5.517896 270)
			(unlocked yes)
			(layer "F.Fab")
			(hide yes)
			(effects
				(font
					(size 1.016 1.016)
					(thickness 0.1524)
				)
			)
		)
		(duplicate_pad_numbers_are_jumpers no)
		(fp_line
			(start -0.508 -0.9398)
			(end -0.508 0.9398)
			(stroke
				(width 0.1524)
				(type default)
			)
			(layer "F.SilkS")
		)
		(fp_line
			(start 0.508 -0.9398)
			(end -0.508 -0.9398)
			(stroke
				(width 0.1524)
				(type default)
			)
			(layer "F.SilkS")
		)
		(fp_rect
			(start -0.508 0.9398)
			(end 0.508 -0.9398)
			(stroke
				(width 0)
				(type default)
			)
			(fill no)
			(layer "F.CrtYd")
		)
		(fp_rect
			(start -0.508 0.9398)
			(end 0.508 -0.9398)
			(stroke
				(width 0)
				(type default)
			)
			(fill no)
			(layer "F.Fab")
		)
		(pad "1" smd custom
			(at 0 -0.4445 270)
			(size 0.1397 0.1397)
			(layers "F.Cu" "F.Mask" "F.Paste")
			(net "P0V9_E_PG")
			(options
				(clearance outline)
				(anchor circle)
			)
			(primitives
				(gr_poly
					(pts
						(arc
							(start -0.1778 -0.2794)
							(mid -0.249642 -0.249642)
							(end -0.2794 -0.1778)
						)
						(arc
							(start -0.2794 0.1778)
							(mid -0.249642 0.249642)
							(end -0.1778 0.2794)
						)
						(arc
							(start 0.1778 0.2794)
							(mid 0.249642 0.249642)
							(end 0.2794 0.1778)
						)
						(arc
							(start 0.2794 -0.1778)
							(mid 0.249642 -0.249642)
							(end 0.1778 -0.2794)
						)
					)
					(width 0)
					(fill yes)
				)
			)
		)
		(pad "2" smd custom
			(at 0 0.4445 270)
			(size 0.1397 0.1397)
			(layers "F.Cu" "F.Mask" "F.Paste")
			(net "P0V9_E_MODE")
			(options
				(clearance outline)
				(anchor circle)
			)
			(primitives
				(gr_poly
					(pts
						(arc
							(start -0.1778 -0.2794)
							(mid -0.249642 -0.249642)
							(end -0.2794 -0.1778)
						)
						(arc
							(start -0.2794 0.1778)
							(mid -0.249642 0.249642)
							(end -0.1778 0.2794)
						)
						(arc
							(start 0.1778 0.2794)
							(mid 0.249642 0.249642)
							(end 0.2794 0.1778)
						)
						(arc
							(start 0.2794 -0.1778)
							(mid 0.249642 -0.249642)
							(end 0.1778 -0.2794)
						)
					)
					(width 0)
					(fill yes)
				)
			)
		)
	)
	(footprint ""
		(layer "F.Cu")
		(at 337.214718 -157.584648)
		(property "Reference" "R535"
			(at 0 0 0)
			(layer "F.SilkS")
			(hide yes)
			(effects
				(font
					(size 1.27 1.27)
				)
			)
		)
		(property "Value" "4K7R2F-GP"
			(at 0.064008 -3.993896 0)
			(unlocked yes)
			(layer "F.Fab")
			(hide yes)
			(effects
				(font
					(size 1.016 1.016)
					(thickness 0.1524)
				)
			)
		)
		(property "Device Type" "R402H16"
			(at 0.064008 -5.517896 0)
			(unlocked yes)
			(layer "F.Fab")
			(hide yes)
			(effects
				(font
					(size 1.016 1.016)
					(thickness 0.1524)
				)
			)
		)
		(duplicate_pad_numbers_are_jumpers no)
		(fp_line
			(start -0.508 -0.9398)
			(end -0.508 0.9398)
			(stroke
				(width 0.1524)
				(type default)
			)
			(layer "F.SilkS")
		)
		(fp_line
			(start 0.508 -0.9398)
			(end -0.508 -0.9398)
			(stroke
				(width 0.1524)
				(type default)
			)
			(layer "F.SilkS")
		)
		(fp_rect
			(start -0.508 0.9398)
			(end 0.508 -0.9398)
			(stroke
				(width 0)
				(type default)
			)
			(fill no)
			(layer "F.CrtYd")
		)
		(fp_rect
			(start -0.508 0.9398)
			(end 0.508 -0.9398)
			(stroke
				(width 0)
				(type default)
			)
			(fill no)
			(layer "F.Fab")
		)
		(pad "1" smd custom
			(at 0 -0.4445)
			(size 0.1397 0.1397)
			(layers "F.Cu" "F.Mask" "F.Paste")
			(net "P3V3_STBY")
			(options
				(clearance outline)
				(anchor circle)
			)
			(primitives
				(gr_poly
					(pts
						(arc
							(start -0.1778 -0.2794)
							(mid -0.249642 -0.249642)
							(end -0.2794 -0.1778)
						)
						(arc
							(start -0.2794 0.1778)
							(mid -0.249642 0.249642)
							(end -0.1778 0.2794)
						)
						(arc
							(start 0.1778 0.2794)
							(mid 0.249642 0.249642)
							(end 0.2794 0.1778)
						)
						(arc
							(start 0.2794 -0.1778)
							(mid 0.249642 -0.249642)
							(end 0.1778 -0.2794)
						)
					)
					(width 0)
					(fill yes)
				)
			)
		)
		(pad "2" smd custom
			(at 0 0.4445)
			(size 0.1397 0.1397)
			(layers "F.Cu" "F.Mask" "F.Paste")
			(net "USB_EN_3")
			(options
				(clearance outline)
				(anchor circle)
			)
			(primitives
				(gr_poly
					(pts
						(arc
							(start -0.1778 -0.2794)
							(mid -0.249642 -0.249642)
							(end -0.2794 -0.1778)
						)
						(arc
							(start -0.2794 0.1778)
							(mid -0.249642 0.249642)
							(end -0.1778 0.2794)
						)
						(arc
							(start 0.1778 0.2794)
							(mid 0.249642 0.249642)
							(end 0.2794 0.1778)
						)
						(arc
							(start 0.2794 -0.1778)
							(mid 0.249642 -0.249642)
							(end 0.1778 -0.2794)
						)
					)
					(width 0)
					(fill yes)
				)
			)
		)
	)
	(footprint ""
		(layer "F.Cu")
		(at 115.951 -29.845 90)
		(property "Reference" "SR684"
			(at 0 0 90)
			(layer "F.SilkS")
			(hide yes)
			(effects
				(font
					(size 1.27 1.27)
				)
			)
		)
		(property "Value" "10KR2F-2-GP"
			(at 0.064008 -3.993896 90)
			(unlocked yes)
			(layer "F.Fab")
			(hide yes)
			(effects
				(font
					(size 1.016 1.016)
					(thickness 0.1524)
				)
			)
		)
		(property "Device Type" "R402H16"
			(at 0.064008 -5.517896 90)
			(unlocked yes)
			(layer "F.Fab")
			(hide yes)
			(effects
				(font
					(size 1.016 1.016)
					(thickness 0.1524)
				)
			)
		)
		(duplicate_pad_numbers_are_jumpers no)
		(fp_line
			(start 0.508 -0.9398)
			(end -0.508 -0.9398)
			(stroke
				(width 0.1524)
				(type default)
			)
			(layer "F.SilkS")
		)
		(fp_line
			(start -0.508 -0.9398)
			(end -0.508 0.9398)
			(stroke
				(width 0.1524)
				(type default)
			)
			(layer "F.SilkS")
		)
		(fp_rect
			(start -0.508 0.9398)
			(end 0.508 -0.9398)
			(stroke
				(width 0)
				(type default)
			)
			(fill no)
			(layer "F.CrtYd")
		)
		(fp_rect
			(start -0.508 0.9398)
			(end 0.508 -0.9398)
			(stroke
				(width 0)
				(type default)
			)
			(fill no)
			(layer "F.Fab")
		)
		(pad "1" smd custom
			(at 0 -0.4445 90)
			(size 0.1397 0.1397)
			(layers "F.Cu" "F.Mask" "F.Paste")
			(net "SYS_DBMODE2")
			(options
				(clearance outline)
				(anchor circle)
			)
			(primitives
				(gr_poly
					(pts
						(arc
							(start -0.1778 -0.2794)
							(mid -0.249642 -0.249642)
							(end -0.2794 -0.1778)
						)
						(arc
							(start -0.2794 0.1778)
							(mid -0.249642 0.249642)
							(end -0.1778 0.2794)
						)
						(arc
							(start 0.1778 0.2794)
							(mid 0.249642 0.249642)
							(end 0.2794 0.1778)
						)
						(arc
							(start 0.2794 -0.1778)
							(mid 0.249642 -0.249642)
							(end 0.1778 -0.2794)
						)
					)
					(width 0)
					(fill yes)
				)
			)
		)
		(pad "2" smd custom
			(at 0 0.4445 90)
			(size 0.1397 0.1397)
			(layers "F.Cu" "F.Mask" "F.Paste")
			(net "GND")
			(options
				(clearance outline)
				(anchor circle)
			)
			(primitives
				(gr_poly
					(pts
						(arc
							(start -0.1778 -0.2794)
							(mid -0.249642 -0.249642)
							(end -0.2794 -0.1778)
						)
						(arc
							(start -0.2794 0.1778)
							(mid -0.249642 0.249642)
							(end -0.1778 0.2794)
						)
						(arc
							(start 0.1778 0.2794)
							(mid 0.249642 0.249642)
							(end 0.2794 0.1778)
						)
						(arc
							(start 0.2794 -0.1778)
							(mid 0.249642 -0.249642)
							(end 0.1778 -0.2794)
						)
					)
					(width 0)
					(fill yes)
				)
			)
		)
	)
	(footprint ""
		(layer "F.Cu")
		(at 220.345 -156.337 180)
		(property "Reference" "R581"
			(at 0 0 180)
			(layer "F.SilkS")
			(hide yes)
			(effects
				(font
					(size 1.27 1.27)
				)
			)
		)
		(property "Value" "4K7R2F-GP"
			(at 0.064008 -3.993896 180)
			(unlocked yes)
			(layer "F.Fab")
			(hide yes)
			(effects
				(font
					(size 1.016 1.016)
					(thickness 0.1524)
				)
			)
		)
		(property "Device Type" "R402H16"
			(at 0.064008 -5.517896 180)
			(unlocked yes)
			(layer "F.Fab")
			(hide yes)
			(effects
				(font
					(size 1.016 1.016)
					(thickness 0.1524)
				)
			)
		)
		(duplicate_pad_numbers_are_jumpers no)
		(fp_line
			(start 0.508 -0.9398)
			(end -0.508 -0.9398)
			(stroke
				(width 0.1524)
				(type default)
			)
			(layer "F.SilkS")
		)
		(fp_line
			(start -0.508 -0.9398)
			(end -0.508 0.9398)
			(stroke
				(width 0.1524)
				(type default)
			)
			(layer "F.SilkS")
		)
		(fp_rect
			(start -0.508 0.9398)
			(end 0.508 -0.9398)
			(stroke
				(width 0)
				(type default)
			)
			(fill no)
			(layer "F.CrtYd")
		)
		(fp_rect
			(start -0.508 0.9398)
			(end 0.508 -0.9398)
			(stroke
				(width 0)
				(type default)
			)
			(fill no)
			(layer "F.Fab")
		)
		(pad "1" smd custom
			(at 0 -0.4445 180)
			(size 0.1397 0.1397)
			(layers "F.Cu" "F.Mask" "F.Paste")
			(net "BMC_JTAG_L")
			(options
				(clearance outline)
				(anchor circle)
			)
			(primitives
				(gr_poly
					(pts
						(arc
							(start -0.1778 -0.2794)
							(mid -0.249642 -0.249642)
							(end -0.2794 -0.1778)
						)
						(arc
							(start -0.2794 0.1778)
							(mid -0.249642 0.249642)
							(end -0.1778 0.2794)
						)
						(arc
							(start 0.1778 0.2794)
							(mid 0.249642 0.249642)
							(end 0.2794 0.1778)
						)
						(arc
							(start 0.2794 -0.1778)
							(mid 0.249642 -0.249642)
							(end 0.1778 -0.2794)
						)
					)
					(width 0)
					(fill yes)
				)
			)
		)
		(pad "2" smd custom
			(at 0 0.4445 180)
			(size 0.1397 0.1397)
			(layers "F.Cu" "F.Mask" "F.Paste")
			(net "P3V3_STBY")
			(options
				(clearance outline)
				(anchor circle)
			)
			(primitives
				(gr_poly
					(pts
						(arc
							(start -0.1778 -0.2794)
							(mid -0.249642 -0.249642)
							(end -0.2794 -0.1778)
						)
						(arc
							(start -0.2794 0.1778)
							(mid -0.249642 0.249642)
							(end -0.1778 0.2794)
						)
						(arc
							(start 0.1778 0.2794)
							(mid 0.249642 0.249642)
							(end 0.2794 0.1778)
						)
						(arc
							(start 0.2794 -0.1778)
							(mid 0.249642 -0.249642)
							(end 0.1778 -0.2794)
						)
					)
					(width 0)
					(fill yes)
				)
			)
		)
	)
	(footprint ""
		(layer "F.Cu")
		(at 184.395872 -206.497936 180)
		(property "Reference" "C241"
			(at 0 0 180)
			(layer "F.SilkS")
			(hide yes)
			(effects
				(font
					(size 1.27 1.27)
				)
			)
		)
		(property "Value" "SCD1U16V2KX-3GP"
			(at 1.1811 -2.7051 180)
			(unlocked yes)
			(layer "F.Fab")
			(hide yes)
			(effects
				(font
					(size 1.016 1.016)
					(thickness 0.1524)
				)
			)
		)
		(property "Device Type" "C402H22"
			(at 1.1811 -4.2291 180)
			(unlocked yes)
			(layer "F.Fab")
			(hide yes)
			(effects
				(font
					(size 1.016 1.016)
					(thickness 0.1524)
				)
			)
		)
		(duplicate_pad_numbers_are_jumpers no)
		(fp_rect
			(start -0.4318 0.9525)
			(end 0.4318 -0.9525)
			(stroke
				(width 0)
				(type default)
			)
			(fill no)
			(layer "F.CrtYd")
		)
		(fp_rect
			(start -0.4318 0.9525)
			(end 0.4318 -0.9525)
			(stroke
				(width 0)
				(type default)
			)
			(fill no)
			(layer "F.Fab")
		)
		(pad "1" smd custom
			(at 0 -0.4445 180)
			(size 0.1524 0.1524)
			(layers "F.Cu" "F.Mask" "F.Paste")
			(net "P3V3_STBY")
			(options
				(clearance outline)
				(anchor circle)
			)
			(primitives
				(gr_poly
					(pts
						(arc
							(start 0.3048 -0.2032)
							(mid 0.275042 -0.275042)
							(end 0.2032 -0.3048)
						)
						(arc
							(start -0.2032 -0.3048)
							(mid -0.275042 -0.275042)
							(end -0.3048 -0.2032)
						)
						(arc
							(start -0.3048 0.2032)
							(mid -0.275042 0.275042)
							(end -0.2032 0.3048)
						)
						(arc
							(start 0.2032 0.3048)
							(mid 0.275042 0.275042)
							(end 0.3048 0.2032)
						)
					)
					(width 0)
					(fill yes)
				)
			)
		)
		(pad "2" smd custom
			(at 0 0.4445 180)
			(size 0.1524 0.1524)
			(layers "F.Cu" "F.Mask" "F.Paste")
			(net "GND")
			(options
				(clearance outline)
				(anchor circle)
			)
			(primitives
				(gr_poly
					(pts
						(arc
							(start 0.3048 -0.2032)
							(mid 0.275042 -0.275042)
							(end 0.2032 -0.3048)
						)
						(arc
							(start -0.2032 -0.3048)
							(mid -0.275042 -0.275042)
							(end -0.3048 -0.2032)
						)
						(arc
							(start -0.3048 0.2032)
							(mid -0.275042 0.275042)
							(end -0.2032 0.3048)
						)
						(arc
							(start 0.2032 0.3048)
							(mid 0.275042 0.275042)
							(end 0.3048 0.2032)
						)
					)
					(width 0)
					(fill yes)
				)
			)
		)
	)
	(footprint ""
		(layer "F.Cu")
		(at 32.424116 -78.855062)
		(property "Reference" "R674"
			(at 0 0 0)
			(layer "F.SilkS")
			(hide yes)
			(effects
				(font
					(size 1.27 1.27)
				)
			)
		)
		(property "Value" "0R2J-2-GP"
			(at 0.064008 -3.993896 0)
			(unlocked yes)
			(layer "F.Fab")
			(hide yes)
			(effects
				(font
					(size 1.016 1.016)
					(thickness 0.1524)
				)
			)
		)
		(property "Device Type" "R402H16"
			(at 0.064008 -5.517896 0)
			(unlocked yes)
			(layer "F.Fab")
			(hide yes)
			(effects
				(font
					(size 1.016 1.016)
					(thickness 0.1524)
				)
			)
		)
		(duplicate_pad_numbers_are_jumpers no)
		(fp_line
			(start -0.508 -0.9398)
			(end -0.508 0.9398)
			(stroke
				(width 0.1524)
				(type default)
			)
			(layer "F.SilkS")
		)
		(fp_line
			(start 0.508 -0.9398)
			(end -0.508 -0.9398)
			(stroke
				(width 0.1524)
				(type default)
			)
			(layer "F.SilkS")
		)
		(fp_rect
			(start -0.508 0.9398)
			(end 0.508 -0.9398)
			(stroke
				(width 0)
				(type default)
			)
			(fill no)
			(layer "F.CrtYd")
		)
		(fp_rect
			(start -0.508 0.9398)
			(end 0.508 -0.9398)
			(stroke
				(width 0)
				(type default)
			)
			(fill no)
			(layer "F.Fab")
		)
		(pad "1" smd custom
			(at 0 -0.4445)
			(size 0.1397 0.1397)
			(layers "F.Cu" "F.Mask" "F.Paste")
			(net "GND")
			(options
				(clearance outline)
				(anchor circle)
			)
			(primitives
				(gr_poly
					(pts
						(arc
							(start -0.1778 -0.2794)
							(mid -0.249642 -0.249642)
							(end -0.2794 -0.1778)
						)
						(arc
							(start -0.2794 0.1778)
							(mid -0.249642 0.249642)
							(end -0.1778 0.2794)
						)
						(arc
							(start 0.1778 0.2794)
							(mid 0.249642 0.249642)
							(end 0.2794 0.1778)
						)
						(arc
							(start 0.2794 -0.1778)
							(mid 0.249642 -0.249642)
							(end 0.1778 -0.2794)
						)
					)
					(width 0)
					(fill yes)
				)
			)
		)
		(pad "2" smd custom
			(at 0 0.4445)
			(size 0.1397 0.1397)
			(layers "F.Cu" "F.Mask" "F.Paste")
			(net "INTA_LED_GND")
			(options
				(clearance outline)
				(anchor circle)
			)
			(primitives
				(gr_poly
					(pts
						(arc
							(start -0.1778 -0.2794)
							(mid -0.249642 -0.249642)
							(end -0.2794 -0.1778)
						)
						(arc
							(start -0.2794 0.1778)
							(mid -0.249642 0.249642)
							(end -0.1778 0.2794)
						)
						(arc
							(start 0.1778 0.2794)
							(mid 0.249642 0.249642)
							(end 0.2794 0.1778)
						)
						(arc
							(start 0.2794 -0.1778)
							(mid 0.249642 -0.249642)
							(end 0.1778 -0.2794)
						)
					)
					(width 0)
					(fill yes)
				)
			)
		)
	)
	(footprint ""
		(layer "F.Cu")
		(at 56.007 -225.298 180)
		(property "Reference" "PC1083"
			(at 0 0 180)
			(layer "F.SilkS")
			(hide yes)
			(effects
				(font
					(size 1.27 1.27)
				)
			)
		)
		(property "Value" "SC1U25V3KX-1-GP"
			(at 0 -2.8194 180)
			(unlocked yes)
			(layer "F.Fab")
			(hide yes)
			(effects
				(font
					(size 1.016 1.016)
					(thickness 0.1524)
				)
			)
		)
		(property "Device Type" "C603H36"
			(at 0 -4.3434 180)
			(unlocked yes)
			(layer "F.Fab")
			(hide yes)
			(effects
				(font
					(size 1.016 1.016)
					(thickness 0.1524)
				)
			)
		)
		(duplicate_pad_numbers_are_jumpers no)
		(fp_line
			(start 0.508 0)
			(end -0.508 0)
			(stroke
				(width 0.2032)
				(type default)
			)
			(layer "F.SilkS")
		)
		(fp_rect
			(start -0.5842 1.3335)
			(end 0.5842 -1.3335)
			(stroke
				(width 0)
				(type default)
			)
			(fill no)
			(layer "F.CrtYd")
		)
		(fp_rect
			(start -0.5842 1.3335)
			(end 0.5842 -1.3335)
			(stroke
				(width 0)
				(type default)
			)
			(fill no)
			(layer "F.Fab")
		)
		(pad "1" smd custom
			(at 0 -0.762 180)
			(size 0.2159 0.2159)
			(layers "F.Cu" "F.Mask" "F.Paste")
			(net "MB0_VCC")
			(options
				(clearance outline)
				(anchor circle)
			)
			(primitives
				(gr_poly
					(pts
						(arc
							(start -0.3302 -0.4318)
							(mid -0.402042 -0.402042)
							(end -0.4318 -0.3302)
						)
						(arc
							(start -0.4318 0.3302)
							(mid -0.402042 0.402042)
							(end -0.3302 0.4318)
						)
						(arc
							(start 0.3302 0.4318)
							(mid 0.402042 0.402042)
							(end 0.4318 0.3302)
						)
						(arc
							(start 0.4318 -0.3302)
							(mid 0.402042 -0.402042)
							(end 0.3302 -0.4318)
						)
					)
					(width 0)
					(fill yes)
				)
			)
		)
		(pad "2" smd custom
			(at 0 0.762 180)
			(size 0.2159 0.2159)
			(layers "F.Cu" "F.Mask" "F.Paste")
			(net "AGND_CURRENT_MON")
			(options
				(clearance outline)
				(anchor circle)
			)
			(primitives
				(gr_poly
					(pts
						(arc
							(start -0.3302 -0.4318)
							(mid -0.402042 -0.402042)
							(end -0.4318 -0.3302)
						)
						(arc
							(start -0.4318 0.3302)
							(mid -0.402042 0.402042)
							(end -0.3302 0.4318)
						)
						(arc
							(start 0.3302 0.4318)
							(mid 0.402042 0.402042)
							(end 0.4318 0.3302)
						)
						(arc
							(start 0.4318 -0.3302)
							(mid 0.402042 -0.402042)
							(end 0.3302 -0.4318)
						)
					)
					(width 0)
					(fill yes)
				)
			)
		)
	)
	(footprint ""
		(layer "F.Cu")
		(at 311.531 -112.268)
		(property "Reference" "PR24"
			(at 0 0 0)
			(layer "F.SilkS")
			(hide yes)
			(effects
				(font
					(size 1.27 1.27)
				)
			)
		)
		(property "Value" "2K7R2J-GP"
			(at 0.064008 -3.993896 0)
			(unlocked yes)
			(layer "F.Fab")
			(hide yes)
			(effects
				(font
					(size 1.016 1.016)
					(thickness 0.1524)
				)
			)
		)
		(property "Device Type" "R402H16"
			(at 0.064008 -5.517896 0)
			(unlocked yes)
			(layer "F.Fab")
			(hide yes)
			(effects
				(font
					(size 1.016 1.016)
					(thickness 0.1524)
				)
			)
		)
		(duplicate_pad_numbers_are_jumpers no)
		(fp_line
			(start -0.508 -0.9398)
			(end -0.508 0.9398)
			(stroke
				(width 0.1524)
				(type default)
			)
			(layer "F.SilkS")
		)
		(fp_line
			(start 0.508 -0.9398)
			(end -0.508 -0.9398)
			(stroke
				(width 0.1524)
				(type default)
			)
			(layer "F.SilkS")
		)
		(fp_rect
			(start -0.508 0.9398)
			(end 0.508 -0.9398)
			(stroke
				(width 0)
				(type default)
			)
			(fill no)
			(layer "F.CrtYd")
		)
		(fp_rect
			(start -0.508 0.9398)
			(end 0.508 -0.9398)
			(stroke
				(width 0)
				(type default)
			)
			(fill no)
			(layer "F.Fab")
		)
		(pad "1" smd custom
			(at 0 -0.4445)
			(size 0.1397 0.1397)
			(layers "F.Cu" "F.Mask" "F.Paste")
			(net "P3V3_STBY_EN")
			(options
				(clearance outline)
				(anchor circle)
			)
			(primitives
				(gr_poly
					(pts
						(arc
							(start -0.1778 -0.2794)
							(mid -0.249642 -0.249642)
							(end -0.2794 -0.1778)
						)
						(arc
							(start -0.2794 0.1778)
							(mid -0.249642 0.249642)
							(end -0.1778 0.2794)
						)
						(arc
							(start 0.1778 0.2794)
							(mid 0.249642 0.249642)
							(end 0.2794 0.1778)
						)
						(arc
							(start 0.2794 -0.1778)
							(mid 0.249642 -0.249642)
							(end 0.1778 -0.2794)
						)
					)
					(width 0)
					(fill yes)
				)
			)
		)
		(pad "2" smd custom
			(at 0 0.4445)
			(size 0.1397 0.1397)
			(layers "F.Cu" "F.Mask" "F.Paste")
			(net "AGND_P3V3_STBY")
			(options
				(clearance outline)
				(anchor circle)
			)
			(primitives
				(gr_poly
					(pts
						(arc
							(start -0.1778 -0.2794)
							(mid -0.249642 -0.249642)
							(end -0.2794 -0.1778)
						)
						(arc
							(start -0.2794 0.1778)
							(mid -0.249642 0.249642)
							(end -0.1778 0.2794)
						)
						(arc
							(start 0.1778 0.2794)
							(mid 0.249642 0.249642)
							(end 0.2794 0.1778)
						)
						(arc
							(start 0.2794 -0.1778)
							(mid 0.249642 -0.249642)
							(end 0.1778 -0.2794)
						)
					)
					(width 0)
					(fill yes)
				)
			)
		)
	)
	(footprint ""
		(layer "F.Cu")
		(at 131.318 -89.789 90)
		(property "Reference" "SC1102"
			(at 0 0 90)
			(layer "F.SilkS")
			(hide yes)
			(effects
				(font
					(size 1.27 1.27)
				)
			)
		)
		(property "Value" "SCD01U10V1KX-GP"
			(at -2.8321 -1.7399 90)
			(unlocked yes)
			(layer "F.Fab")
			(hide yes)
			(effects
				(font
					(size 1.016 1.016)
					(thickness 0.1524)
				)
			)
		)
		(property "Device Type" "C0201H13"
			(at -2.8321 -3.2639 90)
			(unlocked yes)
			(layer "F.Fab")
			(hide yes)
			(effects
				(font
					(size 1.016 1.016)
					(thickness 0.1524)
				)
			)
		)
		(duplicate_pad_numbers_are_jumpers no)
		(fp_rect
			(start -0.2794 0.6477)
			(end 0.2794 -0.6477)
			(stroke
				(width 0)
				(type default)
			)
			(fill no)
			(layer "F.CrtYd")
		)
		(fp_rect
			(start -0.2794 0.6477)
			(end 0.2794 -0.6477)
			(stroke
				(width 0)
				(type default)
			)
			(fill no)
			(layer "F.Fab")
		)
		(pad "1" smd custom
			(at 0 -0.2794 90)
			(size 0.0762 0.0762)
			(layers "F.Cu" "F.Mask" "F.Paste")
			(net "3X24_SAS_TX18_P")
			(options
				(clearance outline)
				(anchor circle)
			)
			(primitives
				(gr_poly
					(pts
						(arc
							(start 0.1524 -0.127)
							(mid 0.137521 -0.162921)
							(end 0.1016 -0.1778)
						)
						(arc
							(start -0.1016 -0.1778)
							(mid -0.137521 -0.162921)
							(end -0.1524 -0.127)
						)
						(arc
							(start -0.1524 0.127)
							(mid -0.137521 0.162921)
							(end -0.1016 0.1778)
						)
						(arc
							(start 0.1016 0.1778)
							(mid 0.137521 0.162921)
							(end 0.1524 0.127)
						)
					)
					(width 0)
					(fill yes)
				)
			)
		)
		(pad "2" smd custom
			(at 0 0.2794 90)
			(size 0.0762 0.0762)
			(layers "F.Cu" "F.Mask" "F.Paste")
			(net "SAS_EXP2CONN_TX_P_22")
			(options
				(clearance outline)
				(anchor circle)
			)
			(primitives
				(gr_poly
					(pts
						(arc
							(start 0.1524 -0.127)
							(mid 0.137521 -0.162921)
							(end 0.1016 -0.1778)
						)
						(arc
							(start -0.1016 -0.1778)
							(mid -0.137521 -0.162921)
							(end -0.1524 -0.127)
						)
						(arc
							(start -0.1524 0.127)
							(mid -0.137521 0.162921)
							(end -0.1016 0.1778)
						)
						(arc
							(start 0.1016 0.1778)
							(mid 0.137521 0.162921)
							(end 0.1524 0.127)
						)
					)
					(width 0)
					(fill yes)
				)
			)
		)
	)
	(footprint ""
		(layer "F.Cu")
		(at 117.221 -71.628 -90)
		(property "Reference" "R588"
			(at 0 0 270)
			(layer "F.SilkS")
			(hide yes)
			(effects
				(font
					(size 1.27 1.27)
				)
			)
		)
		(property "Value" "0R2J-2-GP"
			(at 0.064008 -3.993896 270)
			(unlocked yes)
			(layer "F.Fab")
			(hide yes)
			(effects
				(font
					(size 1.016 1.016)
					(thickness 0.1524)
				)
			)
		)
		(property "Device Type" "R402H16"
			(at 0.064008 -5.517896 270)
			(unlocked yes)
			(layer "F.Fab")
			(hide yes)
			(effects
				(font
					(size 1.016 1.016)
					(thickness 0.1524)
				)
			)
		)
		(duplicate_pad_numbers_are_jumpers no)
		(fp_line
			(start -0.508 -0.9398)
			(end -0.508 0.9398)
			(stroke
				(width 0.1524)
				(type default)
			)
			(layer "F.SilkS")
		)
		(fp_line
			(start 0.508 -0.9398)
			(end -0.508 -0.9398)
			(stroke
				(width 0.1524)
				(type default)
			)
			(layer "F.SilkS")
		)
		(fp_rect
			(start -0.508 0.9398)
			(end 0.508 -0.9398)
			(stroke
				(width 0)
				(type default)
			)
			(fill no)
			(layer "F.CrtYd")
		)
		(fp_rect
			(start -0.508 0.9398)
			(end 0.508 -0.9398)
			(stroke
				(width 0)
				(type default)
			)
			(fill no)
			(layer "F.Fab")
		)
		(pad "1" smd custom
			(at 0 -0.4445 270)
			(size 0.1397 0.1397)
			(layers "F.Cu" "F.Mask" "F.Paste")
			(net "BMC_I2C_D_SCL")
			(options
				(clearance outline)
				(anchor circle)
			)
			(primitives
				(gr_poly
					(pts
						(arc
							(start -0.1778 -0.2794)
							(mid -0.249642 -0.249642)
							(end -0.2794 -0.1778)
						)
						(arc
							(start -0.2794 0.1778)
							(mid -0.249642 0.249642)
							(end -0.1778 0.2794)
						)
						(arc
							(start 0.1778 0.2794)
							(mid 0.249642 0.249642)
							(end 0.2794 0.1778)
						)
						(arc
							(start 0.2794 -0.1778)
							(mid 0.249642 -0.249642)
							(end 0.1778 -0.2794)
						)
					)
					(width 0)
					(fill yes)
				)
			)
		)
		(pad "2" smd custom
			(at 0 0.4445 270)
			(size 0.1397 0.1397)
			(layers "F.Cu" "F.Mask" "F.Paste")
			(net "TEMP_4_SCL")
			(options
				(clearance outline)
				(anchor circle)
			)
			(primitives
				(gr_poly
					(pts
						(arc
							(start -0.1778 -0.2794)
							(mid -0.249642 -0.249642)
							(end -0.2794 -0.1778)
						)
						(arc
							(start -0.2794 0.1778)
							(mid -0.249642 0.249642)
							(end -0.1778 0.2794)
						)
						(arc
							(start 0.1778 0.2794)
							(mid 0.249642 0.249642)
							(end 0.2794 0.1778)
						)
						(arc
							(start 0.2794 -0.1778)
							(mid 0.249642 -0.249642)
							(end 0.1778 -0.2794)
						)
					)
					(width 0)
					(fill yes)
				)
			)
		)
	)
	(footprint ""
		(layer "F.Cu")
		(at 348.390718 -154.155648 -90)
		(property "Reference" "R534"
			(at 0 0 270)
			(layer "F.SilkS")
			(hide yes)
			(effects
				(font
					(size 1.27 1.27)
				)
			)
		)
		(property "Value" "0R2J-2-GP"
			(at 0.064008 -3.993896 270)
			(unlocked yes)
			(layer "F.Fab")
			(hide yes)
			(effects
				(font
					(size 1.016 1.016)
					(thickness 0.1524)
				)
			)
		)
		(property "Device Type" "R402H16"
			(at 0.064008 -5.517896 270)
			(unlocked yes)
			(layer "F.Fab")
			(hide yes)
			(effects
				(font
					(size 1.016 1.016)
					(thickness 0.1524)
				)
			)
		)
		(duplicate_pad_numbers_are_jumpers no)
		(fp_line
			(start -0.508 -0.9398)
			(end -0.508 0.9398)
			(stroke
				(width 0.1524)
				(type default)
			)
			(layer "F.SilkS")
		)
		(fp_line
			(start 0.508 -0.9398)
			(end -0.508 -0.9398)
			(stroke
				(width 0.1524)
				(type default)
			)
			(layer "F.SilkS")
		)
		(fp_rect
			(start -0.508 0.9398)
			(end 0.508 -0.9398)
			(stroke
				(width 0)
				(type default)
			)
			(fill no)
			(layer "F.CrtYd")
		)
		(fp_rect
			(start -0.508 0.9398)
			(end 0.508 -0.9398)
			(stroke
				(width 0)
				(type default)
			)
			(fill no)
			(layer "F.Fab")
		)
		(pad "1" smd custom
			(at 0 -0.4445 270)
			(size 0.1397 0.1397)
			(layers "F.Cu" "F.Mask" "F.Paste")
			(net "BMC_USB1_HDN2")
			(options
				(clearance outline)
				(anchor circle)
			)
			(primitives
				(gr_poly
					(pts
						(arc
							(start -0.1778 -0.2794)
							(mid -0.249642 -0.249642)
							(end -0.2794 -0.1778)
						)
						(arc
							(start -0.2794 0.1778)
							(mid -0.249642 0.249642)
							(end -0.1778 0.2794)
						)
						(arc
							(start 0.1778 0.2794)
							(mid 0.249642 0.249642)
							(end 0.2794 0.1778)
						)
						(arc
							(start 0.2794 -0.1778)
							(mid 0.249642 -0.249642)
							(end 0.1778 -0.2794)
						)
					)
					(width 0)
					(fill yes)
				)
			)
		)
		(pad "2" smd custom
			(at 0 0.4445 270)
			(size 0.1397 0.1397)
			(layers "F.Cu" "F.Mask" "F.Paste")
			(net "USB_P4_DN")
			(options
				(clearance outline)
				(anchor circle)
			)
			(primitives
				(gr_poly
					(pts
						(arc
							(start -0.1778 -0.2794)
							(mid -0.249642 -0.249642)
							(end -0.2794 -0.1778)
						)
						(arc
							(start -0.2794 0.1778)
							(mid -0.249642 0.249642)
							(end -0.1778 0.2794)
						)
						(arc
							(start 0.1778 0.2794)
							(mid 0.249642 0.249642)
							(end 0.2794 0.1778)
						)
						(arc
							(start 0.2794 -0.1778)
							(mid 0.249642 -0.249642)
							(end 0.1778 -0.2794)
						)
					)
					(width 0)
					(fill yes)
				)
			)
		)
	)
	(footprint ""
		(layer "F.Cu")
		(at 86.49716 -38.608 -90)
		(property "Reference" "SC884"
			(at 0 0 270)
			(layer "F.SilkS")
			(hide yes)
			(effects
				(font
					(size 1.27 1.27)
				)
			)
		)
		(property "Value" "SCD01U10V1KX-GP"
			(at -2.8321 -1.7399 270)
			(unlocked yes)
			(layer "F.Fab")
			(hide yes)
			(effects
				(font
					(size 1.016 1.016)
					(thickness 0.1524)
				)
			)
		)
		(property "Device Type" "C0201H13"
			(at -2.8321 -3.2639 270)
			(unlocked yes)
			(layer "F.Fab")
			(hide yes)
			(effects
				(font
					(size 1.016 1.016)
					(thickness 0.1524)
				)
			)
		)
		(duplicate_pad_numbers_are_jumpers no)
		(fp_rect
			(start -0.2794 0.6477)
			(end 0.2794 -0.6477)
			(stroke
				(width 0)
				(type default)
			)
			(fill no)
			(layer "F.CrtYd")
		)
		(fp_rect
			(start -0.2794 0.6477)
			(end 0.2794 -0.6477)
			(stroke
				(width 0)
				(type default)
			)
			(fill no)
			(layer "F.Fab")
		)
		(pad "1" smd custom
			(at 0 -0.2794 270)
			(size 0.0762 0.0762)
			(layers "F.Cu" "F.Mask" "F.Paste")
			(net "SAS3008_RAID_TX_C_P3")
			(options
				(clearance outline)
				(anchor circle)
			)
			(primitives
				(gr_poly
					(pts
						(arc
							(start 0.1524 -0.127)
							(mid 0.137521 -0.162921)
							(end 0.1016 -0.1778)
						)
						(arc
							(start -0.1016 -0.1778)
							(mid -0.137521 -0.162921)
							(end -0.1524 -0.127)
						)
						(arc
							(start -0.1524 0.127)
							(mid -0.137521 0.162921)
							(end -0.1016 0.1778)
						)
						(arc
							(start 0.1016 0.1778)
							(mid 0.137521 0.162921)
							(end 0.1524 0.127)
						)
					)
					(width 0)
					(fill yes)
				)
			)
		)
		(pad "2" smd custom
			(at 0 0.2794 270)
			(size 0.0762 0.0762)
			(layers "F.Cu" "F.Mask" "F.Paste")
			(net "SAS3008_RAID_TX_P3")
			(options
				(clearance outline)
				(anchor circle)
			)
			(primitives
				(gr_poly
					(pts
						(arc
							(start 0.1524 -0.127)
							(mid 0.137521 -0.162921)
							(end 0.1016 -0.1778)
						)
						(arc
							(start -0.1016 -0.1778)
							(mid -0.137521 -0.162921)
							(end -0.1524 -0.127)
						)
						(arc
							(start -0.1524 0.127)
							(mid -0.137521 0.162921)
							(end -0.1016 0.1778)
						)
						(arc
							(start 0.1016 0.1778)
							(mid 0.137521 0.162921)
							(end 0.1524 0.127)
						)
					)
					(width 0)
					(fill yes)
				)
			)
		)
	)
	(footprint ""
		(layer "F.Cu")
		(at 318.389 -48.006 90)
		(property "Reference" "TC13"
			(at 0 0 90)
			(layer "F.SilkS")
			(hide yes)
			(effects
				(font
					(size 1.27 1.27)
				)
			)
		)
		(property "Value" "SC47U16V0MX-GP"
			(at -0.00254 -4.78536 90)
			(unlocked yes)
			(layer "F.Fab")
			(hide yes)
			(effects
				(font
					(size 1.016 1.016)
					(thickness 0.1524)
				)
			)
		)
		(property "Device Type" "C1210H107"
			(at -0.00254 -6.38048 90)
			(unlocked yes)
			(layer "F.Fab")
			(hide yes)
			(effects
				(font
					(size 1.016 1.016)
					(thickness 0.1524)
				)
			)
		)
		(duplicate_pad_numbers_are_jumpers no)
		(fp_line
			(start 1.5748 -2.3368)
			(end -1.5748 -2.3368)
			(stroke
				(width 0.1524)
				(type default)
			)
			(layer "F.SilkS")
		)
		(fp_line
			(start -1.5748 -2.3368)
			(end -1.5748 -0.762)
			(stroke
				(width 0.1524)
				(type default)
			)
			(layer "F.SilkS")
		)
		(fp_line
			(start 1.5748 -0.762)
			(end 1.5748 -2.3368)
			(stroke
				(width 0.1524)
				(type default)
			)
			(layer "F.SilkS")
		)
		(fp_line
			(start -1.5748 0.762)
			(end -1.5748 2.3368)
			(stroke
				(width 0.1524)
				(type default)
			)
			(layer "F.SilkS")
		)
		(fp_line
			(start 1.5748 2.3368)
			(end 1.5748 0.762)
			(stroke
				(width 0.1524)
				(type default)
			)
			(layer "F.SilkS")
		)
		(fp_line
			(start -1.5748 2.3368)
			(end 1.5748 2.3368)
			(stroke
				(width 0.1524)
				(type default)
			)
			(layer "F.SilkS")
		)
		(fp_rect
			(start -1.651 2.413)
			(end 1.651 -2.413)
			(stroke
				(width 0)
				(type default)
			)
			(fill no)
			(layer "F.CrtYd")
		)
		(fp_poly
			(pts
				(xy 1.651 2.413) (xy 1.651 -2.413) (xy -1.651 -2.413) (xy -1.651 2.413)
			)
			(stroke
				(width 0)
				(type default)
			)
			(fill no)
			(layer "F.Fab")
		)
		(pad "1" smd rect
			(at 0 -1.4732 90)
			(size 2.794 1.397)
			(layers "F.Cu" "F.Mask" "F.Paste")
			(net "P5V_STBY")
		)
		(pad "2" smd rect
			(at 0 1.4732 90)
			(size 2.794 1.397)
			(layers "F.Cu" "F.Mask" "F.Paste")
			(net "GND")
		)
	)
	(footprint ""
		(layer "F.Cu")
		(at 115.96497 -114.3 180)
		(property "Reference" "SC1074"
			(at 0 0 180)
			(layer "F.SilkS")
			(hide yes)
			(effects
				(font
					(size 1.27 1.27)
				)
			)
		)
		(property "Value" "SCD01U10V1KX-GP"
			(at -2.8321 -1.7399 180)
			(unlocked yes)
			(layer "F.Fab")
			(hide yes)
			(effects
				(font
					(size 1.016 1.016)
					(thickness 0.1524)
				)
			)
		)
		(property "Device Type" "C0201H13"
			(at -2.8321 -3.2639 180)
			(unlocked yes)
			(layer "F.Fab")
			(hide yes)
			(effects
				(font
					(size 1.016 1.016)
					(thickness 0.1524)
				)
			)
		)
		(duplicate_pad_numbers_are_jumpers no)
		(fp_rect
			(start -0.2794 0.6477)
			(end 0.2794 -0.6477)
			(stroke
				(width 0)
				(type default)
			)
			(fill no)
			(layer "F.CrtYd")
		)
		(fp_rect
			(start -0.2794 0.6477)
			(end 0.2794 -0.6477)
			(stroke
				(width 0)
				(type default)
			)
			(fill no)
			(layer "F.Fab")
		)
		(pad "1" smd custom
			(at 0 -0.2794 180)
			(size 0.0762 0.0762)
			(layers "F.Cu" "F.Mask" "F.Paste")
			(net "SAS_HDD_TX3_N")
			(options
				(clearance outline)
				(anchor circle)
			)
			(primitives
				(gr_poly
					(pts
						(arc
							(start 0.1524 -0.127)
							(mid 0.137521 -0.162921)
							(end 0.1016 -0.1778)
						)
						(arc
							(start -0.1016 -0.1778)
							(mid -0.137521 -0.162921)
							(end -0.1524 -0.127)
						)
						(arc
							(start -0.1524 0.127)
							(mid -0.137521 0.162921)
							(end -0.1016 0.1778)
						)
						(arc
							(start 0.1016 0.1778)
							(mid 0.137521 0.162921)
							(end 0.1524 0.127)
						)
					)
					(width 0)
					(fill yes)
				)
			)
		)
		(pad "2" smd custom
			(at 0 0.2794 180)
			(size 0.0762 0.0762)
			(layers "F.Cu" "F.Mask" "F.Paste")
			(net "SAS_HDD_REDV_TX7_N")
			(options
				(clearance outline)
				(anchor circle)
			)
			(primitives
				(gr_poly
					(pts
						(arc
							(start 0.1524 -0.127)
							(mid 0.137521 -0.162921)
							(end 0.1016 -0.1778)
						)
						(arc
							(start -0.1016 -0.1778)
							(mid -0.137521 -0.162921)
							(end -0.1524 -0.127)
						)
						(arc
							(start -0.1524 0.127)
							(mid -0.137521 0.162921)
							(end -0.1016 0.1778)
						)
						(arc
							(start 0.1016 0.1778)
							(mid 0.137521 0.162921)
							(end 0.1524 0.127)
						)
					)
					(width 0)
					(fill yes)
				)
			)
		)
	)
	(footprint ""
		(layer "F.Cu")
		(at 86.49716 -39.624 -90)
		(property "Reference" "SC893"
			(at 0 0 270)
			(layer "F.SilkS")
			(hide yes)
			(effects
				(font
					(size 1.27 1.27)
				)
			)
		)
		(property "Value" "SCD01U10V1KX-GP"
			(at -2.8321 -1.7399 270)
			(unlocked yes)
			(layer "F.Fab")
			(hide yes)
			(effects
				(font
					(size 1.016 1.016)
					(thickness 0.1524)
				)
			)
		)
		(property "Device Type" "C0201H13"
			(at -2.8321 -3.2639 270)
			(unlocked yes)
			(layer "F.Fab")
			(hide yes)
			(effects
				(font
					(size 1.016 1.016)
					(thickness 0.1524)
				)
			)
		)
		(duplicate_pad_numbers_are_jumpers no)
		(fp_rect
			(start -0.2794 0.6477)
			(end 0.2794 -0.6477)
			(stroke
				(width 0)
				(type default)
			)
			(fill no)
			(layer "F.CrtYd")
		)
		(fp_rect
			(start -0.2794 0.6477)
			(end 0.2794 -0.6477)
			(stroke
				(width 0)
				(type default)
			)
			(fill no)
			(layer "F.Fab")
		)
		(pad "1" smd custom
			(at 0 -0.2794 270)
			(size 0.0762 0.0762)
			(layers "F.Cu" "F.Mask" "F.Paste")
			(net "SAS3008_RAID_TX_C_N7")
			(options
				(clearance outline)
				(anchor circle)
			)
			(primitives
				(gr_poly
					(pts
						(arc
							(start 0.1524 -0.127)
							(mid 0.137521 -0.162921)
							(end 0.1016 -0.1778)
						)
						(arc
							(start -0.1016 -0.1778)
							(mid -0.137521 -0.162921)
							(end -0.1524 -0.127)
						)
						(arc
							(start -0.1524 0.127)
							(mid -0.137521 0.162921)
							(end -0.1016 0.1778)
						)
						(arc
							(start 0.1016 0.1778)
							(mid 0.137521 0.162921)
							(end 0.1524 0.127)
						)
					)
					(width 0)
					(fill yes)
				)
			)
		)
		(pad "2" smd custom
			(at 0 0.2794 270)
			(size 0.0762 0.0762)
			(layers "F.Cu" "F.Mask" "F.Paste")
			(net "IOC_RAID_TX_N7")
			(options
				(clearance outline)
				(anchor circle)
			)
			(primitives
				(gr_poly
					(pts
						(arc
							(start 0.1524 -0.127)
							(mid 0.137521 -0.162921)
							(end 0.1016 -0.1778)
						)
						(arc
							(start -0.1016 -0.1778)
							(mid -0.137521 -0.162921)
							(end -0.1524 -0.127)
						)
						(arc
							(start -0.1524 0.127)
							(mid -0.137521 0.162921)
							(end -0.1016 0.1778)
						)
						(arc
							(start 0.1016 0.1778)
							(mid 0.137521 0.162921)
							(end 0.1524 0.127)
						)
					)
					(width 0)
					(fill yes)
				)
			)
		)
	)
	(footprint ""
		(layer "F.Cu")
		(at 241.9223 -118.1608 180)
		(property "Reference" "SR935"
			(at 0 0 180)
			(layer "F.SilkS")
			(hide yes)
			(effects
				(font
					(size 1.27 1.27)
				)
			)
		)
		(property "Value" "0R2J-2-GP"
			(at 0.064008 -3.993896 180)
			(unlocked yes)
			(layer "F.Fab")
			(hide yes)
			(effects
				(font
					(size 1.016 1.016)
					(thickness 0.1524)
				)
			)
		)
		(property "Device Type" "R402H16"
			(at 0.064008 -5.517896 180)
			(unlocked yes)
			(layer "F.Fab")
			(hide yes)
			(effects
				(font
					(size 1.016 1.016)
					(thickness 0.1524)
				)
			)
		)
		(duplicate_pad_numbers_are_jumpers no)
		(fp_line
			(start 0.508 -0.9398)
			(end -0.508 -0.9398)
			(stroke
				(width 0.1524)
				(type default)
			)
			(layer "F.SilkS")
		)
		(fp_line
			(start -0.508 -0.9398)
			(end -0.508 0.9398)
			(stroke
				(width 0.1524)
				(type default)
			)
			(layer "F.SilkS")
		)
		(fp_rect
			(start -0.508 0.9398)
			(end 0.508 -0.9398)
			(stroke
				(width 0)
				(type default)
			)
			(fill no)
			(layer "F.CrtYd")
		)
		(fp_rect
			(start -0.508 0.9398)
			(end 0.508 -0.9398)
			(stroke
				(width 0)
				(type default)
			)
			(fill no)
			(layer "F.Fab")
		)
		(pad "1" smd custom
			(at 0 -0.4445 180)
			(size 0.1397 0.1397)
			(layers "F.Cu" "F.Mask" "F.Paste")
			(net "SAS_SMART_R_TX")
			(options
				(clearance outline)
				(anchor circle)
			)
			(primitives
				(gr_poly
					(pts
						(arc
							(start -0.1778 -0.2794)
							(mid -0.249642 -0.249642)
							(end -0.2794 -0.1778)
						)
						(arc
							(start -0.2794 0.1778)
							(mid -0.249642 0.249642)
							(end -0.1778 0.2794)
						)
						(arc
							(start 0.1778 0.2794)
							(mid 0.249642 0.249642)
							(end 0.2794 0.1778)
						)
						(arc
							(start 0.2794 -0.1778)
							(mid 0.249642 -0.249642)
							(end 0.1778 -0.2794)
						)
					)
					(width 0)
					(fill yes)
				)
			)
		)
		(pad "2" smd custom
			(at 0 0.4445 180)
			(size 0.1397 0.1397)
			(layers "F.Cu" "F.Mask" "F.Paste")
			(net "SAS_SMART_TX")
			(options
				(clearance outline)
				(anchor circle)
			)
			(primitives
				(gr_poly
					(pts
						(arc
							(start -0.1778 -0.2794)
							(mid -0.249642 -0.249642)
							(end -0.2794 -0.1778)
						)
						(arc
							(start -0.2794 0.1778)
							(mid -0.249642 0.249642)
							(end -0.1778 0.2794)
						)
						(arc
							(start 0.1778 0.2794)
							(mid 0.249642 0.249642)
							(end 0.2794 0.1778)
						)
						(arc
							(start 0.2794 -0.1778)
							(mid 0.249642 -0.249642)
							(end 0.1778 -0.2794)
						)
					)
					(width 0)
					(fill yes)
				)
			)
		)
	)
	(footprint ""
		(layer "F.Cu")
		(at 86.976966 -80.137)
		(property "Reference" "SC1196"
			(at 0 0 0)
			(layer "F.SilkS")
			(hide yes)
			(effects
				(font
					(size 1.27 1.27)
				)
			)
		)
		(property "Value" "SC1U6D3V1MX-GP"
			(at 1.9177 2.0193 0)
			(unlocked yes)
			(layer "F.Fab")
			(hide yes)
			(effects
				(font
					(size 1.016 1.016)
					(thickness 0.1524)
				)
			)
		)
		(property "Device Type" "C0201H14"
			(at 1.9177 0.4953 0)
			(unlocked yes)
			(layer "F.Fab")
			(hide yes)
			(effects
				(font
					(size 1.016 1.016)
					(thickness 0.1524)
				)
			)
		)
		(duplicate_pad_numbers_are_jumpers no)
		(fp_rect
			(start -0.1524 0.3048)
			(end 0.1524 -0.3048)
			(stroke
				(width 0)
				(type default)
			)
			(fill no)
			(layer "F.CrtYd")
		)
		(fp_poly
			(pts
				(xy -0.2794 0.6477) (xy -0.2794 -0.6477) (xy 0.2794 -0.6477) (xy 0.2794 -0.1905) (xy 0.1524 -0.1905)
				(xy 0.1524 -0.3048) (xy -0.1524 -0.3048) (xy -0.1524 0.3048) (xy 0.1524 0.3048) (xy 0.1524 -0.1778)
				(xy 0.2794 -0.1778) (xy 0.2794 0.6477)
			)
			(stroke
				(width 0)
				(type default)
			)
			(fill no)
			(layer "F.CrtYd")
		)
		(fp_rect
			(start -0.2794 0.6477)
			(end 0.2794 -0.6477)
			(stroke
				(width 0)
				(type default)
			)
			(fill no)
			(layer "F.Fab")
		)
		(pad "1" smd custom
			(at 0 -0.2794)
			(size 0.0762 0.0762)
			(layers "F.Cu" "F.Mask" "F.Paste")
			(net "XTAL_VDDA09")
			(options
				(clearance outline)
				(anchor circle)
			)
			(primitives
				(gr_poly
					(pts
						(arc
							(start 0.1524 -0.127)
							(mid 0.137521 -0.162921)
							(end 0.1016 -0.1778)
						)
						(arc
							(start -0.1016 -0.1778)
							(mid -0.137521 -0.162921)
							(end -0.1524 -0.127)
						)
						(arc
							(start -0.1524 0.127)
							(mid -0.137521 0.162921)
							(end -0.1016 0.1778)
						)
						(arc
							(start 0.1016 0.1778)
							(mid 0.137521 0.162921)
							(end 0.1524 0.127)
						)
					)
					(width 0)
					(fill yes)
				)
			)
		)
		(pad "2" smd custom
			(at 0 0.2794)
			(size 0.0762 0.0762)
			(layers "F.Cu" "F.Mask" "F.Paste")
			(net "GND")
			(options
				(clearance outline)
				(anchor circle)
			)
			(primitives
				(gr_poly
					(pts
						(arc
							(start 0.1524 -0.127)
							(mid 0.137521 -0.162921)
							(end 0.1016 -0.1778)
						)
						(arc
							(start -0.1016 -0.1778)
							(mid -0.137521 -0.162921)
							(end -0.1524 -0.127)
						)
						(arc
							(start -0.1524 0.127)
							(mid -0.137521 0.162921)
							(end -0.1016 0.1778)
						)
						(arc
							(start 0.1016 0.1778)
							(mid 0.137521 0.162921)
							(end 0.1524 0.127)
						)
					)
					(width 0)
					(fill yes)
				)
			)
		)
	)
	(footprint ""
		(layer "F.Cu")
		(at 333.912718 -150.091648 90)
		(property "Reference" "R548"
			(at 0 0 90)
			(layer "F.SilkS")
			(hide yes)
			(effects
				(font
					(size 1.27 1.27)
				)
			)
		)
		(property "Value" "4K7R2F-GP"
			(at 0.064008 -3.993896 90)
			(unlocked yes)
			(layer "F.Fab")
			(hide yes)
			(effects
				(font
					(size 1.016 1.016)
					(thickness 0.1524)
				)
			)
		)
		(property "Device Type" "R402H16"
			(at 0.064008 -5.517896 90)
			(unlocked yes)
			(layer "F.Fab")
			(hide yes)
			(effects
				(font
					(size 1.016 1.016)
					(thickness 0.1524)
				)
			)
		)
		(duplicate_pad_numbers_are_jumpers no)
		(fp_line
			(start 0.508 -0.9398)
			(end -0.508 -0.9398)
			(stroke
				(width 0.1524)
				(type default)
			)
			(layer "F.SilkS")
		)
		(fp_line
			(start -0.508 -0.9398)
			(end -0.508 0.9398)
			(stroke
				(width 0.1524)
				(type default)
			)
			(layer "F.SilkS")
		)
		(fp_rect
			(start -0.508 0.9398)
			(end 0.508 -0.9398)
			(stroke
				(width 0)
				(type default)
			)
			(fill no)
			(layer "F.CrtYd")
		)
		(fp_rect
			(start -0.508 0.9398)
			(end 0.508 -0.9398)
			(stroke
				(width 0)
				(type default)
			)
			(fill no)
			(layer "F.Fab")
		)
		(pad "1" smd custom
			(at 0 -0.4445 90)
			(size 0.1397 0.1397)
			(layers "F.Cu" "F.Mask" "F.Paste")
			(net "P3V3_STBY")
			(options
				(clearance outline)
				(anchor circle)
			)
			(primitives
				(gr_poly
					(pts
						(arc
							(start -0.1778 -0.2794)
							(mid -0.249642 -0.249642)
							(end -0.2794 -0.1778)
						)
						(arc
							(start -0.2794 0.1778)
							(mid -0.249642 0.249642)
							(end -0.1778 0.2794)
						)
						(arc
							(start 0.1778 0.2794)
							(mid 0.249642 0.249642)
							(end 0.2794 0.1778)
						)
						(arc
							(start 0.2794 -0.1778)
							(mid 0.249642 -0.249642)
							(end 0.1778 -0.2794)
						)
					)
					(width 0)
					(fill yes)
				)
			)
		)
		(pad "2" smd custom
			(at 0 0.4445 90)
			(size 0.1397 0.1397)
			(layers "F.Cu" "F.Mask" "F.Paste")
			(net "CFG_SEL0")
			(options
				(clearance outline)
				(anchor circle)
			)
			(primitives
				(gr_poly
					(pts
						(arc
							(start -0.1778 -0.2794)
							(mid -0.249642 -0.249642)
							(end -0.2794 -0.1778)
						)
						(arc
							(start -0.2794 0.1778)
							(mid -0.249642 0.249642)
							(end -0.1778 0.2794)
						)
						(arc
							(start 0.1778 0.2794)
							(mid 0.249642 0.249642)
							(end 0.2794 0.1778)
						)
						(arc
							(start 0.2794 -0.1778)
							(mid 0.249642 -0.249642)
							(end 0.1778 -0.2794)
						)
					)
					(width 0)
					(fill yes)
				)
			)
		)
	)
	(footprint ""
		(layer "F.Cu")
		(at 261.874 -37.338 180)
		(property "Reference" "PR53"
			(at 0 0 180)
			(layer "F.SilkS")
			(hide yes)
			(effects
				(font
					(size 1.27 1.27)
				)
			)
		)
		(property "Value" "20KR2F-L-GP"
			(at 0.064008 -3.993896 180)
			(unlocked yes)
			(layer "F.Fab")
			(hide yes)
			(effects
				(font
					(size 1.016 1.016)
					(thickness 0.1524)
				)
			)
		)
		(property "Device Type" "R402H16"
			(at 0.064008 -5.517896 180)
			(unlocked yes)
			(layer "F.Fab")
			(hide yes)
			(effects
				(font
					(size 1.016 1.016)
					(thickness 0.1524)
				)
			)
		)
		(duplicate_pad_numbers_are_jumpers no)
		(fp_line
			(start 0.508 -0.9398)
			(end -0.508 -0.9398)
			(stroke
				(width 0.1524)
				(type default)
			)
			(layer "F.SilkS")
		)
		(fp_line
			(start -0.508 -0.9398)
			(end -0.508 0.9398)
			(stroke
				(width 0.1524)
				(type default)
			)
			(layer "F.SilkS")
		)
		(fp_rect
			(start -0.508 0.9398)
			(end 0.508 -0.9398)
			(stroke
				(width 0)
				(type default)
			)
			(fill no)
			(layer "F.CrtYd")
		)
		(fp_rect
			(start -0.508 0.9398)
			(end 0.508 -0.9398)
			(stroke
				(width 0)
				(type default)
			)
			(fill no)
			(layer "F.Fab")
		)
		(pad "1" smd custom
			(at 0 -0.4445 180)
			(size 0.1397 0.1397)
			(layers "F.Cu" "F.Mask" "F.Paste")
			(net "P1V8_STBY_VFB")
			(options
				(clearance outline)
				(anchor circle)
			)
			(primitives
				(gr_poly
					(pts
						(arc
							(start -0.1778 -0.2794)
							(mid -0.249642 -0.249642)
							(end -0.2794 -0.1778)
						)
						(arc
							(start -0.2794 0.1778)
							(mid -0.249642 0.249642)
							(end -0.1778 0.2794)
						)
						(arc
							(start 0.1778 0.2794)
							(mid 0.249642 0.249642)
							(end 0.2794 0.1778)
						)
						(arc
							(start 0.2794 -0.1778)
							(mid 0.249642 -0.249642)
							(end 0.1778 -0.2794)
						)
					)
					(width 0)
					(fill yes)
				)
			)
		)
		(pad "2" smd custom
			(at 0 0.4445 180)
			(size 0.1397 0.1397)
			(layers "F.Cu" "F.Mask" "F.Paste")
			(net "P1V8_STBY_VFB_R")
			(options
				(clearance outline)
				(anchor circle)
			)
			(primitives
				(gr_poly
					(pts
						(arc
							(start -0.1778 -0.2794)
							(mid -0.249642 -0.249642)
							(end -0.2794 -0.1778)
						)
						(arc
							(start -0.2794 0.1778)
							(mid -0.249642 0.249642)
							(end -0.1778 0.2794)
						)
						(arc
							(start 0.1778 0.2794)
							(mid 0.249642 0.249642)
							(end 0.2794 0.1778)
						)
						(arc
							(start 0.2794 -0.1778)
							(mid 0.249642 -0.249642)
							(end 0.1778 -0.2794)
						)
					)
					(width 0)
					(fill yes)
				)
			)
		)
	)
	(footprint ""
		(layer "F.Cu")
		(at 193.416936 -141.221714 90)
		(property "Reference" "SU67"
			(at 0 0 90)
			(layer "F.SilkS")
			(hide yes)
			(effects
				(font
					(size 1.27 1.27)
				)
			)
		)
		(property "Value" "AT24C64D-SSHM-T-GP"
			(at -3.707384 -1.5367 90)
			(unlocked yes)
			(layer "F.Fab")
			(hide yes)
			(effects
				(font
					(size 1.016 1.016)
					(thickness 0.1524)
				)
			)
		)
		(property "Device Type" "SOIC8H69"
			(at -3.707384 -3.0607 90)
			(unlocked yes)
			(layer "F.Fab")
			(hide yes)
			(effects
				(font
					(size 1.016 1.016)
					(thickness 0.1524)
				)
			)
		)
		(duplicate_pad_numbers_are_jumpers no)
		(fp_line
			(start 2.1336 -1.4224)
			(end -2.7432 -1.4224)
			(stroke
				(width 0.1524)
				(type default)
			)
			(layer "F.SilkS")
		)
		(fp_line
			(start -2.7432 -1.4224)
			(end -2.7432 1.4224)
			(stroke
				(width 0.1524)
				(type default)
			)
			(layer "F.SilkS")
		)
		(fp_line
			(start -2.7178 -0.508)
			(end -2.1844 -0.0508)
			(stroke
				(width 0.1524)
				(type default)
			)
			(layer "F.SilkS")
		)
		(fp_line
			(start -2.1844 -0.0508)
			(end -2.7178 0.508)
			(stroke
				(width 0.1524)
				(type default)
			)
			(layer "F.SilkS")
		)
		(fp_line
			(start 2.1336 1.4224)
			(end 2.1336 -1.4224)
			(stroke
				(width 0.1524)
				(type default)
			)
			(layer "F.SilkS")
		)
		(fp_line
			(start -2.7432 1.4224)
			(end 2.1336 1.4224)
			(stroke
				(width 0.1524)
				(type default)
			)
			(layer "F.SilkS")
		)
		(fp_line
			(start -2.7432 1.4224)
			(end -2.6416 1.4224)
			(stroke
				(width 0.1524)
				(type default)
			)
			(layer "F.SilkS")
		)
		(fp_line
			(start -2.6289 3.4417)
			(end -2.6289 1.4732)
			(stroke
				(width 0.381)
				(type default)
			)
			(layer "F.SilkS")
		)
		(fp_poly
			(pts
				(xy -2.2098 -1.4224) (xy -2.2098 1.4224) (xy 2.2098 1.4224) (xy 2.2098 -1.4224)
			)
			(stroke
				(width 0)
				(type default)
			)
			(fill yes)
			(layer "F.SilkS")
		)
		(fp_rect
			(start -2.450084 2.999994)
			(end 2.450084 -2.999994)
			(stroke
				(width 0)
				(type default)
			)
			(fill no)
			(layer "F.CrtYd")
		)
		(fp_poly
			(pts
				(xy -2.8194 3.6322) (xy -2.8194 -3.6322) (xy 2.8194 -3.6322) (xy 2.8194 1.18364) (xy 2.450084 1.18364)
				(xy 2.450084 -2.999994) (xy -2.450084 -2.999994) (xy -2.450084 2.999994) (xy 2.450084 2.999994)
				(xy 2.450084 1.18618) (xy 2.8194 1.18618) (xy 2.8194 3.6322)
			)
			(stroke
				(width 0)
				(type default)
			)
			(fill no)
			(layer "F.CrtYd")
		)
		(fp_rect
			(start -2.8194 3.6322)
			(end 2.8194 -3.6322)
			(stroke
				(width 0)
				(type default)
			)
			(fill no)
			(layer "F.Fab")
		)
		(pad "1" smd rect
			(at -1.905 2.54 90)
			(size 0.635 1.651)
			(layers "F.Cu" "F.Mask" "F.Paste")
			(net "EXP_EEPROM_A0")
		)
		(pad "2" smd rect
			(at -0.635 2.54 90)
			(size 0.635 1.651)
			(layers "F.Cu" "F.Mask" "F.Paste")
			(net "EXP_EEPROM_A1")
		)
		(pad "3" smd rect
			(at 0.635 2.54 90)
			(size 0.635 1.651)
			(layers "F.Cu" "F.Mask" "F.Paste")
			(net "EXP_EEPROM_A2")
		)
		(pad "4" smd rect
			(at 1.905 2.54 90)
			(size 0.635 1.651)
			(layers "F.Cu" "F.Mask" "F.Paste")
			(net "GND")
		)
		(pad "5" smd rect
			(at 1.905 -2.54 90)
			(size 0.635 1.651)
			(layers "F.Cu" "F.Mask" "F.Paste")
			(net "EXP_EEPROM_SDA")
		)
		(pad "6" smd rect
			(at 0.635 -2.54 90)
			(size 0.635 1.651)
			(layers "F.Cu" "F.Mask" "F.Paste")
			(net "EXP_EEPROM_SCL")
		)
		(pad "7" smd rect
			(at -0.635 -2.54 90)
			(size 0.635 1.651)
			(layers "F.Cu" "F.Mask" "F.Paste")
			(net "EXP_EEPROM_WP")
		)
		(pad "8" smd rect
			(at -1.905 -2.54 90)
			(size 0.635 1.651)
			(layers "F.Cu" "F.Mask" "F.Paste")
			(net "P1V8_E")
		)
	)
	(footprint ""
		(layer "F.Cu")
		(at 346.858336 -76.538328 180)
		(property "Reference" "U19"
			(at 0 0 180)
			(layer "F.SilkS")
			(hide yes)
			(effects
				(font
					(size 1.27 1.27)
				)
			)
		)
		(property "Value" "MX25L25635FMI-10G-GP"
			(at 0 -14.6812 180)
			(unlocked yes)
			(layer "F.Fab")
			(hide yes)
			(effects
				(font
					(size 1.016 1.016)
					(thickness 0.1524)
				)
			)
		)
		(property "Device Type" "SOIC16-6H105"
			(at 0 -16.2052 180)
			(unlocked yes)
			(layer "F.Fab")
			(hide yes)
			(effects
				(font
					(size 1.016 1.016)
					(thickness 0.1524)
				)
			)
		)
		(duplicate_pad_numbers_are_jumpers no)
		(fp_line
			(start 4.7498 3.2258)
			(end -5.588 3.2258)
			(stroke
				(width 0.1524)
				(type default)
			)
			(layer "F.SilkS")
		)
		(fp_line
			(start 4.7498 -3.2258)
			(end 4.7498 3.2258)
			(stroke
				(width 0.1524)
				(type default)
			)
			(layer "F.SilkS")
		)
		(fp_line
			(start -5.08762 0)
			(end -5.588 0.50038)
			(stroke
				(width 0.1524)
				(type default)
			)
			(layer "F.SilkS")
		)
		(fp_line
			(start -5.4102 3.2258)
			(end -5.4102 5.7912)
			(stroke
				(width 0.508)
				(type default)
			)
			(layer "F.SilkS")
		)
		(fp_line
			(start -5.588 3.2258)
			(end -5.588 -3.2258)
			(stroke
				(width 0.1524)
				(type default)
			)
			(layer "F.SilkS")
		)
		(fp_line
			(start -5.588 -0.50038)
			(end -5.08762 0)
			(stroke
				(width 0.1524)
				(type default)
			)
			(layer "F.SilkS")
		)
		(fp_line
			(start -5.588 -3.2258)
			(end 4.7498 -3.2258)
			(stroke
				(width 0.1524)
				(type default)
			)
			(layer "F.SilkS")
		)
		(fp_poly
			(pts
				(xy -4.764786 -3.2258) (xy 4.7625 -3.2258) (xy 4.7625 3.2258) (xy -4.764786 3.2258)
			)
			(stroke
				(width 0)
				(type default)
			)
			(fill yes)
			(layer "F.SilkS")
		)
		(fp_poly
			(pts
				(xy -5.6642 6.0452) (xy 5.6642 6.0452) (xy 5.6642 -6.0452) (xy -5.6642 -6.0452)
			)
			(stroke
				(width 0)
				(type default)
			)
			(fill no)
			(layer "F.CrtYd")
		)
		(fp_poly
			(pts
				(xy -5.6642 -6.0452) (xy 5.6642 -6.0452) (xy 5.6642 6.0452) (xy -5.6642 6.0452)
			)
			(stroke
				(width 0)
				(type default)
			)
			(fill no)
			(layer "F.Fab")
		)
		(pad "1" smd rect
			(at -4.445 4.71805 180)
			(size 0.635 1.651)
			(layers "F.Cu" "F.Mask" "F.Paste")
			(net "PU_IBMC_BT_HOLD_N")
		)
		(pad "2" smd rect
			(at -3.175 4.71805 180)
			(size 0.635 1.651)
			(layers "F.Cu" "F.Mask" "F.Paste")
			(net "P3V3_STBY")
		)
		(pad "3" smd rect
			(at -1.905 4.71805 180)
			(size 0.635 1.651)
			(layers "F.Cu" "F.Mask" "F.Paste")
			(net "Net_2083")
		)
		(pad "4" smd rect
			(at -0.635 4.71805 180)
			(size 0.635 1.651)
			(layers "F.Cu" "F.Mask" "F.Paste")
			(net "Net_2082")
		)
		(pad "5" smd rect
			(at 0.635 4.71805 180)
			(size 0.635 1.651)
			(layers "F.Cu" "F.Mask" "F.Paste")
			(net "Net_2081")
		)
		(pad "6" smd rect
			(at 1.905 4.71805 180)
			(size 0.635 1.651)
			(layers "F.Cu" "F.Mask" "F.Paste")
			(net "Net_2080")
		)
		(pad "7" smd rect
			(at 3.175 4.71805 180)
			(size 0.635 1.651)
			(layers "F.Cu" "F.Mask" "F.Paste")
			(net "FLA_CS_R")
		)
		(pad "8" smd rect
			(at 4.445 4.71805 180)
			(size 0.635 1.651)
			(layers "F.Cu" "F.Mask" "F.Paste")
			(net "ROMD2_R")
		)
		(pad "9" smd rect
			(at 4.445 -4.71805 180)
			(size 0.635 1.651)
			(layers "F.Cu" "F.Mask" "F.Paste")
			(net "FLA_WPN")
		)
		(pad "10" smd rect
			(at 3.175 -4.71805 180)
			(size 0.635 1.651)
			(layers "F.Cu" "F.Mask" "F.Paste")
			(net "GND")
		)
		(pad "11" smd rect
			(at 1.905 -4.71805 180)
			(size 0.635 1.651)
			(layers "F.Cu" "F.Mask" "F.Paste")
			(net "Net_2079")
		)
		(pad "12" smd rect
			(at 0.635 -4.71805 180)
			(size 0.635 1.651)
			(layers "F.Cu" "F.Mask" "F.Paste")
			(net "Net_2078")
		)
		(pad "13" smd rect
			(at -0.635 -4.71805 180)
			(size 0.635 1.651)
			(layers "F.Cu" "F.Mask" "F.Paste")
			(net "Net_2077")
		)
		(pad "14" smd rect
			(at -1.905 -4.71805 180)
			(size 0.635 1.651)
			(layers "F.Cu" "F.Mask" "F.Paste")
			(net "Net_2076")
		)
		(pad "15" smd rect
			(at -3.175 -4.71805 180)
			(size 0.635 1.651)
			(layers "F.Cu" "F.Mask" "F.Paste")
			(net "ROMD1_R")
		)
		(pad "16" smd rect
			(at -4.445 -4.71805 180)
			(size 0.635 1.651)
			(layers "F.Cu" "F.Mask" "F.Paste")
			(net "ROMD0_R")
		)
	)
	(footprint ""
		(layer "F.Cu")
		(at 108.540042 -2.029968 90)
		(property "Reference" "LED4"
			(at 0 0 90)
			(layer "F.SilkS")
			(hide yes)
			(effects
				(font
					(size 1.27 1.27)
				)
			)
		)
		(property "Value" "LED-B-77-GP-U3"
			(at -0.7112 -3.6068 90)
			(unlocked yes)
			(layer "F.Fab")
			(hide yes)
			(effects
				(font
					(size 1.016 1.016)
					(thickness 0.1524)
				)
			)
		)
		(property "Device Type" "LED3020AK-U2H44"
			(at -0.7112 -5.1308 90)
			(unlocked yes)
			(layer "F.Fab")
			(hide yes)
			(effects
				(font
					(size 1.016 1.016)
					(thickness 0.1524)
				)
			)
		)
		(duplicate_pad_numbers_are_jumpers no)
		(fp_line
			(start 0.8382 -2.4003)
			(end -0.8382 -2.4003)
			(stroke
				(width 0.1524)
				(type default)
			)
			(layer "F.SilkS")
		)
		(fp_line
			(start -0.8382 -2.4003)
			(end -0.8382 -1.31445)
			(stroke
				(width 0.1524)
				(type default)
			)
			(layer "F.SilkS")
		)
		(fp_line
			(start -0.8382 1.31445)
			(end -0.8382 2.4003)
			(stroke
				(width 0.1524)
				(type default)
			)
			(layer "F.SilkS")
		)
		(fp_line
			(start 0.8382 2.4003)
			(end 0.8382 -2.4003)
			(stroke
				(width 0.1524)
				(type default)
			)
			(layer "F.SilkS")
		)
		(fp_line
			(start -0.8382 2.4003)
			(end 0.8382 2.4003)
			(stroke
				(width 0.1524)
				(type default)
			)
			(layer "F.SilkS")
		)
		(fp_line
			(start 0.889 2.5273)
			(end -0.889 2.5273)
			(stroke
				(width 0.4064)
				(type default)
			)
			(layer "F.SilkS")
		)
		(fp_arc
			(start -0.8382 1.31445)
			(mid -1.85412 0)
			(end -0.8382 -1.31445)
			(stroke
				(width 0.1524)
				(type default)
			)
			(layer "F.SilkS")
		)
		(fp_poly
			(pts
				(xy -1.0922 2.6543) (xy -1.0922 1.49606) (xy -1.15189 1.4732) (xy -1.27254 1.41351) (xy -1.38557 1.34493)
				(xy -1.49098 1.26873) (xy -1.59258 1.18237) (xy -1.68656 1.08712) (xy -1.77165 0.98552) (xy -1.84785 0.87757)
				(xy -1.91516 0.76454) (xy -1.97358 0.64262) (xy -2.02057 0.5207) (xy -2.05867 0.3937) (xy -2.08534 0.26416)
				(xy -2.10185 0.13335) (xy -2.1082 0) (xy -2.10185 -0.13335) (xy -2.08534 -0.26416) (xy -2.05867 -0.3937)
				(xy -2.02057 -0.5207) (xy -1.97358 -0.64262) (xy -1.91516 -0.76454) (xy -1.84785 -0.87757) (xy -1.77165 -0.98552)
				(xy -1.68656 -1.08712) (xy -1.59258 -1.18237) (xy -1.49098 -1.26873) (xy -1.38557 -1.34493) (xy -1.27254 -1.41351)
				(xy -1.15189 -1.4732) (xy -1.0922 -1.49606) (xy -1.0922 -2.6543) (xy 1.0922 -2.6543) (xy 1.0922 2.6543)
			)
			(stroke
				(width 0)
				(type default)
			)
			(fill no)
			(layer "F.CrtYd")
		)
		(fp_poly
			(pts
				(xy -1.0922 2.6543) (xy -1.0922 1.49606) (xy -1.15189 1.4732) (xy -1.27254 1.41351) (xy -1.38557 1.34493)
				(xy -1.49098 1.26873) (xy -1.59258 1.18237) (xy -1.68656 1.08712) (xy -1.77165 0.98552) (xy -1.84785 0.87757)
				(xy -1.91516 0.76454) (xy -1.97358 0.64262) (xy -2.02057 0.5207) (xy -2.05867 0.3937) (xy -2.08534 0.26416)
				(xy -2.10185 0.13335) (xy -2.1082 0) (xy -2.10185 -0.13335) (xy -2.08534 -0.26416) (xy -2.05867 -0.3937)
				(xy -2.02057 -0.5207) (xy -1.97358 -0.64262) (xy -1.91516 -0.76454) (xy -1.84785 -0.87757) (xy -1.77165 -0.98552)
				(xy -1.68656 -1.08712) (xy -1.59258 -1.18237) (xy -1.49098 -1.26873) (xy -1.38557 -1.34493) (xy -1.27254 -1.41351)
				(xy -1.15189 -1.4732) (xy -1.0922 -1.49606) (xy -1.0922 -2.6543) (xy 1.0922 -2.6543) (xy 1.0922 2.6543)
			)
			(stroke
				(width 0)
				(type default)
			)
			(fill no)
			(layer "F.Fab")
		)
		(pad "A" smd rect
			(at 0 -1.57099 90)
			(size 1.143 1.143)
			(layers "F.Cu" "F.Mask" "F.Paste")
			(net "ENCLO_LED_RED_R")
		)
		(pad "K" smd rect
			(at 0 1.57099 90)
			(size 1.143 1.143)
			(layers "F.Cu" "F.Mask" "F.Paste")
			(net "ENCLO_LED_RED_D1")
		)
	)
	(footprint ""
		(layer "F.Cu")
		(at 216.154 -97.79 -90)
		(property "Reference" "PC138"
			(at 0 0 270)
			(layer "F.SilkS")
			(hide yes)
			(effects
				(font
					(size 1.27 1.27)
				)
			)
		)
		(property "Value" "SCD1U16V2KX-3GP"
			(at 1.1811 -2.7051 270)
			(unlocked yes)
			(layer "F.Fab")
			(hide yes)
			(effects
				(font
					(size 1.016 1.016)
					(thickness 0.1524)
				)
			)
		)
		(property "Device Type" "C402H22"
			(at 1.1811 -4.2291 270)
			(unlocked yes)
			(layer "F.Fab")
			(hide yes)
			(effects
				(font
					(size 1.016 1.016)
					(thickness 0.1524)
				)
			)
		)
		(duplicate_pad_numbers_are_jumpers no)
		(fp_rect
			(start -0.4318 0.9525)
			(end 0.4318 -0.9525)
			(stroke
				(width 0)
				(type default)
			)
			(fill no)
			(layer "F.CrtYd")
		)
		(fp_rect
			(start -0.4318 0.9525)
			(end 0.4318 -0.9525)
			(stroke
				(width 0)
				(type default)
			)
			(fill no)
			(layer "F.Fab")
		)
		(pad "1" smd custom
			(at 0 -0.4445 270)
			(size 0.1524 0.1524)
			(layers "F.Cu" "F.Mask" "F.Paste")
			(net "TPS74801_P1V5_C_IN")
			(options
				(clearance outline)
				(anchor circle)
			)
			(primitives
				(gr_poly
					(pts
						(arc
							(start 0.3048 -0.2032)
							(mid 0.275042 -0.275042)
							(end 0.2032 -0.3048)
						)
						(arc
							(start -0.2032 -0.3048)
							(mid -0.275042 -0.275042)
							(end -0.3048 -0.2032)
						)
						(arc
							(start -0.3048 0.2032)
							(mid -0.275042 0.275042)
							(end -0.2032 0.3048)
						)
						(arc
							(start 0.2032 0.3048)
							(mid 0.275042 0.275042)
							(end 0.3048 0.2032)
						)
					)
					(width 0)
					(fill yes)
				)
			)
		)
		(pad "2" smd custom
			(at 0 0.4445 270)
			(size 0.1524 0.1524)
			(layers "F.Cu" "F.Mask" "F.Paste")
			(net "GND")
			(options
				(clearance outline)
				(anchor circle)
			)
			(primitives
				(gr_poly
					(pts
						(arc
							(start 0.3048 -0.2032)
							(mid 0.275042 -0.275042)
							(end 0.2032 -0.3048)
						)
						(arc
							(start -0.2032 -0.3048)
							(mid -0.275042 -0.275042)
							(end -0.3048 -0.2032)
						)
						(arc
							(start -0.3048 0.2032)
							(mid -0.275042 0.275042)
							(end -0.2032 0.3048)
						)
						(arc
							(start 0.2032 0.3048)
							(mid 0.275042 0.275042)
							(end 0.3048 0.2032)
						)
					)
					(width 0)
					(fill yes)
				)
			)
		)
	)
	(footprint ""
		(layer "F.Cu")
		(at 173.325028 -31.608268)
		(property "Reference" "R385"
			(at 0 0 0)
			(layer "F.SilkS")
			(hide yes)
			(effects
				(font
					(size 1.27 1.27)
				)
			)
		)
		(property "Value" "0R2J-2-GP"
			(at 0.064008 -3.993896 0)
			(unlocked yes)
			(layer "F.Fab")
			(hide yes)
			(effects
				(font
					(size 1.016 1.016)
					(thickness 0.1524)
				)
			)
		)
		(property "Device Type" "R402H16"
			(at 0.064008 -5.517896 0)
			(unlocked yes)
			(layer "F.Fab")
			(hide yes)
			(effects
				(font
					(size 1.016 1.016)
					(thickness 0.1524)
				)
			)
		)
		(duplicate_pad_numbers_are_jumpers no)
		(fp_line
			(start -0.508 -0.9398)
			(end -0.508 0.9398)
			(stroke
				(width 0.1524)
				(type default)
			)
			(layer "F.SilkS")
		)
		(fp_line
			(start 0.508 -0.9398)
			(end -0.508 -0.9398)
			(stroke
				(width 0.1524)
				(type default)
			)
			(layer "F.SilkS")
		)
		(fp_rect
			(start -0.508 0.9398)
			(end 0.508 -0.9398)
			(stroke
				(width 0)
				(type default)
			)
			(fill no)
			(layer "F.CrtYd")
		)
		(fp_rect
			(start -0.508 0.9398)
			(end 0.508 -0.9398)
			(stroke
				(width 0)
				(type default)
			)
			(fill no)
			(layer "F.Fab")
		)
		(pad "1" smd custom
			(at 0 -0.4445)
			(size 0.1397 0.1397)
			(layers "F.Cu" "F.Mask" "F.Paste")
			(net "BCM5221_MB_RX_DP")
			(options
				(clearance outline)
				(anchor circle)
			)
			(primitives
				(gr_poly
					(pts
						(arc
							(start -0.1778 -0.2794)
							(mid -0.249642 -0.249642)
							(end -0.2794 -0.1778)
						)
						(arc
							(start -0.2794 0.1778)
							(mid -0.249642 0.249642)
							(end -0.1778 0.2794)
						)
						(arc
							(start 0.1778 0.2794)
							(mid 0.249642 0.249642)
							(end 0.2794 0.1778)
						)
						(arc
							(start 0.2794 -0.1778)
							(mid 0.249642 -0.249642)
							(end 0.1778 -0.2794)
						)
					)
					(width 0)
					(fill yes)
				)
			)
		)
		(pad "2" smd custom
			(at 0 0.4445)
			(size 0.1397 0.1397)
			(layers "F.Cu" "F.Mask" "F.Paste")
			(net "BCM5221_RX_C_DP")
			(options
				(clearance outline)
				(anchor circle)
			)
			(primitives
				(gr_poly
					(pts
						(arc
							(start -0.1778 -0.2794)
							(mid -0.249642 -0.249642)
							(end -0.2794 -0.1778)
						)
						(arc
							(start -0.2794 0.1778)
							(mid -0.249642 0.249642)
							(end -0.1778 0.2794)
						)
						(arc
							(start 0.1778 0.2794)
							(mid 0.249642 0.249642)
							(end 0.2794 0.1778)
						)
						(arc
							(start 0.2794 -0.1778)
							(mid 0.249642 -0.249642)
							(end 0.1778 -0.2794)
						)
					)
					(width 0)
					(fill yes)
				)
			)
		)
	)
	(footprint ""
		(layer "F.Cu")
		(at 337.557872 -171.395136)
		(property "Reference" "R276"
			(at 0 0 0)
			(layer "F.SilkS")
			(hide yes)
			(effects
				(font
					(size 1.27 1.27)
				)
			)
		)
		(property "Value" "10KR2F-2-GP"
			(at 0.064008 -3.993896 0)
			(unlocked yes)
			(layer "F.Fab")
			(hide yes)
			(effects
				(font
					(size 1.016 1.016)
					(thickness 0.1524)
				)
			)
		)
		(property "Device Type" "R402H16"
			(at 0.064008 -5.517896 0)
			(unlocked yes)
			(layer "F.Fab")
			(hide yes)
			(effects
				(font
					(size 1.016 1.016)
					(thickness 0.1524)
				)
			)
		)
		(duplicate_pad_numbers_are_jumpers no)
		(fp_line
			(start -0.508 -0.9398)
			(end -0.508 0.9398)
			(stroke
				(width 0.1524)
				(type default)
			)
			(layer "F.SilkS")
		)
		(fp_line
			(start 0.508 -0.9398)
			(end -0.508 -0.9398)
			(stroke
				(width 0.1524)
				(type default)
			)
			(layer "F.SilkS")
		)
		(fp_rect
			(start -0.508 0.9398)
			(end 0.508 -0.9398)
			(stroke
				(width 0)
				(type default)
			)
			(fill no)
			(layer "F.CrtYd")
		)
		(fp_rect
			(start -0.508 0.9398)
			(end 0.508 -0.9398)
			(stroke
				(width 0)
				(type default)
			)
			(fill no)
			(layer "F.Fab")
		)
		(pad "1" smd custom
			(at 0 -0.4445)
			(size 0.1397 0.1397)
			(layers "F.Cu" "F.Mask" "F.Paste")
			(net "P3V3_STBY")
			(options
				(clearance outline)
				(anchor circle)
			)
			(primitives
				(gr_poly
					(pts
						(arc
							(start -0.1778 -0.2794)
							(mid -0.249642 -0.249642)
							(end -0.2794 -0.1778)
						)
						(arc
							(start -0.2794 0.1778)
							(mid -0.249642 0.249642)
							(end -0.1778 0.2794)
						)
						(arc
							(start 0.1778 0.2794)
							(mid 0.249642 0.249642)
							(end 0.2794 0.1778)
						)
						(arc
							(start 0.2794 -0.1778)
							(mid 0.249642 -0.249642)
							(end 0.1778 -0.2794)
						)
					)
					(width 0)
					(fill yes)
				)
			)
		)
		(pad "2" smd custom
			(at 0 0.4445)
			(size 0.1397 0.1397)
			(layers "F.Cu" "F.Mask" "F.Paste")
			(net "BMC_UART_SWITCH_R")
			(options
				(clearance outline)
				(anchor circle)
			)
			(primitives
				(gr_poly
					(pts
						(arc
							(start -0.1778 -0.2794)
							(mid -0.249642 -0.249642)
							(end -0.2794 -0.1778)
						)
						(arc
							(start -0.2794 0.1778)
							(mid -0.249642 0.249642)
							(end -0.1778 0.2794)
						)
						(arc
							(start 0.1778 0.2794)
							(mid 0.249642 0.249642)
							(end 0.2794 0.1778)
						)
						(arc
							(start 0.2794 -0.1778)
							(mid 0.249642 -0.249642)
							(end 0.1778 -0.2794)
						)
					)
					(width 0)
					(fill yes)
				)
			)
		)
	)
	(footprint ""
		(layer "F.Cu")
		(at 175.949864 -34.997136 -90)
		(property "Reference" "R382"
			(at 0 0 270)
			(layer "F.SilkS")
			(hide yes)
			(effects
				(font
					(size 1.27 1.27)
				)
			)
		)
		(property "Value" "1K27R2D-GP"
			(at 0.064008 -3.993896 270)
			(unlocked yes)
			(layer "F.Fab")
			(hide yes)
			(effects
				(font
					(size 1.016 1.016)
					(thickness 0.1524)
				)
			)
		)
		(property "Device Type" "R402H16"
			(at 0.064008 -5.517896 270)
			(unlocked yes)
			(layer "F.Fab")
			(hide yes)
			(effects
				(font
					(size 1.016 1.016)
					(thickness 0.1524)
				)
			)
		)
		(duplicate_pad_numbers_are_jumpers no)
		(fp_line
			(start -0.508 -0.9398)
			(end -0.508 0.9398)
			(stroke
				(width 0.1524)
				(type default)
			)
			(layer "F.SilkS")
		)
		(fp_line
			(start 0.508 -0.9398)
			(end -0.508 -0.9398)
			(stroke
				(width 0.1524)
				(type default)
			)
			(layer "F.SilkS")
		)
		(fp_rect
			(start -0.508 0.9398)
			(end 0.508 -0.9398)
			(stroke
				(width 0)
				(type default)
			)
			(fill no)
			(layer "F.CrtYd")
		)
		(fp_rect
			(start -0.508 0.9398)
			(end 0.508 -0.9398)
			(stroke
				(width 0)
				(type default)
			)
			(fill no)
			(layer "F.Fab")
		)
		(pad "1" smd custom
			(at 0 -0.4445 270)
			(size 0.1397 0.1397)
			(layers "F.Cu" "F.Mask" "F.Paste")
			(net "BMC_PHY_RDAC")
			(options
				(clearance outline)
				(anchor circle)
			)
			(primitives
				(gr_poly
					(pts
						(arc
							(start -0.1778 -0.2794)
							(mid -0.249642 -0.249642)
							(end -0.2794 -0.1778)
						)
						(arc
							(start -0.2794 0.1778)
							(mid -0.249642 0.249642)
							(end -0.1778 0.2794)
						)
						(arc
							(start 0.1778 0.2794)
							(mid 0.249642 0.249642)
							(end 0.2794 0.1778)
						)
						(arc
							(start 0.2794 -0.1778)
							(mid 0.249642 -0.249642)
							(end 0.1778 -0.2794)
						)
					)
					(width 0)
					(fill yes)
				)
			)
		)
		(pad "2" smd custom
			(at 0 0.4445 270)
			(size 0.1397 0.1397)
			(layers "F.Cu" "F.Mask" "F.Paste")
			(net "GND")
			(options
				(clearance outline)
				(anchor circle)
			)
			(primitives
				(gr_poly
					(pts
						(arc
							(start -0.1778 -0.2794)
							(mid -0.249642 -0.249642)
							(end -0.2794 -0.1778)
						)
						(arc
							(start -0.2794 0.1778)
							(mid -0.249642 0.249642)
							(end -0.1778 0.2794)
						)
						(arc
							(start 0.1778 0.2794)
							(mid 0.249642 0.249642)
							(end 0.2794 0.1778)
						)
						(arc
							(start 0.2794 -0.1778)
							(mid 0.249642 -0.249642)
							(end 0.1778 -0.2794)
						)
					)
					(width 0)
					(fill yes)
				)
			)
		)
	)
	(footprint ""
		(layer "F.Cu")
		(at 29.884116 -77.585062 180)
		(property "Reference" "Q5"
			(at 0 0 180)
			(layer "F.SilkS")
			(hide yes)
			(effects
				(font
					(size 1.27 1.27)
				)
			)
		)
		(property "Value" "PMBS3904-1-GP"
			(at 0 -9.0932 180)
			(unlocked yes)
			(layer "F.Fab")
			(hide yes)
			(effects
				(font
					(size 1.016 1.016)
					(thickness 0.1524)
				)
			)
		)
		(property "Device Type" "SOT-23-10H44"
			(at 0 -10.6172 180)
			(unlocked yes)
			(layer "F.Fab")
			(hide yes)
			(effects
				(font
					(size 1.016 1.016)
					(thickness 0.1524)
				)
			)
		)
		(duplicate_pad_numbers_are_jumpers no)
		(fp_line
			(start 1.651 1.778)
			(end 1.651 -1.778)
			(stroke
				(width 0.1524)
				(type default)
			)
			(layer "F.SilkS")
		)
		(fp_line
			(start 1.651 -1.778)
			(end -1.651 -1.778)
			(stroke
				(width 0.1524)
				(type default)
			)
			(layer "F.SilkS")
		)
		(fp_line
			(start -0.635 1.8796)
			(end -1.7526 1.8796)
			(stroke
				(width 0.3302)
				(type default)
			)
			(layer "F.SilkS")
		)
		(fp_line
			(start -0.71628 2.15265)
			(end -1.26492 2.15265)
			(stroke
				(width 0.0127)
				(type default)
			)
			(layer "F.SilkS")
		)
		(fp_line
			(start -0.719074 2.145538)
			(end -1.265936 2.14122)
			(stroke
				(width 0.0127)
				(type default)
			)
			(layer "F.SilkS")
		)
		(fp_line
			(start -0.9906 1.86309)
			(end -0.701294 2.15265)
			(stroke
				(width 0.0127)
				(type default)
			)
			(layer "F.SilkS")
		)
		(fp_line
			(start -0.994156 1.8669)
			(end -0.987044 1.8669)
			(stroke
				(width 0.0127)
				(type default)
			)
			(layer "F.SilkS")
		)
		(fp_line
			(start -1.003808 1.876552)
			(end -0.977646 1.876552)
			(stroke
				(width 0.0127)
				(type default)
			)
			(layer "F.SilkS")
		)
		(fp_line
			(start -1.013206 1.88595)
			(end -0.967994 1.88595)
			(stroke
				(width 0.0127)
				(type default)
			)
			(layer "F.SilkS")
		)
		(fp_line
			(start -1.022858 1.895602)
			(end -0.958596 1.895602)
			(stroke
				(width 0.0127)
				(type default)
			)
			(layer "F.SilkS")
		)
		(fp_line
			(start -1.032256 1.905)
			(end -0.948944 1.905)
			(stroke
				(width 0.0127)
				(type default)
			)
			(layer "F.SilkS")
		)
		(fp_line
			(start -1.041908 1.914652)
			(end -0.939546 1.914652)
			(stroke
				(width 0.0127)
				(type default)
			)
			(layer "F.SilkS")
		)
		(fp_line
			(start -1.051306 1.92405)
			(end -0.929894 1.92405)
			(stroke
				(width 0.0127)
				(type default)
			)
			(layer "F.SilkS")
		)
		(fp_line
			(start -1.060958 1.933702)
			(end -0.920496 1.933702)
			(stroke
				(width 0.0127)
				(type default)
			)
			(layer "F.SilkS")
		)
		(fp_line
			(start -1.070356 1.9431)
			(end -0.910844 1.9431)
			(stroke
				(width 0.0127)
				(type default)
			)
			(layer "F.SilkS")
		)
		(fp_line
			(start -1.080008 1.952752)
			(end -0.901446 1.952752)
			(stroke
				(width 0.0127)
				(type default)
			)
			(layer "F.SilkS")
		)
		(fp_line
			(start -1.089406 1.96215)
			(end -0.891794 1.96215)
			(stroke
				(width 0.0127)
				(type default)
			)
			(layer "F.SilkS")
		)
		(fp_line
			(start -1.099058 1.971802)
			(end -0.882396 1.971802)
			(stroke
				(width 0.0127)
				(type default)
			)
			(layer "F.SilkS")
		)
		(fp_line
			(start -1.108456 1.9812)
			(end -0.872744 1.9812)
			(stroke
				(width 0.0127)
				(type default)
			)
			(layer "F.SilkS")
		)
		(fp_line
			(start -1.118108 1.990852)
			(end -0.863346 1.990852)
			(stroke
				(width 0.0127)
				(type default)
			)
			(layer "F.SilkS")
		)
		(fp_line
			(start -1.127506 2.00025)
			(end -0.853694 2.00025)
			(stroke
				(width 0.0127)
				(type default)
			)
			(layer "F.SilkS")
		)
		(fp_line
			(start -1.137158 2.009902)
			(end -0.844296 2.009902)
			(stroke
				(width 0.0127)
				(type default)
			)
			(layer "F.SilkS")
		)
		(fp_line
			(start -1.146556 2.0193)
			(end -0.834644 2.0193)
			(stroke
				(width 0.0127)
				(type default)
			)
			(layer "F.SilkS")
		)
		(fp_line
			(start -1.156208 2.028952)
			(end -0.825246 2.028952)
			(stroke
				(width 0.0127)
				(type default)
			)
			(layer "F.SilkS")
		)
		(fp_line
			(start -1.165606 2.03835)
			(end -0.815594 2.03835)
			(stroke
				(width 0.0127)
				(type default)
			)
			(layer "F.SilkS")
		)
		(fp_line
			(start -1.175258 2.048002)
			(end -0.806196 2.048002)
			(stroke
				(width 0.0127)
				(type default)
			)
			(layer "F.SilkS")
		)
		(fp_line
			(start -1.184656 2.0574)
			(end -0.796544 2.0574)
			(stroke
				(width 0.0127)
				(type default)
			)
			(layer "F.SilkS")
		)
		(fp_line
			(start -1.194308 2.067052)
			(end -0.787146 2.067052)
			(stroke
				(width 0.0127)
				(type default)
			)
			(layer "F.SilkS")
		)
		(fp_line
			(start -1.203706 2.07645)
			(end -0.777494 2.07645)
			(stroke
				(width 0.0127)
				(type default)
			)
			(layer "F.SilkS")
		)
		(fp_line
			(start -1.213358 2.086102)
			(end -0.768096 2.086102)
			(stroke
				(width 0.0127)
				(type default)
			)
			(layer "F.SilkS")
		)
		(fp_line
			(start -1.222756 2.0955)
			(end -0.758444 2.0955)
			(stroke
				(width 0.0127)
				(type default)
			)
			(layer "F.SilkS")
		)
		(fp_line
			(start -1.232408 2.105152)
			(end -0.749046 2.105152)
			(stroke
				(width 0.0127)
				(type default)
			)
			(layer "F.SilkS")
		)
		(fp_line
			(start -1.241806 2.11455)
			(end -0.739394 2.11455)
			(stroke
				(width 0.0127)
				(type default)
			)
			(layer "F.SilkS")
		)
		(fp_line
			(start -1.251458 2.124202)
			(end -0.729996 2.124202)
			(stroke
				(width 0.0127)
				(type default)
			)
			(layer "F.SilkS")
		)
		(fp_line
			(start -1.260856 2.1336)
			(end -0.720344 2.1336)
			(stroke
				(width 0.0127)
				(type default)
			)
			(layer "F.SilkS")
		)
		(fp_line
			(start -1.279144 2.15265)
			(end -0.701294 2.15265)
			(stroke
				(width 0.0127)
				(type default)
			)
			(layer "F.SilkS")
		)
		(fp_line
			(start -1.279398 2.152142)
			(end -0.9906 1.86309)
			(stroke
				(width 0.0127)
				(type default)
			)
			(layer "F.SilkS")
		)
		(fp_line
			(start -1.651 1.778)
			(end 1.651 1.778)
			(stroke
				(width 0.1524)
				(type default)
			)
			(layer "F.SilkS")
		)
		(fp_line
			(start -1.651 -1.778)
			(end -1.651 1.778)
			(stroke
				(width 0.1524)
				(type default)
			)
			(layer "F.SilkS")
		)
		(fp_line
			(start -1.7526 1.8796)
			(end -1.7526 0.9906)
			(stroke
				(width 0.3302)
				(type default)
			)
			(layer "F.SilkS")
		)
		(fp_poly
			(pts
				(xy -1.285748 2.159) (xy -1.285748 1.8796) (xy -1.778 1.8796) (xy -1.778 -1.8796) (xy 1.778 -1.8796)
				(xy 1.778 1.8796) (xy -0.694944 1.8796) (xy -0.694944 2.159)
			)
			(stroke
				(width 0)
				(type default)
			)
			(fill no)
			(layer "F.CrtYd")
		)
		(fp_poly
			(pts
				(xy -1.285748 2.159) (xy -1.285748 1.8796) (xy -1.778 1.8796) (xy -1.778 -1.8796) (xy 1.778 -1.8796)
				(xy 1.778 1.8796) (xy -0.694944 1.8796) (xy -0.694944 2.159)
			)
			(stroke
				(width 0)
				(type default)
			)
			(fill no)
			(layer "F.Fab")
		)
		(pad "1" smd rect
			(at -0.98425 0.9525 180)
			(size 0.762 1.143)
			(layers "F.Cu" "F.Mask" "F.Paste")
			(net "INTA_LED_RED_B")
		)
		(pad "2" smd rect
			(at 0.98425 0.9525 180)
			(size 0.762 1.143)
			(layers "F.Cu" "F.Mask" "F.Paste")
			(net "GND")
		)
		(pad "3" smd rect
			(at 0 -0.9525 180)
			(size 0.762 1.143)
			(layers "F.Cu" "F.Mask" "F.Paste")
			(net "INTA_LED_RED_C")
		)
	)
	(footprint ""
		(layer "F.Cu")
		(at 202.565 -140.589 -90)
		(property "Reference" "SR759"
			(at 0 0 270)
			(layer "F.SilkS")
			(hide yes)
			(effects
				(font
					(size 1.27 1.27)
				)
			)
		)
		(property "Value" "4K7R2F-GP"
			(at 0.064008 -3.993896 270)
			(unlocked yes)
			(layer "F.Fab")
			(hide yes)
			(effects
				(font
					(size 1.016 1.016)
					(thickness 0.1524)
				)
			)
		)
		(property "Device Type" "R402H16"
			(at 0.064008 -5.517896 270)
			(unlocked yes)
			(layer "F.Fab")
			(hide yes)
			(effects
				(font
					(size 1.016 1.016)
					(thickness 0.1524)
				)
			)
		)
		(duplicate_pad_numbers_are_jumpers no)
		(fp_line
			(start -0.508 -0.9398)
			(end -0.508 0.9398)
			(stroke
				(width 0.1524)
				(type default)
			)
			(layer "F.SilkS")
		)
		(fp_line
			(start 0.508 -0.9398)
			(end -0.508 -0.9398)
			(stroke
				(width 0.1524)
				(type default)
			)
			(layer "F.SilkS")
		)
		(fp_rect
			(start -0.508 0.9398)
			(end 0.508 -0.9398)
			(stroke
				(width 0)
				(type default)
			)
			(fill no)
			(layer "F.CrtYd")
		)
		(fp_rect
			(start -0.508 0.9398)
			(end 0.508 -0.9398)
			(stroke
				(width 0)
				(type default)
			)
			(fill no)
			(layer "F.Fab")
		)
		(pad "1" smd custom
			(at 0 -0.4445 270)
			(size 0.1397 0.1397)
			(layers "F.Cu" "F.Mask" "F.Paste")
			(net "P1V8_E")
			(options
				(clearance outline)
				(anchor circle)
			)
			(primitives
				(gr_poly
					(pts
						(arc
							(start -0.1778 -0.2794)
							(mid -0.249642 -0.249642)
							(end -0.2794 -0.1778)
						)
						(arc
							(start -0.2794 0.1778)
							(mid -0.249642 0.249642)
							(end -0.1778 0.2794)
						)
						(arc
							(start 0.1778 0.2794)
							(mid 0.249642 0.249642)
							(end 0.2794 0.1778)
						)
						(arc
							(start 0.2794 -0.1778)
							(mid 0.249642 -0.249642)
							(end 0.1778 -0.2794)
						)
					)
					(width 0)
					(fill yes)
				)
			)
		)
		(pad "2" smd custom
			(at 0 0.4445 270)
			(size 0.1397 0.1397)
			(layers "F.Cu" "F.Mask" "F.Paste")
			(net "EXP_EEPROM_A1")
			(options
				(clearance outline)
				(anchor circle)
			)
			(primitives
				(gr_poly
					(pts
						(arc
							(start -0.1778 -0.2794)
							(mid -0.249642 -0.249642)
							(end -0.2794 -0.1778)
						)
						(arc
							(start -0.2794 0.1778)
							(mid -0.249642 0.249642)
							(end -0.1778 0.2794)
						)
						(arc
							(start 0.1778 0.2794)
							(mid 0.249642 0.249642)
							(end 0.2794 0.1778)
						)
						(arc
							(start 0.2794 -0.1778)
							(mid 0.249642 -0.249642)
							(end 0.1778 -0.2794)
						)
					)
					(width 0)
					(fill yes)
				)
			)
		)
	)
	(footprint ""
		(layer "F.Cu")
		(at 189.865 -22.479 90)
		(property "Reference" "R381"
			(at 0 0 90)
			(layer "F.SilkS")
			(hide yes)
			(effects
				(font
					(size 1.27 1.27)
				)
			)
		)
		(property "Value" "0R2J-2-GP"
			(at 0.064008 -3.993896 90)
			(unlocked yes)
			(layer "F.Fab")
			(hide yes)
			(effects
				(font
					(size 1.016 1.016)
					(thickness 0.1524)
				)
			)
		)
		(property "Device Type" "R402H16"
			(at 0.064008 -5.517896 90)
			(unlocked yes)
			(layer "F.Fab")
			(hide yes)
			(effects
				(font
					(size 1.016 1.016)
					(thickness 0.1524)
				)
			)
		)
		(duplicate_pad_numbers_are_jumpers no)
		(fp_line
			(start 0.508 -0.9398)
			(end -0.508 -0.9398)
			(stroke
				(width 0.1524)
				(type default)
			)
			(layer "F.SilkS")
		)
		(fp_line
			(start -0.508 -0.9398)
			(end -0.508 0.9398)
			(stroke
				(width 0.1524)
				(type default)
			)
			(layer "F.SilkS")
		)
		(fp_rect
			(start -0.508 0.9398)
			(end 0.508 -0.9398)
			(stroke
				(width 0)
				(type default)
			)
			(fill no)
			(layer "F.CrtYd")
		)
		(fp_rect
			(start -0.508 0.9398)
			(end 0.508 -0.9398)
			(stroke
				(width 0)
				(type default)
			)
			(fill no)
			(layer "F.Fab")
		)
		(pad "1" smd custom
			(at 0 -0.4445 90)
			(size 0.1397 0.1397)
			(layers "F.Cu" "F.Mask" "F.Paste")
			(net "RMII_BMC_MDC_R")
			(options
				(clearance outline)
				(anchor circle)
			)
			(primitives
				(gr_poly
					(pts
						(arc
							(start -0.1778 -0.2794)
							(mid -0.249642 -0.249642)
							(end -0.2794 -0.1778)
						)
						(arc
							(start -0.2794 0.1778)
							(mid -0.249642 0.249642)
							(end -0.1778 0.2794)
						)
						(arc
							(start 0.1778 0.2794)
							(mid 0.249642 0.249642)
							(end 0.2794 0.1778)
						)
						(arc
							(start 0.2794 -0.1778)
							(mid 0.249642 -0.249642)
							(end 0.1778 -0.2794)
						)
					)
					(width 0)
					(fill yes)
				)
			)
		)
		(pad "2" smd custom
			(at 0 0.4445 90)
			(size 0.1397 0.1397)
			(layers "F.Cu" "F.Mask" "F.Paste")
			(net "RMII_BMC_MDC")
			(options
				(clearance outline)
				(anchor circle)
			)
			(primitives
				(gr_poly
					(pts
						(arc
							(start -0.1778 -0.2794)
							(mid -0.249642 -0.249642)
							(end -0.2794 -0.1778)
						)
						(arc
							(start -0.2794 0.1778)
							(mid -0.249642 0.249642)
							(end -0.1778 0.2794)
						)
						(arc
							(start 0.1778 0.2794)
							(mid 0.249642 0.249642)
							(end 0.2794 0.1778)
						)
						(arc
							(start 0.2794 -0.1778)
							(mid 0.249642 -0.249642)
							(end 0.1778 -0.2794)
						)
					)
					(width 0)
					(fill yes)
				)
			)
		)
	)
	(footprint ""
		(layer "B.Cu")
		(at 98.787966 -44.196 -90)
		(property "Reference" "SC1063"
			(at 0 0 90)
			(layer "B.SilkS")
			(hide yes)
			(effects
				(font
					(size 1.27 1.27)
				)
				(justify mirror)
			)
		)
		(property "Value" "SCD1U16V2KX-3GP"
			(at -1.1811 -2.7051 270)
			(unlocked yes)
			(layer "B.Fab")
			(hide yes)
			(effects
				(font
					(size 1.016 1.016)
					(thickness 0.1524)
				)
				(justify mirror)
			)
		)
		(property "Device Type" "C402H22"
			(at -1.1811 -4.2291 270)
			(unlocked yes)
			(layer "B.Fab")
			(hide yes)
			(effects
				(font
					(size 1.016 1.016)
					(thickness 0.1524)
				)
				(justify mirror)
			)
		)
		(duplicate_pad_numbers_are_jumpers no)
		(fp_rect
			(start 0.4318 0.9525)
			(end -0.4318 -0.9525)
			(stroke
				(width 0)
				(type default)
			)
			(fill no)
			(layer "B.CrtYd")
		)
		(fp_rect
			(start 0.4318 0.9525)
			(end -0.4318 -0.9525)
			(stroke
				(width 0)
				(type default)
			)
			(fill no)
			(layer "B.Fab")
		)
		(pad "1" smd custom
			(at 0 -0.4445 90)
			(size 0.1524 0.1524)
			(layers "B.Cu" "B.Mask" "B.Paste")
			(net "P0V955_C")
			(options
				(clearance outline)
				(anchor circle)
			)
			(primitives
				(gr_poly
					(pts
						(arc
							(start 0.3048 0.2032)
							(mid 0.275042 0.275042)
							(end 0.2032 0.3048)
						)
						(arc
							(start -0.2032 0.3048)
							(mid -0.275042 0.275042)
							(end -0.3048 0.2032)
						)
						(arc
							(start -0.3048 -0.2032)
							(mid -0.275042 -0.275042)
							(end -0.2032 -0.3048)
						)
						(arc
							(start 0.2032 -0.3048)
							(mid 0.275042 -0.275042)
							(end 0.3048 -0.2032)
						)
					)
					(width 0)
					(fill yes)
				)
			)
		)
		(pad "2" smd custom
			(at 0 0.4445 90)
			(size 0.1524 0.1524)
			(layers "B.Cu" "B.Mask" "B.Paste")
			(net "GND")
			(options
				(clearance outline)
				(anchor circle)
			)
			(primitives
				(gr_poly
					(pts
						(arc
							(start 0.3048 0.2032)
							(mid 0.275042 0.275042)
							(end 0.2032 0.3048)
						)
						(arc
							(start -0.2032 0.3048)
							(mid -0.275042 0.275042)
							(end -0.3048 0.2032)
						)
						(arc
							(start -0.3048 -0.2032)
							(mid -0.275042 -0.275042)
							(end -0.2032 -0.3048)
						)
						(arc
							(start 0.2032 -0.3048)
							(mid 0.275042 -0.275042)
							(end 0.3048 -0.2032)
						)
					)
					(width 0)
					(fill yes)
				)
			)
		)
	)
	(footprint ""
		(layer "B.Cu")
		(at 76.073 -25.019 -90)
		(property "Reference" "SR931"
			(at 0 0 90)
			(layer "B.SilkS")
			(hide yes)
			(effects
				(font
					(size 1.27 1.27)
				)
				(justify mirror)
			)
		)
		(property "Value" "10KR2F-2-GP"
			(at -0.064008 -3.993896 270)
			(unlocked yes)
			(layer "B.Fab")
			(hide yes)
			(effects
				(font
					(size 1.016 1.016)
					(thickness 0.1524)
				)
				(justify mirror)
			)
		)
		(property "Device Type" "R402H16"
			(at -0.064008 -5.517896 270)
			(unlocked yes)
			(layer "B.Fab")
			(hide yes)
			(effects
				(font
					(size 1.016 1.016)
					(thickness 0.1524)
				)
				(justify mirror)
			)
		)
		(duplicate_pad_numbers_are_jumpers no)
		(fp_line
			(start -0.508 -0.9398)
			(end 0.508 -0.9398)
			(stroke
				(width 0.1524)
				(type default)
			)
			(layer "B.SilkS")
		)
		(fp_line
			(start 0.508 -0.9398)
			(end 0.508 0.9398)
			(stroke
				(width 0.1524)
				(type default)
			)
			(layer "B.SilkS")
		)
		(fp_rect
			(start 0.508 0.9398)
			(end -0.508 -0.9398)
			(stroke
				(width 0)
				(type default)
			)
			(fill no)
			(layer "B.CrtYd")
		)
		(fp_rect
			(start 0.508 0.9398)
			(end -0.508 -0.9398)
			(stroke
				(width 0)
				(type default)
			)
			(fill no)
			(layer "B.Fab")
		)
		(pad "1" smd custom
			(at 0 -0.4445 90)
			(size 0.1397 0.1397)
			(layers "B.Cu" "B.Mask" "B.Paste")
			(net "P3V3_STBY_R9")
			(options
				(clearance outline)
				(anchor circle)
			)
			(primitives
				(gr_poly
					(pts
						(arc
							(start -0.1778 0.2794)
							(mid -0.249642 0.249642)
							(end -0.2794 0.1778)
						)
						(arc
							(start -0.2794 -0.1778)
							(mid -0.249642 -0.249642)
							(end -0.1778 -0.2794)
						)
						(arc
							(start 0.1778 -0.2794)
							(mid 0.249642 -0.249642)
							(end 0.2794 -0.1778)
						)
						(arc
							(start 0.2794 0.1778)
							(mid 0.249642 0.249642)
							(end 0.1778 0.2794)
						)
					)
					(width 0)
					(fill yes)
				)
			)
		)
		(pad "2" smd custom
			(at 0 0.4445 90)
			(size 0.1397 0.1397)
			(layers "B.Cu" "B.Mask" "B.Paste")
			(net "P3V3_STBY_G9")
			(options
				(clearance outline)
				(anchor circle)
			)
			(primitives
				(gr_poly
					(pts
						(arc
							(start -0.1778 0.2794)
							(mid -0.249642 0.249642)
							(end -0.2794 0.1778)
						)
						(arc
							(start -0.2794 -0.1778)
							(mid -0.249642 -0.249642)
							(end -0.1778 -0.2794)
						)
						(arc
							(start 0.1778 -0.2794)
							(mid 0.249642 -0.249642)
							(end 0.2794 -0.1778)
						)
						(arc
							(start 0.2794 0.1778)
							(mid 0.249642 0.249642)
							(end 0.1778 0.2794)
						)
					)
					(width 0)
					(fill yes)
				)
			)
		)
	)
	(footprint ""
		(layer "B.Cu")
		(at 100.979986 -54.65572 -90)
		(property "Reference" "SC1003"
			(at 0 0 90)
			(layer "B.SilkS")
			(hide yes)
			(effects
				(font
					(size 1.27 1.27)
				)
				(justify mirror)
			)
		)
		(property "Value" "SCD1U16V2KX-3GP"
			(at -1.1811 -2.7051 270)
			(unlocked yes)
			(layer "B.Fab")
			(hide yes)
			(effects
				(font
					(size 1.016 1.016)
					(thickness 0.1524)
				)
				(justify mirror)
			)
		)
		(property "Device Type" "C402H22"
			(at -1.1811 -4.2291 270)
			(unlocked yes)
			(layer "B.Fab")
			(hide yes)
			(effects
				(font
					(size 1.016 1.016)
					(thickness 0.1524)
				)
				(justify mirror)
			)
		)
		(duplicate_pad_numbers_are_jumpers no)
		(fp_rect
			(start 0.4318 0.9525)
			(end -0.4318 -0.9525)
			(stroke
				(width 0)
				(type default)
			)
			(fill no)
			(layer "B.CrtYd")
		)
		(fp_rect
			(start 0.4318 0.9525)
			(end -0.4318 -0.9525)
			(stroke
				(width 0)
				(type default)
			)
			(fill no)
			(layer "B.Fab")
		)
		(pad "1" smd custom
			(at 0 -0.4445 90)
			(size 0.1524 0.1524)
			(layers "B.Cu" "B.Mask" "B.Paste")
			(net "P1V8_C")
			(options
				(clearance outline)
				(anchor circle)
			)
			(primitives
				(gr_poly
					(pts
						(arc
							(start 0.3048 0.2032)
							(mid 0.275042 0.275042)
							(end 0.2032 0.3048)
						)
						(arc
							(start -0.2032 0.3048)
							(mid -0.275042 0.275042)
							(end -0.3048 0.2032)
						)
						(arc
							(start -0.3048 -0.2032)
							(mid -0.275042 -0.275042)
							(end -0.2032 -0.3048)
						)
						(arc
							(start 0.2032 -0.3048)
							(mid 0.275042 -0.275042)
							(end 0.3048 -0.2032)
						)
					)
					(width 0)
					(fill yes)
				)
			)
		)
		(pad "2" smd custom
			(at 0 0.4445 90)
			(size 0.1524 0.1524)
			(layers "B.Cu" "B.Mask" "B.Paste")
			(net "GND")
			(options
				(clearance outline)
				(anchor circle)
			)
			(primitives
				(gr_poly
					(pts
						(arc
							(start 0.3048 0.2032)
							(mid 0.275042 0.275042)
							(end 0.2032 0.3048)
						)
						(arc
							(start -0.2032 0.3048)
							(mid -0.275042 0.275042)
							(end -0.3048 0.2032)
						)
						(arc
							(start -0.3048 -0.2032)
							(mid -0.275042 -0.275042)
							(end -0.2032 -0.3048)
						)
						(arc
							(start 0.2032 -0.3048)
							(mid 0.275042 -0.275042)
							(end 0.3048 -0.2032)
						)
					)
					(width 0)
					(fill yes)
				)
			)
		)
	)
	(footprint ""
		(layer "B.Cu")
		(at 118.872 -42.926 -90)
		(property "Reference" "SR653"
			(at 0 0 90)
			(layer "B.SilkS")
			(hide yes)
			(effects
				(font
					(size 1.27 1.27)
				)
				(justify mirror)
			)
		)
		(property "Value" "10KR2F-2-GP"
			(at -0.064008 -3.993896 270)
			(unlocked yes)
			(layer "B.Fab")
			(hide yes)
			(effects
				(font
					(size 1.016 1.016)
					(thickness 0.1524)
				)
				(justify mirror)
			)
		)
		(property "Device Type" "R402H16"
			(at -0.064008 -5.517896 270)
			(unlocked yes)
			(layer "B.Fab")
			(hide yes)
			(effects
				(font
					(size 1.016 1.016)
					(thickness 0.1524)
				)
				(justify mirror)
			)
		)
		(duplicate_pad_numbers_are_jumpers no)
		(fp_line
			(start -0.508 -0.9398)
			(end 0.508 -0.9398)
			(stroke
				(width 0.1524)
				(type default)
			)
			(layer "B.SilkS")
		)
		(fp_line
			(start 0.508 -0.9398)
			(end 0.508 0.9398)
			(stroke
				(width 0.1524)
				(type default)
			)
			(layer "B.SilkS")
		)
		(fp_rect
			(start 0.508 0.9398)
			(end -0.508 -0.9398)
			(stroke
				(width 0)
				(type default)
			)
			(fill no)
			(layer "B.CrtYd")
		)
		(fp_rect
			(start 0.508 0.9398)
			(end -0.508 -0.9398)
			(stroke
				(width 0)
				(type default)
			)
			(fill no)
			(layer "B.Fab")
		)
		(pad "1" smd custom
			(at 0 -0.4445 90)
			(size 0.1397 0.1397)
			(layers "B.Cu" "B.Mask" "B.Paste")
			(net "P1V8_C")
			(options
				(clearance outline)
				(anchor circle)
			)
			(primitives
				(gr_poly
					(pts
						(arc
							(start -0.1778 0.2794)
							(mid -0.249642 0.249642)
							(end -0.2794 0.1778)
						)
						(arc
							(start -0.2794 -0.1778)
							(mid -0.249642 -0.249642)
							(end -0.1778 -0.2794)
						)
						(arc
							(start 0.1778 -0.2794)
							(mid 0.249642 -0.249642)
							(end 0.2794 -0.1778)
						)
						(arc
							(start 0.2794 0.1778)
							(mid 0.249642 0.249642)
							(end 0.1778 0.2794)
						)
					)
					(width 0)
					(fill yes)
				)
			)
		)
		(pad "2" smd custom
			(at 0 0.4445 90)
			(size 0.1397 0.1397)
			(layers "B.Cu" "B.Mask" "B.Paste")
			(net "SYS_HB_LED")
			(options
				(clearance outline)
				(anchor circle)
			)
			(primitives
				(gr_poly
					(pts
						(arc
							(start -0.1778 0.2794)
							(mid -0.249642 0.249642)
							(end -0.2794 0.1778)
						)
						(arc
							(start -0.2794 -0.1778)
							(mid -0.249642 -0.249642)
							(end -0.1778 -0.2794)
						)
						(arc
							(start 0.1778 -0.2794)
							(mid 0.249642 -0.249642)
							(end 0.2794 -0.1778)
						)
						(arc
							(start 0.2794 0.1778)
							(mid 0.249642 0.249642)
							(end 0.1778 0.2794)
						)
					)
					(width 0)
					(fill yes)
				)
			)
		)
	)
	(footprint ""
		(layer "B.Cu")
		(at 106.735626 -38.55974)
		(property "Reference" "STP76"
			(at 0 0 0)
			(layer "B.SilkS")
			(hide yes)
			(effects
				(font
					(size 1.27 1.27)
				)
				(justify mirror)
			)
		)
		(property "Value" "TPAD28"
			(at -0.0127 -1.8034 0)
			(unlocked yes)
			(layer "B.Fab")
			(hide yes)
			(effects
				(font
					(size 1.016 1.016)
					(thickness 0.1524)
				)
				(justify mirror)
			)
		)
		(property "Device Type" "TPAD28"
			(at -0.0127 -3.3274 0)
			(unlocked yes)
			(layer "B.Fab")
			(hide yes)
			(effects
				(font
					(size 1.016 1.016)
					(thickness 0.1524)
				)
				(justify mirror)
			)
		)
		(duplicate_pad_numbers_are_jumpers no)
		(fp_poly
			(pts
				(arc
					(start 0.3556 0)
					(mid -0.3556 0)
					(end 0.3556 0)
				)
			)
			(stroke
				(width 0)
				(type default)
			)
			(fill no)
			(layer "B.CrtYd")
		)
		(fp_poly
			(pts
				(arc
					(start 0.6096 0)
					(mid -0.6096 0)
					(end 0.6096 0)
				)
			)
			(stroke
				(width 0)
				(type default)
			)
			(fill no)
			(layer "B.Fab")
		)
		(pad "1" smd circle
			(at 0 0 180)
			(size 0.7112 0.7112)
			(layers "B.Cu" "B.Mask" "B.Paste")
			(net "IOC_GPIO_7")
		)
	)
	(footprint ""
		(layer "B.Cu")
		(at 102.997 -226.949 -90)
		(property "Reference" "R668"
			(at 0 0 90)
			(layer "B.SilkS")
			(hide yes)
			(effects
				(font
					(size 1.27 1.27)
				)
				(justify mirror)
			)
		)
		(property "Value" "0R2J-2-GP"
			(at -0.064008 -3.993896 270)
			(unlocked yes)
			(layer "B.Fab")
			(hide yes)
			(effects
				(font
					(size 1.016 1.016)
					(thickness 0.1524)
				)
				(justify mirror)
			)
		)
		(property "Device Type" "R402H16"
			(at -0.064008 -5.517896 270)
			(unlocked yes)
			(layer "B.Fab")
			(hide yes)
			(effects
				(font
					(size 1.016 1.016)
					(thickness 0.1524)
				)
				(justify mirror)
			)
		)
		(duplicate_pad_numbers_are_jumpers no)
		(fp_line
			(start -0.508 -0.9398)
			(end 0.508 -0.9398)
			(stroke
				(width 0.1524)
				(type default)
			)
			(layer "B.SilkS")
		)
		(fp_line
			(start 0.508 -0.9398)
			(end 0.508 0.9398)
			(stroke
				(width 0.1524)
				(type default)
			)
			(layer "B.SilkS")
		)
		(fp_rect
			(start 0.508 0.9398)
			(end -0.508 -0.9398)
			(stroke
				(width 0)
				(type default)
			)
			(fill no)
			(layer "B.CrtYd")
		)
		(fp_rect
			(start 0.508 0.9398)
			(end -0.508 -0.9398)
			(stroke
				(width 0)
				(type default)
			)
			(fill no)
			(layer "B.Fab")
		)
		(pad "1" smd custom
			(at 0 -0.4445 90)
			(size 0.1397 0.1397)
			(layers "B.Cu" "B.Mask" "B.Paste")
			(net "SAS_FAULT_LED0")
			(options
				(clearance outline)
				(anchor circle)
			)
			(primitives
				(gr_poly
					(pts
						(arc
							(start -0.1778 0.2794)
							(mid -0.249642 0.249642)
							(end -0.2794 0.1778)
						)
						(arc
							(start -0.2794 -0.1778)
							(mid -0.249642 -0.249642)
							(end -0.1778 -0.2794)
						)
						(arc
							(start 0.1778 -0.2794)
							(mid 0.249642 -0.249642)
							(end 0.2794 -0.1778)
						)
						(arc
							(start 0.2794 0.1778)
							(mid 0.249642 0.249642)
							(end 0.1778 0.2794)
						)
					)
					(width 0)
					(fill yes)
				)
			)
		)
		(pad "2" smd custom
			(at 0 0.4445 90)
			(size 0.1397 0.1397)
			(layers "B.Cu" "B.Mask" "B.Paste")
			(net "SAS_HDD_LED_0")
			(options
				(clearance outline)
				(anchor circle)
			)
			(primitives
				(gr_poly
					(pts
						(arc
							(start -0.1778 0.2794)
							(mid -0.249642 0.249642)
							(end -0.2794 0.1778)
						)
						(arc
							(start -0.2794 -0.1778)
							(mid -0.249642 -0.249642)
							(end -0.1778 -0.2794)
						)
						(arc
							(start 0.1778 -0.2794)
							(mid 0.249642 -0.249642)
							(end 0.2794 -0.1778)
						)
						(arc
							(start 0.2794 0.1778)
							(mid 0.249642 0.249642)
							(end 0.1778 0.2794)
						)
					)
					(width 0)
					(fill yes)
				)
			)
		)
	)
	(footprint ""
		(layer "B.Cu")
		(at 107.07116 -31.369)
		(property "Reference" "STP52"
			(at 0 0 0)
			(layer "B.SilkS")
			(hide yes)
			(effects
				(font
					(size 1.27 1.27)
				)
				(justify mirror)
			)
		)
		(property "Value" "TPAD28"
			(at -0.0127 -1.8034 0)
			(unlocked yes)
			(layer "B.Fab")
			(hide yes)
			(effects
				(font
					(size 1.016 1.016)
					(thickness 0.1524)
				)
				(justify mirror)
			)
		)
		(property "Device Type" "TPAD28"
			(at -0.0127 -3.3274 0)
			(unlocked yes)
			(layer "B.Fab")
			(hide yes)
			(effects
				(font
					(size 1.016 1.016)
					(thickness 0.1524)
				)
				(justify mirror)
			)
		)
		(duplicate_pad_numbers_are_jumpers no)
		(fp_poly
			(pts
				(arc
					(start 0.3556 0)
					(mid -0.3556 0)
					(end 0.3556 0)
				)
			)
			(stroke
				(width 0)
				(type default)
			)
			(fill no)
			(layer "B.CrtYd")
		)
		(fp_poly
			(pts
				(arc
					(start 0.6096 0)
					(mid -0.6096 0)
					(end 0.6096 0)
				)
			)
			(stroke
				(width 0)
				(type default)
			)
			(fill no)
			(layer "B.Fab")
		)
		(pad "1" smd circle
			(at 0 0 180)
			(size 0.7112 0.7112)
			(layers "B.Cu" "B.Mask" "B.Paste")
			(net "SPARE2")
		)
	)
	(footprint ""
		(layer "B.Cu")
		(at 114.723926 -40.41648)
		(property "Reference" "STP20"
			(at 0 0 0)
			(layer "B.SilkS")
			(hide yes)
			(effects
				(font
					(size 1.27 1.27)
				)
				(justify mirror)
			)
		)
		(property "Value" "TPAD28"
			(at -0.0127 -1.8034 0)
			(unlocked yes)
			(layer "B.Fab")
			(hide yes)
			(effects
				(font
					(size 1.016 1.016)
					(thickness 0.1524)
				)
				(justify mirror)
			)
		)
		(property "Device Type" "TPAD28"
			(at -0.0127 -3.3274 0)
			(unlocked yes)
			(layer "B.Fab")
			(hide yes)
			(effects
				(font
					(size 1.016 1.016)
					(thickness 0.1524)
				)
				(justify mirror)
			)
		)
		(duplicate_pad_numbers_are_jumpers no)
		(fp_poly
			(pts
				(arc
					(start 0.3556 0)
					(mid -0.3556 0)
					(end 0.3556 0)
				)
			)
			(stroke
				(width 0)
				(type default)
			)
			(fill no)
			(layer "B.CrtYd")
		)
		(fp_poly
			(pts
				(arc
					(start 0.6096 0)
					(mid -0.6096 0)
					(end 0.6096 0)
				)
			)
			(stroke
				(width 0)
				(type default)
			)
			(fill no)
			(layer "B.Fab")
		)
		(pad "1" smd circle
			(at 0 0 180)
			(size 0.7112 0.7112)
			(layers "B.Cu" "B.Mask" "B.Paste")
			(net "IOC_GPIO_35")
		)
	)
	(footprint ""
		(layer "B.Cu")
		(at 90.95232 -46.8122)
		(property "Reference" "STP21"
			(at 0 0 0)
			(layer "B.SilkS")
			(hide yes)
			(effects
				(font
					(size 1.27 1.27)
				)
				(justify mirror)
			)
		)
		(property "Value" "TPAD28"
			(at -0.0127 -1.8034 0)
			(unlocked yes)
			(layer "B.Fab")
			(hide yes)
			(effects
				(font
					(size 1.016 1.016)
					(thickness 0.1524)
				)
				(justify mirror)
			)
		)
		(property "Device Type" "TPAD28"
			(at -0.0127 -3.3274 0)
			(unlocked yes)
			(layer "B.Fab")
			(hide yes)
			(effects
				(font
					(size 1.016 1.016)
					(thickness 0.1524)
				)
				(justify mirror)
			)
		)
		(duplicate_pad_numbers_are_jumpers no)
		(fp_poly
			(pts
				(arc
					(start 0.3556 0)
					(mid -0.3556 0)
					(end 0.3556 0)
				)
			)
			(stroke
				(width 0)
				(type default)
			)
			(fill no)
			(layer "B.CrtYd")
		)
		(fp_poly
			(pts
				(arc
					(start 0.6096 0)
					(mid -0.6096 0)
					(end 0.6096 0)
				)
			)
			(stroke
				(width 0)
				(type default)
			)
			(fill no)
			(layer "B.Fab")
		)
		(pad "1" smd circle
			(at 0 0 180)
			(size 0.7112 0.7112)
			(layers "B.Cu" "B.Mask" "B.Paste")
			(net "IOC_SIO_BLINK")
		)
	)
	(footprint ""
		(layer "B.Cu")
		(at 78.105 -25.019 -90)
		(property "Reference" "SR930"
			(at 0 0 90)
			(layer "B.SilkS")
			(hide yes)
			(effects
				(font
					(size 1.27 1.27)
				)
				(justify mirror)
			)
		)
		(property "Value" "4K7R2F-GP"
			(at -0.064008 -3.993896 270)
			(unlocked yes)
			(layer "B.Fab")
			(hide yes)
			(effects
				(font
					(size 1.016 1.016)
					(thickness 0.1524)
				)
				(justify mirror)
			)
		)
		(property "Device Type" "R402H16"
			(at -0.064008 -5.517896 270)
			(unlocked yes)
			(layer "B.Fab")
			(hide yes)
			(effects
				(font
					(size 1.016 1.016)
					(thickness 0.1524)
				)
				(justify mirror)
			)
		)
		(duplicate_pad_numbers_are_jumpers no)
		(fp_line
			(start -0.508 -0.9398)
			(end 0.508 -0.9398)
			(stroke
				(width 0.1524)
				(type default)
			)
			(layer "B.SilkS")
		)
		(fp_line
			(start 0.508 -0.9398)
			(end 0.508 0.9398)
			(stroke
				(width 0.1524)
				(type default)
			)
			(layer "B.SilkS")
		)
		(fp_rect
			(start 0.508 0.9398)
			(end -0.508 -0.9398)
			(stroke
				(width 0)
				(type default)
			)
			(fill no)
			(layer "B.CrtYd")
		)
		(fp_rect
			(start 0.508 0.9398)
			(end -0.508 -0.9398)
			(stroke
				(width 0)
				(type default)
			)
			(fill no)
			(layer "B.Fab")
		)
		(pad "1" smd custom
			(at 0 -0.4445 90)
			(size 0.1397 0.1397)
			(layers "B.Cu" "B.Mask" "B.Paste")
			(net "P3V3_STBY")
			(options
				(clearance outline)
				(anchor circle)
			)
			(primitives
				(gr_poly
					(pts
						(arc
							(start -0.1778 0.2794)
							(mid -0.249642 0.249642)
							(end -0.2794 0.1778)
						)
						(arc
							(start -0.2794 -0.1778)
							(mid -0.249642 -0.249642)
							(end -0.1778 -0.2794)
						)
						(arc
							(start 0.1778 -0.2794)
							(mid 0.249642 -0.249642)
							(end 0.2794 -0.1778)
						)
						(arc
							(start 0.2794 0.1778)
							(mid 0.249642 0.249642)
							(end 0.1778 0.2794)
						)
					)
					(width 0)
					(fill yes)
				)
			)
		)
		(pad "2" smd custom
			(at 0 0.4445 90)
			(size 0.1397 0.1397)
			(layers "B.Cu" "B.Mask" "B.Paste")
			(net "P3V3_STBY_R9")
			(options
				(clearance outline)
				(anchor circle)
			)
			(primitives
				(gr_poly
					(pts
						(arc
							(start -0.1778 0.2794)
							(mid -0.249642 0.249642)
							(end -0.2794 0.1778)
						)
						(arc
							(start -0.2794 -0.1778)
							(mid -0.249642 -0.249642)
							(end -0.1778 -0.2794)
						)
						(arc
							(start 0.1778 -0.2794)
							(mid 0.249642 -0.249642)
							(end 0.2794 -0.1778)
						)
						(arc
							(start 0.2794 0.1778)
							(mid 0.249642 0.249642)
							(end 0.1778 0.2794)
						)
					)
					(width 0)
					(fill yes)
				)
			)
		)
	)
	(footprint ""
		(layer "B.Cu")
		(at 68.599812 -23.39975)
		(property "Reference" ""
			(at 0 0 0)
			(layer "B.SilkS")
			(hide yes)
			(effects
				(font
					(size 1.27 1.27)
				)
				(justify mirror)
			)
		)
		(property "Value" "*"
			(at 5.5753 -0.4572 0)
			(unlocked yes)
			(layer "B.Fab")
			(hide yes)
			(effects
				(font
					(size 1.016 1.016)
					(thickness 0.1524)
				)
				(justify mirror)
			)
		)
		(duplicate_pad_numbers_are_jumpers no)
		(fp_poly
			(pts
				(arc
					(start 4.3053 0)
					(mid -4.3053 0)
					(end 4.3053 0)
				)
			)
			(stroke
				(width 0)
				(type default)
			)
			(fill no)
			(layer "B.CrtYd")
		)
		(fp_poly
			(pts
				(arc
					(start 4.3053 0)
					(mid -4.3053 0)
					(end 4.3053 0)
				)
			)
			(stroke
				(width 0)
				(type default)
			)
			(fill no)
			(layer "B.Fab")
		)
		(pad "1" smd custom
			(at 2.95275 0 180)
			(size 2.000013 2.000013)
			(layers "B.Cu" "B.Mask" "B.Paste")
			(net "Net_57")
			(options
				(clearance outline)
				(anchor circle)
			)
			(primitives
				(gr_poly
					(pts
						(arc
							(start 4.0005 -0.00254)
							(mid -4.000501 0)
							(end 4.0005 0.00254)
						)
						(arc
							(start 1.905 0.00254)
							(mid -1.905002 0)
							(end 1.905 -0.00254)
						)
					)
					(width 0)
					(fill yes)
				)
			)
		)
	)
	(footprint ""
		(layer "B.Cu")
		(at 108.373926 -53.00218 -90)
		(property "Reference" "SC999"
			(at 0 0 90)
			(layer "B.SilkS")
			(hide yes)
			(effects
				(font
					(size 1.27 1.27)
				)
				(justify mirror)
			)
		)
		(property "Value" "SCD1U16V2KX-3GP"
			(at -1.1811 -2.7051 270)
			(unlocked yes)
			(layer "B.Fab")
			(hide yes)
			(effects
				(font
					(size 1.016 1.016)
					(thickness 0.1524)
				)
				(justify mirror)
			)
		)
		(property "Device Type" "C402H22"
			(at -1.1811 -4.2291 270)
			(unlocked yes)
			(layer "B.Fab")
			(hide yes)
			(effects
				(font
					(size 1.016 1.016)
					(thickness 0.1524)
				)
				(justify mirror)
			)
		)
		(duplicate_pad_numbers_are_jumpers no)
		(fp_rect
			(start 0.4318 0.9525)
			(end -0.4318 -0.9525)
			(stroke
				(width 0)
				(type default)
			)
			(fill no)
			(layer "B.CrtYd")
		)
		(fp_rect
			(start 0.4318 0.9525)
			(end -0.4318 -0.9525)
			(stroke
				(width 0)
				(type default)
			)
			(fill no)
			(layer "B.Fab")
		)
		(pad "1" smd custom
			(at 0 -0.4445 90)
			(size 0.1524 0.1524)
			(layers "B.Cu" "B.Mask" "B.Paste")
			(net "P1V8_C")
			(options
				(clearance outline)
				(anchor circle)
			)
			(primitives
				(gr_poly
					(pts
						(arc
							(start 0.3048 0.2032)
							(mid 0.275042 0.275042)
							(end 0.2032 0.3048)
						)
						(arc
							(start -0.2032 0.3048)
							(mid -0.275042 0.275042)
							(end -0.3048 0.2032)
						)
						(arc
							(start -0.3048 -0.2032)
							(mid -0.275042 -0.275042)
							(end -0.2032 -0.3048)
						)
						(arc
							(start 0.2032 -0.3048)
							(mid 0.275042 -0.275042)
							(end 0.3048 -0.2032)
						)
					)
					(width 0)
					(fill yes)
				)
			)
		)
		(pad "2" smd custom
			(at 0 0.4445 90)
			(size 0.1524 0.1524)
			(layers "B.Cu" "B.Mask" "B.Paste")
			(net "GND")
			(options
				(clearance outline)
				(anchor circle)
			)
			(primitives
				(gr_poly
					(pts
						(arc
							(start 0.3048 0.2032)
							(mid 0.275042 0.275042)
							(end 0.2032 0.3048)
						)
						(arc
							(start -0.2032 0.3048)
							(mid -0.275042 0.275042)
							(end -0.3048 0.2032)
						)
						(arc
							(start -0.3048 -0.2032)
							(mid -0.275042 -0.275042)
							(end -0.2032 -0.3048)
						)
						(arc
							(start 0.2032 -0.3048)
							(mid 0.275042 -0.275042)
							(end 0.3048 -0.2032)
						)
					)
					(width 0)
					(fill yes)
				)
			)
		)
	)
	(footprint ""
		(layer "B.Cu")
		(at 95.26016 -50.165)
		(property "Reference" "STP37"
			(at 0 0 0)
			(layer "B.SilkS")
			(hide yes)
			(effects
				(font
					(size 1.27 1.27)
				)
				(justify mirror)
			)
		)
		(property "Value" "TPAD28"
			(at -0.0127 -1.8034 0)
			(unlocked yes)
			(layer "B.Fab")
			(hide yes)
			(effects
				(font
					(size 1.016 1.016)
					(thickness 0.1524)
				)
				(justify mirror)
			)
		)
		(property "Device Type" "TPAD28"
			(at -0.0127 -3.3274 0)
			(unlocked yes)
			(layer "B.Fab")
			(hide yes)
			(effects
				(font
					(size 1.016 1.016)
					(thickness 0.1524)
				)
				(justify mirror)
			)
		)
		(duplicate_pad_numbers_are_jumpers no)
		(fp_poly
			(pts
				(arc
					(start 0.3556 0)
					(mid -0.3556 0)
					(end 0.3556 0)
				)
			)
			(stroke
				(width 0)
				(type default)
			)
			(fill no)
			(layer "B.CrtYd")
		)
		(fp_poly
			(pts
				(arc
					(start 0.6096 0)
					(mid -0.6096 0)
					(end 0.6096 0)
				)
			)
			(stroke
				(width 0)
				(type default)
			)
			(fill no)
			(layer "B.Fab")
		)
		(pad "1" smd circle
			(at 0 0 180)
			(size 0.7112 0.7112)
			(layers "B.Cu" "B.Mask" "B.Paste")
			(net "ICE1_TDI")
		)
	)
	(footprint ""
		(layer "B.Cu")
		(at 274.193 -170.561 90)
		(property "Reference" "R309"
			(at 0 0 90)
			(layer "B.SilkS")
			(hide yes)
			(effects
				(font
					(size 1.27 1.27)
				)
				(justify mirror)
			)
		)
		(property "Value" "10KR2F-2-GP"
			(at -0.064008 -3.993896 90)
			(unlocked yes)
			(layer "B.Fab")
			(hide yes)
			(effects
				(font
					(size 1.016 1.016)
					(thickness 0.1524)
				)
				(justify mirror)
			)
		)
		(property "Device Type" "R402H16"
			(at -0.064008 -5.517896 90)
			(unlocked yes)
			(layer "B.Fab")
			(hide yes)
			(effects
				(font
					(size 1.016 1.016)
					(thickness 0.1524)
				)
				(justify mirror)
			)
		)
		(duplicate_pad_numbers_are_jumpers no)
		(fp_line
			(start 0.508 -0.9398)
			(end 0.508 0.9398)
			(stroke
				(width 0.1524)
				(type default)
			)
			(layer "B.SilkS")
		)
		(fp_line
			(start -0.508 -0.9398)
			(end 0.508 -0.9398)
			(stroke
				(width 0.1524)
				(type default)
			)
			(layer "B.SilkS")
		)
		(fp_rect
			(start 0.508 0.9398)
			(end -0.508 -0.9398)
			(stroke
				(width 0)
				(type default)
			)
			(fill no)
			(layer "B.CrtYd")
		)
		(fp_rect
			(start 0.508 0.9398)
			(end -0.508 -0.9398)
			(stroke
				(width 0)
				(type default)
			)
			(fill no)
			(layer "B.Fab")
		)
		(pad "1" smd custom
			(at 0 -0.4445 270)
			(size 0.1397 0.1397)
			(layers "B.Cu" "B.Mask" "B.Paste")
			(net "P3V3_STBY")
			(options
				(clearance outline)
				(anchor circle)
			)
			(primitives
				(gr_poly
					(pts
						(arc
							(start -0.1778 0.2794)
							(mid -0.249642 0.249642)
							(end -0.2794 0.1778)
						)
						(arc
							(start -0.2794 -0.1778)
							(mid -0.249642 -0.249642)
							(end -0.1778 -0.2794)
						)
						(arc
							(start 0.1778 -0.2794)
							(mid 0.249642 -0.249642)
							(end 0.2794 -0.1778)
						)
						(arc
							(start 0.2794 0.1778)
							(mid 0.249642 0.249642)
							(end 0.1778 0.2794)
						)
					)
					(width 0)
					(fill yes)
				)
			)
		)
		(pad "2" smd custom
			(at 0 0.4445 270)
			(size 0.1397 0.1397)
			(layers "B.Cu" "B.Mask" "B.Paste")
			(net "BMC_10G_SCL_2")
			(options
				(clearance outline)
				(anchor circle)
			)
			(primitives
				(gr_poly
					(pts
						(arc
							(start -0.1778 0.2794)
							(mid -0.249642 0.249642)
							(end -0.2794 0.1778)
						)
						(arc
							(start -0.2794 -0.1778)
							(mid -0.249642 -0.249642)
							(end -0.1778 -0.2794)
						)
						(arc
							(start 0.1778 -0.2794)
							(mid 0.249642 -0.249642)
							(end 0.2794 -0.1778)
						)
						(arc
							(start 0.2794 0.1778)
							(mid 0.249642 0.249642)
							(end 0.1778 0.2794)
						)
					)
					(width 0)
					(fill yes)
				)
			)
		)
	)
	(footprint ""
		(layer "B.Cu")
		(at 108.020612 -210.439 -90)
		(property "Reference" "SR908"
			(at 0 0 90)
			(layer "B.SilkS")
			(hide yes)
			(effects
				(font
					(size 1.27 1.27)
				)
				(justify mirror)
			)
		)
		(property "Value" "4K7R2F-GP"
			(at -0.064008 -3.993896 270)
			(unlocked yes)
			(layer "B.Fab")
			(hide yes)
			(effects
				(font
					(size 1.016 1.016)
					(thickness 0.1524)
				)
				(justify mirror)
			)
		)
		(property "Device Type" "R402H16"
			(at -0.064008 -5.517896 270)
			(unlocked yes)
			(layer "B.Fab")
			(hide yes)
			(effects
				(font
					(size 1.016 1.016)
					(thickness 0.1524)
				)
				(justify mirror)
			)
		)
		(duplicate_pad_numbers_are_jumpers no)
		(fp_line
			(start -0.508 -0.9398)
			(end 0.508 -0.9398)
			(stroke
				(width 0.1524)
				(type default)
			)
			(layer "B.SilkS")
		)
		(fp_line
			(start 0.508 -0.9398)
			(end 0.508 0.9398)
			(stroke
				(width 0.1524)
				(type default)
			)
			(layer "B.SilkS")
		)
		(fp_rect
			(start 0.508 0.9398)
			(end -0.508 -0.9398)
			(stroke
				(width 0)
				(type default)
			)
			(fill no)
			(layer "B.CrtYd")
		)
		(fp_rect
			(start 0.508 0.9398)
			(end -0.508 -0.9398)
			(stroke
				(width 0)
				(type default)
			)
			(fill no)
			(layer "B.Fab")
		)
		(pad "1" smd custom
			(at 0 -0.4445 90)
			(size 0.1397 0.1397)
			(layers "B.Cu" "B.Mask" "B.Paste")
			(net "REDV_MODE")
			(options
				(clearance outline)
				(anchor circle)
			)
			(primitives
				(gr_poly
					(pts
						(arc
							(start -0.1778 0.2794)
							(mid -0.249642 0.249642)
							(end -0.2794 0.1778)
						)
						(arc
							(start -0.2794 -0.1778)
							(mid -0.249642 -0.249642)
							(end -0.1778 -0.2794)
						)
						(arc
							(start 0.1778 -0.2794)
							(mid 0.249642 -0.249642)
							(end 0.2794 -0.1778)
						)
						(arc
							(start 0.2794 0.1778)
							(mid 0.249642 0.249642)
							(end 0.1778 0.2794)
						)
					)
					(width 0)
					(fill yes)
				)
			)
		)
		(pad "2" smd custom
			(at 0 0.4445 90)
			(size 0.1397 0.1397)
			(layers "B.Cu" "B.Mask" "B.Paste")
			(net "GND")
			(options
				(clearance outline)
				(anchor circle)
			)
			(primitives
				(gr_poly
					(pts
						(arc
							(start -0.1778 0.2794)
							(mid -0.249642 0.249642)
							(end -0.2794 0.1778)
						)
						(arc
							(start -0.2794 -0.1778)
							(mid -0.249642 -0.249642)
							(end -0.1778 -0.2794)
						)
						(arc
							(start 0.1778 -0.2794)
							(mid 0.249642 -0.249642)
							(end 0.2794 -0.1778)
						)
						(arc
							(start 0.2794 0.1778)
							(mid 0.249642 0.249642)
							(end 0.1778 0.2794)
						)
					)
					(width 0)
					(fill yes)
				)
			)
		)
	)
	(footprint ""
		(layer "B.Cu")
		(at 322.961 -109.982 90)
		(property "Reference" "PR20"
			(at 0 0 90)
			(layer "B.SilkS")
			(hide yes)
			(effects
				(font
					(size 1.27 1.27)
				)
				(justify mirror)
			)
		)
		(property "Value" "3D01R5F-GP"
			(at 0 -8.9535 90)
			(unlocked yes)
			(layer "B.Fab")
			(hide yes)
			(effects
				(font
					(size 1.27 1.016)
					(thickness 0.1524)
				)
				(justify mirror)
			)
		)
		(property "Device Type" "R805H24"
			(at 0 -10.6299 90)
			(unlocked yes)
			(layer "B.Fab")
			(hide yes)
			(effects
				(font
					(size 1.27 1.016)
					(thickness 0.1524)
				)
				(justify mirror)
			)
		)
		(duplicate_pad_numbers_are_jumpers no)
		(fp_line
			(start 0.889 -1.7018)
			(end 0.889 0.2794)
			(stroke
				(width 0.1524)
				(type default)
			)
			(layer "B.SilkS")
		)
		(fp_line
			(start -0.889 -1.7018)
			(end 0.889 -1.7018)
			(stroke
				(width 0.1524)
				(type default)
			)
			(layer "B.SilkS")
		)
		(fp_line
			(start -0.889 -1.7018)
			(end -0.889 -0.381)
			(stroke
				(width 0.1524)
				(type default)
			)
			(layer "B.SilkS")
		)
		(fp_line
			(start 0.889 0.0762)
			(end 0.889 1.7018)
			(stroke
				(width 0.1524)
				(type default)
			)
			(layer "B.SilkS")
		)
		(fp_line
			(start 0.889 1.7018)
			(end -0.889 1.7018)
			(stroke
				(width 0.1524)
				(type default)
			)
			(layer "B.SilkS")
		)
		(fp_line
			(start -0.889 1.7018)
			(end -0.889 -0.508)
			(stroke
				(width 0.1524)
				(type default)
			)
			(layer "B.SilkS")
		)
		(fp_poly
			(pts
				(xy -0.9652 -1.778) (xy -0.9652 1.778) (xy 0.9652 1.778) (xy 0.9652 -1.778)
			)
			(stroke
				(width 0)
				(type default)
			)
			(fill no)
			(layer "B.CrtYd")
		)
		(fp_rect
			(start 0.9652 1.778)
			(end -0.9652 -1.778)
			(stroke
				(width 0)
				(type default)
			)
			(fill no)
			(layer "B.Fab")
		)
		(pad "1" smd rect
			(at 0 -0.9652 270)
			(size 1.397 1.143)
			(layers "B.Cu" "B.Mask" "B.Paste")
			(net "P3V3_STBY_VBST")
		)
		(pad "2" smd rect
			(at 0 0.9652 270)
			(size 1.397 1.143)
			(layers "B.Cu" "B.Mask" "B.Paste")
			(net "P3V3_STBY_VBST_RC")
		)
	)
	(footprint ""
		(layer "B.Cu")
		(at 95.26016 -37.719 180)
		(property "Reference" "SC944"
			(at 0 0 0)
			(layer "B.SilkS")
			(hide yes)
			(effects
				(font
					(size 1.27 1.27)
				)
				(justify mirror)
			)
		)
		(property "Value" "SCD1U6D3V1KX-GP"
			(at 2.8321 -1.7399 180)
			(unlocked yes)
			(layer "B.Fab")
			(hide yes)
			(effects
				(font
					(size 1.016 1.016)
					(thickness 0.1524)
				)
				(justify mirror)
			)
		)
		(property "Device Type" "C0201H13"
			(at 2.8321 -3.2639 180)
			(unlocked yes)
			(layer "B.Fab")
			(hide yes)
			(effects
				(font
					(size 1.016 1.016)
					(thickness 0.1524)
				)
				(justify mirror)
			)
		)
		(duplicate_pad_numbers_are_jumpers no)
		(fp_rect
			(start 0.2794 0.6477)
			(end -0.2794 -0.6477)
			(stroke
				(width 0)
				(type default)
			)
			(fill no)
			(layer "B.CrtYd")
		)
		(fp_rect
			(start 0.2794 0.6477)
			(end -0.2794 -0.6477)
			(stroke
				(width 0)
				(type default)
			)
			(fill no)
			(layer "B.Fab")
		)
		(pad "1" smd custom
			(at 0 -0.2794)
			(size 0.0762 0.0762)
			(layers "B.Cu" "B.Mask" "B.Paste")
			(net "P1V5_C")
			(options
				(clearance outline)
				(anchor circle)
			)
			(primitives
				(gr_poly
					(pts
						(arc
							(start 0.1524 0.127)
							(mid 0.137521 0.162921)
							(end 0.1016 0.1778)
						)
						(arc
							(start -0.1016 0.1778)
							(mid -0.137521 0.162921)
							(end -0.1524 0.127)
						)
						(arc
							(start -0.1524 -0.127)
							(mid -0.137521 -0.162921)
							(end -0.1016 -0.1778)
						)
						(arc
							(start 0.1016 -0.1778)
							(mid 0.137521 -0.162921)
							(end 0.1524 -0.127)
						)
					)
					(width 0)
					(fill yes)
				)
			)
		)
		(pad "2" smd custom
			(at 0 0.2794)
			(size 0.0762 0.0762)
			(layers "B.Cu" "B.Mask" "B.Paste")
			(net "GND")
			(options
				(clearance outline)
				(anchor circle)
			)
			(primitives
				(gr_poly
					(pts
						(arc
							(start 0.1524 0.127)
							(mid 0.137521 0.162921)
							(end 0.1016 0.1778)
						)
						(arc
							(start -0.1016 0.1778)
							(mid -0.137521 0.162921)
							(end -0.1524 0.127)
						)
						(arc
							(start -0.1524 -0.127)
							(mid -0.137521 -0.162921)
							(end -0.1016 -0.1778)
						)
						(arc
							(start 0.1016 -0.1778)
							(mid 0.137521 -0.162921)
							(end 0.1524 -0.127)
						)
					)
					(width 0)
					(fill yes)
				)
			)
		)
	)
	(footprint ""
		(layer "B.Cu")
		(at 114.848386 -31.84398)
		(property "Reference" "STP91"
			(at 0 0 0)
			(layer "B.SilkS")
			(hide yes)
			(effects
				(font
					(size 1.27 1.27)
				)
				(justify mirror)
			)
		)
		(property "Value" "TPAD28"
			(at -0.0127 -1.8034 0)
			(unlocked yes)
			(layer "B.Fab")
			(hide yes)
			(effects
				(font
					(size 1.016 1.016)
					(thickness 0.1524)
				)
				(justify mirror)
			)
		)
		(property "Device Type" "TPAD28"
			(at -0.0127 -3.3274 0)
			(unlocked yes)
			(layer "B.Fab")
			(hide yes)
			(effects
				(font
					(size 1.016 1.016)
					(thickness 0.1524)
				)
				(justify mirror)
			)
		)
		(duplicate_pad_numbers_are_jumpers no)
		(fp_poly
			(pts
				(arc
					(start 0.3556 0)
					(mid -0.3556 0)
					(end 0.3556 0)
				)
			)
			(stroke
				(width 0)
				(type default)
			)
			(fill no)
			(layer "B.CrtYd")
		)
		(fp_poly
			(pts
				(arc
					(start 0.6096 0)
					(mid -0.6096 0)
					(end 0.6096 0)
				)
			)
			(stroke
				(width 0)
				(type default)
			)
			(fill no)
			(layer "B.Fab")
		)
		(pad "1" smd circle
			(at 0 0 180)
			(size 0.7112 0.7112)
			(layers "B.Cu" "B.Mask" "B.Paste")
			(net "IOC_GPIO_12")
		)
	)
	(footprint ""
		(layer "B.Cu")
		(at 296.790872 -176.602136 -90)
		(property "Reference" "C214"
			(at 0 0 90)
			(layer "B.SilkS")
			(hide yes)
			(effects
				(font
					(size 1.27 1.27)
				)
				(justify mirror)
			)
		)
		(property "Value" "SC1U10V2KX-1GP"
			(at -1.1811 -2.7051 270)
			(unlocked yes)
			(layer "B.Fab")
			(hide yes)
			(effects
				(font
					(size 1.016 1.016)
					(thickness 0.1524)
				)
				(justify mirror)
			)
		)
		(property "Device Type" "C402H22"
			(at -1.1811 -4.2291 270)
			(unlocked yes)
			(layer "B.Fab")
			(hide yes)
			(effects
				(font
					(size 1.016 1.016)
					(thickness 0.1524)
				)
				(justify mirror)
			)
		)
		(duplicate_pad_numbers_are_jumpers no)
		(fp_rect
			(start 0.4318 0.9525)
			(end -0.4318 -0.9525)
			(stroke
				(width 0)
				(type default)
			)
			(fill no)
			(layer "B.CrtYd")
		)
		(fp_rect
			(start 0.4318 0.9525)
			(end -0.4318 -0.9525)
			(stroke
				(width 0)
				(type default)
			)
			(fill no)
			(layer "B.Fab")
		)
		(pad "1" smd custom
			(at 0 -0.4445 90)
			(size 0.1524 0.1524)
			(layers "B.Cu" "B.Mask" "B.Paste")
			(net "P3V3_STBY")
			(options
				(clearance outline)
				(anchor circle)
			)
			(primitives
				(gr_poly
					(pts
						(arc
							(start 0.3048 0.2032)
							(mid 0.275042 0.275042)
							(end 0.2032 0.3048)
						)
						(arc
							(start -0.2032 0.3048)
							(mid -0.275042 0.275042)
							(end -0.3048 0.2032)
						)
						(arc
							(start -0.3048 -0.2032)
							(mid -0.275042 -0.275042)
							(end -0.2032 -0.3048)
						)
						(arc
							(start 0.2032 -0.3048)
							(mid 0.275042 -0.275042)
							(end 0.3048 -0.2032)
						)
					)
					(width 0)
					(fill yes)
				)
			)
		)
		(pad "2" smd custom
			(at 0 0.4445 90)
			(size 0.1524 0.1524)
			(layers "B.Cu" "B.Mask" "B.Paste")
			(net "GND")
			(options
				(clearance outline)
				(anchor circle)
			)
			(primitives
				(gr_poly
					(pts
						(arc
							(start 0.3048 0.2032)
							(mid 0.275042 0.275042)
							(end 0.2032 0.3048)
						)
						(arc
							(start -0.2032 0.3048)
							(mid -0.275042 0.275042)
							(end -0.3048 0.2032)
						)
						(arc
							(start -0.3048 -0.2032)
							(mid -0.275042 -0.275042)
							(end -0.2032 -0.3048)
						)
						(arc
							(start 0.2032 -0.3048)
							(mid 0.275042 -0.275042)
							(end 0.3048 -0.2032)
						)
					)
					(width 0)
					(fill yes)
				)
			)
		)
	)
	(footprint ""
		(layer "B.Cu")
		(at 323.342 -182.372)
		(property "Reference" "C8083"
			(at 0 0 0)
			(layer "B.SilkS")
			(hide yes)
			(effects
				(font
					(size 1.27 1.27)
				)
				(justify mirror)
			)
		)
		(property "Value" "SCD1U25V2KX-2-GP"
			(at -1.1811 -2.7051 0)
			(unlocked yes)
			(layer "B.Fab")
			(hide yes)
			(effects
				(font
					(size 1.016 1.016)
					(thickness 0.1524)
				)
				(justify mirror)
			)
		)
		(property "Device Type" "C402H22"
			(at -1.1811 -4.2291 0)
			(unlocked yes)
			(layer "B.Fab")
			(hide yes)
			(effects
				(font
					(size 1.016 1.016)
					(thickness 0.1524)
				)
				(justify mirror)
			)
		)
		(duplicate_pad_numbers_are_jumpers no)
		(fp_rect
			(start 0.4318 0.9525)
			(end -0.4318 -0.9525)
			(stroke
				(width 0)
				(type default)
			)
			(fill no)
			(layer "B.CrtYd")
		)
		(fp_rect
			(start 0.4318 0.9525)
			(end -0.4318 -0.9525)
			(stroke
				(width 0)
				(type default)
			)
			(fill no)
			(layer "B.Fab")
		)
		(pad "1" smd custom
			(at 0 -0.4445 180)
			(size 0.1524 0.1524)
			(layers "B.Cu" "B.Mask" "B.Paste")
			(net "ADC_P0V955_C")
			(options
				(clearance outline)
				(anchor circle)
			)
			(primitives
				(gr_poly
					(pts
						(arc
							(start 0.3048 0.2032)
							(mid 0.275042 0.275042)
							(end 0.2032 0.3048)
						)
						(arc
							(start -0.2032 0.3048)
							(mid -0.275042 0.275042)
							(end -0.3048 0.2032)
						)
						(arc
							(start -0.3048 -0.2032)
							(mid -0.275042 -0.275042)
							(end -0.2032 -0.3048)
						)
						(arc
							(start 0.2032 -0.3048)
							(mid 0.275042 -0.275042)
							(end 0.3048 -0.2032)
						)
					)
					(width 0)
					(fill yes)
				)
			)
		)
		(pad "2" smd custom
			(at 0 0.4445 180)
			(size 0.1524 0.1524)
			(layers "B.Cu" "B.Mask" "B.Paste")
			(net "GND")
			(options
				(clearance outline)
				(anchor circle)
			)
			(primitives
				(gr_poly
					(pts
						(arc
							(start 0.3048 0.2032)
							(mid 0.275042 0.275042)
							(end 0.2032 0.3048)
						)
						(arc
							(start -0.2032 0.3048)
							(mid -0.275042 0.275042)
							(end -0.3048 0.2032)
						)
						(arc
							(start -0.3048 -0.2032)
							(mid -0.275042 -0.275042)
							(end -0.2032 -0.3048)
						)
						(arc
							(start 0.2032 -0.3048)
							(mid 0.275042 -0.275042)
							(end 0.3048 -0.2032)
						)
					)
					(width 0)
					(fill yes)
				)
			)
		)
	)
	(footprint ""
		(layer "B.Cu")
		(at 112.40897 -82.296)
		(property "Reference" "STP154"
			(at 0 0 0)
			(layer "B.SilkS")
			(hide yes)
			(effects
				(font
					(size 1.27 1.27)
				)
				(justify mirror)
			)
		)
		(property "Value" "TPAD28"
			(at -0.0127 -1.8034 0)
			(unlocked yes)
			(layer "B.Fab")
			(hide yes)
			(effects
				(font
					(size 1.016 1.016)
					(thickness 0.1524)
				)
				(justify mirror)
			)
		)
		(property "Device Type" "TPAD28"
			(at -0.0127 -3.3274 0)
			(unlocked yes)
			(layer "B.Fab")
			(hide yes)
			(effects
				(font
					(size 1.016 1.016)
					(thickness 0.1524)
				)
				(justify mirror)
			)
		)
		(duplicate_pad_numbers_are_jumpers no)
		(fp_poly
			(pts
				(arc
					(start 0.3556 0)
					(mid -0.3556 0)
					(end 0.3556 0)
				)
			)
			(stroke
				(width 0)
				(type default)
			)
			(fill no)
			(layer "B.CrtYd")
		)
		(fp_poly
			(pts
				(arc
					(start 0.6096 0)
					(mid -0.6096 0)
					(end 0.6096 0)
				)
			)
			(stroke
				(width 0)
				(type default)
			)
			(fill no)
			(layer "B.Fab")
		)
		(pad "1" smd circle
			(at 0 0 180)
			(size 0.7112 0.7112)
			(layers "B.Cu" "B.Mask" "B.Paste")
			(net "EXP_LED_13")
		)
	)
	(footprint ""
		(layer "B.Cu")
		(at 113.55197 -81.661)
		(property "Reference" "STP62"
			(at 0 0 0)
			(layer "B.SilkS")
			(hide yes)
			(effects
				(font
					(size 1.27 1.27)
				)
				(justify mirror)
			)
		)
		(property "Value" "TPAD28"
			(at -0.0127 -1.8034 0)
			(unlocked yes)
			(layer "B.Fab")
			(hide yes)
			(effects
				(font
					(size 1.016 1.016)
					(thickness 0.1524)
				)
				(justify mirror)
			)
		)
		(property "Device Type" "TPAD28"
			(at -0.0127 -3.3274 0)
			(unlocked yes)
			(layer "B.Fab")
			(hide yes)
			(effects
				(font
					(size 1.016 1.016)
					(thickness 0.1524)
				)
				(justify mirror)
			)
		)
		(duplicate_pad_numbers_are_jumpers no)
		(fp_poly
			(pts
				(arc
					(start 0.3556 0)
					(mid -0.3556 0)
					(end 0.3556 0)
				)
			)
			(stroke
				(width 0)
				(type default)
			)
			(fill no)
			(layer "B.CrtYd")
		)
		(fp_poly
			(pts
				(arc
					(start 0.6096 0)
					(mid -0.6096 0)
					(end 0.6096 0)
				)
			)
			(stroke
				(width 0)
				(type default)
			)
			(fill no)
			(layer "B.Fab")
		)
		(pad "1" smd circle
			(at 0 0 180)
			(size 0.7112 0.7112)
			(layers "B.Cu" "B.Mask" "B.Paste")
			(net "EXP_TEST_MUX24")
		)
	)
	(footprint ""
		(layer "B.Cu")
		(at 24.596344 -175.387762 90)
		(property "Reference" "SC1113"
			(at 0 0 90)
			(layer "B.SilkS")
			(hide yes)
			(effects
				(font
					(size 1.27 1.27)
				)
				(justify mirror)
			)
		)
		(property "Value" "SCD1U16V2KX-3GP"
			(at -1.1811 -2.7051 90)
			(unlocked yes)
			(layer "B.Fab")
			(hide yes)
			(effects
				(font
					(size 1.016 1.016)
					(thickness 0.1524)
				)
				(justify mirror)
			)
		)
		(property "Device Type" "C402H22"
			(at -1.1811 -4.2291 90)
			(unlocked yes)
			(layer "B.Fab")
			(hide yes)
			(effects
				(font
					(size 1.016 1.016)
					(thickness 0.1524)
				)
				(justify mirror)
			)
		)
		(duplicate_pad_numbers_are_jumpers no)
		(fp_rect
			(start 0.4318 0.9525)
			(end -0.4318 -0.9525)
			(stroke
				(width 0)
				(type default)
			)
			(fill no)
			(layer "B.CrtYd")
		)
		(fp_rect
			(start 0.4318 0.9525)
			(end -0.4318 -0.9525)
			(stroke
				(width 0)
				(type default)
			)
			(fill no)
			(layer "B.Fab")
		)
		(pad "1" smd custom
			(at 0 -0.4445 270)
			(size 0.1524 0.1524)
			(layers "B.Cu" "B.Mask" "B.Paste")
			(net "P3V3_STBY")
			(options
				(clearance outline)
				(anchor circle)
			)
			(primitives
				(gr_poly
					(pts
						(arc
							(start 0.3048 0.2032)
							(mid 0.275042 0.275042)
							(end 0.2032 0.3048)
						)
						(arc
							(start -0.2032 0.3048)
							(mid -0.275042 0.275042)
							(end -0.3048 0.2032)
						)
						(arc
							(start -0.3048 -0.2032)
							(mid -0.275042 -0.275042)
							(end -0.2032 -0.3048)
						)
						(arc
							(start 0.2032 -0.3048)
							(mid 0.275042 -0.275042)
							(end 0.3048 -0.2032)
						)
					)
					(width 0)
					(fill yes)
				)
			)
		)
		(pad "2" smd custom
			(at 0 0.4445 270)
			(size 0.1524 0.1524)
			(layers "B.Cu" "B.Mask" "B.Paste")
			(net "GND")
			(options
				(clearance outline)
				(anchor circle)
			)
			(primitives
				(gr_poly
					(pts
						(arc
							(start 0.3048 0.2032)
							(mid 0.275042 0.275042)
							(end 0.2032 0.3048)
						)
						(arc
							(start -0.2032 0.3048)
							(mid -0.275042 0.275042)
							(end -0.3048 0.2032)
						)
						(arc
							(start -0.3048 -0.2032)
							(mid -0.275042 -0.275042)
							(end -0.2032 -0.3048)
						)
						(arc
							(start 0.2032 -0.3048)
							(mid 0.275042 -0.275042)
							(end 0.3048 -0.2032)
						)
					)
					(width 0)
					(fill yes)
				)
			)
		)
	)
	(footprint ""
		(layer "B.Cu")
		(at 115.27917 -98.3742)
		(property "Reference" "SC1260"
			(at 0 0 0)
			(layer "B.SilkS")
			(hide yes)
			(effects
				(font
					(size 1.27 1.27)
				)
				(justify mirror)
			)
		)
		(property "Value" "SCD1U6D3V1KX-GP"
			(at 2.8321 -1.7399 0)
			(unlocked yes)
			(layer "B.Fab")
			(hide yes)
			(effects
				(font
					(size 1.016 1.016)
					(thickness 0.1524)
				)
				(justify mirror)
			)
		)
		(property "Device Type" "C0201H13"
			(at 2.8321 -3.2639 0)
			(unlocked yes)
			(layer "B.Fab")
			(hide yes)
			(effects
				(font
					(size 1.016 1.016)
					(thickness 0.1524)
				)
				(justify mirror)
			)
		)
		(duplicate_pad_numbers_are_jumpers no)
		(fp_rect
			(start 0.2794 0.6477)
			(end -0.2794 -0.6477)
			(stroke
				(width 0)
				(type default)
			)
			(fill no)
			(layer "B.CrtYd")
		)
		(fp_rect
			(start 0.2794 0.6477)
			(end -0.2794 -0.6477)
			(stroke
				(width 0)
				(type default)
			)
			(fill no)
			(layer "B.Fab")
		)
		(pad "1" smd custom
			(at 0 -0.2794 180)
			(size 0.0762 0.0762)
			(layers "B.Cu" "B.Mask" "B.Paste")
			(net "P0V9_E")
			(options
				(clearance outline)
				(anchor circle)
			)
			(primitives
				(gr_poly
					(pts
						(arc
							(start 0.1524 0.127)
							(mid 0.137521 0.162921)
							(end 0.1016 0.1778)
						)
						(arc
							(start -0.1016 0.1778)
							(mid -0.137521 0.162921)
							(end -0.1524 0.127)
						)
						(arc
							(start -0.1524 -0.127)
							(mid -0.137521 -0.162921)
							(end -0.1016 -0.1778)
						)
						(arc
							(start 0.1016 -0.1778)
							(mid 0.137521 -0.162921)
							(end 0.1524 -0.127)
						)
					)
					(width 0)
					(fill yes)
				)
			)
		)
		(pad "2" smd custom
			(at 0 0.2794 180)
			(size 0.0762 0.0762)
			(layers "B.Cu" "B.Mask" "B.Paste")
			(net "GND")
			(options
				(clearance outline)
				(anchor circle)
			)
			(primitives
				(gr_poly
					(pts
						(arc
							(start 0.1524 0.127)
							(mid 0.137521 0.162921)
							(end 0.1016 0.1778)
						)
						(arc
							(start -0.1016 0.1778)
							(mid -0.137521 0.162921)
							(end -0.1524 0.127)
						)
						(arc
							(start -0.1524 -0.127)
							(mid -0.137521 -0.162921)
							(end -0.1016 -0.1778)
						)
						(arc
							(start 0.1016 -0.1778)
							(mid 0.137521 -0.162921)
							(end 0.1524 -0.127)
						)
					)
					(width 0)
					(fill yes)
				)
			)
		)
	)
	(footprint ""
		(layer "B.Cu")
		(at 274.447 -187.071 90)
		(property "Reference" "R370"
			(at 0 0 90)
			(layer "B.SilkS")
			(hide yes)
			(effects
				(font
					(size 1.27 1.27)
				)
				(justify mirror)
			)
		)
		(property "Value" "3K3R2F-2-GP"
			(at -0.064008 -3.993896 90)
			(unlocked yes)
			(layer "B.Fab")
			(hide yes)
			(effects
				(font
					(size 1.016 1.016)
					(thickness 0.1524)
				)
				(justify mirror)
			)
		)
		(property "Device Type" "R402H16"
			(at -0.064008 -5.517896 90)
			(unlocked yes)
			(layer "B.Fab")
			(hide yes)
			(effects
				(font
					(size 1.016 1.016)
					(thickness 0.1524)
				)
				(justify mirror)
			)
		)
		(duplicate_pad_numbers_are_jumpers no)
		(fp_line
			(start 0.508 -0.9398)
			(end 0.508 0.9398)
			(stroke
				(width 0.1524)
				(type default)
			)
			(layer "B.SilkS")
		)
		(fp_line
			(start -0.508 -0.9398)
			(end 0.508 -0.9398)
			(stroke
				(width 0.1524)
				(type default)
			)
			(layer "B.SilkS")
		)
		(fp_rect
			(start 0.508 0.9398)
			(end -0.508 -0.9398)
			(stroke
				(width 0)
				(type default)
			)
			(fill no)
			(layer "B.CrtYd")
		)
		(fp_rect
			(start 0.508 0.9398)
			(end -0.508 -0.9398)
			(stroke
				(width 0)
				(type default)
			)
			(fill no)
			(layer "B.Fab")
		)
		(pad "1" smd custom
			(at 0 -0.4445 270)
			(size 0.1397 0.1397)
			(layers "B.Cu" "B.Mask" "B.Paste")
			(net "P3V3_STBY")
			(options
				(clearance outline)
				(anchor circle)
			)
			(primitives
				(gr_poly
					(pts
						(arc
							(start -0.1778 0.2794)
							(mid -0.249642 0.249642)
							(end -0.2794 0.1778)
						)
						(arc
							(start -0.2794 -0.1778)
							(mid -0.249642 -0.249642)
							(end -0.1778 -0.2794)
						)
						(arc
							(start 0.1778 -0.2794)
							(mid 0.249642 -0.249642)
							(end 0.2794 -0.1778)
						)
						(arc
							(start 0.2794 0.1778)
							(mid 0.249642 0.249642)
							(end 0.1778 0.2794)
						)
					)
					(width 0)
					(fill yes)
				)
			)
		)
		(pad "2" smd custom
			(at 0 0.4445 270)
			(size 0.1397 0.1397)
			(layers "B.Cu" "B.Mask" "B.Paste")
			(net "ROMD7")
			(options
				(clearance outline)
				(anchor circle)
			)
			(primitives
				(gr_poly
					(pts
						(arc
							(start -0.1778 0.2794)
							(mid -0.249642 0.249642)
							(end -0.2794 0.1778)
						)
						(arc
							(start -0.2794 -0.1778)
							(mid -0.249642 -0.249642)
							(end -0.1778 -0.2794)
						)
						(arc
							(start 0.1778 -0.2794)
							(mid 0.249642 -0.249642)
							(end 0.2794 -0.1778)
						)
						(arc
							(start 0.2794 0.1778)
							(mid 0.249642 0.249642)
							(end 0.1778 0.2794)
						)
					)
					(width 0)
					(fill yes)
				)
			)
		)
	)
	(footprint ""
		(layer "B.Cu")
		(at 287.3502 -204.978 180)
		(property "Reference" "C198"
			(at 0 0 0)
			(layer "B.SilkS")
			(hide yes)
			(effects
				(font
					(size 1.27 1.27)
				)
				(justify mirror)
			)
		)
		(property "Value" "SC1U10V3KX-4GP-U"
			(at 0 -2.8194 180)
			(unlocked yes)
			(layer "B.Fab")
			(hide yes)
			(effects
				(font
					(size 1.016 1.016)
					(thickness 0.1524)
				)
				(justify mirror)
			)
		)
		(property "Device Type" "C603H36"
			(at 0 -4.3434 180)
			(unlocked yes)
			(layer "B.Fab")
			(hide yes)
			(effects
				(font
					(size 1.016 1.016)
					(thickness 0.1524)
				)
				(justify mirror)
			)
		)
		(duplicate_pad_numbers_are_jumpers no)
		(fp_line
			(start -0.508 0)
			(end 0.508 0)
			(stroke
				(width 0.2032)
				(type default)
			)
			(layer "B.SilkS")
		)
		(fp_rect
			(start 0.5842 1.3335)
			(end -0.5842 -1.3335)
			(stroke
				(width 0)
				(type default)
			)
			(fill no)
			(layer "B.CrtYd")
		)
		(fp_rect
			(start 0.5842 1.3335)
			(end -0.5842 -1.3335)
			(stroke
				(width 0)
				(type default)
			)
			(fill no)
			(layer "B.Fab")
		)
		(pad "1" smd custom
			(at 0 -0.762)
			(size 0.2159 0.2159)
			(layers "B.Cu" "B.Mask" "B.Paste")
			(net "P1V53_STBY")
			(options
				(clearance outline)
				(anchor circle)
			)
			(primitives
				(gr_poly
					(pts
						(arc
							(start -0.3302 0.4318)
							(mid -0.402042 0.402042)
							(end -0.4318 0.3302)
						)
						(arc
							(start -0.4318 -0.3302)
							(mid -0.402042 -0.402042)
							(end -0.3302 -0.4318)
						)
						(arc
							(start 0.3302 -0.4318)
							(mid 0.402042 -0.402042)
							(end 0.4318 -0.3302)
						)
						(arc
							(start 0.4318 0.3302)
							(mid 0.402042 0.402042)
							(end 0.3302 0.4318)
						)
					)
					(width 0)
					(fill yes)
				)
			)
		)
		(pad "2" smd custom
			(at 0 0.762)
			(size 0.2159 0.2159)
			(layers "B.Cu" "B.Mask" "B.Paste")
			(net "GND")
			(options
				(clearance outline)
				(anchor circle)
			)
			(primitives
				(gr_poly
					(pts
						(arc
							(start -0.3302 0.4318)
							(mid -0.402042 0.402042)
							(end -0.4318 0.3302)
						)
						(arc
							(start -0.4318 -0.3302)
							(mid -0.402042 -0.402042)
							(end -0.3302 -0.4318)
						)
						(arc
							(start 0.3302 -0.4318)
							(mid 0.402042 -0.402042)
							(end 0.4318 -0.3302)
						)
						(arc
							(start 0.4318 0.3302)
							(mid 0.402042 0.402042)
							(end 0.3302 0.4318)
						)
					)
					(width 0)
					(fill yes)
				)
			)
		)
	)
	(footprint ""
		(layer "B.Cu")
		(at 323.342 -179.705 180)
		(property "Reference" "R5770"
			(at 0 0 0)
			(layer "B.SilkS")
			(hide yes)
			(effects
				(font
					(size 1.27 1.27)
				)
				(justify mirror)
			)
		)
		(property "Value" "1KR2F-3-GP"
			(at -0.064008 -3.993896 180)
			(unlocked yes)
			(layer "B.Fab")
			(hide yes)
			(effects
				(font
					(size 1.016 1.016)
					(thickness 0.1524)
				)
				(justify mirror)
			)
		)
		(property "Device Type" "R402H16"
			(at -0.064008 -5.517896 180)
			(unlocked yes)
			(layer "B.Fab")
			(hide yes)
			(effects
				(font
					(size 1.016 1.016)
					(thickness 0.1524)
				)
				(justify mirror)
			)
		)
		(duplicate_pad_numbers_are_jumpers no)
		(fp_line
			(start 0.508 -0.9398)
			(end 0.508 0.9398)
			(stroke
				(width 0.1524)
				(type default)
			)
			(layer "B.SilkS")
		)
		(fp_line
			(start -0.508 -0.9398)
			(end 0.508 -0.9398)
			(stroke
				(width 0.1524)
				(type default)
			)
			(layer "B.SilkS")
		)
		(fp_rect
			(start 0.508 0.9398)
			(end -0.508 -0.9398)
			(stroke
				(width 0)
				(type default)
			)
			(fill no)
			(layer "B.CrtYd")
		)
		(fp_rect
			(start 0.508 0.9398)
			(end -0.508 -0.9398)
			(stroke
				(width 0)
				(type default)
			)
			(fill no)
			(layer "B.Fab")
		)
		(pad "1" smd custom
			(at 0 -0.4445)
			(size 0.1397 0.1397)
			(layers "B.Cu" "B.Mask" "B.Paste")
			(net "ADC_P3V3_STBY")
			(options
				(clearance outline)
				(anchor circle)
			)
			(primitives
				(gr_poly
					(pts
						(arc
							(start -0.1778 0.2794)
							(mid -0.249642 0.249642)
							(end -0.2794 0.1778)
						)
						(arc
							(start -0.2794 -0.1778)
							(mid -0.249642 -0.249642)
							(end -0.1778 -0.2794)
						)
						(arc
							(start 0.1778 -0.2794)
							(mid 0.249642 -0.249642)
							(end 0.2794 -0.1778)
						)
						(arc
							(start 0.2794 0.1778)
							(mid 0.249642 0.249642)
							(end 0.1778 0.2794)
						)
					)
					(width 0)
					(fill yes)
				)
			)
		)
		(pad "2" smd custom
			(at 0 0.4445)
			(size 0.1397 0.1397)
			(layers "B.Cu" "B.Mask" "B.Paste")
			(net "GND")
			(options
				(clearance outline)
				(anchor circle)
			)
			(primitives
				(gr_poly
					(pts
						(arc
							(start -0.1778 0.2794)
							(mid -0.249642 0.249642)
							(end -0.2794 0.1778)
						)
						(arc
							(start -0.2794 -0.1778)
							(mid -0.249642 -0.249642)
							(end -0.1778 -0.2794)
						)
						(arc
							(start 0.1778 -0.2794)
							(mid 0.249642 -0.249642)
							(end 0.2794 -0.1778)
						)
						(arc
							(start 0.2794 0.1778)
							(mid 0.249642 0.249642)
							(end 0.1778 0.2794)
						)
					)
					(width 0)
					(fill yes)
				)
			)
		)
	)
	(footprint ""
		(layer "B.Cu")
		(at 111.195612 -221.996)
		(property "Reference" "SR903"
			(at 0 0 0)
			(layer "B.SilkS")
			(hide yes)
			(effects
				(font
					(size 1.27 1.27)
				)
				(justify mirror)
			)
		)
		(property "Value" "0R2J-2-GP"
			(at -0.064008 -3.993896 0)
			(unlocked yes)
			(layer "B.Fab")
			(hide yes)
			(effects
				(font
					(size 1.016 1.016)
					(thickness 0.1524)
				)
				(justify mirror)
			)
		)
		(property "Device Type" "R402H16"
			(at -0.064008 -5.517896 0)
			(unlocked yes)
			(layer "B.Fab")
			(hide yes)
			(effects
				(font
					(size 1.016 1.016)
					(thickness 0.1524)
				)
				(justify mirror)
			)
		)
		(duplicate_pad_numbers_are_jumpers no)
		(fp_line
			(start -0.508 -0.9398)
			(end 0.508 -0.9398)
			(stroke
				(width 0.1524)
				(type default)
			)
			(layer "B.SilkS")
		)
		(fp_line
			(start 0.508 -0.9398)
			(end 0.508 0.9398)
			(stroke
				(width 0.1524)
				(type default)
			)
			(layer "B.SilkS")
		)
		(fp_rect
			(start 0.508 0.9398)
			(end -0.508 -0.9398)
			(stroke
				(width 0)
				(type default)
			)
			(fill no)
			(layer "B.CrtYd")
		)
		(fp_rect
			(start 0.508 0.9398)
			(end -0.508 -0.9398)
			(stroke
				(width 0)
				(type default)
			)
			(fill no)
			(layer "B.Fab")
		)
		(pad "1" smd custom
			(at 0 -0.4445 180)
			(size 0.1397 0.1397)
			(layers "B.Cu" "B.Mask" "B.Paste")
			(net "SAS_GF_EXP_RX_DP8")
			(options
				(clearance outline)
				(anchor circle)
			)
			(primitives
				(gr_poly
					(pts
						(arc
							(start -0.1778 0.2794)
							(mid -0.249642 0.249642)
							(end -0.2794 0.1778)
						)
						(arc
							(start -0.2794 -0.1778)
							(mid -0.249642 -0.249642)
							(end -0.1778 -0.2794)
						)
						(arc
							(start 0.1778 -0.2794)
							(mid 0.249642 -0.249642)
							(end 0.2794 -0.1778)
						)
						(arc
							(start 0.2794 0.1778)
							(mid 0.249642 0.249642)
							(end 0.1778 0.2794)
						)
					)
					(width 0)
					(fill yes)
				)
			)
		)
		(pad "2" smd custom
			(at 0 0.4445 180)
			(size 0.1397 0.1397)
			(layers "B.Cu" "B.Mask" "B.Paste")
			(net "SAS_HDD_CONN_SER_RX8_P")
			(options
				(clearance outline)
				(anchor circle)
			)
			(primitives
				(gr_poly
					(pts
						(arc
							(start -0.1778 0.2794)
							(mid -0.249642 0.249642)
							(end -0.2794 0.1778)
						)
						(arc
							(start -0.2794 -0.1778)
							(mid -0.249642 -0.249642)
							(end -0.1778 -0.2794)
						)
						(arc
							(start 0.1778 -0.2794)
							(mid 0.249642 -0.249642)
							(end 0.2794 -0.1778)
						)
						(arc
							(start 0.2794 0.1778)
							(mid 0.249642 0.249642)
							(end 0.1778 0.2794)
						)
					)
					(width 0)
					(fill yes)
				)
			)
		)
	)
	(footprint ""
		(layer "B.Cu")
		(at 14.471904 -100.400866)
		(property "Reference" "C133"
			(at 0 0 0)
			(layer "B.SilkS")
			(hide yes)
			(effects
				(font
					(size 1.27 1.27)
				)
				(justify mirror)
			)
		)
		(property "Value" "SCD01U50V2KX-1GP"
			(at -1.1811 -2.7051 0)
			(unlocked yes)
			(layer "B.Fab")
			(hide yes)
			(effects
				(font
					(size 1.016 1.016)
					(thickness 0.1524)
				)
				(justify mirror)
			)
		)
		(property "Device Type" "C402H22"
			(at -1.1811 -4.2291 0)
			(unlocked yes)
			(layer "B.Fab")
			(hide yes)
			(effects
				(font
					(size 1.016 1.016)
					(thickness 0.1524)
				)
				(justify mirror)
			)
		)
		(duplicate_pad_numbers_are_jumpers no)
		(fp_rect
			(start 0.4318 0.9525)
			(end -0.4318 -0.9525)
			(stroke
				(width 0)
				(type default)
			)
			(fill no)
			(layer "B.CrtYd")
		)
		(fp_rect
			(start 0.4318 0.9525)
			(end -0.4318 -0.9525)
			(stroke
				(width 0)
				(type default)
			)
			(fill no)
			(layer "B.Fab")
		)
		(pad "1" smd custom
			(at 0 -0.4445 180)
			(size 0.1524 0.1524)
			(layers "B.Cu" "B.Mask" "B.Paste")
			(net "IOC_SAS_RX_N5")
			(options
				(clearance outline)
				(anchor circle)
			)
			(primitives
				(gr_poly
					(pts
						(arc
							(start 0.3048 0.2032)
							(mid 0.275042 0.275042)
							(end 0.2032 0.3048)
						)
						(arc
							(start -0.2032 0.3048)
							(mid -0.275042 0.275042)
							(end -0.3048 0.2032)
						)
						(arc
							(start -0.3048 -0.2032)
							(mid -0.275042 -0.275042)
							(end -0.2032 -0.3048)
						)
						(arc
							(start 0.2032 -0.3048)
							(mid 0.275042 -0.275042)
							(end 0.3048 -0.2032)
						)
					)
					(width 0)
					(fill yes)
				)
			)
		)
		(pad "2" smd custom
			(at 0 0.4445 180)
			(size 0.1524 0.1524)
			(layers "B.Cu" "B.Mask" "B.Paste")
			(net "SAS_EXT_CONN_RX17_N")
			(options
				(clearance outline)
				(anchor circle)
			)
			(primitives
				(gr_poly
					(pts
						(arc
							(start 0.3048 0.2032)
							(mid 0.275042 0.275042)
							(end 0.2032 0.3048)
						)
						(arc
							(start -0.2032 0.3048)
							(mid -0.275042 0.275042)
							(end -0.3048 0.2032)
						)
						(arc
							(start -0.3048 -0.2032)
							(mid -0.275042 -0.275042)
							(end -0.2032 -0.3048)
						)
						(arc
							(start 0.2032 -0.3048)
							(mid 0.275042 -0.275042)
							(end 0.3048 -0.2032)
						)
					)
					(width 0)
					(fill yes)
				)
			)
		)
	)
	(footprint ""
		(layer "B.Cu")
		(at 115.767612 -221.996 180)
		(property "Reference" "SC1292"
			(at 0 0 0)
			(layer "B.SilkS")
			(hide yes)
			(effects
				(font
					(size 1.27 1.27)
				)
				(justify mirror)
			)
		)
		(property "Value" "SCD1U16V2KX-3GP"
			(at -1.1811 -2.7051 180)
			(unlocked yes)
			(layer "B.Fab")
			(hide yes)
			(effects
				(font
					(size 1.016 1.016)
					(thickness 0.1524)
				)
				(justify mirror)
			)
		)
		(property "Device Type" "C402H22"
			(at -1.1811 -4.2291 180)
			(unlocked yes)
			(layer "B.Fab")
			(hide yes)
			(effects
				(font
					(size 1.016 1.016)
					(thickness 0.1524)
				)
				(justify mirror)
			)
		)
		(duplicate_pad_numbers_are_jumpers no)
		(fp_rect
			(start 0.4318 0.9525)
			(end -0.4318 -0.9525)
			(stroke
				(width 0)
				(type default)
			)
			(fill no)
			(layer "B.CrtYd")
		)
		(fp_rect
			(start 0.4318 0.9525)
			(end -0.4318 -0.9525)
			(stroke
				(width 0)
				(type default)
			)
			(fill no)
			(layer "B.Fab")
		)
		(pad "1" smd custom
			(at 0 -0.4445)
			(size 0.1524 0.1524)
			(layers "B.Cu" "B.Mask" "B.Paste")
			(net "1.2V_REDV")
			(options
				(clearance outline)
				(anchor circle)
			)
			(primitives
				(gr_poly
					(pts
						(arc
							(start 0.3048 0.2032)
							(mid 0.275042 0.275042)
							(end 0.2032 0.3048)
						)
						(arc
							(start -0.2032 0.3048)
							(mid -0.275042 0.275042)
							(end -0.3048 0.2032)
						)
						(arc
							(start -0.3048 -0.2032)
							(mid -0.275042 -0.275042)
							(end -0.2032 -0.3048)
						)
						(arc
							(start 0.2032 -0.3048)
							(mid 0.275042 -0.275042)
							(end 0.3048 -0.2032)
						)
					)
					(width 0)
					(fill yes)
				)
			)
		)
		(pad "2" smd custom
			(at 0 0.4445)
			(size 0.1524 0.1524)
			(layers "B.Cu" "B.Mask" "B.Paste")
			(net "GND")
			(options
				(clearance outline)
				(anchor circle)
			)
			(primitives
				(gr_poly
					(pts
						(arc
							(start 0.3048 0.2032)
							(mid 0.275042 0.275042)
							(end 0.2032 0.3048)
						)
						(arc
							(start -0.2032 0.3048)
							(mid -0.275042 0.275042)
							(end -0.3048 0.2032)
						)
						(arc
							(start -0.3048 -0.2032)
							(mid -0.275042 -0.275042)
							(end -0.2032 -0.3048)
						)
						(arc
							(start 0.2032 -0.3048)
							(mid 0.275042 -0.275042)
							(end 0.3048 -0.2032)
						)
					)
					(width 0)
					(fill yes)
				)
			)
		)
	)
	(footprint ""
		(layer "B.Cu")
		(at 290.186872 -174.824136 90)
		(property "Reference" "C212"
			(at 0 0 90)
			(layer "B.SilkS")
			(hide yes)
			(effects
				(font
					(size 1.27 1.27)
				)
				(justify mirror)
			)
		)
		(property "Value" "SC1U10V2KX-1GP"
			(at -1.1811 -2.7051 90)
			(unlocked yes)
			(layer "B.Fab")
			(hide yes)
			(effects
				(font
					(size 1.016 1.016)
					(thickness 0.1524)
				)
				(justify mirror)
			)
		)
		(property "Device Type" "C402H22"
			(at -1.1811 -4.2291 90)
			(unlocked yes)
			(layer "B.Fab")
			(hide yes)
			(effects
				(font
					(size 1.016 1.016)
					(thickness 0.1524)
				)
				(justify mirror)
			)
		)
		(duplicate_pad_numbers_are_jumpers no)
		(fp_rect
			(start 0.4318 0.9525)
			(end -0.4318 -0.9525)
			(stroke
				(width 0)
				(type default)
			)
			(fill no)
			(layer "B.CrtYd")
		)
		(fp_rect
			(start 0.4318 0.9525)
			(end -0.4318 -0.9525)
			(stroke
				(width 0)
				(type default)
			)
			(fill no)
			(layer "B.Fab")
		)
		(pad "1" smd custom
			(at 0 -0.4445 270)
			(size 0.1524 0.1524)
			(layers "B.Cu" "B.Mask" "B.Paste")
			(net "P1V26_STBY")
			(options
				(clearance outline)
				(anchor circle)
			)
			(primitives
				(gr_poly
					(pts
						(arc
							(start 0.3048 0.2032)
							(mid 0.275042 0.275042)
							(end 0.2032 0.3048)
						)
						(arc
							(start -0.2032 0.3048)
							(mid -0.275042 0.275042)
							(end -0.3048 0.2032)
						)
						(arc
							(start -0.3048 -0.2032)
							(mid -0.275042 -0.275042)
							(end -0.2032 -0.3048)
						)
						(arc
							(start 0.2032 -0.3048)
							(mid 0.275042 -0.275042)
							(end 0.3048 -0.2032)
						)
					)
					(width 0)
					(fill yes)
				)
			)
		)
		(pad "2" smd custom
			(at 0 0.4445 270)
			(size 0.1524 0.1524)
			(layers "B.Cu" "B.Mask" "B.Paste")
			(net "GND")
			(options
				(clearance outline)
				(anchor circle)
			)
			(primitives
				(gr_poly
					(pts
						(arc
							(start 0.3048 0.2032)
							(mid 0.275042 0.275042)
							(end 0.2032 0.3048)
						)
						(arc
							(start -0.2032 0.3048)
							(mid -0.275042 0.275042)
							(end -0.3048 0.2032)
						)
						(arc
							(start -0.3048 -0.2032)
							(mid -0.275042 -0.275042)
							(end -0.2032 -0.3048)
						)
						(arc
							(start 0.2032 -0.3048)
							(mid 0.275042 -0.275042)
							(end 0.3048 -0.2032)
						)
					)
					(width 0)
					(fill yes)
				)
			)
		)
	)
	(footprint ""
		(layer "B.Cu")
		(at 117.545612 -204.978 180)
		(property "Reference" "SR888"
			(at 0 0 0)
			(layer "B.SilkS")
			(hide yes)
			(effects
				(font
					(size 1.27 1.27)
				)
				(justify mirror)
			)
		)
		(property "Value" "0R2J-2-GP"
			(at -0.064008 -3.993896 180)
			(unlocked yes)
			(layer "B.Fab")
			(hide yes)
			(effects
				(font
					(size 1.016 1.016)
					(thickness 0.1524)
				)
				(justify mirror)
			)
		)
		(property "Device Type" "R402H16"
			(at -0.064008 -5.517896 180)
			(unlocked yes)
			(layer "B.Fab")
			(hide yes)
			(effects
				(font
					(size 1.016 1.016)
					(thickness 0.1524)
				)
				(justify mirror)
			)
		)
		(duplicate_pad_numbers_are_jumpers no)
		(fp_line
			(start 0.508 -0.9398)
			(end 0.508 0.9398)
			(stroke
				(width 0.1524)
				(type default)
			)
			(layer "B.SilkS")
		)
		(fp_line
			(start -0.508 -0.9398)
			(end 0.508 -0.9398)
			(stroke
				(width 0.1524)
				(type default)
			)
			(layer "B.SilkS")
		)
		(fp_rect
			(start 0.508 0.9398)
			(end -0.508 -0.9398)
			(stroke
				(width 0)
				(type default)
			)
			(fill no)
			(layer "B.CrtYd")
		)
		(fp_rect
			(start 0.508 0.9398)
			(end -0.508 -0.9398)
			(stroke
				(width 0)
				(type default)
			)
			(fill no)
			(layer "B.Fab")
		)
		(pad "1" smd custom
			(at 0 -0.4445)
			(size 0.1397 0.1397)
			(layers "B.Cu" "B.Mask" "B.Paste")
			(net "REDV_RX7_P")
			(options
				(clearance outline)
				(anchor circle)
			)
			(primitives
				(gr_poly
					(pts
						(arc
							(start -0.1778 0.2794)
							(mid -0.249642 0.249642)
							(end -0.2794 0.1778)
						)
						(arc
							(start -0.2794 -0.1778)
							(mid -0.249642 -0.249642)
							(end -0.1778 -0.2794)
						)
						(arc
							(start 0.1778 -0.2794)
							(mid 0.249642 -0.249642)
							(end 0.2794 -0.1778)
						)
						(arc
							(start 0.2794 0.1778)
							(mid 0.249642 0.249642)
							(end 0.1778 0.2794)
						)
					)
					(width 0)
					(fill yes)
				)
			)
		)
		(pad "2" smd custom
			(at 0 0.4445)
			(size 0.1397 0.1397)
			(layers "B.Cu" "B.Mask" "B.Paste")
			(net "SAS_HDD_CONN_RX7_P")
			(options
				(clearance outline)
				(anchor circle)
			)
			(primitives
				(gr_poly
					(pts
						(arc
							(start -0.1778 0.2794)
							(mid -0.249642 0.249642)
							(end -0.2794 0.1778)
						)
						(arc
							(start -0.2794 -0.1778)
							(mid -0.249642 -0.249642)
							(end -0.1778 -0.2794)
						)
						(arc
							(start 0.1778 -0.2794)
							(mid 0.249642 -0.249642)
							(end 0.2794 -0.1778)
						)
						(arc
							(start 0.2794 0.1778)
							(mid 0.249642 0.249642)
							(end 0.1778 0.2794)
						)
					)
					(width 0)
					(fill yes)
				)
			)
		)
	)
	(footprint ""
		(layer "B.Cu")
		(at 309.118 -160.655 180)
		(property "Reference" "R261"
			(at 0 0 0)
			(layer "B.SilkS")
			(hide yes)
			(effects
				(font
					(size 1.27 1.27)
				)
				(justify mirror)
			)
		)
		(property "Value" "10KR2F-2-GP"
			(at -0.064008 -3.993896 180)
			(unlocked yes)
			(layer "B.Fab")
			(hide yes)
			(effects
				(font
					(size 1.016 1.016)
					(thickness 0.1524)
				)
				(justify mirror)
			)
		)
		(property "Device Type" "R402H16"
			(at -0.064008 -5.517896 180)
			(unlocked yes)
			(layer "B.Fab")
			(hide yes)
			(effects
				(font
					(size 1.016 1.016)
					(thickness 0.1524)
				)
				(justify mirror)
			)
		)
		(duplicate_pad_numbers_are_jumpers no)
		(fp_line
			(start 0.508 -0.9398)
			(end 0.508 0.9398)
			(stroke
				(width 0.1524)
				(type default)
			)
			(layer "B.SilkS")
		)
		(fp_line
			(start -0.508 -0.9398)
			(end 0.508 -0.9398)
			(stroke
				(width 0.1524)
				(type default)
			)
			(layer "B.SilkS")
		)
		(fp_rect
			(start 0.508 0.9398)
			(end -0.508 -0.9398)
			(stroke
				(width 0)
				(type default)
			)
			(fill no)
			(layer "B.CrtYd")
		)
		(fp_rect
			(start 0.508 0.9398)
			(end -0.508 -0.9398)
			(stroke
				(width 0)
				(type default)
			)
			(fill no)
			(layer "B.Fab")
		)
		(pad "1" smd custom
			(at 0 -0.4445)
			(size 0.1397 0.1397)
			(layers "B.Cu" "B.Mask" "B.Paste")
			(net "P3V3_STBY")
			(options
				(clearance outline)
				(anchor circle)
			)
			(primitives
				(gr_poly
					(pts
						(arc
							(start -0.1778 0.2794)
							(mid -0.249642 0.249642)
							(end -0.2794 0.1778)
						)
						(arc
							(start -0.2794 -0.1778)
							(mid -0.249642 -0.249642)
							(end -0.1778 -0.2794)
						)
						(arc
							(start 0.1778 -0.2794)
							(mid 0.249642 -0.249642)
							(end 0.2794 -0.1778)
						)
						(arc
							(start 0.2794 0.1778)
							(mid 0.249642 0.249642)
							(end 0.1778 0.2794)
						)
					)
					(width 0)
					(fill yes)
				)
			)
		)
		(pad "2" smd custom
			(at 0 0.4445)
			(size 0.1397 0.1397)
			(layers "B.Cu" "B.Mask" "B.Paste")
			(net "PU_BMC0_SDA11")
			(options
				(clearance outline)
				(anchor circle)
			)
			(primitives
				(gr_poly
					(pts
						(arc
							(start -0.1778 0.2794)
							(mid -0.249642 0.249642)
							(end -0.2794 0.1778)
						)
						(arc
							(start -0.2794 -0.1778)
							(mid -0.249642 -0.249642)
							(end -0.1778 -0.2794)
						)
						(arc
							(start 0.1778 -0.2794)
							(mid 0.249642 -0.249642)
							(end 0.2794 -0.1778)
						)
						(arc
							(start 0.2794 0.1778)
							(mid 0.249642 0.249642)
							(end 0.1778 0.2794)
						)
					)
					(width 0)
					(fill yes)
				)
			)
		)
	)
	(footprint ""
		(layer "B.Cu")
		(at 111.31677 -94.488 90)
		(property "Reference" "SC1259"
			(at 0 0 90)
			(layer "B.SilkS")
			(hide yes)
			(effects
				(font
					(size 1.27 1.27)
				)
				(justify mirror)
			)
		)
		(property "Value" "SCD1U6D3V1KX-GP"
			(at 2.8321 -1.7399 90)
			(unlocked yes)
			(layer "B.Fab")
			(hide yes)
			(effects
				(font
					(size 1.016 1.016)
					(thickness 0.1524)
				)
				(justify mirror)
			)
		)
		(property "Device Type" "C0201H13"
			(at 2.8321 -3.2639 90)
			(unlocked yes)
			(layer "B.Fab")
			(hide yes)
			(effects
				(font
					(size 1.016 1.016)
					(thickness 0.1524)
				)
				(justify mirror)
			)
		)
		(duplicate_pad_numbers_are_jumpers no)
		(fp_rect
			(start 0.2794 0.6477)
			(end -0.2794 -0.6477)
			(stroke
				(width 0)
				(type default)
			)
			(fill no)
			(layer "B.CrtYd")
		)
		(fp_rect
			(start 0.2794 0.6477)
			(end -0.2794 -0.6477)
			(stroke
				(width 0)
				(type default)
			)
			(fill no)
			(layer "B.Fab")
		)
		(pad "1" smd custom
			(at 0 -0.2794 270)
			(size 0.0762 0.0762)
			(layers "B.Cu" "B.Mask" "B.Paste")
			(net "P0V9_E")
			(options
				(clearance outline)
				(anchor circle)
			)
			(primitives
				(gr_poly
					(pts
						(arc
							(start 0.1524 0.127)
							(mid 0.137521 0.162921)
							(end 0.1016 0.1778)
						)
						(arc
							(start -0.1016 0.1778)
							(mid -0.137521 0.162921)
							(end -0.1524 0.127)
						)
						(arc
							(start -0.1524 -0.127)
							(mid -0.137521 -0.162921)
							(end -0.1016 -0.1778)
						)
						(arc
							(start 0.1016 -0.1778)
							(mid 0.137521 -0.162921)
							(end 0.1524 -0.127)
						)
					)
					(width 0)
					(fill yes)
				)
			)
		)
		(pad "2" smd custom
			(at 0 0.2794 270)
			(size 0.0762 0.0762)
			(layers "B.Cu" "B.Mask" "B.Paste")
			(net "GND")
			(options
				(clearance outline)
				(anchor circle)
			)
			(primitives
				(gr_poly
					(pts
						(arc
							(start 0.1524 0.127)
							(mid 0.137521 0.162921)
							(end 0.1016 0.1778)
						)
						(arc
							(start -0.1016 0.1778)
							(mid -0.137521 0.162921)
							(end -0.1524 0.127)
						)
						(arc
							(start -0.1524 -0.127)
							(mid -0.137521 -0.162921)
							(end -0.1016 -0.1778)
						)
						(arc
							(start 0.1016 -0.1778)
							(mid 0.137521 -0.162921)
							(end 0.1524 -0.127)
						)
					)
					(width 0)
					(fill yes)
				)
			)
		)
	)
	(footprint ""
		(layer "B.Cu")
		(at 11.169904 -100.400866)
		(property "Reference" "C129"
			(at 0 0 0)
			(layer "B.SilkS")
			(hide yes)
			(effects
				(font
					(size 1.27 1.27)
				)
				(justify mirror)
			)
		)
		(property "Value" "SCD01U50V2KX-1GP"
			(at -1.1811 -2.7051 0)
			(unlocked yes)
			(layer "B.Fab")
			(hide yes)
			(effects
				(font
					(size 1.016 1.016)
					(thickness 0.1524)
				)
				(justify mirror)
			)
		)
		(property "Device Type" "C402H22"
			(at -1.1811 -4.2291 0)
			(unlocked yes)
			(layer "B.Fab")
			(hide yes)
			(effects
				(font
					(size 1.016 1.016)
					(thickness 0.1524)
				)
				(justify mirror)
			)
		)
		(duplicate_pad_numbers_are_jumpers no)
		(fp_rect
			(start 0.4318 0.9525)
			(end -0.4318 -0.9525)
			(stroke
				(width 0)
				(type default)
			)
			(fill no)
			(layer "B.CrtYd")
		)
		(fp_rect
			(start 0.4318 0.9525)
			(end -0.4318 -0.9525)
			(stroke
				(width 0)
				(type default)
			)
			(fill no)
			(layer "B.Fab")
		)
		(pad "1" smd custom
			(at 0 -0.4445 180)
			(size 0.1524 0.1524)
			(layers "B.Cu" "B.Mask" "B.Paste")
			(net "IOC_SAS_RX_P4")
			(options
				(clearance outline)
				(anchor circle)
			)
			(primitives
				(gr_poly
					(pts
						(arc
							(start 0.3048 0.2032)
							(mid 0.275042 0.275042)
							(end 0.2032 0.3048)
						)
						(arc
							(start -0.2032 0.3048)
							(mid -0.275042 0.275042)
							(end -0.3048 0.2032)
						)
						(arc
							(start -0.3048 -0.2032)
							(mid -0.275042 -0.275042)
							(end -0.2032 -0.3048)
						)
						(arc
							(start 0.2032 -0.3048)
							(mid 0.275042 -0.275042)
							(end 0.3048 -0.2032)
						)
					)
					(width 0)
					(fill yes)
				)
			)
		)
		(pad "2" smd custom
			(at 0 0.4445 180)
			(size 0.1524 0.1524)
			(layers "B.Cu" "B.Mask" "B.Paste")
			(net "SAS_EXT_CONN_RX16_P")
			(options
				(clearance outline)
				(anchor circle)
			)
			(primitives
				(gr_poly
					(pts
						(arc
							(start 0.3048 0.2032)
							(mid 0.275042 0.275042)
							(end 0.2032 0.3048)
						)
						(arc
							(start -0.2032 0.3048)
							(mid -0.275042 0.275042)
							(end -0.3048 0.2032)
						)
						(arc
							(start -0.3048 -0.2032)
							(mid -0.275042 -0.275042)
							(end -0.2032 -0.3048)
						)
						(arc
							(start 0.2032 -0.3048)
							(mid 0.275042 -0.275042)
							(end 0.3048 -0.2032)
						)
					)
					(width 0)
					(fill yes)
				)
			)
		)
	)
	(footprint ""
		(layer "B.Cu")
		(at 102.997 -229.997 -90)
		(property "Reference" "R594"
			(at 0 0 90)
			(layer "B.SilkS")
			(hide yes)
			(effects
				(font
					(size 1.27 1.27)
				)
				(justify mirror)
			)
		)
		(property "Value" "0R2J-2-GP"
			(at -0.064008 -3.993896 270)
			(unlocked yes)
			(layer "B.Fab")
			(hide yes)
			(effects
				(font
					(size 1.016 1.016)
					(thickness 0.1524)
				)
				(justify mirror)
			)
		)
		(property "Device Type" "R402H16"
			(at -0.064008 -5.517896 270)
			(unlocked yes)
			(layer "B.Fab")
			(hide yes)
			(effects
				(font
					(size 1.016 1.016)
					(thickness 0.1524)
				)
				(justify mirror)
			)
		)
		(duplicate_pad_numbers_are_jumpers no)
		(fp_line
			(start -0.508 -0.9398)
			(end 0.508 -0.9398)
			(stroke
				(width 0.1524)
				(type default)
			)
			(layer "B.SilkS")
		)
		(fp_line
			(start 0.508 -0.9398)
			(end 0.508 0.9398)
			(stroke
				(width 0.1524)
				(type default)
			)
			(layer "B.SilkS")
		)
		(fp_rect
			(start 0.508 0.9398)
			(end -0.508 -0.9398)
			(stroke
				(width 0)
				(type default)
			)
			(fill no)
			(layer "B.CrtYd")
		)
		(fp_rect
			(start 0.508 0.9398)
			(end -0.508 -0.9398)
			(stroke
				(width 0)
				(type default)
			)
			(fill no)
			(layer "B.Fab")
		)
		(pad "1" smd custom
			(at 0 -0.4445 90)
			(size 0.1397 0.1397)
			(layers "B.Cu" "B.Mask" "B.Paste")
			(net "SAS_FAULT_LED4")
			(options
				(clearance outline)
				(anchor circle)
			)
			(primitives
				(gr_poly
					(pts
						(arc
							(start -0.1778 0.2794)
							(mid -0.249642 0.249642)
							(end -0.2794 0.1778)
						)
						(arc
							(start -0.2794 -0.1778)
							(mid -0.249642 -0.249642)
							(end -0.1778 -0.2794)
						)
						(arc
							(start 0.1778 -0.2794)
							(mid 0.249642 -0.249642)
							(end 0.2794 -0.1778)
						)
						(arc
							(start 0.2794 0.1778)
							(mid 0.249642 0.249642)
							(end 0.1778 0.2794)
						)
					)
					(width 0)
					(fill yes)
				)
			)
		)
		(pad "2" smd custom
			(at 0 0.4445 90)
			(size 0.1397 0.1397)
			(layers "B.Cu" "B.Mask" "B.Paste")
			(net "SAS_HDD_LED_4")
			(options
				(clearance outline)
				(anchor circle)
			)
			(primitives
				(gr_poly
					(pts
						(arc
							(start -0.1778 0.2794)
							(mid -0.249642 0.249642)
							(end -0.2794 0.1778)
						)
						(arc
							(start -0.2794 -0.1778)
							(mid -0.249642 -0.249642)
							(end -0.1778 -0.2794)
						)
						(arc
							(start 0.1778 -0.2794)
							(mid 0.249642 -0.249642)
							(end 0.2794 -0.1778)
						)
						(arc
							(start 0.2794 0.1778)
							(mid 0.249642 0.249642)
							(end 0.1778 0.2794)
						)
					)
					(width 0)
					(fill yes)
				)
			)
		)
	)
	(footprint ""
		(layer "B.Cu")
		(at 93.136212 -251.587)
		(property "Reference" "TP78"
			(at 0 0 0)
			(layer "B.SilkS")
			(hide yes)
			(effects
				(font
					(size 1.27 1.27)
				)
				(justify mirror)
			)
		)
		(property "Value" "TPAD28"
			(at -0.0127 -1.8034 0)
			(unlocked yes)
			(layer "B.Fab")
			(hide yes)
			(effects
				(font
					(size 1.016 1.016)
					(thickness 0.1524)
				)
				(justify mirror)
			)
		)
		(property "Device Type" "TPAD28"
			(at -0.0127 -3.3274 0)
			(unlocked yes)
			(layer "B.Fab")
			(hide yes)
			(effects
				(font
					(size 1.016 1.016)
					(thickness 0.1524)
				)
				(justify mirror)
			)
		)
		(duplicate_pad_numbers_are_jumpers no)
		(fp_poly
			(pts
				(arc
					(start 0.3556 0)
					(mid -0.3556 0)
					(end 0.3556 0)
				)
			)
			(stroke
				(width 0)
				(type default)
			)
			(fill no)
			(layer "B.CrtYd")
		)
		(fp_poly
			(pts
				(arc
					(start 0.6096 0)
					(mid -0.6096 0)
					(end 0.6096 0)
				)
			)
			(stroke
				(width 0)
				(type default)
			)
			(fill no)
			(layer "B.Fab")
		)
		(pad "1" smd circle
			(at 0 0 180)
			(size 0.7112 0.7112)
			(layers "B.Cu" "B.Mask" "B.Paste")
			(net "SAS_I2C_D_BUF_SCL_R")
		)
	)
	(footprint ""
		(layer "B.Cu")
		(at 348.5642 -71.8058)
		(property "Reference" "R346"
			(at 0 0 0)
			(layer "B.SilkS")
			(hide yes)
			(effects
				(font
					(size 1.27 1.27)
				)
				(justify mirror)
			)
		)
		(property "Value" "3K3R2F-2-GP"
			(at -0.064008 -3.993896 0)
			(unlocked yes)
			(layer "B.Fab")
			(hide yes)
			(effects
				(font
					(size 1.016 1.016)
					(thickness 0.1524)
				)
				(justify mirror)
			)
		)
		(property "Device Type" "R402H16"
			(at -0.064008 -5.517896 0)
			(unlocked yes)
			(layer "B.Fab")
			(hide yes)
			(effects
				(font
					(size 1.016 1.016)
					(thickness 0.1524)
				)
				(justify mirror)
			)
		)
		(duplicate_pad_numbers_are_jumpers no)
		(fp_line
			(start -0.508 -0.9398)
			(end 0.508 -0.9398)
			(stroke
				(width 0.1524)
				(type default)
			)
			(layer "B.SilkS")
		)
		(fp_line
			(start 0.508 -0.9398)
			(end 0.508 0.9398)
			(stroke
				(width 0.1524)
				(type default)
			)
			(layer "B.SilkS")
		)
		(fp_rect
			(start 0.508 0.9398)
			(end -0.508 -0.9398)
			(stroke
				(width 0)
				(type default)
			)
			(fill no)
			(layer "B.CrtYd")
		)
		(fp_rect
			(start 0.508 0.9398)
			(end -0.508 -0.9398)
			(stroke
				(width 0)
				(type default)
			)
			(fill no)
			(layer "B.Fab")
		)
		(pad "1" smd custom
			(at 0 -0.4445 180)
			(size 0.1397 0.1397)
			(layers "B.Cu" "B.Mask" "B.Paste")
			(net "P3V3_STBY")
			(options
				(clearance outline)
				(anchor circle)
			)
			(primitives
				(gr_poly
					(pts
						(arc
							(start -0.1778 0.2794)
							(mid -0.249642 0.249642)
							(end -0.2794 0.1778)
						)
						(arc
							(start -0.2794 -0.1778)
							(mid -0.249642 -0.249642)
							(end -0.1778 -0.2794)
						)
						(arc
							(start 0.1778 -0.2794)
							(mid 0.249642 -0.249642)
							(end 0.2794 -0.1778)
						)
						(arc
							(start 0.2794 0.1778)
							(mid 0.249642 0.249642)
							(end 0.1778 0.2794)
						)
					)
					(width 0)
					(fill yes)
				)
			)
		)
		(pad "2" smd custom
			(at 0 0.4445 180)
			(size 0.1397 0.1397)
			(layers "B.Cu" "B.Mask" "B.Paste")
			(net "ROMD1_R")
			(options
				(clearance outline)
				(anchor circle)
			)
			(primitives
				(gr_poly
					(pts
						(arc
							(start -0.1778 0.2794)
							(mid -0.249642 0.249642)
							(end -0.2794 0.1778)
						)
						(arc
							(start -0.2794 -0.1778)
							(mid -0.249642 -0.249642)
							(end -0.1778 -0.2794)
						)
						(arc
							(start 0.1778 -0.2794)
							(mid 0.249642 -0.249642)
							(end 0.2794 -0.1778)
						)
						(arc
							(start 0.2794 0.1778)
							(mid 0.249642 0.249642)
							(end 0.1778 0.2794)
						)
					)
					(width 0)
					(fill yes)
				)
			)
		)
	)
	(footprint ""
		(layer "B.Cu")
		(at 295.5798 -181.4576)
		(property "Reference" "TP191"
			(at 0 0 0)
			(layer "B.SilkS")
			(hide yes)
			(effects
				(font
					(size 1.27 1.27)
				)
				(justify mirror)
			)
		)
		(property "Value" "TPAD28"
			(at 0.0127 -1.6637 0)
			(unlocked yes)
			(layer "B.Fab")
			(hide yes)
			(effects
				(font
					(size 1.016 1.016)
					(thickness 0.1524)
				)
				(justify mirror)
			)
		)
		(property "Device Type" "TPAD28"
			(at 0.0127 -3.1877 0)
			(unlocked yes)
			(layer "B.Fab")
			(hide yes)
			(effects
				(font
					(size 1.016 1.016)
					(thickness 0.1524)
				)
				(justify mirror)
			)
		)
		(duplicate_pad_numbers_are_jumpers no)
		(fp_poly
			(pts
				(arc
					(start 0.3556 0)
					(mid -0.3556 0)
					(end 0.3556 0)
				)
			)
			(stroke
				(width 0)
				(type default)
			)
			(fill no)
			(layer "B.CrtYd")
		)
		(fp_poly
			(pts
				(arc
					(start 0.6096 0)
					(mid -0.6096 0)
					(end 0.6096 0)
				)
			)
			(stroke
				(width 0)
				(type default)
			)
			(fill no)
			(layer "B.Fab")
		)
		(pad "1" smd circle
			(at 0 0 180)
			(size 0.7112 0.7112)
			(layers "B.Cu" "B.Mask" "B.Paste")
			(net "TP_BMC_GPIOO7")
		)
	)
	(footprint ""
		(layer "B.Cu")
		(at 108.020612 -204.978 180)
		(property "Reference" "SR899"
			(at 0 0 0)
			(layer "B.SilkS")
			(hide yes)
			(effects
				(font
					(size 1.27 1.27)
				)
				(justify mirror)
			)
		)
		(property "Value" "0R2J-2-GP"
			(at -0.064008 -3.993896 180)
			(unlocked yes)
			(layer "B.Fab")
			(hide yes)
			(effects
				(font
					(size 1.016 1.016)
					(thickness 0.1524)
				)
				(justify mirror)
			)
		)
		(property "Device Type" "R402H16"
			(at -0.064008 -5.517896 180)
			(unlocked yes)
			(layer "B.Fab")
			(hide yes)
			(effects
				(font
					(size 1.016 1.016)
					(thickness 0.1524)
				)
				(justify mirror)
			)
		)
		(duplicate_pad_numbers_are_jumpers no)
		(fp_line
			(start 0.508 -0.9398)
			(end 0.508 0.9398)
			(stroke
				(width 0.1524)
				(type default)
			)
			(layer "B.SilkS")
		)
		(fp_line
			(start -0.508 -0.9398)
			(end 0.508 -0.9398)
			(stroke
				(width 0.1524)
				(type default)
			)
			(layer "B.SilkS")
		)
		(fp_rect
			(start 0.508 0.9398)
			(end -0.508 -0.9398)
			(stroke
				(width 0)
				(type default)
			)
			(fill no)
			(layer "B.CrtYd")
		)
		(fp_rect
			(start 0.508 0.9398)
			(end -0.508 -0.9398)
			(stroke
				(width 0)
				(type default)
			)
			(fill no)
			(layer "B.Fab")
		)
		(pad "1" smd custom
			(at 0 -0.4445)
			(size 0.1397 0.1397)
			(layers "B.Cu" "B.Mask" "B.Paste")
			(net "REDV_RX8_N")
			(options
				(clearance outline)
				(anchor circle)
			)
			(primitives
				(gr_poly
					(pts
						(arc
							(start -0.1778 0.2794)
							(mid -0.249642 0.249642)
							(end -0.2794 0.1778)
						)
						(arc
							(start -0.2794 -0.1778)
							(mid -0.249642 -0.249642)
							(end -0.1778 -0.2794)
						)
						(arc
							(start 0.1778 -0.2794)
							(mid 0.249642 -0.249642)
							(end 0.2794 -0.1778)
						)
						(arc
							(start 0.2794 0.1778)
							(mid 0.249642 0.249642)
							(end 0.1778 0.2794)
						)
					)
					(width 0)
					(fill yes)
				)
			)
		)
		(pad "2" smd custom
			(at 0 0.4445)
			(size 0.1397 0.1397)
			(layers "B.Cu" "B.Mask" "B.Paste")
			(net "SAS_HDD_CONN_RX8_N")
			(options
				(clearance outline)
				(anchor circle)
			)
			(primitives
				(gr_poly
					(pts
						(arc
							(start -0.1778 0.2794)
							(mid -0.249642 0.249642)
							(end -0.2794 0.1778)
						)
						(arc
							(start -0.2794 -0.1778)
							(mid -0.249642 -0.249642)
							(end -0.1778 -0.2794)
						)
						(arc
							(start 0.1778 -0.2794)
							(mid 0.249642 -0.249642)
							(end 0.2794 -0.1778)
						)
						(arc
							(start 0.2794 0.1778)
							(mid 0.249642 0.249642)
							(end 0.1778 0.2794)
						)
					)
					(width 0)
					(fill yes)
				)
			)
		)
	)
	(footprint ""
		(layer "B.Cu")
		(at 144.399 -45.847)
		(property "Reference" "STP118"
			(at 0 0 0)
			(layer "B.SilkS")
			(hide yes)
			(effects
				(font
					(size 1.27 1.27)
				)
				(justify mirror)
			)
		)
		(property "Value" "TPAD28"
			(at -0.0127 -1.8034 0)
			(unlocked yes)
			(layer "B.Fab")
			(hide yes)
			(effects
				(font
					(size 1.016 1.016)
					(thickness 0.1524)
				)
				(justify mirror)
			)
		)
		(property "Device Type" "TPAD28"
			(at -0.0127 -3.3274 0)
			(unlocked yes)
			(layer "B.Fab")
			(hide yes)
			(effects
				(font
					(size 1.016 1.016)
					(thickness 0.1524)
				)
				(justify mirror)
			)
		)
		(duplicate_pad_numbers_are_jumpers no)
		(fp_poly
			(pts
				(arc
					(start 0.3556 0)
					(mid -0.3556 0)
					(end 0.3556 0)
				)
			)
			(stroke
				(width 0)
				(type default)
			)
			(fill no)
			(layer "B.CrtYd")
		)
		(fp_poly
			(pts
				(arc
					(start 0.6096 0)
					(mid -0.6096 0)
					(end 0.6096 0)
				)
			)
			(stroke
				(width 0)
				(type default)
			)
			(fill no)
			(layer "B.Fab")
		)
		(pad "1" smd circle
			(at 0 0 180)
			(size 0.7112 0.7112)
			(layers "B.Cu" "B.Mask" "B.Paste")
			(net "XM_ADDR_18")
		)
	)
	(footprint ""
		(layer "B.Cu")
		(at 114.281966 -45.72 -90)
		(property "Reference" "SR625"
			(at 0 0 90)
			(layer "B.SilkS")
			(hide yes)
			(effects
				(font
					(size 1.27 1.27)
				)
				(justify mirror)
			)
		)
		(property "Value" "2K2R2F-GP"
			(at -0.064008 -3.993896 270)
			(unlocked yes)
			(layer "B.Fab")
			(hide yes)
			(effects
				(font
					(size 1.016 1.016)
					(thickness 0.1524)
				)
				(justify mirror)
			)
		)
		(property "Device Type" "R402H16"
			(at -0.064008 -5.517896 270)
			(unlocked yes)
			(layer "B.Fab")
			(hide yes)
			(effects
				(font
					(size 1.016 1.016)
					(thickness 0.1524)
				)
				(justify mirror)
			)
		)
		(duplicate_pad_numbers_are_jumpers no)
		(fp_line
			(start -0.508 -0.9398)
			(end 0.508 -0.9398)
			(stroke
				(width 0.1524)
				(type default)
			)
			(layer "B.SilkS")
		)
		(fp_line
			(start 0.508 -0.9398)
			(end 0.508 0.9398)
			(stroke
				(width 0.1524)
				(type default)
			)
			(layer "B.SilkS")
		)
		(fp_rect
			(start 0.508 0.9398)
			(end -0.508 -0.9398)
			(stroke
				(width 0)
				(type default)
			)
			(fill no)
			(layer "B.CrtYd")
		)
		(fp_rect
			(start 0.508 0.9398)
			(end -0.508 -0.9398)
			(stroke
				(width 0)
				(type default)
			)
			(fill no)
			(layer "B.Fab")
		)
		(pad "1" smd custom
			(at 0 -0.4445 90)
			(size 0.1397 0.1397)
			(layers "B.Cu" "B.Mask" "B.Paste")
			(net "P1V8_C")
			(options
				(clearance outline)
				(anchor circle)
			)
			(primitives
				(gr_poly
					(pts
						(arc
							(start -0.1778 0.2794)
							(mid -0.249642 0.249642)
							(end -0.2794 0.1778)
						)
						(arc
							(start -0.2794 -0.1778)
							(mid -0.249642 -0.249642)
							(end -0.1778 -0.2794)
						)
						(arc
							(start 0.1778 -0.2794)
							(mid 0.249642 -0.249642)
							(end 0.2794 -0.1778)
						)
						(arc
							(start 0.2794 0.1778)
							(mid 0.249642 0.249642)
							(end 0.1778 0.2794)
						)
					)
					(width 0)
					(fill yes)
				)
			)
		)
		(pad "2" smd custom
			(at 0 0.4445 90)
			(size 0.1397 0.1397)
			(layers "B.Cu" "B.Mask" "B.Paste")
			(net "IOC_SDA_4")
			(options
				(clearance outline)
				(anchor circle)
			)
			(primitives
				(gr_poly
					(pts
						(arc
							(start -0.1778 0.2794)
							(mid -0.249642 0.249642)
							(end -0.2794 0.1778)
						)
						(arc
							(start -0.2794 -0.1778)
							(mid -0.249642 -0.249642)
							(end -0.1778 -0.2794)
						)
						(arc
							(start 0.1778 -0.2794)
							(mid 0.249642 -0.249642)
							(end 0.2794 -0.1778)
						)
						(arc
							(start 0.2794 0.1778)
							(mid 0.249642 0.249642)
							(end 0.1778 0.2794)
						)
					)
					(width 0)
					(fill yes)
				)
			)
		)
	)
	(footprint ""
		(layer "B.Cu")
		(at 32.462216 -232.33888)
		(property "Reference" "R509"
			(at 0 0 0)
			(layer "B.SilkS")
			(hide yes)
			(effects
				(font
					(size 1.27 1.27)
				)
				(justify mirror)
			)
		)
		(property "Value" "0R2J-2-GP"
			(at -0.064008 -3.993896 0)
			(unlocked yes)
			(layer "B.Fab")
			(hide yes)
			(effects
				(font
					(size 1.016 1.016)
					(thickness 0.1524)
				)
				(justify mirror)
			)
		)
		(property "Device Type" "R402H16"
			(at -0.064008 -5.517896 0)
			(unlocked yes)
			(layer "B.Fab")
			(hide yes)
			(effects
				(font
					(size 1.016 1.016)
					(thickness 0.1524)
				)
				(justify mirror)
			)
		)
		(duplicate_pad_numbers_are_jumpers no)
		(fp_line
			(start -0.508 -0.9398)
			(end 0.508 -0.9398)
			(stroke
				(width 0.1524)
				(type default)
			)
			(layer "B.SilkS")
		)
		(fp_line
			(start 0.508 -0.9398)
			(end 0.508 0.9398)
			(stroke
				(width 0.1524)
				(type default)
			)
			(layer "B.SilkS")
		)
		(fp_rect
			(start 0.508 0.9398)
			(end -0.508 -0.9398)
			(stroke
				(width 0)
				(type default)
			)
			(fill no)
			(layer "B.CrtYd")
		)
		(fp_rect
			(start 0.508 0.9398)
			(end -0.508 -0.9398)
			(stroke
				(width 0)
				(type default)
			)
			(fill no)
			(layer "B.Fab")
		)
		(pad "1" smd custom
			(at 0 -0.4445 180)
			(size 0.1397 0.1397)
			(layers "B.Cu" "B.Mask" "B.Paste")
			(net "SAS_HDD_PWR7_PCIE")
			(options
				(clearance outline)
				(anchor circle)
			)
			(primitives
				(gr_poly
					(pts
						(arc
							(start -0.1778 0.2794)
							(mid -0.249642 0.249642)
							(end -0.2794 0.1778)
						)
						(arc
							(start -0.2794 -0.1778)
							(mid -0.249642 -0.249642)
							(end -0.1778 -0.2794)
						)
						(arc
							(start 0.1778 -0.2794)
							(mid 0.249642 -0.249642)
							(end 0.2794 -0.1778)
						)
						(arc
							(start 0.2794 0.1778)
							(mid 0.249642 0.249642)
							(end 0.1778 0.2794)
						)
					)
					(width 0)
					(fill yes)
				)
			)
		)
		(pad "2" smd custom
			(at 0 0.4445 180)
			(size 0.1397 0.1397)
			(layers "B.Cu" "B.Mask" "B.Paste")
			(net "SAS_HDD_PWR7")
			(options
				(clearance outline)
				(anchor circle)
			)
			(primitives
				(gr_poly
					(pts
						(arc
							(start -0.1778 0.2794)
							(mid -0.249642 0.249642)
							(end -0.2794 0.1778)
						)
						(arc
							(start -0.2794 -0.1778)
							(mid -0.249642 -0.249642)
							(end -0.1778 -0.2794)
						)
						(arc
							(start 0.1778 -0.2794)
							(mid 0.249642 -0.249642)
							(end 0.2794 -0.1778)
						)
						(arc
							(start 0.2794 0.1778)
							(mid 0.249642 0.249642)
							(end 0.1778 0.2794)
						)
					)
					(width 0)
					(fill yes)
				)
			)
		)
	)
	(footprint ""
		(layer "B.Cu")
		(at 116.186966 -29.972 90)
		(property "Reference" "SC972"
			(at 0 0 90)
			(layer "B.SilkS")
			(hide yes)
			(effects
				(font
					(size 1.27 1.27)
				)
				(justify mirror)
			)
		)
		(property "Value" "SC1U10V2KX-4-GP"
			(at -1.1811 -2.7051 90)
			(unlocked yes)
			(layer "B.Fab")
			(hide yes)
			(effects
				(font
					(size 1.016 1.016)
					(thickness 0.1524)
				)
				(justify mirror)
			)
		)
		(property "Device Type" "C402H22"
			(at -1.1811 -4.2291 90)
			(unlocked yes)
			(layer "B.Fab")
			(hide yes)
			(effects
				(font
					(size 1.016 1.016)
					(thickness 0.1524)
				)
				(justify mirror)
			)
		)
		(duplicate_pad_numbers_are_jumpers no)
		(fp_rect
			(start 0.4318 0.9525)
			(end -0.4318 -0.9525)
			(stroke
				(width 0)
				(type default)
			)
			(fill no)
			(layer "B.CrtYd")
		)
		(fp_rect
			(start 0.4318 0.9525)
			(end -0.4318 -0.9525)
			(stroke
				(width 0)
				(type default)
			)
			(fill no)
			(layer "B.Fab")
		)
		(pad "1" smd custom
			(at 0 -0.4445 270)
			(size 0.1524 0.1524)
			(layers "B.Cu" "B.Mask" "B.Paste")
			(net "P1V8_C")
			(options
				(clearance outline)
				(anchor circle)
			)
			(primitives
				(gr_poly
					(pts
						(arc
							(start 0.3048 0.2032)
							(mid 0.275042 0.275042)
							(end 0.2032 0.3048)
						)
						(arc
							(start -0.2032 0.3048)
							(mid -0.275042 0.275042)
							(end -0.3048 0.2032)
						)
						(arc
							(start -0.3048 -0.2032)
							(mid -0.275042 -0.275042)
							(end -0.2032 -0.3048)
						)
						(arc
							(start 0.2032 -0.3048)
							(mid 0.275042 -0.275042)
							(end 0.3048 -0.2032)
						)
					)
					(width 0)
					(fill yes)
				)
			)
		)
		(pad "2" smd custom
			(at 0 0.4445 270)
			(size 0.1524 0.1524)
			(layers "B.Cu" "B.Mask" "B.Paste")
			(net "GND")
			(options
				(clearance outline)
				(anchor circle)
			)
			(primitives
				(gr_poly
					(pts
						(arc
							(start 0.3048 0.2032)
							(mid 0.275042 0.275042)
							(end 0.2032 0.3048)
						)
						(arc
							(start -0.2032 0.3048)
							(mid -0.275042 0.275042)
							(end -0.3048 0.2032)
						)
						(arc
							(start -0.3048 -0.2032)
							(mid -0.275042 -0.275042)
							(end -0.2032 -0.3048)
						)
						(arc
							(start 0.2032 -0.3048)
							(mid 0.275042 -0.275042)
							(end 0.3048 -0.2032)
						)
					)
					(width 0)
					(fill yes)
				)
			)
		)
	)
	(footprint ""
		(layer "B.Cu")
		(at 188.949584 -89.799922)
		(property "Reference" ""
			(at 0 0 0)
			(layer "B.SilkS")
			(hide yes)
			(effects
				(font
					(size 1.27 1.27)
				)
				(justify mirror)
			)
		)
		(property "Value" "*"
			(at 5.5753 -0.4572 0)
			(unlocked yes)
			(layer "B.Fab")
			(hide yes)
			(effects
				(font
					(size 1.016 1.016)
					(thickness 0.1524)
				)
				(justify mirror)
			)
		)
		(duplicate_pad_numbers_are_jumpers no)
		(fp_poly
			(pts
				(arc
					(start 4.3053 0)
					(mid -4.3053 0)
					(end 4.3053 0)
				)
			)
			(stroke
				(width 0)
				(type default)
			)
			(fill no)
			(layer "B.CrtYd")
		)
		(fp_poly
			(pts
				(arc
					(start 4.3053 0)
					(mid -4.3053 0)
					(end 4.3053 0)
				)
			)
			(stroke
				(width 0)
				(type default)
			)
			(fill no)
			(layer "B.Fab")
		)
		(pad "1" smd custom
			(at 2.95275 0 180)
			(size 2.000013 2.000013)
			(layers "B.Cu" "B.Mask" "B.Paste")
			(net "Net_50")
			(options
				(clearance outline)
				(anchor circle)
			)
			(primitives
				(gr_poly
					(pts
						(arc
							(start 4.0005 -0.00254)
							(mid -4.000501 0)
							(end 4.0005 0.00254)
						)
						(arc
							(start 1.905 0.00254)
							(mid -1.905002 0)
							(end 1.905 -0.00254)
						)
					)
					(width 0)
					(fill yes)
				)
			)
		)
	)
	(footprint ""
		(layer "B.Cu")
		(at 98.56216 -31.623)
		(property "Reference" "SC868"
			(at 0 0 0)
			(layer "B.SilkS")
			(hide yes)
			(effects
				(font
					(size 1.27 1.27)
				)
				(justify mirror)
			)
		)
		(property "Value" "SCD22U6D3V1MX-1-GP"
			(at 2.8321 -1.7399 0)
			(unlocked yes)
			(layer "B.Fab")
			(hide yes)
			(effects
				(font
					(size 1.016 1.016)
					(thickness 0.1524)
				)
				(justify mirror)
			)
		)
		(property "Device Type" "C0201H13"
			(at 2.8321 -3.2639 0)
			(unlocked yes)
			(layer "B.Fab")
			(hide yes)
			(effects
				(font
					(size 1.016 1.016)
					(thickness 0.1524)
				)
				(justify mirror)
			)
		)
		(duplicate_pad_numbers_are_jumpers no)
		(fp_rect
			(start 0.2794 0.6477)
			(end -0.2794 -0.6477)
			(stroke
				(width 0)
				(type default)
			)
			(fill no)
			(layer "B.CrtYd")
		)
		(fp_rect
			(start 0.2794 0.6477)
			(end -0.2794 -0.6477)
			(stroke
				(width 0)
				(type default)
			)
			(fill no)
			(layer "B.Fab")
		)
		(pad "1" smd custom
			(at 0 -0.2794 180)
			(size 0.0762 0.0762)
			(layers "B.Cu" "B.Mask" "B.Paste")
			(net "PCIE_SAS_C_CPU_RX_N3")
			(options
				(clearance outline)
				(anchor circle)
			)
			(primitives
				(gr_poly
					(pts
						(arc
							(start 0.1524 0.127)
							(mid 0.137521 0.162921)
							(end 0.1016 0.1778)
						)
						(arc
							(start -0.1016 0.1778)
							(mid -0.137521 0.162921)
							(end -0.1524 0.127)
						)
						(arc
							(start -0.1524 -0.127)
							(mid -0.137521 -0.162921)
							(end -0.1016 -0.1778)
						)
						(arc
							(start 0.1016 -0.1778)
							(mid 0.137521 -0.162921)
							(end 0.1524 -0.127)
						)
					)
					(width 0)
					(fill yes)
				)
			)
		)
		(pad "2" smd custom
			(at 0 0.2794 180)
			(size 0.0762 0.0762)
			(layers "B.Cu" "B.Mask" "B.Paste")
			(net "PCIE_SAS_CPU_RX_N3")
			(options
				(clearance outline)
				(anchor circle)
			)
			(primitives
				(gr_poly
					(pts
						(arc
							(start 0.1524 0.127)
							(mid 0.137521 0.162921)
							(end 0.1016 0.1778)
						)
						(arc
							(start -0.1016 0.1778)
							(mid -0.137521 0.162921)
							(end -0.1524 0.127)
						)
						(arc
							(start -0.1524 -0.127)
							(mid -0.137521 -0.162921)
							(end -0.1016 -0.1778)
						)
						(arc
							(start 0.1016 -0.1778)
							(mid 0.137521 -0.162921)
							(end 0.1524 -0.127)
						)
					)
					(width 0)
					(fill yes)
				)
			)
		)
	)
	(footprint ""
		(layer "B.Cu")
		(at 172.3136 -101.7524 180)
		(property "Reference" "PC186"
			(at 0 0 0)
			(layer "B.SilkS")
			(hide yes)
			(effects
				(font
					(size 1.27 1.27)
				)
				(justify mirror)
			)
		)
		(property "Value" "SCD1U16V2KX-3GP"
			(at -1.1811 -2.7051 180)
			(unlocked yes)
			(layer "B.Fab")
			(hide yes)
			(effects
				(font
					(size 1.016 1.016)
					(thickness 0.1524)
				)
				(justify mirror)
			)
		)
		(property "Device Type" "C402H22"
			(at -1.1811 -4.2291 180)
			(unlocked yes)
			(layer "B.Fab")
			(hide yes)
			(effects
				(font
					(size 1.016 1.016)
					(thickness 0.1524)
				)
				(justify mirror)
			)
		)
		(duplicate_pad_numbers_are_jumpers no)
		(fp_rect
			(start 0.4318 0.9525)
			(end -0.4318 -0.9525)
			(stroke
				(width 0)
				(type default)
			)
			(fill no)
			(layer "B.CrtYd")
		)
		(fp_rect
			(start 0.4318 0.9525)
			(end -0.4318 -0.9525)
			(stroke
				(width 0)
				(type default)
			)
			(fill no)
			(layer "B.Fab")
		)
		(pad "1" smd custom
			(at 0 -0.4445)
			(size 0.1524 0.1524)
			(layers "B.Cu" "B.Mask" "B.Paste")
			(net "P0V9_E")
			(options
				(clearance outline)
				(anchor circle)
			)
			(primitives
				(gr_poly
					(pts
						(arc
							(start 0.3048 0.2032)
							(mid 0.275042 0.275042)
							(end 0.2032 0.3048)
						)
						(arc
							(start -0.2032 0.3048)
							(mid -0.275042 0.275042)
							(end -0.3048 0.2032)
						)
						(arc
							(start -0.3048 -0.2032)
							(mid -0.275042 -0.275042)
							(end -0.2032 -0.3048)
						)
						(arc
							(start 0.2032 -0.3048)
							(mid 0.275042 -0.275042)
							(end 0.3048 -0.2032)
						)
					)
					(width 0)
					(fill yes)
				)
			)
		)
		(pad "2" smd custom
			(at 0 0.4445)
			(size 0.1524 0.1524)
			(layers "B.Cu" "B.Mask" "B.Paste")
			(net "P0V9_E_SW_R")
			(options
				(clearance outline)
				(anchor circle)
			)
			(primitives
				(gr_poly
					(pts
						(arc
							(start 0.3048 0.2032)
							(mid 0.275042 0.275042)
							(end 0.2032 0.3048)
						)
						(arc
							(start -0.2032 0.3048)
							(mid -0.275042 0.275042)
							(end -0.3048 0.2032)
						)
						(arc
							(start -0.3048 -0.2032)
							(mid -0.275042 -0.275042)
							(end -0.2032 -0.3048)
						)
						(arc
							(start 0.2032 -0.3048)
							(mid 0.275042 -0.275042)
							(end 0.3048 -0.2032)
						)
					)
					(width 0)
					(fill yes)
				)
			)
		)
	)
	(footprint ""
		(layer "B.Cu")
		(at 98.000566 -46.1518 -90)
		(property "Reference" "SC1021"
			(at 0 0 90)
			(layer "B.SilkS")
			(hide yes)
			(effects
				(font
					(size 1.27 1.27)
				)
				(justify mirror)
			)
		)
		(property "Value" "SC10U6D3V5KX-4GP"
			(at 0.0762 -6.1214 270)
			(unlocked yes)
			(layer "B.Fab")
			(hide yes)
			(effects
				(font
					(size 1.016 1.016)
					(thickness 0.1524)
				)
				(justify mirror)
			)
		)
		(property "Device Type" "C805H58"
			(at 0.0762 -8.1534 270)
			(unlocked yes)
			(layer "B.Fab")
			(hide yes)
			(effects
				(font
					(size 1.016 1.016)
					(thickness 0.1524)
				)
				(justify mirror)
			)
		)
		(duplicate_pad_numbers_are_jumpers no)
		(fp_line
			(start -0.635 0)
			(end 0.635 0)
			(stroke
				(width 0.508)
				(type default)
			)
			(layer "B.SilkS")
		)
		(fp_rect
			(start 0.9652 1.778)
			(end -0.9652 -1.778)
			(stroke
				(width 0)
				(type default)
			)
			(fill no)
			(layer "B.CrtYd")
		)
		(fp_poly
			(pts
				(xy 0.9652 -1.778) (xy -0.9652 -1.778) (xy -0.9652 1.778) (xy 0.9652 1.778)
			)
			(stroke
				(width 0)
				(type default)
			)
			(fill no)
			(layer "B.Fab")
		)
		(pad "1" smd rect
			(at 0 -0.9652 90)
			(size 1.397 1.143)
			(layers "B.Cu" "B.Mask" "B.Paste")
			(net "P0V955_C")
		)
		(pad "2" smd rect
			(at 0 0.9652 90)
			(size 1.397 1.143)
			(layers "B.Cu" "B.Mask" "B.Paste")
			(net "GND")
		)
	)
	(footprint ""
		(layer "B.Cu")
		(at 115.640612 -214.884 180)
		(property "Reference" "SU77"
			(at 0 0 0)
			(layer "B.SilkS")
			(hide yes)
			(effects
				(font
					(size 1.27 1.27)
				)
				(justify mirror)
			)
		)
		(property "Value" "PI2EQX6812ZHE-GP"
			(at -6.6548 -1.7526 180)
			(unlocked yes)
			(layer "B.Fab")
			(hide yes)
			(effects
				(font
					(size 1.016 1.016)
					(thickness 0.1524)
				)
				(justify mirror)
			)
		)
		(property "Device Type" "QFN42-G7722H34"
			(at -6.6548 -3.2766 180)
			(unlocked yes)
			(layer "B.Fab")
			(hide yes)
			(effects
				(font
					(size 1.016 1.016)
					(thickness 0.1524)
				)
				(justify mirror)
			)
		)
		(duplicate_pad_numbers_are_jumpers no)
		(fp_line
			(start 5.5118 2.7686)
			(end 4.2418 2.7686)
			(stroke
				(width 0.1524)
				(type default)
			)
			(layer "B.SilkS")
		)
		(fp_line
			(start 5.5118 1.4986)
			(end 5.5118 2.7686)
			(stroke
				(width 0.1524)
				(type default)
			)
			(layer "B.SilkS")
		)
		(fp_line
			(start 5.5118 -2.7686)
			(end 5.5118 -1.4986)
			(stroke
				(width 0.1524)
				(type default)
			)
			(layer "B.SilkS")
		)
		(fp_line
			(start 5.2832 0.2413)
			(end 6.0452 0.2413)
			(stroke
				(width 0.1524)
				(type default)
			)
			(layer "B.SilkS")
		)
		(fp_line
			(start 4.2418 -2.7686)
			(end 5.5118 -2.7686)
			(stroke
				(width 0.1524)
				(type default)
			)
			(layer "B.SilkS")
		)
		(fp_line
			(start 3.0099 -3.048)
			(end 3.0099 -2.54)
			(stroke
				(width 0.1524)
				(type default)
			)
			(layer "B.SilkS")
		)
		(fp_line
			(start 2.4892 2.54)
			(end 2.4892 3.048)
			(stroke
				(width 0.1524)
				(type default)
			)
			(layer "B.SilkS")
		)
		(fp_line
			(start 0.508 -3.302)
			(end 0.508 -2.54)
			(stroke
				(width 0.1524)
				(type default)
			)
			(layer "B.SilkS")
		)
		(fp_line
			(start -0.0127 2.54)
			(end -0.0127 3.302)
			(stroke
				(width 0.1524)
				(type default)
			)
			(layer "B.SilkS")
		)
		(fp_line
			(start -1.9939 -3.048)
			(end -1.9939 -2.54)
			(stroke
				(width 0.1524)
				(type default)
			)
			(layer "B.SilkS")
		)
		(fp_line
			(start -2.5019 2.54)
			(end -2.5019 3.048)
			(stroke
				(width 0.1524)
				(type default)
			)
			(layer "B.SilkS")
		)
		(fp_line
			(start -4.2418 2.7686)
			(end -5.5118 2.7686)
			(stroke
				(width 0.1524)
				(type default)
			)
			(layer "B.SilkS")
		)
		(fp_line
			(start -5.2832 0.254)
			(end -6.0452 0.254)
			(stroke
				(width 0.1524)
				(type default)
			)
			(layer "B.SilkS")
		)
		(fp_line
			(start -5.5118 2.7686)
			(end -5.5118 1.4986)
			(stroke
				(width 0.1524)
				(type default)
			)
			(layer "B.SilkS")
		)
		(fp_poly
			(pts
				(xy -4.2418 -2.7686) (xy -5.5118 -2.7686) (xy -5.5118 -1.4986)
			)
			(stroke
				(width 0)
				(type default)
			)
			(fill yes)
			(layer "B.SilkS")
		)
		(fp_rect
			(start 4.4958 1.7526)
			(end -4.4958 -1.7526)
			(stroke
				(width 0)
				(type default)
			)
			(fill no)
			(layer "B.CrtYd")
		)
		(fp_poly
			(pts
				(xy 5.5118 2.7686) (xy 5.5118 -2.7686) (xy 4.4958 -2.7686) (xy 4.4958 1.7526) (xy -4.4958 1.7526)
				(xy -4.4958 -1.7526) (xy 4.49072 -1.7526) (xy 4.49072 -2.7686) (xy -5.5118 -2.7686) (xy -5.5118 2.7686)
			)
			(stroke
				(width 0)
				(type default)
			)
			(fill no)
			(layer "B.CrtYd")
		)
		(fp_rect
			(start 5.5118 2.7686)
			(end -5.5118 -2.7686)
			(stroke
				(width 0)
				(type default)
			)
			(fill no)
			(layer "B.Fab")
		)
		(pad "1" smd rect
			(at -3.999992 -1.778)
			(size 0.3048 0.9652)
			(layers "B.Cu" "B.Mask" "B.Paste")
			(net "REDV_I2C_SEL1A")
		)
		(pad "2" smd rect
			(at -3.50012 -1.778)
			(size 0.3048 0.9652)
			(layers "B.Cu" "B.Mask" "B.Paste")
			(net "Net_1005")
		)
		(pad "3" smd rect
			(at -2.999994 -1.778)
			(size 0.3048 0.9652)
			(layers "B.Cu" "B.Mask" "B.Paste")
			(net "1.2V_REDV")
		)
		(pad "4" smd rect
			(at -2.500122 -1.778)
			(size 0.3048 0.9652)
			(layers "B.Cu" "B.Mask" "B.Paste")
			(net "SAS_HDD_REDV_SER_TX7_P")
		)
		(pad "5" smd rect
			(at -1.999996 -1.778)
			(size 0.3048 0.9652)
			(layers "B.Cu" "B.Mask" "B.Paste")
			(net "SAS_HDD_REDV_SER_TX7_N")
		)
		(pad "6" smd rect
			(at -1.500124 -1.778)
			(size 0.3048 0.9652)
			(layers "B.Cu" "B.Mask" "B.Paste")
			(net "SAS_HDD_REDV_SER_RX7_P")
		)
		(pad "7" smd rect
			(at -0.999998 -1.778)
			(size 0.3048 0.9652)
			(layers "B.Cu" "B.Mask" "B.Paste")
			(net "SAS_HDD_REDV_SER_RX7_N")
		)
		(pad "8" smd rect
			(at -0.500126 -1.778)
			(size 0.3048 0.9652)
			(layers "B.Cu" "B.Mask" "B.Paste")
			(net "1.2V_REDV")
		)
		(pad "9" smd rect
			(at 0 -1.778)
			(size 0.3048 0.9652)
			(layers "B.Cu" "B.Mask" "B.Paste")
			(net "1.2V_REDV")
		)
		(pad "10" smd rect
			(at 0.500126 -1.778)
			(size 0.3048 0.9652)
			(layers "B.Cu" "B.Mask" "B.Paste")
			(net "SAS_HDD_REDV_SER_TX8_P")
		)
		(pad "11" smd rect
			(at 0.999998 -1.778)
			(size 0.3048 0.9652)
			(layers "B.Cu" "B.Mask" "B.Paste")
			(net "SAS_HDD_REDV_SER_TX8_N")
		)
		(pad "12" smd rect
			(at 1.500124 -1.778)
			(size 0.3048 0.9652)
			(layers "B.Cu" "B.Mask" "B.Paste")
			(net "SAS_HDD_REDV_SER_RX8_P")
		)
		(pad "13" smd rect
			(at 1.999996 -1.778)
			(size 0.3048 0.9652)
			(layers "B.Cu" "B.Mask" "B.Paste")
			(net "SAS_HDD_REDV_SER_RX8_N")
		)
		(pad "14" smd rect
			(at 2.500122 -1.778)
			(size 0.3048 0.9652)
			(layers "B.Cu" "B.Mask" "B.Paste")
			(net "1.2V_REDV")
		)
		(pad "15" smd rect
			(at 2.999994 -1.778)
			(size 0.3048 0.9652)
			(layers "B.Cu" "B.Mask" "B.Paste")
			(net "REDV_MODE")
		)
		(pad "16" smd rect
			(at 3.50012 -1.778)
			(size 0.3048 0.9652)
			(layers "B.Cu" "B.Mask" "B.Paste")
			(net "REDV_D2_B")
		)
		(pad "17" smd rect
			(at 3.999992 -1.778)
			(size 0.3048 0.9652)
			(layers "B.Cu" "B.Mask" "B.Paste")
			(net "REDV_I2C_A4")
		)
		(pad "18" smd rect
			(at 4.5212 -0.750062)
			(size 0.9652 0.3048)
			(layers "B.Cu" "B.Mask" "B.Paste")
			(net "Net_1007")
		)
		(pad "19" smd rect
			(at 4.5212 -0.249936)
			(size 0.9652 0.3048)
			(layers "B.Cu" "B.Mask" "B.Paste")
			(net "REDV_D1_B")
		)
		(pad "20" smd rect
			(at 4.5212 0.249936)
			(size 0.9652 0.3048)
			(layers "B.Cu" "B.Mask" "B.Paste")
			(net "Net_1006")
		)
		(pad "21" smd rect
			(at 4.5212 0.750062)
			(size 0.9652 0.3048)
			(layers "B.Cu" "B.Mask" "B.Paste")
			(net "REDV_I2C_A0")
		)
		(pad "22" smd rect
			(at 3.999992 1.778)
			(size 0.3048 0.9652)
			(layers "B.Cu" "B.Mask" "B.Paste")
			(net "REDV_I2C_A1")
		)
		(pad "23" smd rect
			(at 3.50012 1.778)
			(size 0.3048 0.9652)
			(layers "B.Cu" "B.Mask" "B.Paste")
			(net "REDV_I2C_SEL2B")
		)
		(pad "24" smd rect
			(at 2.999994 1.778)
			(size 0.3048 0.9652)
			(layers "B.Cu" "B.Mask" "B.Paste")
			(net "REDV_I2C_SEL1B")
		)
		(pad "25" smd rect
			(at 2.500122 1.778)
			(size 0.3048 0.9652)
			(layers "B.Cu" "B.Mask" "B.Paste")
			(net "1.2V_REDV")
		)
		(pad "26" smd rect
			(at 1.999996 1.778)
			(size 0.3048 0.9652)
			(layers "B.Cu" "B.Mask" "B.Paste")
			(net "SAS_HDD_CONN_SER_RX8_N")
		)
		(pad "27" smd rect
			(at 1.500124 1.778)
			(size 0.3048 0.9652)
			(layers "B.Cu" "B.Mask" "B.Paste")
			(net "SAS_HDD_CONN_SER_RX8_P")
		)
		(pad "28" smd rect
			(at 0.999998 1.778)
			(size 0.3048 0.9652)
			(layers "B.Cu" "B.Mask" "B.Paste")
			(net "SAS_HDD_CONN_SER_TX8_N")
		)
		(pad "29" smd rect
			(at 0.500126 1.778)
			(size 0.3048 0.9652)
			(layers "B.Cu" "B.Mask" "B.Paste")
			(net "SAS_HDD_CONN_SER_TX8_P")
		)
		(pad "30" smd rect
			(at 0 1.778)
			(size 0.3048 0.9652)
			(layers "B.Cu" "B.Mask" "B.Paste")
			(net "1.2V_REDV")
		)
		(pad "31" smd rect
			(at -0.500126 1.778)
			(size 0.3048 0.9652)
			(layers "B.Cu" "B.Mask" "B.Paste")
			(net "1.2V_REDV")
		)
		(pad "32" smd rect
			(at -0.999998 1.778)
			(size 0.3048 0.9652)
			(layers "B.Cu" "B.Mask" "B.Paste")
			(net "SAS_HDD_CONN_SER_RX7_N")
		)
		(pad "33" smd rect
			(at -1.500124 1.778)
			(size 0.3048 0.9652)
			(layers "B.Cu" "B.Mask" "B.Paste")
			(net "SAS_HDD_CONN_SER_RX7_P")
		)
		(pad "34" smd rect
			(at -1.999996 1.778)
			(size 0.3048 0.9652)
			(layers "B.Cu" "B.Mask" "B.Paste")
			(net "SAS_HDD_CONN_SER_TX7_N")
		)
		(pad "35" smd rect
			(at -2.500122 1.778)
			(size 0.3048 0.9652)
			(layers "B.Cu" "B.Mask" "B.Paste")
			(net "SAS_HDD_CONN_SER_TX7_P")
		)
		(pad "36" smd rect
			(at -2.999994 1.778)
			(size 0.3048 0.9652)
			(layers "B.Cu" "B.Mask" "B.Paste")
			(net "1.2V_REDV")
		)
		(pad "37" smd rect
			(at -3.50012 1.778)
			(size 0.3048 0.9652)
			(layers "B.Cu" "B.Mask" "B.Paste")
			(net "REDV_PD#")
		)
		(pad "38" smd rect
			(at -3.999992 1.778)
			(size 0.3048 0.9652)
			(layers "B.Cu" "B.Mask" "B.Paste")
			(net "REDV_I2C_SDA")
		)
		(pad "39" smd rect
			(at -4.5212 0.750062)
			(size 0.9652 0.3048)
			(layers "B.Cu" "B.Mask" "B.Paste")
			(net "REDV_I2C_SCL")
		)
		(pad "40" smd rect
			(at -4.5212 0.249936)
			(size 0.9652 0.3048)
			(layers "B.Cu" "B.Mask" "B.Paste")
			(net "REDV_D2_A")
		)
		(pad "41" smd rect
			(at -4.5212 -0.249936)
			(size 0.9652 0.3048)
			(layers "B.Cu" "B.Mask" "B.Paste")
			(net "REDV_D1_A")
		)
		(pad "42" smd rect
			(at -4.5212 -0.750062)
			(size 0.9652 0.3048)
			(layers "B.Cu" "B.Mask" "B.Paste")
			(net "REDV_I2C_SEL2A")
		)
		(pad "43" smd rect
			(at 0 0)
			(size 7.6454 2.159)
			(layers "B.Cu" "B.Mask" "B.Paste")
			(net "GND")
		)
	)
	(footprint ""
		(layer "B.Cu")
		(at 19.373088 -191.136016 90)
		(property "Reference" "SC545"
			(at 0 0 90)
			(layer "B.SilkS")
			(hide yes)
			(effects
				(font
					(size 1.27 1.27)
				)
				(justify mirror)
			)
		)
		(property "Value" "SCD1U16V2KX-3GP"
			(at -1.1811 -2.7051 90)
			(unlocked yes)
			(layer "B.Fab")
			(hide yes)
			(effects
				(font
					(size 1.016 1.016)
					(thickness 0.1524)
				)
				(justify mirror)
			)
		)
		(property "Device Type" "C402H22"
			(at -1.1811 -4.2291 90)
			(unlocked yes)
			(layer "B.Fab")
			(hide yes)
			(effects
				(font
					(size 1.016 1.016)
					(thickness 0.1524)
				)
				(justify mirror)
			)
		)
		(duplicate_pad_numbers_are_jumpers no)
		(fp_rect
			(start 0.4318 0.9525)
			(end -0.4318 -0.9525)
			(stroke
				(width 0)
				(type default)
			)
			(fill no)
			(layer "B.CrtYd")
		)
		(fp_rect
			(start 0.4318 0.9525)
			(end -0.4318 -0.9525)
			(stroke
				(width 0)
				(type default)
			)
			(fill no)
			(layer "B.Fab")
		)
		(pad "1" smd custom
			(at 0 -0.4445 270)
			(size 0.1524 0.1524)
			(layers "B.Cu" "B.Mask" "B.Paste")
			(net "P3V3_STBY")
			(options
				(clearance outline)
				(anchor circle)
			)
			(primitives
				(gr_poly
					(pts
						(arc
							(start 0.3048 0.2032)
							(mid 0.275042 0.275042)
							(end 0.2032 0.3048)
						)
						(arc
							(start -0.2032 0.3048)
							(mid -0.275042 0.275042)
							(end -0.3048 0.2032)
						)
						(arc
							(start -0.3048 -0.2032)
							(mid -0.275042 -0.275042)
							(end -0.2032 -0.3048)
						)
						(arc
							(start 0.2032 -0.3048)
							(mid 0.275042 -0.275042)
							(end 0.3048 -0.2032)
						)
					)
					(width 0)
					(fill yes)
				)
			)
		)
		(pad "2" smd custom
			(at 0 0.4445 270)
			(size 0.1524 0.1524)
			(layers "B.Cu" "B.Mask" "B.Paste")
			(net "GND")
			(options
				(clearance outline)
				(anchor circle)
			)
			(primitives
				(gr_poly
					(pts
						(arc
							(start 0.3048 0.2032)
							(mid 0.275042 0.275042)
							(end 0.2032 0.3048)
						)
						(arc
							(start -0.2032 0.3048)
							(mid -0.275042 0.275042)
							(end -0.3048 0.2032)
						)
						(arc
							(start -0.3048 -0.2032)
							(mid -0.275042 -0.275042)
							(end -0.2032 -0.3048)
						)
						(arc
							(start 0.2032 -0.3048)
							(mid 0.275042 -0.275042)
							(end 0.3048 -0.2032)
						)
					)
					(width 0)
					(fill yes)
				)
			)
		)
	)
	(footprint ""
		(layer "B.Cu")
		(at 105.264966 -48.26 90)
		(property "Reference" "SC1059"
			(at 0 0 90)
			(layer "B.SilkS")
			(hide yes)
			(effects
				(font
					(size 1.27 1.27)
				)
				(justify mirror)
			)
		)
		(property "Value" "SCD1U16V2KX-3GP"
			(at -1.1811 -2.7051 90)
			(unlocked yes)
			(layer "B.Fab")
			(hide yes)
			(effects
				(font
					(size 1.016 1.016)
					(thickness 0.1524)
				)
				(justify mirror)
			)
		)
		(property "Device Type" "C402H22"
			(at -1.1811 -4.2291 90)
			(unlocked yes)
			(layer "B.Fab")
			(hide yes)
			(effects
				(font
					(size 1.016 1.016)
					(thickness 0.1524)
				)
				(justify mirror)
			)
		)
		(duplicate_pad_numbers_are_jumpers no)
		(fp_rect
			(start 0.4318 0.9525)
			(end -0.4318 -0.9525)
			(stroke
				(width 0)
				(type default)
			)
			(fill no)
			(layer "B.CrtYd")
		)
		(fp_rect
			(start 0.4318 0.9525)
			(end -0.4318 -0.9525)
			(stroke
				(width 0)
				(type default)
			)
			(fill no)
			(layer "B.Fab")
		)
		(pad "1" smd custom
			(at 0 -0.4445 270)
			(size 0.1524 0.1524)
			(layers "B.Cu" "B.Mask" "B.Paste")
			(net "P0V955_C")
			(options
				(clearance outline)
				(anchor circle)
			)
			(primitives
				(gr_poly
					(pts
						(arc
							(start 0.3048 0.2032)
							(mid 0.275042 0.275042)
							(end 0.2032 0.3048)
						)
						(arc
							(start -0.2032 0.3048)
							(mid -0.275042 0.275042)
							(end -0.3048 0.2032)
						)
						(arc
							(start -0.3048 -0.2032)
							(mid -0.275042 -0.275042)
							(end -0.2032 -0.3048)
						)
						(arc
							(start 0.2032 -0.3048)
							(mid 0.275042 -0.275042)
							(end 0.3048 -0.2032)
						)
					)
					(width 0)
					(fill yes)
				)
			)
		)
		(pad "2" smd custom
			(at 0 0.4445 270)
			(size 0.1524 0.1524)
			(layers "B.Cu" "B.Mask" "B.Paste")
			(net "GND")
			(options
				(clearance outline)
				(anchor circle)
			)
			(primitives
				(gr_poly
					(pts
						(arc
							(start 0.3048 0.2032)
							(mid 0.275042 0.275042)
							(end 0.2032 0.3048)
						)
						(arc
							(start -0.2032 0.3048)
							(mid -0.275042 0.275042)
							(end -0.3048 0.2032)
						)
						(arc
							(start -0.3048 -0.2032)
							(mid -0.275042 -0.275042)
							(end -0.2032 -0.3048)
						)
						(arc
							(start 0.2032 -0.3048)
							(mid 0.275042 -0.275042)
							(end 0.3048 -0.2032)
						)
					)
					(width 0)
					(fill yes)
				)
			)
		)
	)
	(footprint ""
		(layer "B.Cu")
		(at 94.358206 -54.71668 90)
		(property "Reference" "SC980"
			(at 0 0 90)
			(layer "B.SilkS")
			(hide yes)
			(effects
				(font
					(size 1.27 1.27)
				)
				(justify mirror)
			)
		)
		(property "Value" "SCD1U16V2KX-3GP"
			(at -1.1811 -2.7051 90)
			(unlocked yes)
			(layer "B.Fab")
			(hide yes)
			(effects
				(font
					(size 1.016 1.016)
					(thickness 0.1524)
				)
				(justify mirror)
			)
		)
		(property "Device Type" "C402H22"
			(at -1.1811 -4.2291 90)
			(unlocked yes)
			(layer "B.Fab")
			(hide yes)
			(effects
				(font
					(size 1.016 1.016)
					(thickness 0.1524)
				)
				(justify mirror)
			)
		)
		(duplicate_pad_numbers_are_jumpers no)
		(fp_rect
			(start 0.4318 0.9525)
			(end -0.4318 -0.9525)
			(stroke
				(width 0)
				(type default)
			)
			(fill no)
			(layer "B.CrtYd")
		)
		(fp_rect
			(start 0.4318 0.9525)
			(end -0.4318 -0.9525)
			(stroke
				(width 0)
				(type default)
			)
			(fill no)
			(layer "B.Fab")
		)
		(pad "1" smd custom
			(at 0 -0.4445 270)
			(size 0.1524 0.1524)
			(layers "B.Cu" "B.Mask" "B.Paste")
			(net "P1V8_C")
			(options
				(clearance outline)
				(anchor circle)
			)
			(primitives
				(gr_poly
					(pts
						(arc
							(start 0.3048 0.2032)
							(mid 0.275042 0.275042)
							(end 0.2032 0.3048)
						)
						(arc
							(start -0.2032 0.3048)
							(mid -0.275042 0.275042)
							(end -0.3048 0.2032)
						)
						(arc
							(start -0.3048 -0.2032)
							(mid -0.275042 -0.275042)
							(end -0.2032 -0.3048)
						)
						(arc
							(start 0.2032 -0.3048)
							(mid 0.275042 -0.275042)
							(end 0.3048 -0.2032)
						)
					)
					(width 0)
					(fill yes)
				)
			)
		)
		(pad "2" smd custom
			(at 0 0.4445 270)
			(size 0.1524 0.1524)
			(layers "B.Cu" "B.Mask" "B.Paste")
			(net "GND")
			(options
				(clearance outline)
				(anchor circle)
			)
			(primitives
				(gr_poly
					(pts
						(arc
							(start 0.3048 0.2032)
							(mid 0.275042 0.275042)
							(end 0.2032 0.3048)
						)
						(arc
							(start -0.2032 0.3048)
							(mid -0.275042 0.275042)
							(end -0.3048 0.2032)
						)
						(arc
							(start -0.3048 -0.2032)
							(mid -0.275042 -0.275042)
							(end -0.2032 -0.3048)
						)
						(arc
							(start 0.2032 -0.3048)
							(mid 0.275042 -0.275042)
							(end 0.3048 -0.2032)
						)
					)
					(width 0)
					(fill yes)
				)
			)
		)
	)
	(footprint ""
		(layer "B.Cu")
		(at 311.702958 -51.308 180)
		(property "Reference" "C276"
			(at 0 0 0)
			(layer "B.SilkS")
			(hide yes)
			(effects
				(font
					(size 1.27 1.27)
				)
				(justify mirror)
			)
		)
		(property "Value" "SC22U25V5MX-GP"
			(at 0.0762 -6.1214 180)
			(unlocked yes)
			(layer "B.Fab")
			(hide yes)
			(effects
				(font
					(size 1.016 1.016)
					(thickness 0.1524)
				)
				(justify mirror)
			)
		)
		(property "Device Type" "C805H58"
			(at 0.0762 -8.1534 180)
			(unlocked yes)
			(layer "B.Fab")
			(hide yes)
			(effects
				(font
					(size 1.016 1.016)
					(thickness 0.1524)
				)
				(justify mirror)
			)
		)
		(duplicate_pad_numbers_are_jumpers no)
		(fp_line
			(start -0.635 0)
			(end 0.635 0)
			(stroke
				(width 0.508)
				(type default)
			)
			(layer "B.SilkS")
		)
		(fp_rect
			(start 0.9652 1.778)
			(end -0.9652 -1.778)
			(stroke
				(width 0)
				(type default)
			)
			(fill no)
			(layer "B.CrtYd")
		)
		(fp_poly
			(pts
				(xy 0.9652 -1.778) (xy -0.9652 -1.778) (xy -0.9652 1.778) (xy 0.9652 1.778)
			)
			(stroke
				(width 0)
				(type default)
			)
			(fill no)
			(layer "B.Fab")
		)
		(pad "1" smd rect
			(at 0 -0.9652)
			(size 1.397 1.143)
			(layers "B.Cu" "B.Mask" "B.Paste")
			(net "P12V")
		)
		(pad "2" smd rect
			(at 0 0.9652)
			(size 1.397 1.143)
			(layers "B.Cu" "B.Mask" "B.Paste")
			(net "GND")
		)
	)
	(footprint ""
		(layer "B.Cu")
		(at 109.671612 -205.867)
		(property "Reference" "SR893"
			(at 0 0 0)
			(layer "B.SilkS")
			(hide yes)
			(effects
				(font
					(size 1.27 1.27)
				)
				(justify mirror)
			)
		)
		(property "Value" "0R2J-2-GP"
			(at -0.064008 -3.993896 0)
			(unlocked yes)
			(layer "B.Fab")
			(hide yes)
			(effects
				(font
					(size 1.016 1.016)
					(thickness 0.1524)
				)
				(justify mirror)
			)
		)
		(property "Device Type" "R402H16"
			(at -0.064008 -5.517896 0)
			(unlocked yes)
			(layer "B.Fab")
			(hide yes)
			(effects
				(font
					(size 1.016 1.016)
					(thickness 0.1524)
				)
				(justify mirror)
			)
		)
		(duplicate_pad_numbers_are_jumpers no)
		(fp_line
			(start -0.508 -0.9398)
			(end 0.508 -0.9398)
			(stroke
				(width 0.1524)
				(type default)
			)
			(layer "B.SilkS")
		)
		(fp_line
			(start 0.508 -0.9398)
			(end 0.508 0.9398)
			(stroke
				(width 0.1524)
				(type default)
			)
			(layer "B.SilkS")
		)
		(fp_rect
			(start 0.508 0.9398)
			(end -0.508 -0.9398)
			(stroke
				(width 0)
				(type default)
			)
			(fill no)
			(layer "B.CrtYd")
		)
		(fp_rect
			(start 0.508 0.9398)
			(end -0.508 -0.9398)
			(stroke
				(width 0)
				(type default)
			)
			(fill no)
			(layer "B.Fab")
		)
		(pad "1" smd custom
			(at 0 -0.4445 180)
			(size 0.1397 0.1397)
			(layers "B.Cu" "B.Mask" "B.Paste")
			(net "SAS_HDD_REDV_SER_RX8_P")
			(options
				(clearance outline)
				(anchor circle)
			)
			(primitives
				(gr_poly
					(pts
						(arc
							(start -0.1778 0.2794)
							(mid -0.249642 0.249642)
							(end -0.2794 0.1778)
						)
						(arc
							(start -0.2794 -0.1778)
							(mid -0.249642 -0.249642)
							(end -0.1778 -0.2794)
						)
						(arc
							(start 0.1778 -0.2794)
							(mid 0.249642 -0.249642)
							(end 0.2794 -0.1778)
						)
						(arc
							(start 0.2794 0.1778)
							(mid 0.249642 0.249642)
							(end 0.1778 0.2794)
						)
					)
					(width 0)
					(fill yes)
				)
			)
		)
		(pad "2" smd custom
			(at 0 0.4445 180)
			(size 0.1397 0.1397)
			(layers "B.Cu" "B.Mask" "B.Paste")
			(net "SAS_HDD_CONN_RX8_P")
			(options
				(clearance outline)
				(anchor circle)
			)
			(primitives
				(gr_poly
					(pts
						(arc
							(start -0.1778 0.2794)
							(mid -0.249642 0.249642)
							(end -0.2794 0.1778)
						)
						(arc
							(start -0.2794 -0.1778)
							(mid -0.249642 -0.249642)
							(end -0.1778 -0.2794)
						)
						(arc
							(start 0.1778 -0.2794)
							(mid 0.249642 -0.249642)
							(end 0.2794 -0.1778)
						)
						(arc
							(start 0.2794 0.1778)
							(mid 0.249642 0.249642)
							(end 0.1778 0.2794)
						)
					)
					(width 0)
					(fill yes)
				)
			)
		)
	)
	(footprint ""
		(layer "B.Cu")
		(at 119.234966 -30.988 -90)
		(property "Reference" "SR643"
			(at 0 0 90)
			(layer "B.SilkS")
			(hide yes)
			(effects
				(font
					(size 1.27 1.27)
				)
				(justify mirror)
			)
		)
		(property "Value" "4K7R2F-GP"
			(at -0.064008 -3.993896 270)
			(unlocked yes)
			(layer "B.Fab")
			(hide yes)
			(effects
				(font
					(size 1.016 1.016)
					(thickness 0.1524)
				)
				(justify mirror)
			)
		)
		(property "Device Type" "R402H16"
			(at -0.064008 -5.517896 270)
			(unlocked yes)
			(layer "B.Fab")
			(hide yes)
			(effects
				(font
					(size 1.016 1.016)
					(thickness 0.1524)
				)
				(justify mirror)
			)
		)
		(duplicate_pad_numbers_are_jumpers no)
		(fp_line
			(start -0.508 -0.9398)
			(end 0.508 -0.9398)
			(stroke
				(width 0.1524)
				(type default)
			)
			(layer "B.SilkS")
		)
		(fp_line
			(start 0.508 -0.9398)
			(end 0.508 0.9398)
			(stroke
				(width 0.1524)
				(type default)
			)
			(layer "B.SilkS")
		)
		(fp_rect
			(start 0.508 0.9398)
			(end -0.508 -0.9398)
			(stroke
				(width 0)
				(type default)
			)
			(fill no)
			(layer "B.CrtYd")
		)
		(fp_rect
			(start 0.508 0.9398)
			(end -0.508 -0.9398)
			(stroke
				(width 0)
				(type default)
			)
			(fill no)
			(layer "B.Fab")
		)
		(pad "1" smd custom
			(at 0 -0.4445 90)
			(size 0.1397 0.1397)
			(layers "B.Cu" "B.Mask" "B.Paste")
			(net "P1V8_C")
			(options
				(clearance outline)
				(anchor circle)
			)
			(primitives
				(gr_poly
					(pts
						(arc
							(start -0.1778 0.2794)
							(mid -0.249642 0.249642)
							(end -0.2794 0.1778)
						)
						(arc
							(start -0.2794 -0.1778)
							(mid -0.249642 -0.249642)
							(end -0.1778 -0.2794)
						)
						(arc
							(start 0.1778 -0.2794)
							(mid 0.249642 -0.249642)
							(end 0.2794 -0.1778)
						)
						(arc
							(start 0.2794 0.1778)
							(mid 0.249642 0.249642)
							(end 0.1778 0.2794)
						)
					)
					(width 0)
					(fill yes)
				)
			)
		)
		(pad "2" smd custom
			(at 0 0.4445 90)
			(size 0.1397 0.1397)
			(layers "B.Cu" "B.Mask" "B.Paste")
			(net "UART_SERCLK")
			(options
				(clearance outline)
				(anchor circle)
			)
			(primitives
				(gr_poly
					(pts
						(arc
							(start -0.1778 0.2794)
							(mid -0.249642 0.249642)
							(end -0.2794 0.1778)
						)
						(arc
							(start -0.2794 -0.1778)
							(mid -0.249642 -0.249642)
							(end -0.1778 -0.2794)
						)
						(arc
							(start 0.1778 -0.2794)
							(mid 0.249642 -0.249642)
							(end 0.2794 -0.1778)
						)
						(arc
							(start 0.2794 0.1778)
							(mid 0.249642 0.249642)
							(end 0.1778 0.2794)
						)
					)
					(width 0)
					(fill yes)
				)
			)
		)
	)
	(footprint ""
		(layer "B.Cu")
		(at 90.30716 -37.084 90)
		(property "Reference" "SC937"
			(at 0 0 90)
			(layer "B.SilkS")
			(hide yes)
			(effects
				(font
					(size 1.27 1.27)
				)
				(justify mirror)
			)
		)
		(property "Value" "SC1U6D3V1MX-GP"
			(at -1.9177 2.0193 90)
			(unlocked yes)
			(layer "B.Fab")
			(hide yes)
			(effects
				(font
					(size 1.016 1.016)
					(thickness 0.1524)
				)
				(justify mirror)
			)
		)
		(property "Device Type" "C0201H14"
			(at -1.9177 0.4953 90)
			(unlocked yes)
			(layer "B.Fab")
			(hide yes)
			(effects
				(font
					(size 1.016 1.016)
					(thickness 0.1524)
				)
				(justify mirror)
			)
		)
		(duplicate_pad_numbers_are_jumpers no)
		(fp_rect
			(start 0.1524 0.3048)
			(end -0.1524 -0.3048)
			(stroke
				(width 0)
				(type default)
			)
			(fill no)
			(layer "B.CrtYd")
		)
		(fp_poly
			(pts
				(xy 0.2794 0.6477) (xy 0.2794 -0.6477) (xy -0.2794 -0.6477) (xy -0.2794 -0.1905) (xy -0.1524 -0.1905)
				(xy -0.1524 -0.3048) (xy 0.1524 -0.3048) (xy 0.1524 0.3048) (xy -0.1524 0.3048) (xy -0.1524 -0.1778)
				(xy -0.2794 -0.1778) (xy -0.2794 0.6477)
			)
			(stroke
				(width 0)
				(type default)
			)
			(fill no)
			(layer "B.CrtYd")
		)
		(fp_rect
			(start 0.2794 0.6477)
			(end -0.2794 -0.6477)
			(stroke
				(width 0)
				(type default)
			)
			(fill no)
			(layer "B.Fab")
		)
		(pad "1" smd custom
			(at 0 -0.2794 270)
			(size 0.0762 0.0762)
			(layers "B.Cu" "B.Mask" "B.Paste")
			(net "SAS0_VDDH")
			(options
				(clearance outline)
				(anchor circle)
			)
			(primitives
				(gr_poly
					(pts
						(arc
							(start 0.1524 0.127)
							(mid 0.137521 0.162921)
							(end 0.1016 0.1778)
						)
						(arc
							(start -0.1016 0.1778)
							(mid -0.137521 0.162921)
							(end -0.1524 0.127)
						)
						(arc
							(start -0.1524 -0.127)
							(mid -0.137521 -0.162921)
							(end -0.1016 -0.1778)
						)
						(arc
							(start 0.1016 -0.1778)
							(mid 0.137521 -0.162921)
							(end 0.1524 -0.127)
						)
					)
					(width 0)
					(fill yes)
				)
			)
		)
		(pad "2" smd custom
			(at 0 0.2794 270)
			(size 0.0762 0.0762)
			(layers "B.Cu" "B.Mask" "B.Paste")
			(net "GND")
			(options
				(clearance outline)
				(anchor circle)
			)
			(primitives
				(gr_poly
					(pts
						(arc
							(start 0.1524 0.127)
							(mid 0.137521 0.162921)
							(end 0.1016 0.1778)
						)
						(arc
							(start -0.1016 0.1778)
							(mid -0.137521 0.162921)
							(end -0.1524 0.127)
						)
						(arc
							(start -0.1524 -0.127)
							(mid -0.137521 -0.162921)
							(end -0.1016 -0.1778)
						)
						(arc
							(start 0.1016 -0.1778)
							(mid 0.137521 -0.162921)
							(end 0.1524 -0.127)
						)
					)
					(width 0)
					(fill yes)
				)
			)
		)
	)
	(footprint ""
		(layer "B.Cu")
		(at 305.91506 -179.3748 180)
		(property "Reference" "C192"
			(at 0 0 0)
			(layer "B.SilkS")
			(hide yes)
			(effects
				(font
					(size 1.27 1.27)
				)
				(justify mirror)
			)
		)
		(property "Value" "SC1U6D3V3KX-2GP"
			(at 0 -2.8194 180)
			(unlocked yes)
			(layer "B.Fab")
			(hide yes)
			(effects
				(font
					(size 1.016 1.016)
					(thickness 0.1524)
				)
				(justify mirror)
			)
		)
		(property "Device Type" "C603H36"
			(at 0 -4.3434 180)
			(unlocked yes)
			(layer "B.Fab")
			(hide yes)
			(effects
				(font
					(size 1.016 1.016)
					(thickness 0.1524)
				)
				(justify mirror)
			)
		)
		(duplicate_pad_numbers_are_jumpers no)
		(fp_line
			(start -0.508 0)
			(end 0.508 0)
			(stroke
				(width 0.2032)
				(type default)
			)
			(layer "B.SilkS")
		)
		(fp_rect
			(start 0.5842 1.3335)
			(end -0.5842 -1.3335)
			(stroke
				(width 0)
				(type default)
			)
			(fill no)
			(layer "B.CrtYd")
		)
		(fp_rect
			(start 0.5842 1.3335)
			(end -0.5842 -1.3335)
			(stroke
				(width 0)
				(type default)
			)
			(fill no)
			(layer "B.Fab")
		)
		(pad "1" smd custom
			(at 0 -0.762)
			(size 0.2159 0.2159)
			(layers "B.Cu" "B.Mask" "B.Paste")
			(net "ADCAV33")
			(options
				(clearance outline)
				(anchor circle)
			)
			(primitives
				(gr_poly
					(pts
						(arc
							(start -0.3302 0.4318)
							(mid -0.402042 0.402042)
							(end -0.4318 0.3302)
						)
						(arc
							(start -0.4318 -0.3302)
							(mid -0.402042 -0.402042)
							(end -0.3302 -0.4318)
						)
						(arc
							(start 0.3302 -0.4318)
							(mid 0.402042 -0.402042)
							(end 0.4318 -0.3302)
						)
						(arc
							(start 0.4318 0.3302)
							(mid 0.402042 0.402042)
							(end 0.3302 0.4318)
						)
					)
					(width 0)
					(fill yes)
				)
			)
		)
		(pad "2" smd custom
			(at 0 0.762)
			(size 0.2159 0.2159)
			(layers "B.Cu" "B.Mask" "B.Paste")
			(net "GND")
			(options
				(clearance outline)
				(anchor circle)
			)
			(primitives
				(gr_poly
					(pts
						(arc
							(start -0.3302 0.4318)
							(mid -0.402042 0.402042)
							(end -0.4318 0.3302)
						)
						(arc
							(start -0.4318 -0.3302)
							(mid -0.402042 -0.402042)
							(end -0.3302 -0.4318)
						)
						(arc
							(start 0.3302 -0.4318)
							(mid 0.402042 -0.402042)
							(end 0.4318 -0.3302)
						)
						(arc
							(start 0.4318 0.3302)
							(mid 0.402042 0.402042)
							(end 0.3302 0.4318)
						)
					)
					(width 0)
					(fill yes)
				)
			)
		)
	)
	(footprint ""
		(layer "B.Cu")
		(at 324.358 -184.404 180)
		(property "Reference" "R3100"
			(at 0 0 0)
			(layer "B.SilkS")
			(hide yes)
			(effects
				(font
					(size 1.27 1.27)
				)
				(justify mirror)
			)
		)
		(property "Value" "1KR2F-3-GP"
			(at -0.064008 -3.993896 180)
			(unlocked yes)
			(layer "B.Fab")
			(hide yes)
			(effects
				(font
					(size 1.016 1.016)
					(thickness 0.1524)
				)
				(justify mirror)
			)
		)
		(property "Device Type" "R402H16"
			(at -0.064008 -5.517896 180)
			(unlocked yes)
			(layer "B.Fab")
			(hide yes)
			(effects
				(font
					(size 1.016 1.016)
					(thickness 0.1524)
				)
				(justify mirror)
			)
		)
		(duplicate_pad_numbers_are_jumpers no)
		(fp_line
			(start 0.508 -0.9398)
			(end 0.508 0.9398)
			(stroke
				(width 0.1524)
				(type default)
			)
			(layer "B.SilkS")
		)
		(fp_line
			(start -0.508 -0.9398)
			(end 0.508 -0.9398)
			(stroke
				(width 0.1524)
				(type default)
			)
			(layer "B.SilkS")
		)
		(fp_rect
			(start 0.508 0.9398)
			(end -0.508 -0.9398)
			(stroke
				(width 0)
				(type default)
			)
			(fill no)
			(layer "B.CrtYd")
		)
		(fp_rect
			(start 0.508 0.9398)
			(end -0.508 -0.9398)
			(stroke
				(width 0)
				(type default)
			)
			(fill no)
			(layer "B.Fab")
		)
		(pad "1" smd custom
			(at 0 -0.4445)
			(size 0.1397 0.1397)
			(layers "B.Cu" "B.Mask" "B.Paste")
			(net "ADC_P0V9_E")
			(options
				(clearance outline)
				(anchor circle)
			)
			(primitives
				(gr_poly
					(pts
						(arc
							(start -0.1778 0.2794)
							(mid -0.249642 0.249642)
							(end -0.2794 0.1778)
						)
						(arc
							(start -0.2794 -0.1778)
							(mid -0.249642 -0.249642)
							(end -0.1778 -0.2794)
						)
						(arc
							(start 0.1778 -0.2794)
							(mid 0.249642 -0.249642)
							(end 0.2794 -0.1778)
						)
						(arc
							(start 0.2794 0.1778)
							(mid 0.249642 0.249642)
							(end 0.1778 0.2794)
						)
					)
					(width 0)
					(fill yes)
				)
			)
		)
		(pad "2" smd custom
			(at 0 0.4445)
			(size 0.1397 0.1397)
			(layers "B.Cu" "B.Mask" "B.Paste")
			(net "GND")
			(options
				(clearance outline)
				(anchor circle)
			)
			(primitives
				(gr_poly
					(pts
						(arc
							(start -0.1778 0.2794)
							(mid -0.249642 0.249642)
							(end -0.2794 0.1778)
						)
						(arc
							(start -0.2794 -0.1778)
							(mid -0.249642 -0.249642)
							(end -0.1778 -0.2794)
						)
						(arc
							(start 0.1778 -0.2794)
							(mid 0.249642 -0.249642)
							(end 0.2794 -0.1778)
						)
						(arc
							(start 0.2794 0.1778)
							(mid 0.249642 0.249642)
							(end 0.1778 0.2794)
						)
					)
					(width 0)
					(fill yes)
				)
			)
		)
	)
	(footprint ""
		(layer "B.Cu")
		(at 100.870766 -37.719 90)
		(property "Reference" "SC942"
			(at 0 0 90)
			(layer "B.SilkS")
			(hide yes)
			(effects
				(font
					(size 1.27 1.27)
				)
				(justify mirror)
			)
		)
		(property "Value" "SCD1U6D3V1KX-GP"
			(at 2.8321 -1.7399 90)
			(unlocked yes)
			(layer "B.Fab")
			(hide yes)
			(effects
				(font
					(size 1.016 1.016)
					(thickness 0.1524)
				)
				(justify mirror)
			)
		)
		(property "Device Type" "C0201H13"
			(at 2.8321 -3.2639 90)
			(unlocked yes)
			(layer "B.Fab")
			(hide yes)
			(effects
				(font
					(size 1.016 1.016)
					(thickness 0.1524)
				)
				(justify mirror)
			)
		)
		(duplicate_pad_numbers_are_jumpers no)
		(fp_rect
			(start 0.2794 0.6477)
			(end -0.2794 -0.6477)
			(stroke
				(width 0)
				(type default)
			)
			(fill no)
			(layer "B.CrtYd")
		)
		(fp_rect
			(start 0.2794 0.6477)
			(end -0.2794 -0.6477)
			(stroke
				(width 0)
				(type default)
			)
			(fill no)
			(layer "B.Fab")
		)
		(pad "1" smd custom
			(at 0 -0.2794 270)
			(size 0.0762 0.0762)
			(layers "B.Cu" "B.Mask" "B.Paste")
			(net "P1V5_C")
			(options
				(clearance outline)
				(anchor circle)
			)
			(primitives
				(gr_poly
					(pts
						(arc
							(start 0.1524 0.127)
							(mid 0.137521 0.162921)
							(end 0.1016 0.1778)
						)
						(arc
							(start -0.1016 0.1778)
							(mid -0.137521 0.162921)
							(end -0.1524 0.127)
						)
						(arc
							(start -0.1524 -0.127)
							(mid -0.137521 -0.162921)
							(end -0.1016 -0.1778)
						)
						(arc
							(start 0.1016 -0.1778)
							(mid 0.137521 -0.162921)
							(end 0.1524 -0.127)
						)
					)
					(width 0)
					(fill yes)
				)
			)
		)
		(pad "2" smd custom
			(at 0 0.2794 270)
			(size 0.0762 0.0762)
			(layers "B.Cu" "B.Mask" "B.Paste")
			(net "GND")
			(options
				(clearance outline)
				(anchor circle)
			)
			(primitives
				(gr_poly
					(pts
						(arc
							(start 0.1524 0.127)
							(mid 0.137521 0.162921)
							(end 0.1016 0.1778)
						)
						(arc
							(start -0.1016 0.1778)
							(mid -0.137521 0.162921)
							(end -0.1524 0.127)
						)
						(arc
							(start -0.1524 -0.127)
							(mid -0.137521 -0.162921)
							(end -0.1016 -0.1778)
						)
						(arc
							(start 0.1016 -0.1778)
							(mid 0.137521 -0.162921)
							(end 0.1524 -0.127)
						)
					)
					(width 0)
					(fill yes)
				)
			)
		)
	)
	(footprint ""
		(layer "B.Cu")
		(at 91.19616 -34.417 90)
		(property "Reference" "SC938"
			(at 0 0 90)
			(layer "B.SilkS")
			(hide yes)
			(effects
				(font
					(size 1.27 1.27)
				)
				(justify mirror)
			)
		)
		(property "Value" "SCD1U6D3V1KX-GP"
			(at 2.8321 -1.7399 90)
			(unlocked yes)
			(layer "B.Fab")
			(hide yes)
			(effects
				(font
					(size 1.016 1.016)
					(thickness 0.1524)
				)
				(justify mirror)
			)
		)
		(property "Device Type" "C0201H13"
			(at 2.8321 -3.2639 90)
			(unlocked yes)
			(layer "B.Fab")
			(hide yes)
			(effects
				(font
					(size 1.016 1.016)
					(thickness 0.1524)
				)
				(justify mirror)
			)
		)
		(duplicate_pad_numbers_are_jumpers no)
		(fp_rect
			(start 0.2794 0.6477)
			(end -0.2794 -0.6477)
			(stroke
				(width 0)
				(type default)
			)
			(fill no)
			(layer "B.CrtYd")
		)
		(fp_rect
			(start 0.2794 0.6477)
			(end -0.2794 -0.6477)
			(stroke
				(width 0)
				(type default)
			)
			(fill no)
			(layer "B.Fab")
		)
		(pad "1" smd custom
			(at 0 -0.2794 270)
			(size 0.0762 0.0762)
			(layers "B.Cu" "B.Mask" "B.Paste")
			(net "SAS0_VDDH")
			(options
				(clearance outline)
				(anchor circle)
			)
			(primitives
				(gr_poly
					(pts
						(arc
							(start 0.1524 0.127)
							(mid 0.137521 0.162921)
							(end 0.1016 0.1778)
						)
						(arc
							(start -0.1016 0.1778)
							(mid -0.137521 0.162921)
							(end -0.1524 0.127)
						)
						(arc
							(start -0.1524 -0.127)
							(mid -0.137521 -0.162921)
							(end -0.1016 -0.1778)
						)
						(arc
							(start 0.1016 -0.1778)
							(mid 0.137521 -0.162921)
							(end 0.1524 -0.127)
						)
					)
					(width 0)
					(fill yes)
				)
			)
		)
		(pad "2" smd custom
			(at 0 0.2794 270)
			(size 0.0762 0.0762)
			(layers "B.Cu" "B.Mask" "B.Paste")
			(net "GND")
			(options
				(clearance outline)
				(anchor circle)
			)
			(primitives
				(gr_poly
					(pts
						(arc
							(start 0.1524 0.127)
							(mid 0.137521 0.162921)
							(end 0.1016 0.1778)
						)
						(arc
							(start -0.1016 0.1778)
							(mid -0.137521 0.162921)
							(end -0.1524 0.127)
						)
						(arc
							(start -0.1524 -0.127)
							(mid -0.137521 -0.162921)
							(end -0.1016 -0.1778)
						)
						(arc
							(start 0.1016 -0.1778)
							(mid 0.137521 -0.162921)
							(end 0.1524 -0.127)
						)
					)
					(width 0)
					(fill yes)
				)
			)
		)
	)
	(footprint ""
		(layer "B.Cu")
		(at 90.913966 -31.623 -90)
		(property "Reference" "SC959"
			(at 0 0 90)
			(layer "B.SilkS")
			(hide yes)
			(effects
				(font
					(size 1.27 1.27)
				)
				(justify mirror)
			)
		)
		(property "Value" "SCD1U6D3V1KX-GP"
			(at 2.8321 -1.7399 270)
			(unlocked yes)
			(layer "B.Fab")
			(hide yes)
			(effects
				(font
					(size 1.016 1.016)
					(thickness 0.1524)
				)
				(justify mirror)
			)
		)
		(property "Device Type" "C0201H13"
			(at 2.8321 -3.2639 270)
			(unlocked yes)
			(layer "B.Fab")
			(hide yes)
			(effects
				(font
					(size 1.016 1.016)
					(thickness 0.1524)
				)
				(justify mirror)
			)
		)
		(duplicate_pad_numbers_are_jumpers no)
		(fp_rect
			(start 0.2794 0.6477)
			(end -0.2794 -0.6477)
			(stroke
				(width 0)
				(type default)
			)
			(fill no)
			(layer "B.CrtYd")
		)
		(fp_rect
			(start 0.2794 0.6477)
			(end -0.2794 -0.6477)
			(stroke
				(width 0)
				(type default)
			)
			(fill no)
			(layer "B.Fab")
		)
		(pad "1" smd custom
			(at 0 -0.2794 90)
			(size 0.0762 0.0762)
			(layers "B.Cu" "B.Mask" "B.Paste")
			(net "SAS0_AVDD")
			(options
				(clearance outline)
				(anchor circle)
			)
			(primitives
				(gr_poly
					(pts
						(arc
							(start 0.1524 0.127)
							(mid 0.137521 0.162921)
							(end 0.1016 0.1778)
						)
						(arc
							(start -0.1016 0.1778)
							(mid -0.137521 0.162921)
							(end -0.1524 0.127)
						)
						(arc
							(start -0.1524 -0.127)
							(mid -0.137521 -0.162921)
							(end -0.1016 -0.1778)
						)
						(arc
							(start 0.1016 -0.1778)
							(mid 0.137521 -0.162921)
							(end 0.1524 -0.127)
						)
					)
					(width 0)
					(fill yes)
				)
			)
		)
		(pad "2" smd custom
			(at 0 0.2794 90)
			(size 0.0762 0.0762)
			(layers "B.Cu" "B.Mask" "B.Paste")
			(net "GND")
			(options
				(clearance outline)
				(anchor circle)
			)
			(primitives
				(gr_poly
					(pts
						(arc
							(start 0.1524 0.127)
							(mid 0.137521 0.162921)
							(end 0.1016 0.1778)
						)
						(arc
							(start -0.1016 0.1778)
							(mid -0.137521 0.162921)
							(end -0.1524 0.127)
						)
						(arc
							(start -0.1524 -0.127)
							(mid -0.137521 -0.162921)
							(end -0.1016 -0.1778)
						)
						(arc
							(start 0.1016 -0.1778)
							(mid 0.137521 -0.162921)
							(end 0.1524 -0.127)
						)
					)
					(width 0)
					(fill yes)
				)
			)
		)
	)
	(footprint ""
		(layer "B.Cu")
		(at 87.63 -100.584 90)
		(property "Reference" "SR825"
			(at 0 0 90)
			(layer "B.SilkS")
			(hide yes)
			(effects
				(font
					(size 1.27 1.27)
				)
				(justify mirror)
			)
		)
		(property "Value" "4K75R2F-1-GP"
			(at -0.064008 -3.993896 90)
			(unlocked yes)
			(layer "B.Fab")
			(hide yes)
			(effects
				(font
					(size 1.016 1.016)
					(thickness 0.1524)
				)
				(justify mirror)
			)
		)
		(property "Device Type" "R402H16"
			(at -0.064008 -5.517896 90)
			(unlocked yes)
			(layer "B.Fab")
			(hide yes)
			(effects
				(font
					(size 1.016 1.016)
					(thickness 0.1524)
				)
				(justify mirror)
			)
		)
		(duplicate_pad_numbers_are_jumpers no)
		(fp_line
			(start 0.508 -0.9398)
			(end 0.508 0.9398)
			(stroke
				(width 0.1524)
				(type default)
			)
			(layer "B.SilkS")
		)
		(fp_line
			(start -0.508 -0.9398)
			(end 0.508 -0.9398)
			(stroke
				(width 0.1524)
				(type default)
			)
			(layer "B.SilkS")
		)
		(fp_rect
			(start 0.508 0.9398)
			(end -0.508 -0.9398)
			(stroke
				(width 0)
				(type default)
			)
			(fill no)
			(layer "B.CrtYd")
		)
		(fp_rect
			(start 0.508 0.9398)
			(end -0.508 -0.9398)
			(stroke
				(width 0)
				(type default)
			)
			(fill no)
			(layer "B.Fab")
		)
		(pad "1" smd custom
			(at 0 -0.4445 270)
			(size 0.1397 0.1397)
			(layers "B.Cu" "B.Mask" "B.Paste")
			(net "P1V8_E")
			(options
				(clearance outline)
				(anchor circle)
			)
			(primitives
				(gr_poly
					(pts
						(arc
							(start -0.1778 0.2794)
							(mid -0.249642 0.249642)
							(end -0.2794 0.1778)
						)
						(arc
							(start -0.2794 -0.1778)
							(mid -0.249642 -0.249642)
							(end -0.1778 -0.2794)
						)
						(arc
							(start 0.1778 -0.2794)
							(mid 0.249642 -0.249642)
							(end 0.2794 -0.1778)
						)
						(arc
							(start 0.2794 0.1778)
							(mid 0.249642 0.249642)
							(end 0.1778 0.2794)
						)
					)
					(width 0)
					(fill yes)
				)
			)
		)
		(pad "2" smd custom
			(at 0 0.4445 270)
			(size 0.1397 0.1397)
			(layers "B.Cu" "B.Mask" "B.Paste")
			(net "EXP_FW_DET_BOARD_VER_1")
			(options
				(clearance outline)
				(anchor circle)
			)
			(primitives
				(gr_poly
					(pts
						(arc
							(start -0.1778 0.2794)
							(mid -0.249642 0.249642)
							(end -0.2794 0.1778)
						)
						(arc
							(start -0.2794 -0.1778)
							(mid -0.249642 -0.249642)
							(end -0.1778 -0.2794)
						)
						(arc
							(start 0.1778 -0.2794)
							(mid 0.249642 -0.249642)
							(end 0.2794 -0.1778)
						)
						(arc
							(start 0.2794 0.1778)
							(mid 0.249642 0.249642)
							(end 0.1778 0.2794)
						)
					)
					(width 0)
					(fill yes)
				)
			)
		)
	)
	(footprint ""
		(layer "B.Cu")
		(at 318.008 -171.577 -90)
		(property "Reference" "R466"
			(at 0 0 90)
			(layer "B.SilkS")
			(hide yes)
			(effects
				(font
					(size 1.27 1.27)
				)
				(justify mirror)
			)
		)
		(property "Value" "0R2J-2-GP"
			(at -0.064008 -3.993896 270)
			(unlocked yes)
			(layer "B.Fab")
			(hide yes)
			(effects
				(font
					(size 1.016 1.016)
					(thickness 0.1524)
				)
				(justify mirror)
			)
		)
		(property "Device Type" "R402H16"
			(at -0.064008 -5.517896 270)
			(unlocked yes)
			(layer "B.Fab")
			(hide yes)
			(effects
				(font
					(size 1.016 1.016)
					(thickness 0.1524)
				)
				(justify mirror)
			)
		)
		(duplicate_pad_numbers_are_jumpers no)
		(fp_line
			(start -0.508 -0.9398)
			(end 0.508 -0.9398)
			(stroke
				(width 0.1524)
				(type default)
			)
			(layer "B.SilkS")
		)
		(fp_line
			(start 0.508 -0.9398)
			(end 0.508 0.9398)
			(stroke
				(width 0.1524)
				(type default)
			)
			(layer "B.SilkS")
		)
		(fp_rect
			(start 0.508 0.9398)
			(end -0.508 -0.9398)
			(stroke
				(width 0)
				(type default)
			)
			(fill no)
			(layer "B.CrtYd")
		)
		(fp_rect
			(start 0.508 0.9398)
			(end -0.508 -0.9398)
			(stroke
				(width 0)
				(type default)
			)
			(fill no)
			(layer "B.Fab")
		)
		(pad "1" smd custom
			(at 0 -0.4445 90)
			(size 0.1397 0.1397)
			(layers "B.Cu" "B.Mask" "B.Paste")
			(net "BMC_I2C_F_SCL")
			(options
				(clearance outline)
				(anchor circle)
			)
			(primitives
				(gr_poly
					(pts
						(arc
							(start -0.1778 0.2794)
							(mid -0.249642 0.249642)
							(end -0.2794 0.1778)
						)
						(arc
							(start -0.2794 -0.1778)
							(mid -0.249642 -0.249642)
							(end -0.1778 -0.2794)
						)
						(arc
							(start 0.1778 -0.2794)
							(mid 0.249642 -0.249642)
							(end 0.2794 -0.1778)
						)
						(arc
							(start 0.2794 0.1778)
							(mid 0.249642 0.249642)
							(end 0.1778 0.2794)
						)
					)
					(width 0)
					(fill yes)
				)
			)
		)
		(pad "2" smd custom
			(at 0 0.4445 90)
			(size 0.1397 0.1397)
			(layers "B.Cu" "B.Mask" "B.Paste")
			(net "BMC0_SMB8_CLK")
			(options
				(clearance outline)
				(anchor circle)
			)
			(primitives
				(gr_poly
					(pts
						(arc
							(start -0.1778 0.2794)
							(mid -0.249642 0.249642)
							(end -0.2794 0.1778)
						)
						(arc
							(start -0.2794 -0.1778)
							(mid -0.249642 -0.249642)
							(end -0.1778 -0.2794)
						)
						(arc
							(start 0.1778 -0.2794)
							(mid 0.249642 -0.249642)
							(end 0.2794 -0.1778)
						)
						(arc
							(start 0.2794 0.1778)
							(mid 0.249642 0.249642)
							(end 0.1778 0.2794)
						)
					)
					(width 0)
					(fill yes)
				)
			)
		)
	)
	(footprint ""
		(layer "B.Cu")
		(at 290.449 -167.767)
		(property "Reference" "TP142"
			(at 0 0 0)
			(layer "B.SilkS")
			(hide yes)
			(effects
				(font
					(size 1.27 1.27)
				)
				(justify mirror)
			)
		)
		(property "Value" "TPAD28"
			(at -0.0127 -1.8034 0)
			(unlocked yes)
			(layer "B.Fab")
			(hide yes)
			(effects
				(font
					(size 1.016 1.016)
					(thickness 0.1524)
				)
				(justify mirror)
			)
		)
		(property "Device Type" "TPAD28"
			(at -0.0127 -3.3274 0)
			(unlocked yes)
			(layer "B.Fab")
			(hide yes)
			(effects
				(font
					(size 1.016 1.016)
					(thickness 0.1524)
				)
				(justify mirror)
			)
		)
		(duplicate_pad_numbers_are_jumpers no)
		(fp_poly
			(pts
				(arc
					(start 0.3556 0)
					(mid -0.3556 0)
					(end 0.3556 0)
				)
			)
			(stroke
				(width 0)
				(type default)
			)
			(fill no)
			(layer "B.CrtYd")
		)
		(fp_poly
			(pts
				(arc
					(start 0.6096 0)
					(mid -0.6096 0)
					(end 0.6096 0)
				)
			)
			(stroke
				(width 0)
				(type default)
			)
			(fill no)
			(layer "B.Fab")
		)
		(pad "1" smd circle
			(at 0 0 180)
			(size 0.7112 0.7112)
			(layers "B.Cu" "B.Mask" "B.Paste")
			(net "TP_BMC_GPIOE5")
		)
	)
	(footprint ""
		(layer "B.Cu")
		(at 116.47297 -94.615 90)
		(property "Reference" "SC1219"
			(at 0 0 90)
			(layer "B.SilkS")
			(hide yes)
			(effects
				(font
					(size 1.27 1.27)
				)
				(justify mirror)
			)
		)
		(property "Value" "SC1KP50V2KX-1GP"
			(at -1.1811 -2.7051 90)
			(unlocked yes)
			(layer "B.Fab")
			(hide yes)
			(effects
				(font
					(size 1.016 1.016)
					(thickness 0.1524)
				)
				(justify mirror)
			)
		)
		(property "Device Type" "C402H22"
			(at -1.1811 -4.2291 90)
			(unlocked yes)
			(layer "B.Fab")
			(hide yes)
			(effects
				(font
					(size 1.016 1.016)
					(thickness 0.1524)
				)
				(justify mirror)
			)
		)
		(duplicate_pad_numbers_are_jumpers no)
		(fp_rect
			(start 0.4318 0.9525)
			(end -0.4318 -0.9525)
			(stroke
				(width 0)
				(type default)
			)
			(fill no)
			(layer "B.CrtYd")
		)
		(fp_rect
			(start 0.4318 0.9525)
			(end -0.4318 -0.9525)
			(stroke
				(width 0)
				(type default)
			)
			(fill no)
			(layer "B.Fab")
		)
		(pad "1" smd custom
			(at 0 -0.4445 270)
			(size 0.1524 0.1524)
			(layers "B.Cu" "B.Mask" "B.Paste")
			(net "P0V9_E")
			(options
				(clearance outline)
				(anchor circle)
			)
			(primitives
				(gr_poly
					(pts
						(arc
							(start 0.3048 0.2032)
							(mid 0.275042 0.275042)
							(end 0.2032 0.3048)
						)
						(arc
							(start -0.2032 0.3048)
							(mid -0.275042 0.275042)
							(end -0.3048 0.2032)
						)
						(arc
							(start -0.3048 -0.2032)
							(mid -0.275042 -0.275042)
							(end -0.2032 -0.3048)
						)
						(arc
							(start 0.2032 -0.3048)
							(mid 0.275042 -0.275042)
							(end 0.3048 -0.2032)
						)
					)
					(width 0)
					(fill yes)
				)
			)
		)
		(pad "2" smd custom
			(at 0 0.4445 270)
			(size 0.1524 0.1524)
			(layers "B.Cu" "B.Mask" "B.Paste")
			(net "GND")
			(options
				(clearance outline)
				(anchor circle)
			)
			(primitives
				(gr_poly
					(pts
						(arc
							(start 0.3048 0.2032)
							(mid 0.275042 0.275042)
							(end 0.2032 0.3048)
						)
						(arc
							(start -0.2032 0.3048)
							(mid -0.275042 0.275042)
							(end -0.3048 0.2032)
						)
						(arc
							(start -0.3048 -0.2032)
							(mid -0.275042 -0.275042)
							(end -0.2032 -0.3048)
						)
						(arc
							(start 0.2032 -0.3048)
							(mid 0.275042 -0.275042)
							(end 0.3048 -0.2032)
						)
					)
					(width 0)
					(fill yes)
				)
			)
		)
	)
	(footprint ""
		(layer "B.Cu")
		(at 120.30837 -97.4852 90)
		(property "Reference" "SC1141"
			(at 0 0 90)
			(layer "B.SilkS")
			(hide yes)
			(effects
				(font
					(size 1.27 1.27)
				)
				(justify mirror)
			)
		)
		(property "Value" "SCD1U6D3V1KX-GP"
			(at 2.8321 -1.7399 90)
			(unlocked yes)
			(layer "B.Fab")
			(hide yes)
			(effects
				(font
					(size 1.016 1.016)
					(thickness 0.1524)
				)
				(justify mirror)
			)
		)
		(property "Device Type" "C0201H13"
			(at 2.8321 -3.2639 90)
			(unlocked yes)
			(layer "B.Fab")
			(hide yes)
			(effects
				(font
					(size 1.016 1.016)
					(thickness 0.1524)
				)
				(justify mirror)
			)
		)
		(duplicate_pad_numbers_are_jumpers no)
		(fp_rect
			(start 0.2794 0.6477)
			(end -0.2794 -0.6477)
			(stroke
				(width 0)
				(type default)
			)
			(fill no)
			(layer "B.CrtYd")
		)
		(fp_rect
			(start 0.2794 0.6477)
			(end -0.2794 -0.6477)
			(stroke
				(width 0)
				(type default)
			)
			(fill no)
			(layer "B.Fab")
		)
		(pad "1" smd custom
			(at 0 -0.2794 270)
			(size 0.0762 0.0762)
			(layers "B.Cu" "B.Mask" "B.Paste")
			(net "GB_VDDH2")
			(options
				(clearance outline)
				(anchor circle)
			)
			(primitives
				(gr_poly
					(pts
						(arc
							(start 0.1524 0.127)
							(mid 0.137521 0.162921)
							(end 0.1016 0.1778)
						)
						(arc
							(start -0.1016 0.1778)
							(mid -0.137521 0.162921)
							(end -0.1524 0.127)
						)
						(arc
							(start -0.1524 -0.127)
							(mid -0.137521 -0.162921)
							(end -0.1016 -0.1778)
						)
						(arc
							(start 0.1016 -0.1778)
							(mid 0.137521 -0.162921)
							(end 0.1524 -0.127)
						)
					)
					(width 0)
					(fill yes)
				)
			)
		)
		(pad "2" smd custom
			(at 0 0.2794 270)
			(size 0.0762 0.0762)
			(layers "B.Cu" "B.Mask" "B.Paste")
			(net "GND")
			(options
				(clearance outline)
				(anchor circle)
			)
			(primitives
				(gr_poly
					(pts
						(arc
							(start 0.1524 0.127)
							(mid 0.137521 0.162921)
							(end 0.1016 0.1778)
						)
						(arc
							(start -0.1016 0.1778)
							(mid -0.137521 0.162921)
							(end -0.1524 0.127)
						)
						(arc
							(start -0.1524 -0.127)
							(mid -0.137521 -0.162921)
							(end -0.1016 -0.1778)
						)
						(arc
							(start 0.1016 -0.1778)
							(mid 0.137521 -0.162921)
							(end 0.1524 -0.127)
						)
					)
					(width 0)
					(fill yes)
				)
			)
		)
	)
	(footprint ""
		(layer "B.Cu")
		(at 112.630966 -33.6296)
		(property "Reference" "STP138"
			(at 0 0 0)
			(layer "B.SilkS")
			(hide yes)
			(effects
				(font
					(size 1.27 1.27)
				)
				(justify mirror)
			)
		)
		(property "Value" "TPAD28"
			(at -0.0127 -1.8034 0)
			(unlocked yes)
			(layer "B.Fab")
			(hide yes)
			(effects
				(font
					(size 1.016 1.016)
					(thickness 0.1524)
				)
				(justify mirror)
			)
		)
		(property "Device Type" "TPAD28"
			(at -0.0127 -3.3274 0)
			(unlocked yes)
			(layer "B.Fab")
			(hide yes)
			(effects
				(font
					(size 1.016 1.016)
					(thickness 0.1524)
				)
				(justify mirror)
			)
		)
		(duplicate_pad_numbers_are_jumpers no)
		(fp_poly
			(pts
				(arc
					(start 0.3556 0)
					(mid -0.3556 0)
					(end 0.3556 0)
				)
			)
			(stroke
				(width 0)
				(type default)
			)
			(fill no)
			(layer "B.CrtYd")
		)
		(fp_poly
			(pts
				(arc
					(start 0.6096 0)
					(mid -0.6096 0)
					(end 0.6096 0)
				)
			)
			(stroke
				(width 0)
				(type default)
			)
			(fill no)
			(layer "B.Fab")
		)
		(pad "1" smd circle
			(at 0 0 180)
			(size 0.7112 0.7112)
			(layers "B.Cu" "B.Mask" "B.Paste")
			(net "IOC_GPIO_20")
		)
	)
	(footprint ""
		(layer "B.Cu")
		(at 111.29137 -97.5106 90)
		(property "Reference" "SC1255"
			(at 0 0 90)
			(layer "B.SilkS")
			(hide yes)
			(effects
				(font
					(size 1.27 1.27)
				)
				(justify mirror)
			)
		)
		(property "Value" "SCD1U6D3V1KX-GP"
			(at 2.8321 -1.7399 90)
			(unlocked yes)
			(layer "B.Fab")
			(hide yes)
			(effects
				(font
					(size 1.016 1.016)
					(thickness 0.1524)
				)
				(justify mirror)
			)
		)
		(property "Device Type" "C0201H13"
			(at 2.8321 -3.2639 90)
			(unlocked yes)
			(layer "B.Fab")
			(hide yes)
			(effects
				(font
					(size 1.016 1.016)
					(thickness 0.1524)
				)
				(justify mirror)
			)
		)
		(duplicate_pad_numbers_are_jumpers no)
		(fp_rect
			(start 0.2794 0.6477)
			(end -0.2794 -0.6477)
			(stroke
				(width 0)
				(type default)
			)
			(fill no)
			(layer "B.CrtYd")
		)
		(fp_rect
			(start 0.2794 0.6477)
			(end -0.2794 -0.6477)
			(stroke
				(width 0)
				(type default)
			)
			(fill no)
			(layer "B.Fab")
		)
		(pad "1" smd custom
			(at 0 -0.2794 270)
			(size 0.0762 0.0762)
			(layers "B.Cu" "B.Mask" "B.Paste")
			(net "P0V9_E")
			(options
				(clearance outline)
				(anchor circle)
			)
			(primitives
				(gr_poly
					(pts
						(arc
							(start 0.1524 0.127)
							(mid 0.137521 0.162921)
							(end 0.1016 0.1778)
						)
						(arc
							(start -0.1016 0.1778)
							(mid -0.137521 0.162921)
							(end -0.1524 0.127)
						)
						(arc
							(start -0.1524 -0.127)
							(mid -0.137521 -0.162921)
							(end -0.1016 -0.1778)
						)
						(arc
							(start 0.1016 -0.1778)
							(mid 0.137521 -0.162921)
							(end 0.1524 -0.127)
						)
					)
					(width 0)
					(fill yes)
				)
			)
		)
		(pad "2" smd custom
			(at 0 0.2794 270)
			(size 0.0762 0.0762)
			(layers "B.Cu" "B.Mask" "B.Paste")
			(net "GND")
			(options
				(clearance outline)
				(anchor circle)
			)
			(primitives
				(gr_poly
					(pts
						(arc
							(start 0.1524 0.127)
							(mid 0.137521 0.162921)
							(end 0.1016 0.1778)
						)
						(arc
							(start -0.1016 0.1778)
							(mid -0.137521 0.162921)
							(end -0.1524 0.127)
						)
						(arc
							(start -0.1524 -0.127)
							(mid -0.137521 -0.162921)
							(end -0.1016 -0.1778)
						)
						(arc
							(start 0.1016 -0.1778)
							(mid 0.137521 -0.162921)
							(end 0.1524 -0.127)
						)
					)
					(width 0)
					(fill yes)
				)
			)
		)
	)
	(footprint ""
		(layer "B.Cu")
		(at 107.07116 -30.099)
		(property "Reference" "STP115"
			(at 0 0 0)
			(layer "B.SilkS")
			(hide yes)
			(effects
				(font
					(size 1.27 1.27)
				)
				(justify mirror)
			)
		)
		(property "Value" "TPAD28"
			(at -0.0127 -1.8034 0)
			(unlocked yes)
			(layer "B.Fab")
			(hide yes)
			(effects
				(font
					(size 1.016 1.016)
					(thickness 0.1524)
				)
				(justify mirror)
			)
		)
		(property "Device Type" "TPAD28"
			(at -0.0127 -3.3274 0)
			(unlocked yes)
			(layer "B.Fab")
			(hide yes)
			(effects
				(font
					(size 1.016 1.016)
					(thickness 0.1524)
				)
				(justify mirror)
			)
		)
		(duplicate_pad_numbers_are_jumpers no)
		(fp_poly
			(pts
				(arc
					(start 0.3556 0)
					(mid -0.3556 0)
					(end 0.3556 0)
				)
			)
			(stroke
				(width 0)
				(type default)
			)
			(fill no)
			(layer "B.CrtYd")
		)
		(fp_poly
			(pts
				(arc
					(start 0.6096 0)
					(mid -0.6096 0)
					(end 0.6096 0)
				)
			)
			(stroke
				(width 0)
				(type default)
			)
			(fill no)
			(layer "B.Fab")
		)
		(pad "1" smd circle
			(at 0 0 180)
			(size 0.7112 0.7112)
			(layers "B.Cu" "B.Mask" "B.Paste")
			(net "SYS_ERROR1")
		)
	)
	(footprint ""
		(layer "B.Cu")
		(at 115.437666 -38.1381)
		(property "Reference" "STP8"
			(at 0 0 0)
			(layer "B.SilkS")
			(hide yes)
			(effects
				(font
					(size 1.27 1.27)
				)
				(justify mirror)
			)
		)
		(property "Value" "TPAD28"
			(at -0.0127 -1.8034 0)
			(unlocked yes)
			(layer "B.Fab")
			(hide yes)
			(effects
				(font
					(size 1.016 1.016)
					(thickness 0.1524)
				)
				(justify mirror)
			)
		)
		(property "Device Type" "TPAD28"
			(at -0.0127 -3.3274 0)
			(unlocked yes)
			(layer "B.Fab")
			(hide yes)
			(effects
				(font
					(size 1.016 1.016)
					(thickness 0.1524)
				)
				(justify mirror)
			)
		)
		(duplicate_pad_numbers_are_jumpers no)
		(fp_poly
			(pts
				(arc
					(start 0.3556 0)
					(mid -0.3556 0)
					(end 0.3556 0)
				)
			)
			(stroke
				(width 0)
				(type default)
			)
			(fill no)
			(layer "B.CrtYd")
		)
		(fp_poly
			(pts
				(arc
					(start 0.6096 0)
					(mid -0.6096 0)
					(end 0.6096 0)
				)
			)
			(stroke
				(width 0)
				(type default)
			)
			(fill no)
			(layer "B.Fab")
		)
		(pad "1" smd circle
			(at 0 0 180)
			(size 0.7112 0.7112)
			(layers "B.Cu" "B.Mask" "B.Paste")
			(net "IOC_GPIO_28")
		)
	)
	(footprint ""
		(layer "B.Cu")
		(at 118.872 -44.704 -90)
		(property "Reference" "SR617"
			(at 0 0 90)
			(layer "B.SilkS")
			(hide yes)
			(effects
				(font
					(size 1.27 1.27)
				)
				(justify mirror)
			)
		)
		(property "Value" "2K2R2F-GP"
			(at -0.064008 -3.993896 270)
			(unlocked yes)
			(layer "B.Fab")
			(hide yes)
			(effects
				(font
					(size 1.016 1.016)
					(thickness 0.1524)
				)
				(justify mirror)
			)
		)
		(property "Device Type" "R402H16"
			(at -0.064008 -5.517896 270)
			(unlocked yes)
			(layer "B.Fab")
			(hide yes)
			(effects
				(font
					(size 1.016 1.016)
					(thickness 0.1524)
				)
				(justify mirror)
			)
		)
		(duplicate_pad_numbers_are_jumpers no)
		(fp_line
			(start -0.508 -0.9398)
			(end 0.508 -0.9398)
			(stroke
				(width 0.1524)
				(type default)
			)
			(layer "B.SilkS")
		)
		(fp_line
			(start 0.508 -0.9398)
			(end 0.508 0.9398)
			(stroke
				(width 0.1524)
				(type default)
			)
			(layer "B.SilkS")
		)
		(fp_rect
			(start 0.508 0.9398)
			(end -0.508 -0.9398)
			(stroke
				(width 0)
				(type default)
			)
			(fill no)
			(layer "B.CrtYd")
		)
		(fp_rect
			(start 0.508 0.9398)
			(end -0.508 -0.9398)
			(stroke
				(width 0)
				(type default)
			)
			(fill no)
			(layer "B.Fab")
		)
		(pad "1" smd custom
			(at 0 -0.4445 90)
			(size 0.1397 0.1397)
			(layers "B.Cu" "B.Mask" "B.Paste")
			(net "P1V8_C")
			(options
				(clearance outline)
				(anchor circle)
			)
			(primitives
				(gr_poly
					(pts
						(arc
							(start -0.1778 0.2794)
							(mid -0.249642 0.249642)
							(end -0.2794 0.1778)
						)
						(arc
							(start -0.2794 -0.1778)
							(mid -0.249642 -0.249642)
							(end -0.1778 -0.2794)
						)
						(arc
							(start 0.1778 -0.2794)
							(mid 0.249642 -0.249642)
							(end 0.2794 -0.1778)
						)
						(arc
							(start 0.2794 0.1778)
							(mid 0.249642 0.249642)
							(end 0.1778 0.2794)
						)
					)
					(width 0)
					(fill yes)
				)
			)
		)
		(pad "2" smd custom
			(at 0 0.4445 90)
			(size 0.1397 0.1397)
			(layers "B.Cu" "B.Mask" "B.Paste")
			(net "IOC_SDA_0")
			(options
				(clearance outline)
				(anchor circle)
			)
			(primitives
				(gr_poly
					(pts
						(arc
							(start -0.1778 0.2794)
							(mid -0.249642 0.249642)
							(end -0.2794 0.1778)
						)
						(arc
							(start -0.2794 -0.1778)
							(mid -0.249642 -0.249642)
							(end -0.1778 -0.2794)
						)
						(arc
							(start 0.1778 -0.2794)
							(mid 0.249642 -0.249642)
							(end 0.2794 -0.1778)
						)
						(arc
							(start 0.2794 0.1778)
							(mid 0.249642 0.249642)
							(end 0.1778 0.2794)
						)
					)
					(width 0)
					(fill yes)
				)
			)
		)
	)
	(footprint ""
		(layer "B.Cu")
		(at 119.13997 -105.918 180)
		(property "Reference" "SC1163"
			(at 0 0 0)
			(layer "B.SilkS")
			(hide yes)
			(effects
				(font
					(size 1.27 1.27)
				)
				(justify mirror)
			)
		)
		(property "Value" "SCD1U6D3V1KX-GP"
			(at 2.8321 -1.7399 180)
			(unlocked yes)
			(layer "B.Fab")
			(hide yes)
			(effects
				(font
					(size 1.016 1.016)
					(thickness 0.1524)
				)
				(justify mirror)
			)
		)
		(property "Device Type" "C0201H13"
			(at 2.8321 -3.2639 180)
			(unlocked yes)
			(layer "B.Fab")
			(hide yes)
			(effects
				(font
					(size 1.016 1.016)
					(thickness 0.1524)
				)
				(justify mirror)
			)
		)
		(duplicate_pad_numbers_are_jumpers no)
		(fp_rect
			(start 0.2794 0.6477)
			(end -0.2794 -0.6477)
			(stroke
				(width 0)
				(type default)
			)
			(fill no)
			(layer "B.CrtYd")
		)
		(fp_rect
			(start 0.2794 0.6477)
			(end -0.2794 -0.6477)
			(stroke
				(width 0)
				(type default)
			)
			(fill no)
			(layer "B.Fab")
		)
		(pad "1" smd custom
			(at 0 -0.2794)
			(size 0.0762 0.0762)
			(layers "B.Cu" "B.Mask" "B.Paste")
			(net "GB_VDDA")
			(options
				(clearance outline)
				(anchor circle)
			)
			(primitives
				(gr_poly
					(pts
						(arc
							(start 0.1524 0.127)
							(mid 0.137521 0.162921)
							(end 0.1016 0.1778)
						)
						(arc
							(start -0.1016 0.1778)
							(mid -0.137521 0.162921)
							(end -0.1524 0.127)
						)
						(arc
							(start -0.1524 -0.127)
							(mid -0.137521 -0.162921)
							(end -0.1016 -0.1778)
						)
						(arc
							(start 0.1016 -0.1778)
							(mid 0.137521 -0.162921)
							(end 0.1524 -0.127)
						)
					)
					(width 0)
					(fill yes)
				)
			)
		)
		(pad "2" smd custom
			(at 0 0.2794)
			(size 0.0762 0.0762)
			(layers "B.Cu" "B.Mask" "B.Paste")
			(net "GND")
			(options
				(clearance outline)
				(anchor circle)
			)
			(primitives
				(gr_poly
					(pts
						(arc
							(start 0.1524 0.127)
							(mid 0.137521 0.162921)
							(end 0.1016 0.1778)
						)
						(arc
							(start -0.1016 0.1778)
							(mid -0.137521 0.162921)
							(end -0.1524 0.127)
						)
						(arc
							(start -0.1524 -0.127)
							(mid -0.137521 -0.162921)
							(end -0.1016 -0.1778)
						)
						(arc
							(start 0.1016 -0.1778)
							(mid 0.137521 -0.162921)
							(end 0.1524 -0.127)
						)
					)
					(width 0)
					(fill yes)
				)
			)
		)
	)
	(footprint ""
		(layer "B.Cu")
		(at 121.417842 -84.907882 90)
		(property "Reference" "SR802"
			(at 0 0 90)
			(layer "B.SilkS")
			(hide yes)
			(effects
				(font
					(size 1.27 1.27)
				)
				(justify mirror)
			)
		)
		(property "Value" "4K75R2F-1-GP"
			(at -0.064008 -3.993896 90)
			(unlocked yes)
			(layer "B.Fab")
			(hide yes)
			(effects
				(font
					(size 1.016 1.016)
					(thickness 0.1524)
				)
				(justify mirror)
			)
		)
		(property "Device Type" "R402H16"
			(at -0.064008 -5.517896 90)
			(unlocked yes)
			(layer "B.Fab")
			(hide yes)
			(effects
				(font
					(size 1.016 1.016)
					(thickness 0.1524)
				)
				(justify mirror)
			)
		)
		(duplicate_pad_numbers_are_jumpers no)
		(fp_line
			(start 0.508 -0.9398)
			(end 0.508 0.9398)
			(stroke
				(width 0.1524)
				(type default)
			)
			(layer "B.SilkS")
		)
		(fp_line
			(start -0.508 -0.9398)
			(end 0.508 -0.9398)
			(stroke
				(width 0.1524)
				(type default)
			)
			(layer "B.SilkS")
		)
		(fp_rect
			(start 0.508 0.9398)
			(end -0.508 -0.9398)
			(stroke
				(width 0)
				(type default)
			)
			(fill no)
			(layer "B.CrtYd")
		)
		(fp_rect
			(start 0.508 0.9398)
			(end -0.508 -0.9398)
			(stroke
				(width 0)
				(type default)
			)
			(fill no)
			(layer "B.Fab")
		)
		(pad "1" smd custom
			(at 0 -0.4445 270)
			(size 0.1397 0.1397)
			(layers "B.Cu" "B.Mask" "B.Paste")
			(net "TEST_MUX_47")
			(options
				(clearance outline)
				(anchor circle)
			)
			(primitives
				(gr_poly
					(pts
						(arc
							(start -0.1778 0.2794)
							(mid -0.249642 0.249642)
							(end -0.2794 0.1778)
						)
						(arc
							(start -0.2794 -0.1778)
							(mid -0.249642 -0.249642)
							(end -0.1778 -0.2794)
						)
						(arc
							(start 0.1778 -0.2794)
							(mid 0.249642 -0.249642)
							(end 0.2794 -0.1778)
						)
						(arc
							(start 0.2794 0.1778)
							(mid 0.249642 0.249642)
							(end 0.1778 0.2794)
						)
					)
					(width 0)
					(fill yes)
				)
			)
		)
		(pad "2" smd custom
			(at 0 0.4445 270)
			(size 0.1397 0.1397)
			(layers "B.Cu" "B.Mask" "B.Paste")
			(net "GND")
			(options
				(clearance outline)
				(anchor circle)
			)
			(primitives
				(gr_poly
					(pts
						(arc
							(start -0.1778 0.2794)
							(mid -0.249642 0.249642)
							(end -0.2794 0.1778)
						)
						(arc
							(start -0.2794 -0.1778)
							(mid -0.249642 -0.249642)
							(end -0.1778 -0.2794)
						)
						(arc
							(start 0.1778 -0.2794)
							(mid 0.249642 -0.249642)
							(end 0.2794 -0.1778)
						)
						(arc
							(start 0.2794 0.1778)
							(mid 0.249642 0.249642)
							(end 0.1778 0.2794)
						)
					)
					(width 0)
					(fill yes)
				)
			)
		)
	)
	(footprint ""
		(layer "B.Cu")
		(at 294.132 -164.211 180)
		(property "Reference" "R287"
			(at 0 0 0)
			(layer "B.SilkS")
			(hide yes)
			(effects
				(font
					(size 1.27 1.27)
				)
				(justify mirror)
			)
		)
		(property "Value" "0R2J-2-GP"
			(at -0.064008 -3.993896 180)
			(unlocked yes)
			(layer "B.Fab")
			(hide yes)
			(effects
				(font
					(size 1.016 1.016)
					(thickness 0.1524)
				)
				(justify mirror)
			)
		)
		(property "Device Type" "R402H16"
			(at -0.064008 -5.517896 180)
			(unlocked yes)
			(layer "B.Fab")
			(hide yes)
			(effects
				(font
					(size 1.016 1.016)
					(thickness 0.1524)
				)
				(justify mirror)
			)
		)
		(duplicate_pad_numbers_are_jumpers no)
		(fp_line
			(start 0.508 -0.9398)
			(end 0.508 0.9398)
			(stroke
				(width 0.1524)
				(type default)
			)
			(layer "B.SilkS")
		)
		(fp_line
			(start -0.508 -0.9398)
			(end 0.508 -0.9398)
			(stroke
				(width 0.1524)
				(type default)
			)
			(layer "B.SilkS")
		)
		(fp_rect
			(start 0.508 0.9398)
			(end -0.508 -0.9398)
			(stroke
				(width 0)
				(type default)
			)
			(fill no)
			(layer "B.CrtYd")
		)
		(fp_rect
			(start 0.508 0.9398)
			(end -0.508 -0.9398)
			(stroke
				(width 0)
				(type default)
			)
			(fill no)
			(layer "B.Fab")
		)
		(pad "1" smd custom
			(at 0 -0.4445)
			(size 0.1397 0.1397)
			(layers "B.Cu" "B.Mask" "B.Paste")
			(net "RMII_BMC_RX_ER")
			(options
				(clearance outline)
				(anchor circle)
			)
			(primitives
				(gr_poly
					(pts
						(arc
							(start -0.1778 0.2794)
							(mid -0.249642 0.249642)
							(end -0.2794 0.1778)
						)
						(arc
							(start -0.2794 -0.1778)
							(mid -0.249642 -0.249642)
							(end -0.1778 -0.2794)
						)
						(arc
							(start 0.1778 -0.2794)
							(mid 0.249642 -0.249642)
							(end 0.2794 -0.1778)
						)
						(arc
							(start 0.2794 0.1778)
							(mid 0.249642 0.249642)
							(end 0.1778 0.2794)
						)
					)
					(width 0)
					(fill yes)
				)
			)
		)
		(pad "2" smd custom
			(at 0 0.4445)
			(size 0.1397 0.1397)
			(layers "B.Cu" "B.Mask" "B.Paste")
			(net "RMII0_BMC_C_RX_ER")
			(options
				(clearance outline)
				(anchor circle)
			)
			(primitives
				(gr_poly
					(pts
						(arc
							(start -0.1778 0.2794)
							(mid -0.249642 0.249642)
							(end -0.2794 0.1778)
						)
						(arc
							(start -0.2794 -0.1778)
							(mid -0.249642 -0.249642)
							(end -0.1778 -0.2794)
						)
						(arc
							(start 0.1778 -0.2794)
							(mid 0.249642 -0.249642)
							(end 0.2794 -0.1778)
						)
						(arc
							(start 0.2794 0.1778)
							(mid 0.249642 0.249642)
							(end 0.1778 0.2794)
						)
					)
					(width 0)
					(fill yes)
				)
			)
		)
	)
	(footprint ""
		(layer "B.Cu")
		(at 124.403612 -213.36 90)
		(property "Reference" "SR911"
			(at 0 0 90)
			(layer "B.SilkS")
			(hide yes)
			(effects
				(font
					(size 1.27 1.27)
				)
				(justify mirror)
			)
		)
		(property "Value" "4K7R2F-GP"
			(at -0.064008 -3.993896 90)
			(unlocked yes)
			(layer "B.Fab")
			(hide yes)
			(effects
				(font
					(size 1.016 1.016)
					(thickness 0.1524)
				)
				(justify mirror)
			)
		)
		(property "Device Type" "R402H16"
			(at -0.064008 -5.517896 90)
			(unlocked yes)
			(layer "B.Fab")
			(hide yes)
			(effects
				(font
					(size 1.016 1.016)
					(thickness 0.1524)
				)
				(justify mirror)
			)
		)
		(duplicate_pad_numbers_are_jumpers no)
		(fp_line
			(start 0.508 -0.9398)
			(end 0.508 0.9398)
			(stroke
				(width 0.1524)
				(type default)
			)
			(layer "B.SilkS")
		)
		(fp_line
			(start -0.508 -0.9398)
			(end 0.508 -0.9398)
			(stroke
				(width 0.1524)
				(type default)
			)
			(layer "B.SilkS")
		)
		(fp_rect
			(start 0.508 0.9398)
			(end -0.508 -0.9398)
			(stroke
				(width 0)
				(type default)
			)
			(fill no)
			(layer "B.CrtYd")
		)
		(fp_rect
			(start 0.508 0.9398)
			(end -0.508 -0.9398)
			(stroke
				(width 0)
				(type default)
			)
			(fill no)
			(layer "B.Fab")
		)
		(pad "1" smd custom
			(at 0 -0.4445 270)
			(size 0.1397 0.1397)
			(layers "B.Cu" "B.Mask" "B.Paste")
			(net "REDV_I2C_SEL2A")
			(options
				(clearance outline)
				(anchor circle)
			)
			(primitives
				(gr_poly
					(pts
						(arc
							(start -0.1778 0.2794)
							(mid -0.249642 0.249642)
							(end -0.2794 0.1778)
						)
						(arc
							(start -0.2794 -0.1778)
							(mid -0.249642 -0.249642)
							(end -0.1778 -0.2794)
						)
						(arc
							(start 0.1778 -0.2794)
							(mid 0.249642 -0.249642)
							(end 0.2794 -0.1778)
						)
						(arc
							(start 0.2794 0.1778)
							(mid 0.249642 0.249642)
							(end 0.1778 0.2794)
						)
					)
					(width 0)
					(fill yes)
				)
			)
		)
		(pad "2" smd custom
			(at 0 0.4445 270)
			(size 0.1397 0.1397)
			(layers "B.Cu" "B.Mask" "B.Paste")
			(net "GND")
			(options
				(clearance outline)
				(anchor circle)
			)
			(primitives
				(gr_poly
					(pts
						(arc
							(start -0.1778 0.2794)
							(mid -0.249642 0.249642)
							(end -0.2794 0.1778)
						)
						(arc
							(start -0.2794 -0.1778)
							(mid -0.249642 -0.249642)
							(end -0.1778 -0.2794)
						)
						(arc
							(start 0.1778 -0.2794)
							(mid 0.249642 -0.249642)
							(end 0.2794 -0.1778)
						)
						(arc
							(start 0.2794 0.1778)
							(mid 0.249642 0.249642)
							(end 0.1778 0.2794)
						)
					)
					(width 0)
					(fill yes)
				)
			)
		)
	)
	(footprint ""
		(layer "B.Cu")
		(at 114.014504 -49.59985)
		(property "Reference" "STP160"
			(at 0 0 0)
			(layer "B.SilkS")
			(hide yes)
			(effects
				(font
					(size 1.27 1.27)
				)
				(justify mirror)
			)
		)
		(property "Value" "TPAD28"
			(at -0.0127 -1.8034 0)
			(unlocked yes)
			(layer "B.Fab")
			(hide yes)
			(effects
				(font
					(size 1.016 1.016)
					(thickness 0.1524)
				)
				(justify mirror)
			)
		)
		(property "Device Type" "TPAD28"
			(at -0.0127 -3.3274 0)
			(unlocked yes)
			(layer "B.Fab")
			(hide yes)
			(effects
				(font
					(size 1.016 1.016)
					(thickness 0.1524)
				)
				(justify mirror)
			)
		)
		(duplicate_pad_numbers_are_jumpers no)
		(fp_poly
			(pts
				(arc
					(start 0.3556 0)
					(mid -0.3556 0)
					(end 0.3556 0)
				)
			)
			(stroke
				(width 0)
				(type default)
			)
			(fill no)
			(layer "B.CrtYd")
		)
		(fp_poly
			(pts
				(arc
					(start 0.6096 0)
					(mid -0.6096 0)
					(end 0.6096 0)
				)
			)
			(stroke
				(width 0)
				(type default)
			)
			(fill no)
			(layer "B.Fab")
		)
		(pad "1" smd circle
			(at 0 0 180)
			(size 0.7112 0.7112)
			(layers "B.Cu" "B.Mask" "B.Paste")
			(net "XM_ADDR_24")
		)
	)
	(footprint ""
		(layer "B.Cu")
		(at 317.5 -182.753 -90)
		(property "Reference" "R3099"
			(at 0 0 90)
			(layer "B.SilkS")
			(hide yes)
			(effects
				(font
					(size 1.27 1.27)
				)
				(justify mirror)
			)
		)
		(property "Value" "1KR2F-3-GP"
			(at -0.064008 -3.993896 270)
			(unlocked yes)
			(layer "B.Fab")
			(hide yes)
			(effects
				(font
					(size 1.016 1.016)
					(thickness 0.1524)
				)
				(justify mirror)
			)
		)
		(property "Device Type" "R402H16"
			(at -0.064008 -5.517896 270)
			(unlocked yes)
			(layer "B.Fab")
			(hide yes)
			(effects
				(font
					(size 1.016 1.016)
					(thickness 0.1524)
				)
				(justify mirror)
			)
		)
		(duplicate_pad_numbers_are_jumpers no)
		(fp_line
			(start -0.508 -0.9398)
			(end 0.508 -0.9398)
			(stroke
				(width 0.1524)
				(type default)
			)
			(layer "B.SilkS")
		)
		(fp_line
			(start 0.508 -0.9398)
			(end 0.508 0.9398)
			(stroke
				(width 0.1524)
				(type default)
			)
			(layer "B.SilkS")
		)
		(fp_rect
			(start 0.508 0.9398)
			(end -0.508 -0.9398)
			(stroke
				(width 0)
				(type default)
			)
			(fill no)
			(layer "B.CrtYd")
		)
		(fp_rect
			(start 0.508 0.9398)
			(end -0.508 -0.9398)
			(stroke
				(width 0)
				(type default)
			)
			(fill no)
			(layer "B.Fab")
		)
		(pad "1" smd custom
			(at 0 -0.4445 90)
			(size 0.1397 0.1397)
			(layers "B.Cu" "B.Mask" "B.Paste")
			(net "ADC_P1V5_E")
			(options
				(clearance outline)
				(anchor circle)
			)
			(primitives
				(gr_poly
					(pts
						(arc
							(start -0.1778 0.2794)
							(mid -0.249642 0.249642)
							(end -0.2794 0.1778)
						)
						(arc
							(start -0.2794 -0.1778)
							(mid -0.249642 -0.249642)
							(end -0.1778 -0.2794)
						)
						(arc
							(start 0.1778 -0.2794)
							(mid 0.249642 -0.249642)
							(end 0.2794 -0.1778)
						)
						(arc
							(start 0.2794 0.1778)
							(mid 0.249642 0.249642)
							(end 0.1778 0.2794)
						)
					)
					(width 0)
					(fill yes)
				)
			)
		)
		(pad "2" smd custom
			(at 0 0.4445 90)
			(size 0.1397 0.1397)
			(layers "B.Cu" "B.Mask" "B.Paste")
			(net "GND")
			(options
				(clearance outline)
				(anchor circle)
			)
			(primitives
				(gr_poly
					(pts
						(arc
							(start -0.1778 0.2794)
							(mid -0.249642 0.249642)
							(end -0.2794 0.1778)
						)
						(arc
							(start -0.2794 -0.1778)
							(mid -0.249642 -0.249642)
							(end -0.1778 -0.2794)
						)
						(arc
							(start 0.1778 -0.2794)
							(mid 0.249642 -0.249642)
							(end 0.2794 -0.1778)
						)
						(arc
							(start 0.2794 0.1778)
							(mid 0.249642 0.249642)
							(end 0.1778 0.2794)
						)
					)
					(width 0)
					(fill yes)
				)
			)
		)
	)
	(footprint ""
		(layer "B.Cu")
		(at 324.358 -179.705 180)
		(property "Reference" "C8087"
			(at 0 0 0)
			(layer "B.SilkS")
			(hide yes)
			(effects
				(font
					(size 1.27 1.27)
				)
				(justify mirror)
			)
		)
		(property "Value" "SCD1U25V2KX-2-GP"
			(at -1.1811 -2.7051 180)
			(unlocked yes)
			(layer "B.Fab")
			(hide yes)
			(effects
				(font
					(size 1.016 1.016)
					(thickness 0.1524)
				)
				(justify mirror)
			)
		)
		(property "Device Type" "C402H22"
			(at -1.1811 -4.2291 180)
			(unlocked yes)
			(layer "B.Fab")
			(hide yes)
			(effects
				(font
					(size 1.016 1.016)
					(thickness 0.1524)
				)
				(justify mirror)
			)
		)
		(duplicate_pad_numbers_are_jumpers no)
		(fp_rect
			(start 0.4318 0.9525)
			(end -0.4318 -0.9525)
			(stroke
				(width 0)
				(type default)
			)
			(fill no)
			(layer "B.CrtYd")
		)
		(fp_rect
			(start 0.4318 0.9525)
			(end -0.4318 -0.9525)
			(stroke
				(width 0)
				(type default)
			)
			(fill no)
			(layer "B.Fab")
		)
		(pad "1" smd custom
			(at 0 -0.4445)
			(size 0.1524 0.1524)
			(layers "B.Cu" "B.Mask" "B.Paste")
			(net "ADC_P3V3_STBY")
			(options
				(clearance outline)
				(anchor circle)
			)
			(primitives
				(gr_poly
					(pts
						(arc
							(start 0.3048 0.2032)
							(mid 0.275042 0.275042)
							(end 0.2032 0.3048)
						)
						(arc
							(start -0.2032 0.3048)
							(mid -0.275042 0.275042)
							(end -0.3048 0.2032)
						)
						(arc
							(start -0.3048 -0.2032)
							(mid -0.275042 -0.275042)
							(end -0.2032 -0.3048)
						)
						(arc
							(start 0.2032 -0.3048)
							(mid 0.275042 -0.275042)
							(end 0.3048 -0.2032)
						)
					)
					(width 0)
					(fill yes)
				)
			)
		)
		(pad "2" smd custom
			(at 0 0.4445)
			(size 0.1524 0.1524)
			(layers "B.Cu" "B.Mask" "B.Paste")
			(net "GND")
			(options
				(clearance outline)
				(anchor circle)
			)
			(primitives
				(gr_poly
					(pts
						(arc
							(start 0.3048 0.2032)
							(mid 0.275042 0.275042)
							(end 0.2032 0.3048)
						)
						(arc
							(start -0.2032 0.3048)
							(mid -0.275042 0.275042)
							(end -0.3048 0.2032)
						)
						(arc
							(start -0.3048 -0.2032)
							(mid -0.275042 -0.275042)
							(end -0.2032 -0.3048)
						)
						(arc
							(start 0.2032 -0.3048)
							(mid 0.275042 -0.275042)
							(end 0.3048 -0.2032)
						)
					)
					(width 0)
					(fill yes)
				)
			)
		)
	)
	(footprint ""
		(layer "B.Cu")
		(at 101.480366 -41.91 -90)
		(property "Reference" "SC1027"
			(at 0 0 90)
			(layer "B.SilkS")
			(hide yes)
			(effects
				(font
					(size 1.27 1.27)
				)
				(justify mirror)
			)
		)
		(property "Value" "SC1U10V2KX-4-GP"
			(at -1.1811 -2.7051 270)
			(unlocked yes)
			(layer "B.Fab")
			(hide yes)
			(effects
				(font
					(size 1.016 1.016)
					(thickness 0.1524)
				)
				(justify mirror)
			)
		)
		(property "Device Type" "C402H22"
			(at -1.1811 -4.2291 270)
			(unlocked yes)
			(layer "B.Fab")
			(hide yes)
			(effects
				(font
					(size 1.016 1.016)
					(thickness 0.1524)
				)
				(justify mirror)
			)
		)
		(duplicate_pad_numbers_are_jumpers no)
		(fp_rect
			(start 0.4318 0.9525)
			(end -0.4318 -0.9525)
			(stroke
				(width 0)
				(type default)
			)
			(fill no)
			(layer "B.CrtYd")
		)
		(fp_rect
			(start 0.4318 0.9525)
			(end -0.4318 -0.9525)
			(stroke
				(width 0)
				(type default)
			)
			(fill no)
			(layer "B.Fab")
		)
		(pad "1" smd custom
			(at 0 -0.4445 90)
			(size 0.1524 0.1524)
			(layers "B.Cu" "B.Mask" "B.Paste")
			(net "P0V955_C")
			(options
				(clearance outline)
				(anchor circle)
			)
			(primitives
				(gr_poly
					(pts
						(arc
							(start 0.3048 0.2032)
							(mid 0.275042 0.275042)
							(end 0.2032 0.3048)
						)
						(arc
							(start -0.2032 0.3048)
							(mid -0.275042 0.275042)
							(end -0.3048 0.2032)
						)
						(arc
							(start -0.3048 -0.2032)
							(mid -0.275042 -0.275042)
							(end -0.2032 -0.3048)
						)
						(arc
							(start 0.2032 -0.3048)
							(mid 0.275042 -0.275042)
							(end 0.3048 -0.2032)
						)
					)
					(width 0)
					(fill yes)
				)
			)
		)
		(pad "2" smd custom
			(at 0 0.4445 90)
			(size 0.1524 0.1524)
			(layers "B.Cu" "B.Mask" "B.Paste")
			(net "GND")
			(options
				(clearance outline)
				(anchor circle)
			)
			(primitives
				(gr_poly
					(pts
						(arc
							(start 0.3048 0.2032)
							(mid 0.275042 0.275042)
							(end 0.2032 0.3048)
						)
						(arc
							(start -0.2032 0.3048)
							(mid -0.275042 0.275042)
							(end -0.3048 0.2032)
						)
						(arc
							(start -0.3048 -0.2032)
							(mid -0.275042 -0.275042)
							(end -0.2032 -0.3048)
						)
						(arc
							(start 0.2032 -0.3048)
							(mid 0.275042 -0.275042)
							(end 0.3048 -0.2032)
						)
					)
					(width 0)
					(fill yes)
				)
			)
		)
	)
	(footprint ""
		(layer "B.Cu")
		(at 163.957 -117.475)
		(property "Reference" "SQ12"
			(at 0 0 0)
			(layer "B.SilkS")
			(hide yes)
			(effects
				(font
					(size 1.27 1.27)
				)
				(justify mirror)
			)
		)
		(property "Value" "2N7002A-7-GP"
			(at -0.127 -8.9662 0)
			(unlocked yes)
			(layer "B.Fab")
			(hide yes)
			(effects
				(font
					(size 1.016 1.016)
					(thickness 0.1524)
				)
				(justify mirror)
			)
		)
		(property "Device Type" "SOT23DGS2D4H48"
			(at -0.127 -10.4902 0)
			(unlocked yes)
			(layer "B.Fab")
			(hide yes)
			(effects
				(font
					(size 1.016 1.016)
					(thickness 0.1524)
				)
				(justify mirror)
			)
		)
		(duplicate_pad_numbers_are_jumpers no)
		(fp_line
			(start -1.651 -1.778)
			(end 1.651 -1.778)
			(stroke
				(width 0.1524)
				(type default)
			)
			(layer "B.SilkS")
		)
		(fp_line
			(start -1.651 1.778)
			(end -1.651 -1.778)
			(stroke
				(width 0.1524)
				(type default)
			)
			(layer "B.SilkS")
		)
		(fp_line
			(start 1.651 -1.778)
			(end 1.651 1.778)
			(stroke
				(width 0.1524)
				(type default)
			)
			(layer "B.SilkS")
		)
		(fp_line
			(start 1.651 1.778)
			(end -1.651 1.778)
			(stroke
				(width 0.1524)
				(type default)
			)
			(layer "B.SilkS")
		)
		(fp_poly
			(pts
				(xy 1.778 1.8796) (xy 1.778 -1.8796) (xy -1.778 -1.8796) (xy -1.778 1.8796)
			)
			(stroke
				(width 0)
				(type default)
			)
			(fill no)
			(layer "B.CrtYd")
		)
		(fp_poly
			(pts
				(xy 1.778 1.8796) (xy 1.778 -1.8796) (xy -1.778 -1.8796) (xy -1.778 1.8796)
			)
			(stroke
				(width 0)
				(type default)
			)
			(fill no)
			(layer "B.Fab")
		)
		(pad "D" smd custom
			(at 0 -0.9525 180)
			(size 0.1905 0.1905)
			(layers "B.Cu" "B.Mask" "B.Paste")
			(net "EXP_RST")
			(options
				(clearance outline)
				(anchor circle)
			)
			(primitives
				(gr_poly
					(pts
						(arc
							(start -0.1778 -0.5715)
							(mid -0.321484 -0.511984)
							(end -0.381 -0.3683)
						)
						(arc
							(start -0.381 0.3683)
							(mid -0.321484 0.511984)
							(end -0.1778 0.5715)
						)
						(arc
							(start 0.1778 0.5715)
							(mid 0.321484 0.511984)
							(end 0.381 0.3683)
						)
						(arc
							(start 0.381 -0.3683)
							(mid 0.321484 -0.511984)
							(end 0.1778 -0.5715)
						)
					)
					(width 0)
					(fill yes)
				)
			)
		)
		(pad "G" smd custom
			(at 0.98425 0.9525 180)
			(size 0.1905 0.1905)
			(layers "B.Cu" "B.Mask" "B.Paste")
			(net "P3V3_STBY_G4")
			(options
				(clearance outline)
				(anchor circle)
			)
			(primitives
				(gr_poly
					(pts
						(arc
							(start -0.1778 -0.5715)
							(mid -0.321484 -0.511984)
							(end -0.381 -0.3683)
						)
						(arc
							(start -0.381 0.3683)
							(mid -0.321484 0.511984)
							(end -0.1778 0.5715)
						)
						(arc
							(start 0.1778 0.5715)
							(mid 0.321484 0.511984)
							(end 0.381 0.3683)
						)
						(arc
							(start 0.381 -0.3683)
							(mid 0.321484 -0.511984)
							(end 0.1778 -0.5715)
						)
					)
					(width 0)
					(fill yes)
				)
			)
		)
		(pad "S" smd custom
			(at -0.98425 0.9525 180)
			(size 0.1905 0.1905)
			(layers "B.Cu" "B.Mask" "B.Paste")
			(net "GND")
			(options
				(clearance outline)
				(anchor circle)
			)
			(primitives
				(gr_poly
					(pts
						(arc
							(start -0.1778 -0.5715)
							(mid -0.321484 -0.511984)
							(end -0.381 -0.3683)
						)
						(arc
							(start -0.381 0.3683)
							(mid -0.321484 0.511984)
							(end -0.1778 0.5715)
						)
						(arc
							(start 0.1778 0.5715)
							(mid 0.321484 0.511984)
							(end 0.381 0.3683)
						)
						(arc
							(start 0.381 -0.3683)
							(mid 0.321484 -0.511984)
							(end 0.1778 -0.5715)
						)
					)
					(width 0)
					(fill yes)
				)
			)
		)
	)
	(footprint ""
		(layer "B.Cu")
		(at 123.298966 -45.466 90)
		(property "Reference" "SC974"
			(at 0 0 90)
			(layer "B.SilkS")
			(hide yes)
			(effects
				(font
					(size 1.27 1.27)
				)
				(justify mirror)
			)
		)
		(property "Value" "SCD1U16V2KX-3GP"
			(at -1.1811 -2.7051 90)
			(unlocked yes)
			(layer "B.Fab")
			(hide yes)
			(effects
				(font
					(size 1.016 1.016)
					(thickness 0.1524)
				)
				(justify mirror)
			)
		)
		(property "Device Type" "C402H22"
			(at -1.1811 -4.2291 90)
			(unlocked yes)
			(layer "B.Fab")
			(hide yes)
			(effects
				(font
					(size 1.016 1.016)
					(thickness 0.1524)
				)
				(justify mirror)
			)
		)
		(duplicate_pad_numbers_are_jumpers no)
		(fp_rect
			(start 0.4318 0.9525)
			(end -0.4318 -0.9525)
			(stroke
				(width 0)
				(type default)
			)
			(fill no)
			(layer "B.CrtYd")
		)
		(fp_rect
			(start 0.4318 0.9525)
			(end -0.4318 -0.9525)
			(stroke
				(width 0)
				(type default)
			)
			(fill no)
			(layer "B.Fab")
		)
		(pad "1" smd custom
			(at 0 -0.4445 270)
			(size 0.1524 0.1524)
			(layers "B.Cu" "B.Mask" "B.Paste")
			(net "P1V8_C")
			(options
				(clearance outline)
				(anchor circle)
			)
			(primitives
				(gr_poly
					(pts
						(arc
							(start 0.3048 0.2032)
							(mid 0.275042 0.275042)
							(end 0.2032 0.3048)
						)
						(arc
							(start -0.2032 0.3048)
							(mid -0.275042 0.275042)
							(end -0.3048 0.2032)
						)
						(arc
							(start -0.3048 -0.2032)
							(mid -0.275042 -0.275042)
							(end -0.2032 -0.3048)
						)
						(arc
							(start 0.2032 -0.3048)
							(mid 0.275042 -0.275042)
							(end 0.3048 -0.2032)
						)
					)
					(width 0)
					(fill yes)
				)
			)
		)
		(pad "2" smd custom
			(at 0 0.4445 270)
			(size 0.1524 0.1524)
			(layers "B.Cu" "B.Mask" "B.Paste")
			(net "GND")
			(options
				(clearance outline)
				(anchor circle)
			)
			(primitives
				(gr_poly
					(pts
						(arc
							(start 0.3048 0.2032)
							(mid 0.275042 0.275042)
							(end 0.2032 0.3048)
						)
						(arc
							(start -0.2032 0.3048)
							(mid -0.275042 0.275042)
							(end -0.3048 0.2032)
						)
						(arc
							(start -0.3048 -0.2032)
							(mid -0.275042 -0.275042)
							(end -0.2032 -0.3048)
						)
						(arc
							(start 0.2032 -0.3048)
							(mid 0.275042 -0.275042)
							(end 0.3048 -0.2032)
						)
					)
					(width 0)
					(fill yes)
				)
			)
		)
	)
	(footprint ""
		(layer "B.Cu")
		(at 116.85397 -102.616 -90)
		(property "Reference" "SC1169"
			(at 0 0 90)
			(layer "B.SilkS")
			(hide yes)
			(effects
				(font
					(size 1.27 1.27)
				)
				(justify mirror)
			)
		)
		(property "Value" "SCD1U6D3V1KX-GP"
			(at 2.8321 -1.7399 270)
			(unlocked yes)
			(layer "B.Fab")
			(hide yes)
			(effects
				(font
					(size 1.016 1.016)
					(thickness 0.1524)
				)
				(justify mirror)
			)
		)
		(property "Device Type" "C0201H13"
			(at 2.8321 -3.2639 270)
			(unlocked yes)
			(layer "B.Fab")
			(hide yes)
			(effects
				(font
					(size 1.016 1.016)
					(thickness 0.1524)
				)
				(justify mirror)
			)
		)
		(duplicate_pad_numbers_are_jumpers no)
		(fp_rect
			(start 0.2794 0.6477)
			(end -0.2794 -0.6477)
			(stroke
				(width 0)
				(type default)
			)
			(fill no)
			(layer "B.CrtYd")
		)
		(fp_rect
			(start 0.2794 0.6477)
			(end -0.2794 -0.6477)
			(stroke
				(width 0)
				(type default)
			)
			(fill no)
			(layer "B.Fab")
		)
		(pad "1" smd custom
			(at 0 -0.2794 90)
			(size 0.0762 0.0762)
			(layers "B.Cu" "B.Mask" "B.Paste")
			(net "GB_VDDA")
			(options
				(clearance outline)
				(anchor circle)
			)
			(primitives
				(gr_poly
					(pts
						(arc
							(start 0.1524 0.127)
							(mid 0.137521 0.162921)
							(end 0.1016 0.1778)
						)
						(arc
							(start -0.1016 0.1778)
							(mid -0.137521 0.162921)
							(end -0.1524 0.127)
						)
						(arc
							(start -0.1524 -0.127)
							(mid -0.137521 -0.162921)
							(end -0.1016 -0.1778)
						)
						(arc
							(start 0.1016 -0.1778)
							(mid 0.137521 -0.162921)
							(end 0.1524 -0.127)
						)
					)
					(width 0)
					(fill yes)
				)
			)
		)
		(pad "2" smd custom
			(at 0 0.2794 90)
			(size 0.0762 0.0762)
			(layers "B.Cu" "B.Mask" "B.Paste")
			(net "GND")
			(options
				(clearance outline)
				(anchor circle)
			)
			(primitives
				(gr_poly
					(pts
						(arc
							(start 0.1524 0.127)
							(mid 0.137521 0.162921)
							(end 0.1016 0.1778)
						)
						(arc
							(start -0.1016 0.1778)
							(mid -0.137521 0.162921)
							(end -0.1524 0.127)
						)
						(arc
							(start -0.1524 -0.127)
							(mid -0.137521 -0.162921)
							(end -0.1016 -0.1778)
						)
						(arc
							(start 0.1016 -0.1778)
							(mid 0.137521 -0.162921)
							(end 0.1524 -0.127)
						)
					)
					(width 0)
					(fill yes)
				)
			)
		)
	)
	(footprint ""
		(layer "B.Cu")
		(at 120.30837 -94.615 90)
		(property "Reference" "SC1142"
			(at 0 0 90)
			(layer "B.SilkS")
			(hide yes)
			(effects
				(font
					(size 1.27 1.27)
				)
				(justify mirror)
			)
		)
		(property "Value" "SCD1U6D3V1KX-GP"
			(at 2.8321 -1.7399 90)
			(unlocked yes)
			(layer "B.Fab")
			(hide yes)
			(effects
				(font
					(size 1.016 1.016)
					(thickness 0.1524)
				)
				(justify mirror)
			)
		)
		(property "Device Type" "C0201H13"
			(at 2.8321 -3.2639 90)
			(unlocked yes)
			(layer "B.Fab")
			(hide yes)
			(effects
				(font
					(size 1.016 1.016)
					(thickness 0.1524)
				)
				(justify mirror)
			)
		)
		(duplicate_pad_numbers_are_jumpers no)
		(fp_rect
			(start 0.2794 0.6477)
			(end -0.2794 -0.6477)
			(stroke
				(width 0)
				(type default)
			)
			(fill no)
			(layer "B.CrtYd")
		)
		(fp_rect
			(start 0.2794 0.6477)
			(end -0.2794 -0.6477)
			(stroke
				(width 0)
				(type default)
			)
			(fill no)
			(layer "B.Fab")
		)
		(pad "1" smd custom
			(at 0 -0.2794 270)
			(size 0.0762 0.0762)
			(layers "B.Cu" "B.Mask" "B.Paste")
			(net "GB_VDDH2")
			(options
				(clearance outline)
				(anchor circle)
			)
			(primitives
				(gr_poly
					(pts
						(arc
							(start 0.1524 0.127)
							(mid 0.137521 0.162921)
							(end 0.1016 0.1778)
						)
						(arc
							(start -0.1016 0.1778)
							(mid -0.137521 0.162921)
							(end -0.1524 0.127)
						)
						(arc
							(start -0.1524 -0.127)
							(mid -0.137521 -0.162921)
							(end -0.1016 -0.1778)
						)
						(arc
							(start 0.1016 -0.1778)
							(mid 0.137521 -0.162921)
							(end 0.1524 -0.127)
						)
					)
					(width 0)
					(fill yes)
				)
			)
		)
		(pad "2" smd custom
			(at 0 0.2794 270)
			(size 0.0762 0.0762)
			(layers "B.Cu" "B.Mask" "B.Paste")
			(net "GND")
			(options
				(clearance outline)
				(anchor circle)
			)
			(primitives
				(gr_poly
					(pts
						(arc
							(start 0.1524 0.127)
							(mid 0.137521 0.162921)
							(end 0.1016 0.1778)
						)
						(arc
							(start -0.1016 0.1778)
							(mid -0.137521 0.162921)
							(end -0.1524 0.127)
						)
						(arc
							(start -0.1524 -0.127)
							(mid -0.137521 -0.162921)
							(end -0.1016 -0.1778)
						)
						(arc
							(start 0.1016 -0.1778)
							(mid 0.137521 -0.162921)
							(end 0.1524 -0.127)
						)
					)
					(width 0)
					(fill yes)
				)
			)
		)
	)
	(footprint ""
		(layer "B.Cu")
		(at 349.749872 -54.99989)
		(property "Reference" ""
			(at 0 0 0)
			(layer "B.SilkS")
			(hide yes)
			(effects
				(font
					(size 1.27 1.27)
				)
				(justify mirror)
			)
		)
		(property "Value" "*"
			(at 5.5753 -0.4572 0)
			(unlocked yes)
			(layer "B.Fab")
			(hide yes)
			(effects
				(font
					(size 1.016 1.016)
					(thickness 0.1524)
				)
				(justify mirror)
			)
		)
		(duplicate_pad_numbers_are_jumpers no)
		(fp_poly
			(pts
				(arc
					(start 4.3053 0)
					(mid -4.3053 0)
					(end 4.3053 0)
				)
			)
			(stroke
				(width 0)
				(type default)
			)
			(fill no)
			(layer "B.CrtYd")
		)
		(fp_poly
			(pts
				(arc
					(start 4.3053 0)
					(mid -4.3053 0)
					(end 4.3053 0)
				)
			)
			(stroke
				(width 0)
				(type default)
			)
			(fill no)
			(layer "B.Fab")
		)
		(pad "1" smd custom
			(at 2.95275 0 180)
			(size 2.000013 2.000013)
			(layers "B.Cu" "B.Mask" "B.Paste")
			(net "Net_52")
			(options
				(clearance outline)
				(anchor circle)
			)
			(primitives
				(gr_poly
					(pts
						(arc
							(start 4.0005 -0.00254)
							(mid -4.000501 0)
							(end 4.0005 0.00254)
						)
						(arc
							(start 1.905 0.00254)
							(mid -1.905002 0)
							(end 1.905 -0.00254)
						)
					)
					(width 0)
					(fill yes)
				)
			)
		)
	)
	(footprint ""
		(layer "B.Cu")
		(at 325.374 -179.705)
		(property "Reference" "R5768"
			(at 0 0 0)
			(layer "B.SilkS")
			(hide yes)
			(effects
				(font
					(size 1.27 1.27)
				)
				(justify mirror)
			)
		)
		(property "Value" "1KR2F-3-GP"
			(at -0.064008 -3.993896 0)
			(unlocked yes)
			(layer "B.Fab")
			(hide yes)
			(effects
				(font
					(size 1.016 1.016)
					(thickness 0.1524)
				)
				(justify mirror)
			)
		)
		(property "Device Type" "R402H16"
			(at -0.064008 -5.517896 0)
			(unlocked yes)
			(layer "B.Fab")
			(hide yes)
			(effects
				(font
					(size 1.016 1.016)
					(thickness 0.1524)
				)
				(justify mirror)
			)
		)
		(duplicate_pad_numbers_are_jumpers no)
		(fp_line
			(start -0.508 -0.9398)
			(end 0.508 -0.9398)
			(stroke
				(width 0.1524)
				(type default)
			)
			(layer "B.SilkS")
		)
		(fp_line
			(start 0.508 -0.9398)
			(end 0.508 0.9398)
			(stroke
				(width 0.1524)
				(type default)
			)
			(layer "B.SilkS")
		)
		(fp_rect
			(start 0.508 0.9398)
			(end -0.508 -0.9398)
			(stroke
				(width 0)
				(type default)
			)
			(fill no)
			(layer "B.CrtYd")
		)
		(fp_rect
			(start 0.508 0.9398)
			(end -0.508 -0.9398)
			(stroke
				(width 0)
				(type default)
			)
			(fill no)
			(layer "B.Fab")
		)
		(pad "1" smd custom
			(at 0 -0.4445 180)
			(size 0.1397 0.1397)
			(layers "B.Cu" "B.Mask" "B.Paste")
			(net "P3V3_STBY")
			(options
				(clearance outline)
				(anchor circle)
			)
			(primitives
				(gr_poly
					(pts
						(arc
							(start -0.1778 0.2794)
							(mid -0.249642 0.249642)
							(end -0.2794 0.1778)
						)
						(arc
							(start -0.2794 -0.1778)
							(mid -0.249642 -0.249642)
							(end -0.1778 -0.2794)
						)
						(arc
							(start 0.1778 -0.2794)
							(mid 0.249642 -0.249642)
							(end 0.2794 -0.1778)
						)
						(arc
							(start 0.2794 0.1778)
							(mid 0.249642 0.249642)
							(end 0.1778 0.2794)
						)
					)
					(width 0)
					(fill yes)
				)
			)
		)
		(pad "2" smd custom
			(at 0 0.4445 180)
			(size 0.1397 0.1397)
			(layers "B.Cu" "B.Mask" "B.Paste")
			(net "ADC_P3V3_STBY")
			(options
				(clearance outline)
				(anchor circle)
			)
			(primitives
				(gr_poly
					(pts
						(arc
							(start -0.1778 0.2794)
							(mid -0.249642 0.249642)
							(end -0.2794 0.1778)
						)
						(arc
							(start -0.2794 -0.1778)
							(mid -0.249642 -0.249642)
							(end -0.1778 -0.2794)
						)
						(arc
							(start 0.1778 -0.2794)
							(mid 0.249642 -0.249642)
							(end 0.2794 -0.1778)
						)
						(arc
							(start 0.2794 0.1778)
							(mid 0.249642 0.249642)
							(end 0.1778 0.2794)
						)
					)
					(width 0)
					(fill yes)
				)
			)
		)
	)
	(footprint ""
		(layer "B.Cu")
		(at 33.478216 -232.33888)
		(property "Reference" "R510"
			(at 0 0 0)
			(layer "B.SilkS")
			(hide yes)
			(effects
				(font
					(size 1.27 1.27)
				)
				(justify mirror)
			)
		)
		(property "Value" "0R2J-2-GP"
			(at -0.064008 -3.993896 0)
			(unlocked yes)
			(layer "B.Fab")
			(hide yes)
			(effects
				(font
					(size 1.016 1.016)
					(thickness 0.1524)
				)
				(justify mirror)
			)
		)
		(property "Device Type" "R402H16"
			(at -0.064008 -5.517896 0)
			(unlocked yes)
			(layer "B.Fab")
			(hide yes)
			(effects
				(font
					(size 1.016 1.016)
					(thickness 0.1524)
				)
				(justify mirror)
			)
		)
		(duplicate_pad_numbers_are_jumpers no)
		(fp_line
			(start -0.508 -0.9398)
			(end 0.508 -0.9398)
			(stroke
				(width 0.1524)
				(type default)
			)
			(layer "B.SilkS")
		)
		(fp_line
			(start 0.508 -0.9398)
			(end 0.508 0.9398)
			(stroke
				(width 0.1524)
				(type default)
			)
			(layer "B.SilkS")
		)
		(fp_rect
			(start 0.508 0.9398)
			(end -0.508 -0.9398)
			(stroke
				(width 0)
				(type default)
			)
			(fill no)
			(layer "B.CrtYd")
		)
		(fp_rect
			(start 0.508 0.9398)
			(end -0.508 -0.9398)
			(stroke
				(width 0)
				(type default)
			)
			(fill no)
			(layer "B.Fab")
		)
		(pad "1" smd custom
			(at 0 -0.4445 180)
			(size 0.1397 0.1397)
			(layers "B.Cu" "B.Mask" "B.Paste")
			(net "SAS_HDD_PWR8_PCIE")
			(options
				(clearance outline)
				(anchor circle)
			)
			(primitives
				(gr_poly
					(pts
						(arc
							(start -0.1778 0.2794)
							(mid -0.249642 0.249642)
							(end -0.2794 0.1778)
						)
						(arc
							(start -0.2794 -0.1778)
							(mid -0.249642 -0.249642)
							(end -0.1778 -0.2794)
						)
						(arc
							(start 0.1778 -0.2794)
							(mid 0.249642 -0.249642)
							(end 0.2794 -0.1778)
						)
						(arc
							(start 0.2794 0.1778)
							(mid 0.249642 0.249642)
							(end 0.1778 0.2794)
						)
					)
					(width 0)
					(fill yes)
				)
			)
		)
		(pad "2" smd custom
			(at 0 0.4445 180)
			(size 0.1397 0.1397)
			(layers "B.Cu" "B.Mask" "B.Paste")
			(net "SAS_HDD_PWR8")
			(options
				(clearance outline)
				(anchor circle)
			)
			(primitives
				(gr_poly
					(pts
						(arc
							(start -0.1778 0.2794)
							(mid -0.249642 0.249642)
							(end -0.2794 0.1778)
						)
						(arc
							(start -0.2794 -0.1778)
							(mid -0.249642 -0.249642)
							(end -0.1778 -0.2794)
						)
						(arc
							(start 0.1778 -0.2794)
							(mid 0.249642 -0.249642)
							(end 0.2794 -0.1778)
						)
						(arc
							(start 0.2794 0.1778)
							(mid 0.249642 0.249642)
							(end 0.1778 0.2794)
						)
					)
					(width 0)
					(fill yes)
				)
			)
		)
	)
	(footprint ""
		(layer "B.Cu")
		(at 183.577992 -27.305 -90)
		(property "Reference" "C227"
			(at 0 0 90)
			(layer "B.SilkS")
			(hide yes)
			(effects
				(font
					(size 1.27 1.27)
				)
				(justify mirror)
			)
		)
		(property "Value" "SC10U6D3V5KX-1GP"
			(at 0.0762 -6.1214 270)
			(unlocked yes)
			(layer "B.Fab")
			(hide yes)
			(effects
				(font
					(size 1.016 1.016)
					(thickness 0.1524)
				)
				(justify mirror)
			)
		)
		(property "Device Type" "C805H54"
			(at 0.0762 -8.1534 270)
			(unlocked yes)
			(layer "B.Fab")
			(hide yes)
			(effects
				(font
					(size 1.016 1.016)
					(thickness 0.1524)
				)
				(justify mirror)
			)
		)
		(duplicate_pad_numbers_are_jumpers no)
		(fp_line
			(start -0.635 0)
			(end 0.635 0)
			(stroke
				(width 0.508)
				(type default)
			)
			(layer "B.SilkS")
		)
		(fp_rect
			(start 0.9652 1.778)
			(end -0.9652 -1.778)
			(stroke
				(width 0)
				(type default)
			)
			(fill no)
			(layer "B.CrtYd")
		)
		(fp_poly
			(pts
				(xy 0.9652 -1.778) (xy -0.9652 -1.778) (xy -0.9652 1.778) (xy 0.9652 1.778)
			)
			(stroke
				(width 0)
				(type default)
			)
			(fill no)
			(layer "B.Fab")
		)
		(pad "1" smd rect
			(at 0 -0.9652 90)
			(size 1.397 1.143)
			(layers "B.Cu" "B.Mask" "B.Paste")
			(net "P3V3_STBY")
		)
		(pad "2" smd rect
			(at 0 0.9652 90)
			(size 1.397 1.143)
			(layers "B.Cu" "B.Mask" "B.Paste")
			(net "GND")
		)
	)
	(footprint ""
		(layer "B.Cu")
		(at 187.895992 -33.909)
		(property "Reference" "C226"
			(at 0 0 0)
			(layer "B.SilkS")
			(hide yes)
			(effects
				(font
					(size 1.27 1.27)
				)
				(justify mirror)
			)
		)
		(property "Value" "SC10U6D3V5KX-1GP"
			(at 0.0762 -6.1214 0)
			(unlocked yes)
			(layer "B.Fab")
			(hide yes)
			(effects
				(font
					(size 1.016 1.016)
					(thickness 0.1524)
				)
				(justify mirror)
			)
		)
		(property "Device Type" "C805H54"
			(at 0.0762 -8.1534 0)
			(unlocked yes)
			(layer "B.Fab")
			(hide yes)
			(effects
				(font
					(size 1.016 1.016)
					(thickness 0.1524)
				)
				(justify mirror)
			)
		)
		(duplicate_pad_numbers_are_jumpers no)
		(fp_line
			(start -0.635 0)
			(end 0.635 0)
			(stroke
				(width 0.508)
				(type default)
			)
			(layer "B.SilkS")
		)
		(fp_rect
			(start 0.9652 1.778)
			(end -0.9652 -1.778)
			(stroke
				(width 0)
				(type default)
			)
			(fill no)
			(layer "B.CrtYd")
		)
		(fp_poly
			(pts
				(xy 0.9652 -1.778) (xy -0.9652 -1.778) (xy -0.9652 1.778) (xy 0.9652 1.778)
			)
			(stroke
				(width 0)
				(type default)
			)
			(fill no)
			(layer "B.Fab")
		)
		(pad "1" smd rect
			(at 0 -0.9652 180)
			(size 1.397 1.143)
			(layers "B.Cu" "B.Mask" "B.Paste")
			(net "P3V3_STBY")
		)
		(pad "2" smd rect
			(at 0 0.9652 180)
			(size 1.397 1.143)
			(layers "B.Cu" "B.Mask" "B.Paste")
			(net "GND")
		)
	)
	(footprint ""
		(layer "B.Cu")
		(at 15.995904 -100.400866)
		(property "Reference" "C134"
			(at 0 0 0)
			(layer "B.SilkS")
			(hide yes)
			(effects
				(font
					(size 1.27 1.27)
				)
				(justify mirror)
			)
		)
		(property "Value" "SCD01U50V2KX-1GP"
			(at -1.1811 -2.7051 0)
			(unlocked yes)
			(layer "B.Fab")
			(hide yes)
			(effects
				(font
					(size 1.016 1.016)
					(thickness 0.1524)
				)
				(justify mirror)
			)
		)
		(property "Device Type" "C402H22"
			(at -1.1811 -4.2291 0)
			(unlocked yes)
			(layer "B.Fab")
			(hide yes)
			(effects
				(font
					(size 1.016 1.016)
					(thickness 0.1524)
				)
				(justify mirror)
			)
		)
		(duplicate_pad_numbers_are_jumpers no)
		(fp_rect
			(start 0.4318 0.9525)
			(end -0.4318 -0.9525)
			(stroke
				(width 0)
				(type default)
			)
			(fill no)
			(layer "B.CrtYd")
		)
		(fp_rect
			(start 0.4318 0.9525)
			(end -0.4318 -0.9525)
			(stroke
				(width 0)
				(type default)
			)
			(fill no)
			(layer "B.Fab")
		)
		(pad "1" smd custom
			(at 0 -0.4445 180)
			(size 0.1524 0.1524)
			(layers "B.Cu" "B.Mask" "B.Paste")
			(net "IOC_SAS_RX_P6")
			(options
				(clearance outline)
				(anchor circle)
			)
			(primitives
				(gr_poly
					(pts
						(arc
							(start 0.3048 0.2032)
							(mid 0.275042 0.275042)
							(end 0.2032 0.3048)
						)
						(arc
							(start -0.2032 0.3048)
							(mid -0.275042 0.275042)
							(end -0.3048 0.2032)
						)
						(arc
							(start -0.3048 -0.2032)
							(mid -0.275042 -0.275042)
							(end -0.2032 -0.3048)
						)
						(arc
							(start 0.2032 -0.3048)
							(mid 0.275042 -0.275042)
							(end 0.3048 -0.2032)
						)
					)
					(width 0)
					(fill yes)
				)
			)
		)
		(pad "2" smd custom
			(at 0 0.4445 180)
			(size 0.1524 0.1524)
			(layers "B.Cu" "B.Mask" "B.Paste")
			(net "SAS_EXT_CONN_RX18_P")
			(options
				(clearance outline)
				(anchor circle)
			)
			(primitives
				(gr_poly
					(pts
						(arc
							(start 0.3048 0.2032)
							(mid 0.275042 0.275042)
							(end 0.2032 0.3048)
						)
						(arc
							(start -0.2032 0.3048)
							(mid -0.275042 0.275042)
							(end -0.3048 0.2032)
						)
						(arc
							(start -0.3048 -0.2032)
							(mid -0.275042 -0.275042)
							(end -0.2032 -0.3048)
						)
						(arc
							(start 0.2032 -0.3048)
							(mid 0.275042 -0.275042)
							(end 0.3048 -0.2032)
						)
					)
					(width 0)
					(fill yes)
				)
			)
		)
	)
	(footprint ""
		(layer "B.Cu")
		(at 120.30837 -95.1992 90)
		(property "Reference" "SC1144"
			(at 0 0 90)
			(layer "B.SilkS")
			(hide yes)
			(effects
				(font
					(size 1.27 1.27)
				)
				(justify mirror)
			)
		)
		(property "Value" "SCD1U6D3V1KX-GP"
			(at 2.8321 -1.7399 90)
			(unlocked yes)
			(layer "B.Fab")
			(hide yes)
			(effects
				(font
					(size 1.016 1.016)
					(thickness 0.1524)
				)
				(justify mirror)
			)
		)
		(property "Device Type" "C0201H13"
			(at 2.8321 -3.2639 90)
			(unlocked yes)
			(layer "B.Fab")
			(hide yes)
			(effects
				(font
					(size 1.016 1.016)
					(thickness 0.1524)
				)
				(justify mirror)
			)
		)
		(duplicate_pad_numbers_are_jumpers no)
		(fp_rect
			(start 0.2794 0.6477)
			(end -0.2794 -0.6477)
			(stroke
				(width 0)
				(type default)
			)
			(fill no)
			(layer "B.CrtYd")
		)
		(fp_rect
			(start 0.2794 0.6477)
			(end -0.2794 -0.6477)
			(stroke
				(width 0)
				(type default)
			)
			(fill no)
			(layer "B.Fab")
		)
		(pad "1" smd custom
			(at 0 -0.2794 270)
			(size 0.0762 0.0762)
			(layers "B.Cu" "B.Mask" "B.Paste")
			(net "GB_VDDH2")
			(options
				(clearance outline)
				(anchor circle)
			)
			(primitives
				(gr_poly
					(pts
						(arc
							(start 0.1524 0.127)
							(mid 0.137521 0.162921)
							(end 0.1016 0.1778)
						)
						(arc
							(start -0.1016 0.1778)
							(mid -0.137521 0.162921)
							(end -0.1524 0.127)
						)
						(arc
							(start -0.1524 -0.127)
							(mid -0.137521 -0.162921)
							(end -0.1016 -0.1778)
						)
						(arc
							(start 0.1016 -0.1778)
							(mid 0.137521 -0.162921)
							(end 0.1524 -0.127)
						)
					)
					(width 0)
					(fill yes)
				)
			)
		)
		(pad "2" smd custom
			(at 0 0.2794 270)
			(size 0.0762 0.0762)
			(layers "B.Cu" "B.Mask" "B.Paste")
			(net "GND")
			(options
				(clearance outline)
				(anchor circle)
			)
			(primitives
				(gr_poly
					(pts
						(arc
							(start 0.1524 0.127)
							(mid 0.137521 0.162921)
							(end 0.1016 0.1778)
						)
						(arc
							(start -0.1016 0.1778)
							(mid -0.137521 0.162921)
							(end -0.1524 0.127)
						)
						(arc
							(start -0.1524 -0.127)
							(mid -0.137521 -0.162921)
							(end -0.1016 -0.1778)
						)
						(arc
							(start 0.1016 -0.1778)
							(mid 0.137521 -0.162921)
							(end 0.1524 -0.127)
						)
					)
					(width 0)
					(fill yes)
				)
			)
		)
	)
	(footprint ""
		(layer "B.Cu")
		(at 141.97457 -93.9546)
		(property "Reference" "R5315"
			(at 0 0 0)
			(layer "B.SilkS")
			(hide yes)
			(effects
				(font
					(size 1.27 1.27)
				)
				(justify mirror)
			)
		)
		(property "Value" "0R2J-2-GP"
			(at -0.064008 -3.993896 0)
			(unlocked yes)
			(layer "B.Fab")
			(hide yes)
			(effects
				(font
					(size 1.016 1.016)
					(thickness 0.1524)
				)
				(justify mirror)
			)
		)
		(property "Device Type" "R402H16"
			(at -0.064008 -5.517896 0)
			(unlocked yes)
			(layer "B.Fab")
			(hide yes)
			(effects
				(font
					(size 1.016 1.016)
					(thickness 0.1524)
				)
				(justify mirror)
			)
		)
		(duplicate_pad_numbers_are_jumpers no)
		(fp_line
			(start -0.508 -0.9398)
			(end 0.508 -0.9398)
			(stroke
				(width 0.1524)
				(type default)
			)
			(layer "B.SilkS")
		)
		(fp_line
			(start 0.508 -0.9398)
			(end 0.508 0.9398)
			(stroke
				(width 0.1524)
				(type default)
			)
			(layer "B.SilkS")
		)
		(fp_rect
			(start 0.508 0.9398)
			(end -0.508 -0.9398)
			(stroke
				(width 0)
				(type default)
			)
			(fill no)
			(layer "B.CrtYd")
		)
		(fp_rect
			(start 0.508 0.9398)
			(end -0.508 -0.9398)
			(stroke
				(width 0)
				(type default)
			)
			(fill no)
			(layer "B.Fab")
		)
		(pad "1" smd custom
			(at 0 -0.4445 180)
			(size 0.1397 0.1397)
			(layers "B.Cu" "B.Mask" "B.Paste")
			(net "BMC_I2C_SDA_10")
			(options
				(clearance outline)
				(anchor circle)
			)
			(primitives
				(gr_poly
					(pts
						(arc
							(start -0.1778 0.2794)
							(mid -0.249642 0.249642)
							(end -0.2794 0.1778)
						)
						(arc
							(start -0.2794 -0.1778)
							(mid -0.249642 -0.249642)
							(end -0.1778 -0.2794)
						)
						(arc
							(start 0.1778 -0.2794)
							(mid 0.249642 -0.249642)
							(end 0.2794 -0.1778)
						)
						(arc
							(start 0.2794 0.1778)
							(mid 0.249642 0.249642)
							(end 0.1778 0.2794)
						)
					)
					(width 0)
					(fill yes)
				)
			)
		)
		(pad "2" smd custom
			(at 0 0.4445 180)
			(size 0.1397 0.1397)
			(layers "B.Cu" "B.Mask" "B.Paste")
			(net "TEMP_3_SDA")
			(options
				(clearance outline)
				(anchor circle)
			)
			(primitives
				(gr_poly
					(pts
						(arc
							(start -0.1778 0.2794)
							(mid -0.249642 0.249642)
							(end -0.2794 0.1778)
						)
						(arc
							(start -0.2794 -0.1778)
							(mid -0.249642 -0.249642)
							(end -0.1778 -0.2794)
						)
						(arc
							(start 0.1778 -0.2794)
							(mid 0.249642 -0.249642)
							(end 0.2794 -0.1778)
						)
						(arc
							(start 0.2794 0.1778)
							(mid 0.249642 0.249642)
							(end 0.1778 0.2794)
						)
					)
					(width 0)
					(fill yes)
				)
			)
		)
	)
	(footprint ""
		(layer "B.Cu")
		(at 105.30967 -87.9475 -90)
		(property "Reference" "SC1221"
			(at 0 0 90)
			(layer "B.SilkS")
			(hide yes)
			(effects
				(font
					(size 1.27 1.27)
				)
				(justify mirror)
			)
		)
		(property "Value" "SCD1U6D3V1KX-GP"
			(at 2.8321 -1.7399 270)
			(unlocked yes)
			(layer "B.Fab")
			(hide yes)
			(effects
				(font
					(size 1.016 1.016)
					(thickness 0.1524)
				)
				(justify mirror)
			)
		)
		(property "Device Type" "C0201H13"
			(at 2.8321 -3.2639 270)
			(unlocked yes)
			(layer "B.Fab")
			(hide yes)
			(effects
				(font
					(size 1.016 1.016)
					(thickness 0.1524)
				)
				(justify mirror)
			)
		)
		(duplicate_pad_numbers_are_jumpers no)
		(fp_rect
			(start 0.2794 0.6477)
			(end -0.2794 -0.6477)
			(stroke
				(width 0)
				(type default)
			)
			(fill no)
			(layer "B.CrtYd")
		)
		(fp_rect
			(start 0.2794 0.6477)
			(end -0.2794 -0.6477)
			(stroke
				(width 0)
				(type default)
			)
			(fill no)
			(layer "B.Fab")
		)
		(pad "1" smd custom
			(at 0 -0.2794 90)
			(size 0.0762 0.0762)
			(layers "B.Cu" "B.Mask" "B.Paste")
			(net "P1V8_E")
			(options
				(clearance outline)
				(anchor circle)
			)
			(primitives
				(gr_poly
					(pts
						(arc
							(start 0.1524 0.127)
							(mid 0.137521 0.162921)
							(end 0.1016 0.1778)
						)
						(arc
							(start -0.1016 0.1778)
							(mid -0.137521 0.162921)
							(end -0.1524 0.127)
						)
						(arc
							(start -0.1524 -0.127)
							(mid -0.137521 -0.162921)
							(end -0.1016 -0.1778)
						)
						(arc
							(start 0.1016 -0.1778)
							(mid 0.137521 -0.162921)
							(end 0.1524 -0.127)
						)
					)
					(width 0)
					(fill yes)
				)
			)
		)
		(pad "2" smd custom
			(at 0 0.2794 90)
			(size 0.0762 0.0762)
			(layers "B.Cu" "B.Mask" "B.Paste")
			(net "GND")
			(options
				(clearance outline)
				(anchor circle)
			)
			(primitives
				(gr_poly
					(pts
						(arc
							(start 0.1524 0.127)
							(mid 0.137521 0.162921)
							(end 0.1016 0.1778)
						)
						(arc
							(start -0.1016 0.1778)
							(mid -0.137521 0.162921)
							(end -0.1524 0.127)
						)
						(arc
							(start -0.1524 -0.127)
							(mid -0.137521 -0.162921)
							(end -0.1016 -0.1778)
						)
						(arc
							(start 0.1016 -0.1778)
							(mid 0.137521 -0.162921)
							(end 0.1524 -0.127)
						)
					)
					(width 0)
					(fill yes)
				)
			)
		)
	)
	(footprint ""
		(layer "B.Cu")
		(at 116.545106 -37.5666)
		(property "Reference" "STP23"
			(at 0 0 0)
			(layer "B.SilkS")
			(hide yes)
			(effects
				(font
					(size 1.27 1.27)
				)
				(justify mirror)
			)
		)
		(property "Value" "TPAD28"
			(at -0.0127 -1.8034 0)
			(unlocked yes)
			(layer "B.Fab")
			(hide yes)
			(effects
				(font
					(size 1.016 1.016)
					(thickness 0.1524)
				)
				(justify mirror)
			)
		)
		(property "Device Type" "TPAD28"
			(at -0.0127 -3.3274 0)
			(unlocked yes)
			(layer "B.Fab")
			(hide yes)
			(effects
				(font
					(size 1.016 1.016)
					(thickness 0.1524)
				)
				(justify mirror)
			)
		)
		(duplicate_pad_numbers_are_jumpers no)
		(fp_poly
			(pts
				(arc
					(start 0.3556 0)
					(mid -0.3556 0)
					(end 0.3556 0)
				)
			)
			(stroke
				(width 0)
				(type default)
			)
			(fill no)
			(layer "B.CrtYd")
		)
		(fp_poly
			(pts
				(arc
					(start 0.6096 0)
					(mid -0.6096 0)
					(end 0.6096 0)
				)
			)
			(stroke
				(width 0)
				(type default)
			)
			(fill no)
			(layer "B.Fab")
		)
		(pad "1" smd circle
			(at 0 0 180)
			(size 0.7112 0.7112)
			(layers "B.Cu" "B.Mask" "B.Paste")
			(net "IOC_GPIO_37")
		)
	)
	(footprint ""
		(layer "B.Cu")
		(at 318.008 -162.814 -90)
		(property "Reference" "R244"
			(at 0 0 90)
			(layer "B.SilkS")
			(hide yes)
			(effects
				(font
					(size 1.27 1.27)
				)
				(justify mirror)
			)
		)
		(property "Value" "0R2J-2-GP"
			(at -0.064008 -3.993896 270)
			(unlocked yes)
			(layer "B.Fab")
			(hide yes)
			(effects
				(font
					(size 1.016 1.016)
					(thickness 0.1524)
				)
				(justify mirror)
			)
		)
		(property "Device Type" "R402H16"
			(at -0.064008 -5.517896 270)
			(unlocked yes)
			(layer "B.Fab")
			(hide yes)
			(effects
				(font
					(size 1.016 1.016)
					(thickness 0.1524)
				)
				(justify mirror)
			)
		)
		(duplicate_pad_numbers_are_jumpers no)
		(fp_line
			(start -0.508 -0.9398)
			(end 0.508 -0.9398)
			(stroke
				(width 0.1524)
				(type default)
			)
			(layer "B.SilkS")
		)
		(fp_line
			(start 0.508 -0.9398)
			(end 0.508 0.9398)
			(stroke
				(width 0.1524)
				(type default)
			)
			(layer "B.SilkS")
		)
		(fp_rect
			(start 0.508 0.9398)
			(end -0.508 -0.9398)
			(stroke
				(width 0)
				(type default)
			)
			(fill no)
			(layer "B.CrtYd")
		)
		(fp_rect
			(start 0.508 0.9398)
			(end -0.508 -0.9398)
			(stroke
				(width 0)
				(type default)
			)
			(fill no)
			(layer "B.Fab")
		)
		(pad "1" smd custom
			(at 0 -0.4445 90)
			(size 0.1397 0.1397)
			(layers "B.Cu" "B.Mask" "B.Paste")
			(net "NIC_SMBUS_SCL")
			(options
				(clearance outline)
				(anchor circle)
			)
			(primitives
				(gr_poly
					(pts
						(arc
							(start -0.1778 0.2794)
							(mid -0.249642 0.249642)
							(end -0.2794 0.1778)
						)
						(arc
							(start -0.2794 -0.1778)
							(mid -0.249642 -0.249642)
							(end -0.1778 -0.2794)
						)
						(arc
							(start 0.1778 -0.2794)
							(mid 0.249642 -0.249642)
							(end 0.2794 -0.1778)
						)
						(arc
							(start 0.2794 0.1778)
							(mid 0.249642 0.249642)
							(end 0.1778 0.2794)
						)
					)
					(width 0)
					(fill yes)
				)
			)
		)
		(pad "2" smd custom
			(at 0 0.4445 90)
			(size 0.1397 0.1397)
			(layers "B.Cu" "B.Mask" "B.Paste")
			(net "BMC0_SMB4_CLK")
			(options
				(clearance outline)
				(anchor circle)
			)
			(primitives
				(gr_poly
					(pts
						(arc
							(start -0.1778 0.2794)
							(mid -0.249642 0.249642)
							(end -0.2794 0.1778)
						)
						(arc
							(start -0.2794 -0.1778)
							(mid -0.249642 -0.249642)
							(end -0.1778 -0.2794)
						)
						(arc
							(start 0.1778 -0.2794)
							(mid 0.249642 -0.249642)
							(end 0.2794 -0.1778)
						)
						(arc
							(start 0.2794 0.1778)
							(mid 0.249642 0.249642)
							(end 0.1778 0.2794)
						)
					)
					(width 0)
					(fill yes)
				)
			)
		)
	)
	(footprint ""
		(layer "B.Cu")
		(at 107.121706 -54.5211 -90)
		(property "Reference" "SC1010"
			(at 0 0 90)
			(layer "B.SilkS")
			(hide yes)
			(effects
				(font
					(size 1.27 1.27)
				)
				(justify mirror)
			)
		)
		(property "Value" "SC1KP50V2KX-1GP"
			(at -1.1811 -2.7051 270)
			(unlocked yes)
			(layer "B.Fab")
			(hide yes)
			(effects
				(font
					(size 1.016 1.016)
					(thickness 0.1524)
				)
				(justify mirror)
			)
		)
		(property "Device Type" "C402H22"
			(at -1.1811 -4.2291 270)
			(unlocked yes)
			(layer "B.Fab")
			(hide yes)
			(effects
				(font
					(size 1.016 1.016)
					(thickness 0.1524)
				)
				(justify mirror)
			)
		)
		(duplicate_pad_numbers_are_jumpers no)
		(fp_rect
			(start 0.4318 0.9525)
			(end -0.4318 -0.9525)
			(stroke
				(width 0)
				(type default)
			)
			(fill no)
			(layer "B.CrtYd")
		)
		(fp_rect
			(start 0.4318 0.9525)
			(end -0.4318 -0.9525)
			(stroke
				(width 0)
				(type default)
			)
			(fill no)
			(layer "B.Fab")
		)
		(pad "1" smd custom
			(at 0 -0.4445 90)
			(size 0.1524 0.1524)
			(layers "B.Cu" "B.Mask" "B.Paste")
			(net "P1V8_C")
			(options
				(clearance outline)
				(anchor circle)
			)
			(primitives
				(gr_poly
					(pts
						(arc
							(start 0.3048 0.2032)
							(mid 0.275042 0.275042)
							(end 0.2032 0.3048)
						)
						(arc
							(start -0.2032 0.3048)
							(mid -0.275042 0.275042)
							(end -0.3048 0.2032)
						)
						(arc
							(start -0.3048 -0.2032)
							(mid -0.275042 -0.275042)
							(end -0.2032 -0.3048)
						)
						(arc
							(start 0.2032 -0.3048)
							(mid 0.275042 -0.275042)
							(end 0.3048 -0.2032)
						)
					)
					(width 0)
					(fill yes)
				)
			)
		)
		(pad "2" smd custom
			(at 0 0.4445 90)
			(size 0.1524 0.1524)
			(layers "B.Cu" "B.Mask" "B.Paste")
			(net "GND")
			(options
				(clearance outline)
				(anchor circle)
			)
			(primitives
				(gr_poly
					(pts
						(arc
							(start 0.3048 0.2032)
							(mid 0.275042 0.275042)
							(end 0.2032 0.3048)
						)
						(arc
							(start -0.2032 0.3048)
							(mid -0.275042 0.275042)
							(end -0.3048 0.2032)
						)
						(arc
							(start -0.3048 -0.2032)
							(mid -0.275042 -0.275042)
							(end -0.2032 -0.3048)
						)
						(arc
							(start 0.2032 -0.3048)
							(mid 0.275042 -0.275042)
							(end 0.3048 -0.2032)
						)
					)
					(width 0)
					(fill yes)
				)
			)
		)
	)
	(footprint ""
		(layer "B.Cu")
		(at 119.16537 -78.4098 90)
		(property "Reference" "SR829"
			(at 0 0 90)
			(layer "B.SilkS")
			(hide yes)
			(effects
				(font
					(size 1.27 1.27)
				)
				(justify mirror)
			)
		)
		(property "Value" "10R2F-L-GP"
			(at -0.064008 -3.993896 90)
			(unlocked yes)
			(layer "B.Fab")
			(hide yes)
			(effects
				(font
					(size 1.016 1.016)
					(thickness 0.1524)
				)
				(justify mirror)
			)
		)
		(property "Device Type" "R402H14"
			(at -0.064008 -5.517896 90)
			(unlocked yes)
			(layer "B.Fab")
			(hide yes)
			(effects
				(font
					(size 1.016 1.016)
					(thickness 0.1524)
				)
				(justify mirror)
			)
		)
		(duplicate_pad_numbers_are_jumpers no)
		(fp_line
			(start 0.508 -0.9398)
			(end 0.508 0.9398)
			(stroke
				(width 0.1524)
				(type default)
			)
			(layer "B.SilkS")
		)
		(fp_line
			(start -0.508 -0.9398)
			(end 0.508 -0.9398)
			(stroke
				(width 0.1524)
				(type default)
			)
			(layer "B.SilkS")
		)
		(fp_rect
			(start 0.508 0.9398)
			(end -0.508 -0.9398)
			(stroke
				(width 0)
				(type default)
			)
			(fill no)
			(layer "B.CrtYd")
		)
		(fp_rect
			(start 0.508 0.9398)
			(end -0.508 -0.9398)
			(stroke
				(width 0)
				(type default)
			)
			(fill no)
			(layer "B.Fab")
		)
		(pad "1" smd custom
			(at 0 -0.4445 270)
			(size 0.1397 0.1397)
			(layers "B.Cu" "B.Mask" "B.Paste")
			(net "P1V8_E")
			(options
				(clearance outline)
				(anchor circle)
			)
			(primitives
				(gr_poly
					(pts
						(arc
							(start -0.1778 0.2794)
							(mid -0.249642 0.249642)
							(end -0.2794 0.1778)
						)
						(arc
							(start -0.2794 -0.1778)
							(mid -0.249642 -0.249642)
							(end -0.1778 -0.2794)
						)
						(arc
							(start 0.1778 -0.2794)
							(mid 0.249642 -0.249642)
							(end 0.2794 -0.1778)
						)
						(arc
							(start 0.2794 0.1778)
							(mid 0.249642 0.249642)
							(end 0.1778 0.2794)
						)
					)
					(width 0)
					(fill yes)
				)
			)
		)
		(pad "2" smd custom
			(at 0 0.4445 270)
			(size 0.1397 0.1397)
			(layers "B.Cu" "B.Mask" "B.Paste")
			(net "XTAL_VDDA18")
			(options
				(clearance outline)
				(anchor circle)
			)
			(primitives
				(gr_poly
					(pts
						(arc
							(start -0.1778 0.2794)
							(mid -0.249642 0.249642)
							(end -0.2794 0.1778)
						)
						(arc
							(start -0.2794 -0.1778)
							(mid -0.249642 -0.249642)
							(end -0.1778 -0.2794)
						)
						(arc
							(start 0.1778 -0.2794)
							(mid 0.249642 -0.249642)
							(end 0.2794 -0.1778)
						)
						(arc
							(start 0.2794 0.1778)
							(mid 0.249642 0.249642)
							(end 0.1778 0.2794)
						)
					)
					(width 0)
					(fill yes)
				)
			)
		)
	)
	(footprint ""
		(layer "B.Cu")
		(at 318.008 -169.418 -90)
		(property "Reference" "R247"
			(at 0 0 90)
			(layer "B.SilkS")
			(hide yes)
			(effects
				(font
					(size 1.27 1.27)
				)
				(justify mirror)
			)
		)
		(property "Value" "0R2J-2-GP"
			(at -0.064008 -3.993896 270)
			(unlocked yes)
			(layer "B.Fab")
			(hide yes)
			(effects
				(font
					(size 1.016 1.016)
					(thickness 0.1524)
				)
				(justify mirror)
			)
		)
		(property "Device Type" "R402H16"
			(at -0.064008 -5.517896 270)
			(unlocked yes)
			(layer "B.Fab")
			(hide yes)
			(effects
				(font
					(size 1.016 1.016)
					(thickness 0.1524)
				)
				(justify mirror)
			)
		)
		(duplicate_pad_numbers_are_jumpers no)
		(fp_line
			(start -0.508 -0.9398)
			(end 0.508 -0.9398)
			(stroke
				(width 0.1524)
				(type default)
			)
			(layer "B.SilkS")
		)
		(fp_line
			(start 0.508 -0.9398)
			(end 0.508 0.9398)
			(stroke
				(width 0.1524)
				(type default)
			)
			(layer "B.SilkS")
		)
		(fp_rect
			(start 0.508 0.9398)
			(end -0.508 -0.9398)
			(stroke
				(width 0)
				(type default)
			)
			(fill no)
			(layer "B.CrtYd")
		)
		(fp_rect
			(start 0.508 0.9398)
			(end -0.508 -0.9398)
			(stroke
				(width 0)
				(type default)
			)
			(fill no)
			(layer "B.Fab")
		)
		(pad "1" smd custom
			(at 0 -0.4445 90)
			(size 0.1397 0.1397)
			(layers "B.Cu" "B.Mask" "B.Paste")
			(net "BMC_I2C_A_SDA")
			(options
				(clearance outline)
				(anchor circle)
			)
			(primitives
				(gr_poly
					(pts
						(arc
							(start -0.1778 0.2794)
							(mid -0.249642 0.249642)
							(end -0.2794 0.1778)
						)
						(arc
							(start -0.2794 -0.1778)
							(mid -0.249642 -0.249642)
							(end -0.1778 -0.2794)
						)
						(arc
							(start 0.1778 -0.2794)
							(mid 0.249642 -0.249642)
							(end 0.2794 -0.1778)
						)
						(arc
							(start 0.2794 0.1778)
							(mid 0.249642 0.249642)
							(end 0.1778 0.2794)
						)
					)
					(width 0)
					(fill yes)
				)
			)
		)
		(pad "2" smd custom
			(at 0 0.4445 90)
			(size 0.1397 0.1397)
			(layers "B.Cu" "B.Mask" "B.Paste")
			(net "BMC0_SMB5_DAT")
			(options
				(clearance outline)
				(anchor circle)
			)
			(primitives
				(gr_poly
					(pts
						(arc
							(start -0.1778 0.2794)
							(mid -0.249642 0.249642)
							(end -0.2794 0.1778)
						)
						(arc
							(start -0.2794 -0.1778)
							(mid -0.249642 -0.249642)
							(end -0.1778 -0.2794)
						)
						(arc
							(start 0.1778 -0.2794)
							(mid 0.249642 -0.249642)
							(end 0.2794 -0.1778)
						)
						(arc
							(start 0.2794 0.1778)
							(mid 0.249642 0.249642)
							(end 0.1778 0.2794)
						)
					)
					(width 0)
					(fill yes)
				)
			)
		)
	)
	(footprint ""
		(layer "B.Cu")
		(at 31.446216 -232.33888)
		(property "Reference" "R508"
			(at 0 0 0)
			(layer "B.SilkS")
			(hide yes)
			(effects
				(font
					(size 1.27 1.27)
				)
				(justify mirror)
			)
		)
		(property "Value" "0R2J-2-GP"
			(at -0.064008 -3.993896 0)
			(unlocked yes)
			(layer "B.Fab")
			(hide yes)
			(effects
				(font
					(size 1.016 1.016)
					(thickness 0.1524)
				)
				(justify mirror)
			)
		)
		(property "Device Type" "R402H16"
			(at -0.064008 -5.517896 0)
			(unlocked yes)
			(layer "B.Fab")
			(hide yes)
			(effects
				(font
					(size 1.016 1.016)
					(thickness 0.1524)
				)
				(justify mirror)
			)
		)
		(duplicate_pad_numbers_are_jumpers no)
		(fp_line
			(start -0.508 -0.9398)
			(end 0.508 -0.9398)
			(stroke
				(width 0.1524)
				(type default)
			)
			(layer "B.SilkS")
		)
		(fp_line
			(start 0.508 -0.9398)
			(end 0.508 0.9398)
			(stroke
				(width 0.1524)
				(type default)
			)
			(layer "B.SilkS")
		)
		(fp_rect
			(start 0.508 0.9398)
			(end -0.508 -0.9398)
			(stroke
				(width 0)
				(type default)
			)
			(fill no)
			(layer "B.CrtYd")
		)
		(fp_rect
			(start 0.508 0.9398)
			(end -0.508 -0.9398)
			(stroke
				(width 0)
				(type default)
			)
			(fill no)
			(layer "B.Fab")
		)
		(pad "1" smd custom
			(at 0 -0.4445 180)
			(size 0.1397 0.1397)
			(layers "B.Cu" "B.Mask" "B.Paste")
			(net "SAS_HDD_PWR6_PCIE")
			(options
				(clearance outline)
				(anchor circle)
			)
			(primitives
				(gr_poly
					(pts
						(arc
							(start -0.1778 0.2794)
							(mid -0.249642 0.249642)
							(end -0.2794 0.1778)
						)
						(arc
							(start -0.2794 -0.1778)
							(mid -0.249642 -0.249642)
							(end -0.1778 -0.2794)
						)
						(arc
							(start 0.1778 -0.2794)
							(mid 0.249642 -0.249642)
							(end 0.2794 -0.1778)
						)
						(arc
							(start 0.2794 0.1778)
							(mid 0.249642 0.249642)
							(end 0.1778 0.2794)
						)
					)
					(width 0)
					(fill yes)
				)
			)
		)
		(pad "2" smd custom
			(at 0 0.4445 180)
			(size 0.1397 0.1397)
			(layers "B.Cu" "B.Mask" "B.Paste")
			(net "SAS_HDD_PWR6")
			(options
				(clearance outline)
				(anchor circle)
			)
			(primitives
				(gr_poly
					(pts
						(arc
							(start -0.1778 0.2794)
							(mid -0.249642 0.249642)
							(end -0.2794 0.1778)
						)
						(arc
							(start -0.2794 -0.1778)
							(mid -0.249642 -0.249642)
							(end -0.1778 -0.2794)
						)
						(arc
							(start 0.1778 -0.2794)
							(mid 0.249642 -0.249642)
							(end 0.2794 -0.1778)
						)
						(arc
							(start 0.2794 0.1778)
							(mid 0.249642 0.249642)
							(end 0.1778 0.2794)
						)
					)
					(width 0)
					(fill yes)
				)
			)
		)
	)
	(footprint ""
		(layer "B.Cu")
		(at 96.901 -228.981 -90)
		(property "Reference" "R629"
			(at 0 0 90)
			(layer "B.SilkS")
			(hide yes)
			(effects
				(font
					(size 1.27 1.27)
				)
				(justify mirror)
			)
		)
		(property "Value" "0R2J-2-GP"
			(at -0.064008 -3.993896 270)
			(unlocked yes)
			(layer "B.Fab")
			(hide yes)
			(effects
				(font
					(size 1.016 1.016)
					(thickness 0.1524)
				)
				(justify mirror)
			)
		)
		(property "Device Type" "R402H16"
			(at -0.064008 -5.517896 270)
			(unlocked yes)
			(layer "B.Fab")
			(hide yes)
			(effects
				(font
					(size 1.016 1.016)
					(thickness 0.1524)
				)
				(justify mirror)
			)
		)
		(duplicate_pad_numbers_are_jumpers no)
		(fp_line
			(start -0.508 -0.9398)
			(end 0.508 -0.9398)
			(stroke
				(width 0.1524)
				(type default)
			)
			(layer "B.SilkS")
		)
		(fp_line
			(start 0.508 -0.9398)
			(end 0.508 0.9398)
			(stroke
				(width 0.1524)
				(type default)
			)
			(layer "B.SilkS")
		)
		(fp_rect
			(start 0.508 0.9398)
			(end -0.508 -0.9398)
			(stroke
				(width 0)
				(type default)
			)
			(fill no)
			(layer "B.CrtYd")
		)
		(fp_rect
			(start 0.508 0.9398)
			(end -0.508 -0.9398)
			(stroke
				(width 0)
				(type default)
			)
			(fill no)
			(layer "B.Fab")
		)
		(pad "1" smd custom
			(at 0 -0.4445 90)
			(size 0.1397 0.1397)
			(layers "B.Cu" "B.Mask" "B.Paste")
			(net "SAS_FAULT_LED11")
			(options
				(clearance outline)
				(anchor circle)
			)
			(primitives
				(gr_poly
					(pts
						(arc
							(start -0.1778 0.2794)
							(mid -0.249642 0.249642)
							(end -0.2794 0.1778)
						)
						(arc
							(start -0.2794 -0.1778)
							(mid -0.249642 -0.249642)
							(end -0.1778 -0.2794)
						)
						(arc
							(start 0.1778 -0.2794)
							(mid 0.249642 -0.249642)
							(end 0.2794 -0.1778)
						)
						(arc
							(start 0.2794 0.1778)
							(mid 0.249642 0.249642)
							(end 0.1778 0.2794)
						)
					)
					(width 0)
					(fill yes)
				)
			)
		)
		(pad "2" smd custom
			(at 0 0.4445 90)
			(size 0.1397 0.1397)
			(layers "B.Cu" "B.Mask" "B.Paste")
			(net "SAS_HDD_LED_11")
			(options
				(clearance outline)
				(anchor circle)
			)
			(primitives
				(gr_poly
					(pts
						(arc
							(start -0.1778 0.2794)
							(mid -0.249642 0.249642)
							(end -0.2794 0.1778)
						)
						(arc
							(start -0.2794 -0.1778)
							(mid -0.249642 -0.249642)
							(end -0.1778 -0.2794)
						)
						(arc
							(start 0.1778 -0.2794)
							(mid 0.249642 -0.249642)
							(end 0.2794 -0.1778)
						)
						(arc
							(start 0.2794 0.1778)
							(mid 0.249642 0.249642)
							(end 0.1778 0.2794)
						)
					)
					(width 0)
					(fill yes)
				)
			)
		)
	)
	(footprint ""
		(layer "B.Cu")
		(at 180.013864 -32.965136 90)
		(property "Reference" "C220"
			(at 0 0 90)
			(layer "B.SilkS")
			(hide yes)
			(effects
				(font
					(size 1.27 1.27)
				)
				(justify mirror)
			)
		)
		(property "Value" "SC1KP50V2KX-1GP"
			(at -1.1811 -2.7051 90)
			(unlocked yes)
			(layer "B.Fab")
			(hide yes)
			(effects
				(font
					(size 1.016 1.016)
					(thickness 0.1524)
				)
				(justify mirror)
			)
		)
		(property "Device Type" "C402H22"
			(at -1.1811 -4.2291 90)
			(unlocked yes)
			(layer "B.Fab")
			(hide yes)
			(effects
				(font
					(size 1.016 1.016)
					(thickness 0.1524)
				)
				(justify mirror)
			)
		)
		(duplicate_pad_numbers_are_jumpers no)
		(fp_rect
			(start 0.4318 0.9525)
			(end -0.4318 -0.9525)
			(stroke
				(width 0)
				(type default)
			)
			(fill no)
			(layer "B.CrtYd")
		)
		(fp_rect
			(start 0.4318 0.9525)
			(end -0.4318 -0.9525)
			(stroke
				(width 0)
				(type default)
			)
			(fill no)
			(layer "B.Fab")
		)
		(pad "1" smd custom
			(at 0 -0.4445 270)
			(size 0.1524 0.1524)
			(layers "B.Cu" "B.Mask" "B.Paste")
			(net "P3V3_STBY")
			(options
				(clearance outline)
				(anchor circle)
			)
			(primitives
				(gr_poly
					(pts
						(arc
							(start 0.3048 0.2032)
							(mid 0.275042 0.275042)
							(end 0.2032 0.3048)
						)
						(arc
							(start -0.2032 0.3048)
							(mid -0.275042 0.275042)
							(end -0.3048 0.2032)
						)
						(arc
							(start -0.3048 -0.2032)
							(mid -0.275042 -0.275042)
							(end -0.2032 -0.3048)
						)
						(arc
							(start 0.2032 -0.3048)
							(mid 0.275042 -0.275042)
							(end 0.3048 -0.2032)
						)
					)
					(width 0)
					(fill yes)
				)
			)
		)
		(pad "2" smd custom
			(at 0 0.4445 270)
			(size 0.1524 0.1524)
			(layers "B.Cu" "B.Mask" "B.Paste")
			(net "GND")
			(options
				(clearance outline)
				(anchor circle)
			)
			(primitives
				(gr_poly
					(pts
						(arc
							(start 0.3048 0.2032)
							(mid 0.275042 0.275042)
							(end 0.2032 0.3048)
						)
						(arc
							(start -0.2032 0.3048)
							(mid -0.275042 0.275042)
							(end -0.3048 0.2032)
						)
						(arc
							(start -0.3048 -0.2032)
							(mid -0.275042 -0.275042)
							(end -0.2032 -0.3048)
						)
						(arc
							(start 0.2032 -0.3048)
							(mid 0.275042 -0.275042)
							(end 0.3048 -0.2032)
						)
					)
					(width 0)
					(fill yes)
				)
			)
		)
	)
	(footprint ""
		(layer "B.Cu")
		(at 120.86717 -89.8652 180)
		(property "Reference" "SC1145"
			(at 0 0 0)
			(layer "B.SilkS")
			(hide yes)
			(effects
				(font
					(size 1.27 1.27)
				)
				(justify mirror)
			)
		)
		(property "Value" "SCD1U6D3V1KX-GP"
			(at 2.8321 -1.7399 180)
			(unlocked yes)
			(layer "B.Fab")
			(hide yes)
			(effects
				(font
					(size 1.016 1.016)
					(thickness 0.1524)
				)
				(justify mirror)
			)
		)
		(property "Device Type" "C0201H13"
			(at 2.8321 -3.2639 180)
			(unlocked yes)
			(layer "B.Fab")
			(hide yes)
			(effects
				(font
					(size 1.016 1.016)
					(thickness 0.1524)
				)
				(justify mirror)
			)
		)
		(duplicate_pad_numbers_are_jumpers no)
		(fp_rect
			(start 0.2794 0.6477)
			(end -0.2794 -0.6477)
			(stroke
				(width 0)
				(type default)
			)
			(fill no)
			(layer "B.CrtYd")
		)
		(fp_rect
			(start 0.2794 0.6477)
			(end -0.2794 -0.6477)
			(stroke
				(width 0)
				(type default)
			)
			(fill no)
			(layer "B.Fab")
		)
		(pad "1" smd custom
			(at 0 -0.2794)
			(size 0.0762 0.0762)
			(layers "B.Cu" "B.Mask" "B.Paste")
			(net "GB_VDDH2")
			(options
				(clearance outline)
				(anchor circle)
			)
			(primitives
				(gr_poly
					(pts
						(arc
							(start 0.1524 0.127)
							(mid 0.137521 0.162921)
							(end 0.1016 0.1778)
						)
						(arc
							(start -0.1016 0.1778)
							(mid -0.137521 0.162921)
							(end -0.1524 0.127)
						)
						(arc
							(start -0.1524 -0.127)
							(mid -0.137521 -0.162921)
							(end -0.1016 -0.1778)
						)
						(arc
							(start 0.1016 -0.1778)
							(mid 0.137521 -0.162921)
							(end 0.1524 -0.127)
						)
					)
					(width 0)
					(fill yes)
				)
			)
		)
		(pad "2" smd custom
			(at 0 0.2794)
			(size 0.0762 0.0762)
			(layers "B.Cu" "B.Mask" "B.Paste")
			(net "GND")
			(options
				(clearance outline)
				(anchor circle)
			)
			(primitives
				(gr_poly
					(pts
						(arc
							(start 0.1524 0.127)
							(mid 0.137521 0.162921)
							(end 0.1016 0.1778)
						)
						(arc
							(start -0.1016 0.1778)
							(mid -0.137521 0.162921)
							(end -0.1524 0.127)
						)
						(arc
							(start -0.1524 -0.127)
							(mid -0.137521 -0.162921)
							(end -0.1016 -0.1778)
						)
						(arc
							(start 0.1016 -0.1778)
							(mid 0.137521 -0.162921)
							(end 0.1524 -0.127)
						)
					)
					(width 0)
					(fill yes)
				)
			)
		)
	)
	(footprint ""
		(layer "B.Cu")
		(at 296.799 -174.117 -90)
		(property "Reference" "C215"
			(at 0 0 90)
			(layer "B.SilkS")
			(hide yes)
			(effects
				(font
					(size 1.27 1.27)
				)
				(justify mirror)
			)
		)
		(property "Value" "SC1U10V2KX-1GP"
			(at -1.1811 -2.7051 270)
			(unlocked yes)
			(layer "B.Fab")
			(hide yes)
			(effects
				(font
					(size 1.016 1.016)
					(thickness 0.1524)
				)
				(justify mirror)
			)
		)
		(property "Device Type" "C402H22"
			(at -1.1811 -4.2291 270)
			(unlocked yes)
			(layer "B.Fab")
			(hide yes)
			(effects
				(font
					(size 1.016 1.016)
					(thickness 0.1524)
				)
				(justify mirror)
			)
		)
		(duplicate_pad_numbers_are_jumpers no)
		(fp_rect
			(start 0.4318 0.9525)
			(end -0.4318 -0.9525)
			(stroke
				(width 0)
				(type default)
			)
			(fill no)
			(layer "B.CrtYd")
		)
		(fp_rect
			(start 0.4318 0.9525)
			(end -0.4318 -0.9525)
			(stroke
				(width 0)
				(type default)
			)
			(fill no)
			(layer "B.Fab")
		)
		(pad "1" smd custom
			(at 0 -0.4445 90)
			(size 0.1524 0.1524)
			(layers "B.Cu" "B.Mask" "B.Paste")
			(net "P3V3_STBY")
			(options
				(clearance outline)
				(anchor circle)
			)
			(primitives
				(gr_poly
					(pts
						(arc
							(start 0.3048 0.2032)
							(mid 0.275042 0.275042)
							(end 0.2032 0.3048)
						)
						(arc
							(start -0.2032 0.3048)
							(mid -0.275042 0.275042)
							(end -0.3048 0.2032)
						)
						(arc
							(start -0.3048 -0.2032)
							(mid -0.275042 -0.275042)
							(end -0.2032 -0.3048)
						)
						(arc
							(start 0.2032 -0.3048)
							(mid 0.275042 -0.275042)
							(end 0.3048 -0.2032)
						)
					)
					(width 0)
					(fill yes)
				)
			)
		)
		(pad "2" smd custom
			(at 0 0.4445 90)
			(size 0.1524 0.1524)
			(layers "B.Cu" "B.Mask" "B.Paste")
			(net "GND")
			(options
				(clearance outline)
				(anchor circle)
			)
			(primitives
				(gr_poly
					(pts
						(arc
							(start 0.3048 0.2032)
							(mid 0.275042 0.275042)
							(end 0.2032 0.3048)
						)
						(arc
							(start -0.2032 0.3048)
							(mid -0.275042 0.275042)
							(end -0.3048 0.2032)
						)
						(arc
							(start -0.3048 -0.2032)
							(mid -0.275042 -0.275042)
							(end -0.2032 -0.3048)
						)
						(arc
							(start 0.2032 -0.3048)
							(mid 0.275042 -0.275042)
							(end 0.3048 -0.2032)
						)
					)
					(width 0)
					(fill yes)
				)
			)
		)
	)
	(footprint ""
		(layer "B.Cu")
		(at 102.997 -231.013 -90)
		(property "Reference" "R664"
			(at 0 0 90)
			(layer "B.SilkS")
			(hide yes)
			(effects
				(font
					(size 1.27 1.27)
				)
				(justify mirror)
			)
		)
		(property "Value" "0R2J-2-GP"
			(at -0.064008 -3.993896 270)
			(unlocked yes)
			(layer "B.Fab")
			(hide yes)
			(effects
				(font
					(size 1.016 1.016)
					(thickness 0.1524)
				)
				(justify mirror)
			)
		)
		(property "Device Type" "R402H16"
			(at -0.064008 -5.517896 270)
			(unlocked yes)
			(layer "B.Fab")
			(hide yes)
			(effects
				(font
					(size 1.016 1.016)
					(thickness 0.1524)
				)
				(justify mirror)
			)
		)
		(duplicate_pad_numbers_are_jumpers no)
		(fp_line
			(start -0.508 -0.9398)
			(end 0.508 -0.9398)
			(stroke
				(width 0.1524)
				(type default)
			)
			(layer "B.SilkS")
		)
		(fp_line
			(start 0.508 -0.9398)
			(end 0.508 0.9398)
			(stroke
				(width 0.1524)
				(type default)
			)
			(layer "B.SilkS")
		)
		(fp_rect
			(start 0.508 0.9398)
			(end -0.508 -0.9398)
			(stroke
				(width 0)
				(type default)
			)
			(fill no)
			(layer "B.CrtYd")
		)
		(fp_rect
			(start 0.508 0.9398)
			(end -0.508 -0.9398)
			(stroke
				(width 0)
				(type default)
			)
			(fill no)
			(layer "B.Fab")
		)
		(pad "1" smd custom
			(at 0 -0.4445 90)
			(size 0.1397 0.1397)
			(layers "B.Cu" "B.Mask" "B.Paste")
			(net "SAS_FAULT_LED5")
			(options
				(clearance outline)
				(anchor circle)
			)
			(primitives
				(gr_poly
					(pts
						(arc
							(start -0.1778 0.2794)
							(mid -0.249642 0.249642)
							(end -0.2794 0.1778)
						)
						(arc
							(start -0.2794 -0.1778)
							(mid -0.249642 -0.249642)
							(end -0.1778 -0.2794)
						)
						(arc
							(start 0.1778 -0.2794)
							(mid 0.249642 -0.249642)
							(end 0.2794 -0.1778)
						)
						(arc
							(start 0.2794 0.1778)
							(mid 0.249642 0.249642)
							(end 0.1778 0.2794)
						)
					)
					(width 0)
					(fill yes)
				)
			)
		)
		(pad "2" smd custom
			(at 0 0.4445 90)
			(size 0.1397 0.1397)
			(layers "B.Cu" "B.Mask" "B.Paste")
			(net "SAS_HDD_LED_5")
			(options
				(clearance outline)
				(anchor circle)
			)
			(primitives
				(gr_poly
					(pts
						(arc
							(start -0.1778 0.2794)
							(mid -0.249642 0.249642)
							(end -0.2794 0.1778)
						)
						(arc
							(start -0.2794 -0.1778)
							(mid -0.249642 -0.249642)
							(end -0.1778 -0.2794)
						)
						(arc
							(start 0.1778 -0.2794)
							(mid 0.249642 -0.249642)
							(end 0.2794 -0.1778)
						)
						(arc
							(start 0.2794 0.1778)
							(mid 0.249642 0.249642)
							(end 0.1778 0.2794)
						)
					)
					(width 0)
					(fill yes)
				)
			)
		)
	)
	(footprint ""
		(layer "B.Cu")
		(at 318.008 -176.657 -90)
		(property "Reference" "R315"
			(at 0 0 90)
			(layer "B.SilkS")
			(hide yes)
			(effects
				(font
					(size 1.27 1.27)
				)
				(justify mirror)
			)
		)
		(property "Value" "0R2J-2-GP"
			(at -0.064008 -3.993896 270)
			(unlocked yes)
			(layer "B.Fab")
			(hide yes)
			(effects
				(font
					(size 1.016 1.016)
					(thickness 0.1524)
				)
				(justify mirror)
			)
		)
		(property "Device Type" "R402H16"
			(at -0.064008 -5.517896 270)
			(unlocked yes)
			(layer "B.Fab")
			(hide yes)
			(effects
				(font
					(size 1.016 1.016)
					(thickness 0.1524)
				)
				(justify mirror)
			)
		)
		(duplicate_pad_numbers_are_jumpers no)
		(fp_line
			(start -0.508 -0.9398)
			(end 0.508 -0.9398)
			(stroke
				(width 0.1524)
				(type default)
			)
			(layer "B.SilkS")
		)
		(fp_line
			(start 0.508 -0.9398)
			(end 0.508 0.9398)
			(stroke
				(width 0.1524)
				(type default)
			)
			(layer "B.SilkS")
		)
		(fp_rect
			(start 0.508 0.9398)
			(end -0.508 -0.9398)
			(stroke
				(width 0)
				(type default)
			)
			(fill no)
			(layer "B.CrtYd")
		)
		(fp_rect
			(start 0.508 0.9398)
			(end -0.508 -0.9398)
			(stroke
				(width 0)
				(type default)
			)
			(fill no)
			(layer "B.Fab")
		)
		(pad "1" smd custom
			(at 0 -0.4445 90)
			(size 0.1397 0.1397)
			(layers "B.Cu" "B.Mask" "B.Paste")
			(net "ADC_12V")
			(options
				(clearance outline)
				(anchor circle)
			)
			(primitives
				(gr_poly
					(pts
						(arc
							(start -0.1778 0.2794)
							(mid -0.249642 0.249642)
							(end -0.2794 0.1778)
						)
						(arc
							(start -0.2794 -0.1778)
							(mid -0.249642 -0.249642)
							(end -0.1778 -0.2794)
						)
						(arc
							(start 0.1778 -0.2794)
							(mid 0.249642 -0.249642)
							(end 0.2794 -0.1778)
						)
						(arc
							(start 0.2794 0.1778)
							(mid 0.249642 0.249642)
							(end 0.1778 0.2794)
						)
					)
					(width 0)
					(fill yes)
				)
			)
		)
		(pad "2" smd custom
			(at 0 0.4445 90)
			(size 0.1397 0.1397)
			(layers "B.Cu" "B.Mask" "B.Paste")
			(net "ADC0_12V_BMC")
			(options
				(clearance outline)
				(anchor circle)
			)
			(primitives
				(gr_poly
					(pts
						(arc
							(start -0.1778 0.2794)
							(mid -0.249642 0.249642)
							(end -0.2794 0.1778)
						)
						(arc
							(start -0.2794 -0.1778)
							(mid -0.249642 -0.249642)
							(end -0.1778 -0.2794)
						)
						(arc
							(start 0.1778 -0.2794)
							(mid 0.249642 -0.249642)
							(end 0.2794 -0.1778)
						)
						(arc
							(start 0.2794 0.1778)
							(mid 0.249642 0.249642)
							(end 0.1778 0.2794)
						)
					)
					(width 0)
					(fill yes)
				)
			)
		)
	)
	(footprint ""
		(layer "B.Cu")
		(at 122.69597 -100.33 180)
		(property "Reference" "SC1186"
			(at 0 0 0)
			(layer "B.SilkS")
			(hide yes)
			(effects
				(font
					(size 1.27 1.27)
				)
				(justify mirror)
			)
		)
		(property "Value" "SCD1U6D3V1KX-GP"
			(at 2.8321 -1.7399 180)
			(unlocked yes)
			(layer "B.Fab")
			(hide yes)
			(effects
				(font
					(size 1.016 1.016)
					(thickness 0.1524)
				)
				(justify mirror)
			)
		)
		(property "Device Type" "C0201H13"
			(at 2.8321 -3.2639 180)
			(unlocked yes)
			(layer "B.Fab")
			(hide yes)
			(effects
				(font
					(size 1.016 1.016)
					(thickness 0.1524)
				)
				(justify mirror)
			)
		)
		(duplicate_pad_numbers_are_jumpers no)
		(fp_rect
			(start 0.2794 0.6477)
			(end -0.2794 -0.6477)
			(stroke
				(width 0)
				(type default)
			)
			(fill no)
			(layer "B.CrtYd")
		)
		(fp_rect
			(start 0.2794 0.6477)
			(end -0.2794 -0.6477)
			(stroke
				(width 0)
				(type default)
			)
			(fill no)
			(layer "B.Fab")
		)
		(pad "1" smd custom
			(at 0 -0.2794)
			(size 0.0762 0.0762)
			(layers "B.Cu" "B.Mask" "B.Paste")
			(net "GB_VDDA")
			(options
				(clearance outline)
				(anchor circle)
			)
			(primitives
				(gr_poly
					(pts
						(arc
							(start 0.1524 0.127)
							(mid 0.137521 0.162921)
							(end 0.1016 0.1778)
						)
						(arc
							(start -0.1016 0.1778)
							(mid -0.137521 0.162921)
							(end -0.1524 0.127)
						)
						(arc
							(start -0.1524 -0.127)
							(mid -0.137521 -0.162921)
							(end -0.1016 -0.1778)
						)
						(arc
							(start 0.1016 -0.1778)
							(mid 0.137521 -0.162921)
							(end 0.1524 -0.127)
						)
					)
					(width 0)
					(fill yes)
				)
			)
		)
		(pad "2" smd custom
			(at 0 0.2794)
			(size 0.0762 0.0762)
			(layers "B.Cu" "B.Mask" "B.Paste")
			(net "GND")
			(options
				(clearance outline)
				(anchor circle)
			)
			(primitives
				(gr_poly
					(pts
						(arc
							(start 0.1524 0.127)
							(mid 0.137521 0.162921)
							(end 0.1016 0.1778)
						)
						(arc
							(start -0.1016 0.1778)
							(mid -0.137521 0.162921)
							(end -0.1524 0.127)
						)
						(arc
							(start -0.1524 -0.127)
							(mid -0.137521 -0.162921)
							(end -0.1016 -0.1778)
						)
						(arc
							(start 0.1016 -0.1778)
							(mid 0.137521 -0.162921)
							(end 0.1524 -0.127)
						)
					)
					(width 0)
					(fill yes)
				)
			)
		)
	)
	(footprint ""
		(layer "B.Cu")
		(at 19.170904 -100.400866)
		(property "Reference" "C136"
			(at 0 0 0)
			(layer "B.SilkS")
			(hide yes)
			(effects
				(font
					(size 1.27 1.27)
				)
				(justify mirror)
			)
		)
		(property "Value" "SCD01U50V2KX-1GP"
			(at -1.1811 -2.7051 0)
			(unlocked yes)
			(layer "B.Fab")
			(hide yes)
			(effects
				(font
					(size 1.016 1.016)
					(thickness 0.1524)
				)
				(justify mirror)
			)
		)
		(property "Device Type" "C402H22"
			(at -1.1811 -4.2291 0)
			(unlocked yes)
			(layer "B.Fab")
			(hide yes)
			(effects
				(font
					(size 1.016 1.016)
					(thickness 0.1524)
				)
				(justify mirror)
			)
		)
		(duplicate_pad_numbers_are_jumpers no)
		(fp_rect
			(start 0.4318 0.9525)
			(end -0.4318 -0.9525)
			(stroke
				(width 0)
				(type default)
			)
			(fill no)
			(layer "B.CrtYd")
		)
		(fp_rect
			(start 0.4318 0.9525)
			(end -0.4318 -0.9525)
			(stroke
				(width 0)
				(type default)
			)
			(fill no)
			(layer "B.Fab")
		)
		(pad "1" smd custom
			(at 0 -0.4445 180)
			(size 0.1524 0.1524)
			(layers "B.Cu" "B.Mask" "B.Paste")
			(net "IOC_SAS_RX_N7")
			(options
				(clearance outline)
				(anchor circle)
			)
			(primitives
				(gr_poly
					(pts
						(arc
							(start 0.3048 0.2032)
							(mid 0.275042 0.275042)
							(end 0.2032 0.3048)
						)
						(arc
							(start -0.2032 0.3048)
							(mid -0.275042 0.275042)
							(end -0.3048 0.2032)
						)
						(arc
							(start -0.3048 -0.2032)
							(mid -0.275042 -0.275042)
							(end -0.2032 -0.3048)
						)
						(arc
							(start 0.2032 -0.3048)
							(mid 0.275042 -0.275042)
							(end 0.3048 -0.2032)
						)
					)
					(width 0)
					(fill yes)
				)
			)
		)
		(pad "2" smd custom
			(at 0 0.4445 180)
			(size 0.1524 0.1524)
			(layers "B.Cu" "B.Mask" "B.Paste")
			(net "SAS_EXT_CONN_RX19_N")
			(options
				(clearance outline)
				(anchor circle)
			)
			(primitives
				(gr_poly
					(pts
						(arc
							(start 0.3048 0.2032)
							(mid 0.275042 0.275042)
							(end 0.2032 0.3048)
						)
						(arc
							(start -0.2032 0.3048)
							(mid -0.275042 0.275042)
							(end -0.3048 0.2032)
						)
						(arc
							(start -0.3048 -0.2032)
							(mid -0.275042 -0.275042)
							(end -0.2032 -0.3048)
						)
						(arc
							(start 0.2032 -0.3048)
							(mid 0.275042 -0.275042)
							(end 0.3048 -0.2032)
						)
					)
					(width 0)
					(fill yes)
				)
			)
		)
	)
	(footprint ""
		(layer "B.Cu")
		(at 104.325166 -50.292 180)
		(property "Reference" "SC1037"
			(at 0 0 0)
			(layer "B.SilkS")
			(hide yes)
			(effects
				(font
					(size 1.27 1.27)
				)
				(justify mirror)
			)
		)
		(property "Value" "SCD1U16V2KX-3GP"
			(at -1.1811 -2.7051 180)
			(unlocked yes)
			(layer "B.Fab")
			(hide yes)
			(effects
				(font
					(size 1.016 1.016)
					(thickness 0.1524)
				)
				(justify mirror)
			)
		)
		(property "Device Type" "C402H22"
			(at -1.1811 -4.2291 180)
			(unlocked yes)
			(layer "B.Fab")
			(hide yes)
			(effects
				(font
					(size 1.016 1.016)
					(thickness 0.1524)
				)
				(justify mirror)
			)
		)
		(duplicate_pad_numbers_are_jumpers no)
		(fp_rect
			(start 0.4318 0.9525)
			(end -0.4318 -0.9525)
			(stroke
				(width 0)
				(type default)
			)
			(fill no)
			(layer "B.CrtYd")
		)
		(fp_rect
			(start 0.4318 0.9525)
			(end -0.4318 -0.9525)
			(stroke
				(width 0)
				(type default)
			)
			(fill no)
			(layer "B.Fab")
		)
		(pad "1" smd custom
			(at 0 -0.4445)
			(size 0.1524 0.1524)
			(layers "B.Cu" "B.Mask" "B.Paste")
			(net "P0V955_C")
			(options
				(clearance outline)
				(anchor circle)
			)
			(primitives
				(gr_poly
					(pts
						(arc
							(start 0.3048 0.2032)
							(mid 0.275042 0.275042)
							(end 0.2032 0.3048)
						)
						(arc
							(start -0.2032 0.3048)
							(mid -0.275042 0.275042)
							(end -0.3048 0.2032)
						)
						(arc
							(start -0.3048 -0.2032)
							(mid -0.275042 -0.275042)
							(end -0.2032 -0.3048)
						)
						(arc
							(start 0.2032 -0.3048)
							(mid 0.275042 -0.275042)
							(end 0.3048 -0.2032)
						)
					)
					(width 0)
					(fill yes)
				)
			)
		)
		(pad "2" smd custom
			(at 0 0.4445)
			(size 0.1524 0.1524)
			(layers "B.Cu" "B.Mask" "B.Paste")
			(net "GND")
			(options
				(clearance outline)
				(anchor circle)
			)
			(primitives
				(gr_poly
					(pts
						(arc
							(start 0.3048 0.2032)
							(mid 0.275042 0.275042)
							(end 0.2032 0.3048)
						)
						(arc
							(start -0.2032 0.3048)
							(mid -0.275042 0.275042)
							(end -0.3048 0.2032)
						)
						(arc
							(start -0.3048 -0.2032)
							(mid -0.275042 -0.275042)
							(end -0.2032 -0.3048)
						)
						(arc
							(start 0.2032 -0.3048)
							(mid 0.275042 -0.275042)
							(end 0.3048 -0.2032)
						)
					)
					(width 0)
					(fill yes)
				)
			)
		)
	)
	(footprint ""
		(layer "B.Cu")
		(at 274.193 -175.641 90)
		(property "Reference" "R364"
			(at 0 0 90)
			(layer "B.SilkS")
			(hide yes)
			(effects
				(font
					(size 1.27 1.27)
				)
				(justify mirror)
			)
		)
		(property "Value" "3K3R2F-2-GP"
			(at -0.064008 -3.993896 90)
			(unlocked yes)
			(layer "B.Fab")
			(hide yes)
			(effects
				(font
					(size 1.016 1.016)
					(thickness 0.1524)
				)
				(justify mirror)
			)
		)
		(property "Device Type" "R402H16"
			(at -0.064008 -5.517896 90)
			(unlocked yes)
			(layer "B.Fab")
			(hide yes)
			(effects
				(font
					(size 1.016 1.016)
					(thickness 0.1524)
				)
				(justify mirror)
			)
		)
		(duplicate_pad_numbers_are_jumpers no)
		(fp_line
			(start 0.508 -0.9398)
			(end 0.508 0.9398)
			(stroke
				(width 0.1524)
				(type default)
			)
			(layer "B.SilkS")
		)
		(fp_line
			(start -0.508 -0.9398)
			(end 0.508 -0.9398)
			(stroke
				(width 0.1524)
				(type default)
			)
			(layer "B.SilkS")
		)
		(fp_rect
			(start 0.508 0.9398)
			(end -0.508 -0.9398)
			(stroke
				(width 0)
				(type default)
			)
			(fill no)
			(layer "B.CrtYd")
		)
		(fp_rect
			(start 0.508 0.9398)
			(end -0.508 -0.9398)
			(stroke
				(width 0)
				(type default)
			)
			(fill no)
			(layer "B.Fab")
		)
		(pad "1" smd custom
			(at 0 -0.4445 270)
			(size 0.1397 0.1397)
			(layers "B.Cu" "B.Mask" "B.Paste")
			(net "P3V3_STBY")
			(options
				(clearance outline)
				(anchor circle)
			)
			(primitives
				(gr_poly
					(pts
						(arc
							(start -0.1778 0.2794)
							(mid -0.249642 0.249642)
							(end -0.2794 0.1778)
						)
						(arc
							(start -0.2794 -0.1778)
							(mid -0.249642 -0.249642)
							(end -0.1778 -0.2794)
						)
						(arc
							(start 0.1778 -0.2794)
							(mid 0.249642 -0.249642)
							(end 0.2794 -0.1778)
						)
						(arc
							(start 0.2794 0.1778)
							(mid 0.249642 0.249642)
							(end 0.1778 0.2794)
						)
					)
					(width 0)
					(fill yes)
				)
			)
		)
		(pad "2" smd custom
			(at 0 0.4445 270)
			(size 0.1397 0.1397)
			(layers "B.Cu" "B.Mask" "B.Paste")
			(net "ROMA14")
			(options
				(clearance outline)
				(anchor circle)
			)
			(primitives
				(gr_poly
					(pts
						(arc
							(start -0.1778 0.2794)
							(mid -0.249642 0.249642)
							(end -0.2794 0.1778)
						)
						(arc
							(start -0.2794 -0.1778)
							(mid -0.249642 -0.249642)
							(end -0.1778 -0.2794)
						)
						(arc
							(start 0.1778 -0.2794)
							(mid 0.249642 -0.249642)
							(end 0.2794 -0.1778)
						)
						(arc
							(start 0.2794 0.1778)
							(mid 0.249642 0.249642)
							(end 0.1778 0.2794)
						)
					)
					(width 0)
					(fill yes)
				)
			)
		)
	)
	(footprint ""
		(layer "B.Cu")
		(at 15.62608 -231.822752)
		(property "Reference" "R516"
			(at 0 0 0)
			(layer "B.SilkS")
			(hide yes)
			(effects
				(font
					(size 1.27 1.27)
				)
				(justify mirror)
			)
		)
		(property "Value" "0R2J-2-GP"
			(at -0.064008 -3.993896 0)
			(unlocked yes)
			(layer "B.Fab")
			(hide yes)
			(effects
				(font
					(size 1.016 1.016)
					(thickness 0.1524)
				)
				(justify mirror)
			)
		)
		(property "Device Type" "R402H16"
			(at -0.064008 -5.517896 0)
			(unlocked yes)
			(layer "B.Fab")
			(hide yes)
			(effects
				(font
					(size 1.016 1.016)
					(thickness 0.1524)
				)
				(justify mirror)
			)
		)
		(duplicate_pad_numbers_are_jumpers no)
		(fp_line
			(start -0.508 -0.9398)
			(end 0.508 -0.9398)
			(stroke
				(width 0.1524)
				(type default)
			)
			(layer "B.SilkS")
		)
		(fp_line
			(start 0.508 -0.9398)
			(end 0.508 0.9398)
			(stroke
				(width 0.1524)
				(type default)
			)
			(layer "B.SilkS")
		)
		(fp_rect
			(start 0.508 0.9398)
			(end -0.508 -0.9398)
			(stroke
				(width 0)
				(type default)
			)
			(fill no)
			(layer "B.CrtYd")
		)
		(fp_rect
			(start 0.508 0.9398)
			(end -0.508 -0.9398)
			(stroke
				(width 0)
				(type default)
			)
			(fill no)
			(layer "B.Fab")
		)
		(pad "1" smd custom
			(at 0 -0.4445 180)
			(size 0.1397 0.1397)
			(layers "B.Cu" "B.Mask" "B.Paste")
			(net "SAS_HDD_PWR14_PCIE")
			(options
				(clearance outline)
				(anchor circle)
			)
			(primitives
				(gr_poly
					(pts
						(arc
							(start -0.1778 0.2794)
							(mid -0.249642 0.249642)
							(end -0.2794 0.1778)
						)
						(arc
							(start -0.2794 -0.1778)
							(mid -0.249642 -0.249642)
							(end -0.1778 -0.2794)
						)
						(arc
							(start 0.1778 -0.2794)
							(mid 0.249642 -0.249642)
							(end 0.2794 -0.1778)
						)
						(arc
							(start 0.2794 0.1778)
							(mid 0.249642 0.249642)
							(end 0.1778 0.2794)
						)
					)
					(width 0)
					(fill yes)
				)
			)
		)
		(pad "2" smd custom
			(at 0 0.4445 180)
			(size 0.1397 0.1397)
			(layers "B.Cu" "B.Mask" "B.Paste")
			(net "SAS_HDD_PWR14")
			(options
				(clearance outline)
				(anchor circle)
			)
			(primitives
				(gr_poly
					(pts
						(arc
							(start -0.1778 0.2794)
							(mid -0.249642 0.249642)
							(end -0.2794 0.1778)
						)
						(arc
							(start -0.2794 -0.1778)
							(mid -0.249642 -0.249642)
							(end -0.1778 -0.2794)
						)
						(arc
							(start 0.1778 -0.2794)
							(mid 0.249642 -0.249642)
							(end 0.2794 -0.1778)
						)
						(arc
							(start 0.2794 0.1778)
							(mid 0.249642 0.249642)
							(end 0.1778 0.2794)
						)
					)
					(width 0)
					(fill yes)
				)
			)
		)
	)
	(footprint ""
		(layer "B.Cu")
		(at 102.87 -239.395)
		(property "Reference" "SR846"
			(at 0 0 0)
			(layer "B.SilkS")
			(hide yes)
			(effects
				(font
					(size 1.27 1.27)
				)
				(justify mirror)
			)
		)
		(property "Value" "4K7R2F-GP"
			(at -0.064008 -3.993896 0)
			(unlocked yes)
			(layer "B.Fab")
			(hide yes)
			(effects
				(font
					(size 1.016 1.016)
					(thickness 0.1524)
				)
				(justify mirror)
			)
		)
		(property "Device Type" "R402H16"
			(at -0.064008 -5.517896 0)
			(unlocked yes)
			(layer "B.Fab")
			(hide yes)
			(effects
				(font
					(size 1.016 1.016)
					(thickness 0.1524)
				)
				(justify mirror)
			)
		)
		(duplicate_pad_numbers_are_jumpers no)
		(fp_line
			(start -0.508 -0.9398)
			(end 0.508 -0.9398)
			(stroke
				(width 0.1524)
				(type default)
			)
			(layer "B.SilkS")
		)
		(fp_line
			(start 0.508 -0.9398)
			(end 0.508 0.9398)
			(stroke
				(width 0.1524)
				(type default)
			)
			(layer "B.SilkS")
		)
		(fp_rect
			(start 0.508 0.9398)
			(end -0.508 -0.9398)
			(stroke
				(width 0)
				(type default)
			)
			(fill no)
			(layer "B.CrtYd")
		)
		(fp_rect
			(start 0.508 0.9398)
			(end -0.508 -0.9398)
			(stroke
				(width 0)
				(type default)
			)
			(fill no)
			(layer "B.Fab")
		)
		(pad "1" smd custom
			(at 0 -0.4445 180)
			(size 0.1397 0.1397)
			(layers "B.Cu" "B.Mask" "B.Paste")
			(net "SAS_FAULT_LED3")
			(options
				(clearance outline)
				(anchor circle)
			)
			(primitives
				(gr_poly
					(pts
						(arc
							(start -0.1778 0.2794)
							(mid -0.249642 0.249642)
							(end -0.2794 0.1778)
						)
						(arc
							(start -0.2794 -0.1778)
							(mid -0.249642 -0.249642)
							(end -0.1778 -0.2794)
						)
						(arc
							(start 0.1778 -0.2794)
							(mid 0.249642 -0.249642)
							(end 0.2794 -0.1778)
						)
						(arc
							(start 0.2794 0.1778)
							(mid 0.249642 0.249642)
							(end 0.1778 0.2794)
						)
					)
					(width 0)
					(fill yes)
				)
			)
		)
		(pad "2" smd custom
			(at 0 0.4445 180)
			(size 0.1397 0.1397)
			(layers "B.Cu" "B.Mask" "B.Paste")
			(net "P3V3_STBY")
			(options
				(clearance outline)
				(anchor circle)
			)
			(primitives
				(gr_poly
					(pts
						(arc
							(start -0.1778 0.2794)
							(mid -0.249642 0.249642)
							(end -0.2794 0.1778)
						)
						(arc
							(start -0.2794 -0.1778)
							(mid -0.249642 -0.249642)
							(end -0.1778 -0.2794)
						)
						(arc
							(start 0.1778 -0.2794)
							(mid 0.249642 -0.249642)
							(end 0.2794 -0.1778)
						)
						(arc
							(start 0.2794 0.1778)
							(mid 0.249642 0.249642)
							(end 0.1778 0.2794)
						)
					)
					(width 0)
					(fill yes)
				)
			)
		)
	)
	(footprint ""
		(layer "B.Cu")
		(at 104.902 -239.395)
		(property "Reference" "SR946"
			(at 0 0 0)
			(layer "B.SilkS")
			(hide yes)
			(effects
				(font
					(size 1.27 1.27)
				)
				(justify mirror)
			)
		)
		(property "Value" "4K7R2F-GP"
			(at -0.064008 -3.993896 0)
			(unlocked yes)
			(layer "B.Fab")
			(hide yes)
			(effects
				(font
					(size 1.016 1.016)
					(thickness 0.1524)
				)
				(justify mirror)
			)
		)
		(property "Device Type" "R402H16"
			(at -0.064008 -5.517896 0)
			(unlocked yes)
			(layer "B.Fab")
			(hide yes)
			(effects
				(font
					(size 1.016 1.016)
					(thickness 0.1524)
				)
				(justify mirror)
			)
		)
		(duplicate_pad_numbers_are_jumpers no)
		(fp_line
			(start -0.508 -0.9398)
			(end 0.508 -0.9398)
			(stroke
				(width 0.1524)
				(type default)
			)
			(layer "B.SilkS")
		)
		(fp_line
			(start 0.508 -0.9398)
			(end 0.508 0.9398)
			(stroke
				(width 0.1524)
				(type default)
			)
			(layer "B.SilkS")
		)
		(fp_rect
			(start 0.508 0.9398)
			(end -0.508 -0.9398)
			(stroke
				(width 0)
				(type default)
			)
			(fill no)
			(layer "B.CrtYd")
		)
		(fp_rect
			(start 0.508 0.9398)
			(end -0.508 -0.9398)
			(stroke
				(width 0)
				(type default)
			)
			(fill no)
			(layer "B.Fab")
		)
		(pad "1" smd custom
			(at 0 -0.4445 180)
			(size 0.1397 0.1397)
			(layers "B.Cu" "B.Mask" "B.Paste")
			(net "SAS_FAULT_LED5")
			(options
				(clearance outline)
				(anchor circle)
			)
			(primitives
				(gr_poly
					(pts
						(arc
							(start -0.1778 0.2794)
							(mid -0.249642 0.249642)
							(end -0.2794 0.1778)
						)
						(arc
							(start -0.2794 -0.1778)
							(mid -0.249642 -0.249642)
							(end -0.1778 -0.2794)
						)
						(arc
							(start 0.1778 -0.2794)
							(mid 0.249642 -0.249642)
							(end 0.2794 -0.1778)
						)
						(arc
							(start 0.2794 0.1778)
							(mid 0.249642 0.249642)
							(end 0.1778 0.2794)
						)
					)
					(width 0)
					(fill yes)
				)
			)
		)
		(pad "2" smd custom
			(at 0 0.4445 180)
			(size 0.1397 0.1397)
			(layers "B.Cu" "B.Mask" "B.Paste")
			(net "P3V3_STBY")
			(options
				(clearance outline)
				(anchor circle)
			)
			(primitives
				(gr_poly
					(pts
						(arc
							(start -0.1778 0.2794)
							(mid -0.249642 0.249642)
							(end -0.2794 0.1778)
						)
						(arc
							(start -0.2794 -0.1778)
							(mid -0.249642 -0.249642)
							(end -0.1778 -0.2794)
						)
						(arc
							(start 0.1778 -0.2794)
							(mid 0.249642 -0.249642)
							(end 0.2794 -0.1778)
						)
						(arc
							(start 0.2794 0.1778)
							(mid 0.249642 0.249642)
							(end 0.1778 0.2794)
						)
					)
					(width 0)
					(fill yes)
				)
			)
		)
	)
	(footprint ""
		(layer "B.Cu")
		(at 139.33297 -87.249)
		(property "Reference" "R597"
			(at 0 0 0)
			(layer "B.SilkS")
			(hide yes)
			(effects
				(font
					(size 1.27 1.27)
				)
				(justify mirror)
			)
		)
		(property "Value" "4K7R2F-GP"
			(at -0.064008 -3.993896 0)
			(unlocked yes)
			(layer "B.Fab")
			(hide yes)
			(effects
				(font
					(size 1.016 1.016)
					(thickness 0.1524)
				)
				(justify mirror)
			)
		)
		(property "Device Type" "R402H16"
			(at -0.064008 -5.517896 0)
			(unlocked yes)
			(layer "B.Fab")
			(hide yes)
			(effects
				(font
					(size 1.016 1.016)
					(thickness 0.1524)
				)
				(justify mirror)
			)
		)
		(duplicate_pad_numbers_are_jumpers no)
		(fp_line
			(start -0.508 -0.9398)
			(end 0.508 -0.9398)
			(stroke
				(width 0.1524)
				(type default)
			)
			(layer "B.SilkS")
		)
		(fp_line
			(start 0.508 -0.9398)
			(end 0.508 0.9398)
			(stroke
				(width 0.1524)
				(type default)
			)
			(layer "B.SilkS")
		)
		(fp_rect
			(start 0.508 0.9398)
			(end -0.508 -0.9398)
			(stroke
				(width 0)
				(type default)
			)
			(fill no)
			(layer "B.CrtYd")
		)
		(fp_rect
			(start 0.508 0.9398)
			(end -0.508 -0.9398)
			(stroke
				(width 0)
				(type default)
			)
			(fill no)
			(layer "B.Fab")
		)
		(pad "1" smd custom
			(at 0 -0.4445 180)
			(size 0.1397 0.1397)
			(layers "B.Cu" "B.Mask" "B.Paste")
			(net "P3V3_STBY")
			(options
				(clearance outline)
				(anchor circle)
			)
			(primitives
				(gr_poly
					(pts
						(arc
							(start -0.1778 0.2794)
							(mid -0.249642 0.249642)
							(end -0.2794 0.1778)
						)
						(arc
							(start -0.2794 -0.1778)
							(mid -0.249642 -0.249642)
							(end -0.1778 -0.2794)
						)
						(arc
							(start 0.1778 -0.2794)
							(mid 0.249642 -0.249642)
							(end 0.2794 -0.1778)
						)
						(arc
							(start 0.2794 0.1778)
							(mid 0.249642 0.249642)
							(end 0.1778 0.2794)
						)
					)
					(width 0)
					(fill yes)
				)
			)
		)
		(pad "2" smd custom
			(at 0 0.4445 180)
			(size 0.1397 0.1397)
			(layers "B.Cu" "B.Mask" "B.Paste")
			(net "TEMP_3_A2")
			(options
				(clearance outline)
				(anchor circle)
			)
			(primitives
				(gr_poly
					(pts
						(arc
							(start -0.1778 0.2794)
							(mid -0.249642 0.249642)
							(end -0.2794 0.1778)
						)
						(arc
							(start -0.2794 -0.1778)
							(mid -0.249642 -0.249642)
							(end -0.1778 -0.2794)
						)
						(arc
							(start 0.1778 -0.2794)
							(mid 0.249642 -0.249642)
							(end 0.2794 -0.1778)
						)
						(arc
							(start 0.2794 0.1778)
							(mid 0.249642 0.249642)
							(end 0.1778 0.2794)
						)
					)
					(width 0)
					(fill yes)
				)
			)
		)
	)
	(footprint ""
		(layer "B.Cu")
		(at 158.42996 -105.003854 90)
		(property "Reference" "SC1241"
			(at 0 0 90)
			(layer "B.SilkS")
			(hide yes)
			(effects
				(font
					(size 1.27 1.27)
				)
				(justify mirror)
			)
		)
		(property "Value" "SCD1U6D3V1KX-GP"
			(at 2.8321 -1.7399 90)
			(unlocked yes)
			(layer "B.Fab")
			(hide yes)
			(effects
				(font
					(size 1.016 1.016)
					(thickness 0.1524)
				)
				(justify mirror)
			)
		)
		(property "Device Type" "C0201H13"
			(at 2.8321 -3.2639 90)
			(unlocked yes)
			(layer "B.Fab")
			(hide yes)
			(effects
				(font
					(size 1.016 1.016)
					(thickness 0.1524)
				)
				(justify mirror)
			)
		)
		(duplicate_pad_numbers_are_jumpers no)
		(fp_rect
			(start 0.2794 0.6477)
			(end -0.2794 -0.6477)
			(stroke
				(width 0)
				(type default)
			)
			(fill no)
			(layer "B.CrtYd")
		)
		(fp_rect
			(start 0.2794 0.6477)
			(end -0.2794 -0.6477)
			(stroke
				(width 0)
				(type default)
			)
			(fill no)
			(layer "B.Fab")
		)
		(pad "1" smd custom
			(at 0 -0.2794 270)
			(size 0.0762 0.0762)
			(layers "B.Cu" "B.Mask" "B.Paste")
			(net "P0V9_E")
			(options
				(clearance outline)
				(anchor circle)
			)
			(primitives
				(gr_poly
					(pts
						(arc
							(start 0.1524 0.127)
							(mid 0.137521 0.162921)
							(end 0.1016 0.1778)
						)
						(arc
							(start -0.1016 0.1778)
							(mid -0.137521 0.162921)
							(end -0.1524 0.127)
						)
						(arc
							(start -0.1524 -0.127)
							(mid -0.137521 -0.162921)
							(end -0.1016 -0.1778)
						)
						(arc
							(start 0.1016 -0.1778)
							(mid 0.137521 -0.162921)
							(end 0.1524 -0.127)
						)
					)
					(width 0)
					(fill yes)
				)
			)
		)
		(pad "2" smd custom
			(at 0 0.2794 270)
			(size 0.0762 0.0762)
			(layers "B.Cu" "B.Mask" "B.Paste")
			(net "GND")
			(options
				(clearance outline)
				(anchor circle)
			)
			(primitives
				(gr_poly
					(pts
						(arc
							(start 0.1524 0.127)
							(mid 0.137521 0.162921)
							(end 0.1016 0.1778)
						)
						(arc
							(start -0.1016 0.1778)
							(mid -0.137521 0.162921)
							(end -0.1524 0.127)
						)
						(arc
							(start -0.1524 -0.127)
							(mid -0.137521 -0.162921)
							(end -0.1016 -0.1778)
						)
						(arc
							(start 0.1016 -0.1778)
							(mid 0.137521 -0.162921)
							(end 0.1524 -0.127)
						)
					)
					(width 0)
					(fill yes)
				)
			)
		)
	)
	(footprint ""
		(layer "B.Cu")
		(at 104.65816 -31.623)
		(property "Reference" "SC876"
			(at 0 0 0)
			(layer "B.SilkS")
			(hide yes)
			(effects
				(font
					(size 1.27 1.27)
				)
				(justify mirror)
			)
		)
		(property "Value" "SCD22U6D3V1MX-1-GP"
			(at 2.8321 -1.7399 0)
			(unlocked yes)
			(layer "B.Fab")
			(hide yes)
			(effects
				(font
					(size 1.016 1.016)
					(thickness 0.1524)
				)
				(justify mirror)
			)
		)
		(property "Device Type" "C0201H13"
			(at 2.8321 -3.2639 0)
			(unlocked yes)
			(layer "B.Fab")
			(hide yes)
			(effects
				(font
					(size 1.016 1.016)
					(thickness 0.1524)
				)
				(justify mirror)
			)
		)
		(duplicate_pad_numbers_are_jumpers no)
		(fp_rect
			(start 0.2794 0.6477)
			(end -0.2794 -0.6477)
			(stroke
				(width 0)
				(type default)
			)
			(fill no)
			(layer "B.CrtYd")
		)
		(fp_rect
			(start 0.2794 0.6477)
			(end -0.2794 -0.6477)
			(stroke
				(width 0)
				(type default)
			)
			(fill no)
			(layer "B.Fab")
		)
		(pad "1" smd custom
			(at 0 -0.2794 180)
			(size 0.0762 0.0762)
			(layers "B.Cu" "B.Mask" "B.Paste")
			(net "PCIE_SAS_C_CPU_RX_N7")
			(options
				(clearance outline)
				(anchor circle)
			)
			(primitives
				(gr_poly
					(pts
						(arc
							(start 0.1524 0.127)
							(mid 0.137521 0.162921)
							(end 0.1016 0.1778)
						)
						(arc
							(start -0.1016 0.1778)
							(mid -0.137521 0.162921)
							(end -0.1524 0.127)
						)
						(arc
							(start -0.1524 -0.127)
							(mid -0.137521 -0.162921)
							(end -0.1016 -0.1778)
						)
						(arc
							(start 0.1016 -0.1778)
							(mid 0.137521 -0.162921)
							(end 0.1524 -0.127)
						)
					)
					(width 0)
					(fill yes)
				)
			)
		)
		(pad "2" smd custom
			(at 0 0.2794 180)
			(size 0.0762 0.0762)
			(layers "B.Cu" "B.Mask" "B.Paste")
			(net "PCIE_SAS_CPU_RX_N7")
			(options
				(clearance outline)
				(anchor circle)
			)
			(primitives
				(gr_poly
					(pts
						(arc
							(start 0.1524 0.127)
							(mid 0.137521 0.162921)
							(end 0.1016 0.1778)
						)
						(arc
							(start -0.1016 0.1778)
							(mid -0.137521 0.162921)
							(end -0.1524 0.127)
						)
						(arc
							(start -0.1524 -0.127)
							(mid -0.137521 -0.162921)
							(end -0.1016 -0.1778)
						)
						(arc
							(start 0.1016 -0.1778)
							(mid 0.137521 -0.162921)
							(end 0.1524 -0.127)
						)
					)
					(width 0)
					(fill yes)
				)
			)
		)
	)
	(footprint ""
		(layer "B.Cu")
		(at 119.90197 -86.741)
		(property "Reference" "STP103"
			(at 0 0 0)
			(layer "B.SilkS")
			(hide yes)
			(effects
				(font
					(size 1.27 1.27)
				)
				(justify mirror)
			)
		)
		(property "Value" "TPAD28"
			(at -0.0127 -1.8034 0)
			(unlocked yes)
			(layer "B.Fab")
			(hide yes)
			(effects
				(font
					(size 1.016 1.016)
					(thickness 0.1524)
				)
				(justify mirror)
			)
		)
		(property "Device Type" "TPAD28"
			(at -0.0127 -3.3274 0)
			(unlocked yes)
			(layer "B.Fab")
			(hide yes)
			(effects
				(font
					(size 1.016 1.016)
					(thickness 0.1524)
				)
				(justify mirror)
			)
		)
		(duplicate_pad_numbers_are_jumpers no)
		(fp_poly
			(pts
				(arc
					(start 0.3556 0)
					(mid -0.3556 0)
					(end 0.3556 0)
				)
			)
			(stroke
				(width 0)
				(type default)
			)
			(fill no)
			(layer "B.CrtYd")
		)
		(fp_poly
			(pts
				(arc
					(start 0.6096 0)
					(mid -0.6096 0)
					(end 0.6096 0)
				)
			)
			(stroke
				(width 0)
				(type default)
			)
			(fill no)
			(layer "B.Fab")
		)
		(pad "1" smd circle
			(at 0 0 180)
			(size 0.7112 0.7112)
			(layers "B.Cu" "B.Mask" "B.Paste")
			(net "TEST_MUX_36")
		)
	)
	(footprint ""
		(layer "B.Cu")
		(at 300.9519 -182.91048)
		(property "Reference" "TP112"
			(at 0 0 0)
			(layer "B.SilkS")
			(hide yes)
			(effects
				(font
					(size 1.27 1.27)
				)
				(justify mirror)
			)
		)
		(property "Value" "TPAD28"
			(at -0.0127 -1.8034 0)
			(unlocked yes)
			(layer "B.Fab")
			(hide yes)
			(effects
				(font
					(size 1.016 1.016)
					(thickness 0.1524)
				)
				(justify mirror)
			)
		)
		(property "Device Type" "TPAD28"
			(at -0.0127 -3.3274 0)
			(unlocked yes)
			(layer "B.Fab")
			(hide yes)
			(effects
				(font
					(size 1.016 1.016)
					(thickness 0.1524)
				)
				(justify mirror)
			)
		)
		(duplicate_pad_numbers_are_jumpers no)
		(fp_poly
			(pts
				(arc
					(start 0.3556 0)
					(mid -0.3556 0)
					(end 0.3556 0)
				)
			)
			(stroke
				(width 0)
				(type default)
			)
			(fill no)
			(layer "B.CrtYd")
		)
		(fp_poly
			(pts
				(arc
					(start 0.6096 0)
					(mid -0.6096 0)
					(end 0.6096 0)
				)
			)
			(stroke
				(width 0)
				(type default)
			)
			(fill no)
			(layer "B.Fab")
		)
		(pad "1" smd circle
			(at 0 0 180)
			(size 0.7112 0.7112)
			(layers "B.Cu" "B.Mask" "B.Paste")
			(net "TP_BMC_GPIOM4")
		)
	)
	(footprint ""
		(layer "B.Cu")
		(at 295.9862 -203.962 180)
		(property "Reference" "C181"
			(at 0 0 0)
			(layer "B.SilkS")
			(hide yes)
			(effects
				(font
					(size 1.27 1.27)
				)
				(justify mirror)
			)
		)
		(property "Value" "SCD1U16V2KX-3GP"
			(at -1.1811 -2.7051 180)
			(unlocked yes)
			(layer "B.Fab")
			(hide yes)
			(effects
				(font
					(size 1.016 1.016)
					(thickness 0.1524)
				)
				(justify mirror)
			)
		)
		(property "Device Type" "C402H22"
			(at -1.1811 -4.2291 180)
			(unlocked yes)
			(layer "B.Fab")
			(hide yes)
			(effects
				(font
					(size 1.016 1.016)
					(thickness 0.1524)
				)
				(justify mirror)
			)
		)
		(duplicate_pad_numbers_are_jumpers no)
		(fp_rect
			(start 0.4318 0.9525)
			(end -0.4318 -0.9525)
			(stroke
				(width 0)
				(type default)
			)
			(fill no)
			(layer "B.CrtYd")
		)
		(fp_rect
			(start 0.4318 0.9525)
			(end -0.4318 -0.9525)
			(stroke
				(width 0)
				(type default)
			)
			(fill no)
			(layer "B.Fab")
		)
		(pad "1" smd custom
			(at 0 -0.4445)
			(size 0.1524 0.1524)
			(layers "B.Cu" "B.Mask" "B.Paste")
			(net "P1V53_STBY")
			(options
				(clearance outline)
				(anchor circle)
			)
			(primitives
				(gr_poly
					(pts
						(arc
							(start 0.3048 0.2032)
							(mid 0.275042 0.275042)
							(end 0.2032 0.3048)
						)
						(arc
							(start -0.2032 0.3048)
							(mid -0.275042 0.275042)
							(end -0.3048 0.2032)
						)
						(arc
							(start -0.3048 -0.2032)
							(mid -0.275042 -0.275042)
							(end -0.2032 -0.3048)
						)
						(arc
							(start 0.2032 -0.3048)
							(mid 0.275042 -0.275042)
							(end 0.3048 -0.2032)
						)
					)
					(width 0)
					(fill yes)
				)
			)
		)
		(pad "2" smd custom
			(at 0 0.4445)
			(size 0.1524 0.1524)
			(layers "B.Cu" "B.Mask" "B.Paste")
			(net "GND")
			(options
				(clearance outline)
				(anchor circle)
			)
			(primitives
				(gr_poly
					(pts
						(arc
							(start 0.3048 0.2032)
							(mid 0.275042 0.275042)
							(end 0.2032 0.3048)
						)
						(arc
							(start -0.2032 0.3048)
							(mid -0.275042 0.275042)
							(end -0.3048 0.2032)
						)
						(arc
							(start -0.3048 -0.2032)
							(mid -0.275042 -0.275042)
							(end -0.2032 -0.3048)
						)
						(arc
							(start 0.2032 -0.3048)
							(mid 0.275042 -0.275042)
							(end 0.3048 -0.2032)
						)
					)
					(width 0)
					(fill yes)
				)
			)
		)
	)
	(footprint ""
		(layer "B.Cu")
		(at 83.82 -21.844)
		(property "Reference" "PR187"
			(at 0 0 0)
			(layer "B.SilkS")
			(hide yes)
			(effects
				(font
					(size 1.27 1.27)
				)
				(justify mirror)
			)
		)
		(property "Value" "100KR2F-L1-GP"
			(at -0.064008 -3.993896 0)
			(unlocked yes)
			(layer "B.Fab")
			(hide yes)
			(effects
				(font
					(size 1.016 1.016)
					(thickness 0.1524)
				)
				(justify mirror)
			)
		)
		(property "Device Type" "R402H16"
			(at -0.064008 -5.517896 0)
			(unlocked yes)
			(layer "B.Fab")
			(hide yes)
			(effects
				(font
					(size 1.016 1.016)
					(thickness 0.1524)
				)
				(justify mirror)
			)
		)
		(duplicate_pad_numbers_are_jumpers no)
		(fp_line
			(start -0.508 -0.9398)
			(end 0.508 -0.9398)
			(stroke
				(width 0.1524)
				(type default)
			)
			(layer "B.SilkS")
		)
		(fp_line
			(start 0.508 -0.9398)
			(end 0.508 0.9398)
			(stroke
				(width 0.1524)
				(type default)
			)
			(layer "B.SilkS")
		)
		(fp_rect
			(start 0.508 0.9398)
			(end -0.508 -0.9398)
			(stroke
				(width 0)
				(type default)
			)
			(fill no)
			(layer "B.CrtYd")
		)
		(fp_rect
			(start 0.508 0.9398)
			(end -0.508 -0.9398)
			(stroke
				(width 0)
				(type default)
			)
			(fill no)
			(layer "B.Fab")
		)
		(pad "1" smd custom
			(at 0 -0.4445 180)
			(size 0.1397 0.1397)
			(layers "B.Cu" "B.Mask" "B.Paste")
			(net "VT235_VDES")
			(options
				(clearance outline)
				(anchor circle)
			)
			(primitives
				(gr_poly
					(pts
						(arc
							(start -0.1778 0.2794)
							(mid -0.249642 0.249642)
							(end -0.2794 0.1778)
						)
						(arc
							(start -0.2794 -0.1778)
							(mid -0.249642 -0.249642)
							(end -0.1778 -0.2794)
						)
						(arc
							(start 0.1778 -0.2794)
							(mid 0.249642 -0.249642)
							(end 0.2794 -0.1778)
						)
						(arc
							(start 0.2794 0.1778)
							(mid 0.249642 0.249642)
							(end 0.1778 0.2794)
						)
					)
					(width 0)
					(fill yes)
				)
			)
		)
		(pad "2" smd custom
			(at 0 0.4445 180)
			(size 0.1397 0.1397)
			(layers "B.Cu" "B.Mask" "B.Paste")
			(net "AVSO_VREF")
			(options
				(clearance outline)
				(anchor circle)
			)
			(primitives
				(gr_poly
					(pts
						(arc
							(start -0.1778 0.2794)
							(mid -0.249642 0.249642)
							(end -0.2794 0.1778)
						)
						(arc
							(start -0.2794 -0.1778)
							(mid -0.249642 -0.249642)
							(end -0.1778 -0.2794)
						)
						(arc
							(start 0.1778 -0.2794)
							(mid 0.249642 -0.249642)
							(end 0.2794 -0.1778)
						)
						(arc
							(start 0.2794 0.1778)
							(mid 0.249642 0.249642)
							(end 0.1778 0.2794)
						)
					)
					(width 0)
					(fill yes)
				)
			)
		)
	)
	(footprint ""
		(layer "B.Cu")
		(at 158.42996 -109.474254 90)
		(property "Reference" "SC1245"
			(at 0 0 90)
			(layer "B.SilkS")
			(hide yes)
			(effects
				(font
					(size 1.27 1.27)
				)
				(justify mirror)
			)
		)
		(property "Value" "SCD1U6D3V1KX-GP"
			(at 2.8321 -1.7399 90)
			(unlocked yes)
			(layer "B.Fab")
			(hide yes)
			(effects
				(font
					(size 1.016 1.016)
					(thickness 0.1524)
				)
				(justify mirror)
			)
		)
		(property "Device Type" "C0201H13"
			(at 2.8321 -3.2639 90)
			(unlocked yes)
			(layer "B.Fab")
			(hide yes)
			(effects
				(font
					(size 1.016 1.016)
					(thickness 0.1524)
				)
				(justify mirror)
			)
		)
		(duplicate_pad_numbers_are_jumpers no)
		(fp_rect
			(start 0.2794 0.6477)
			(end -0.2794 -0.6477)
			(stroke
				(width 0)
				(type default)
			)
			(fill no)
			(layer "B.CrtYd")
		)
		(fp_rect
			(start 0.2794 0.6477)
			(end -0.2794 -0.6477)
			(stroke
				(width 0)
				(type default)
			)
			(fill no)
			(layer "B.Fab")
		)
		(pad "1" smd custom
			(at 0 -0.2794 270)
			(size 0.0762 0.0762)
			(layers "B.Cu" "B.Mask" "B.Paste")
			(net "P0V9_E")
			(options
				(clearance outline)
				(anchor circle)
			)
			(primitives
				(gr_poly
					(pts
						(arc
							(start 0.1524 0.127)
							(mid 0.137521 0.162921)
							(end 0.1016 0.1778)
						)
						(arc
							(start -0.1016 0.1778)
							(mid -0.137521 0.162921)
							(end -0.1524 0.127)
						)
						(arc
							(start -0.1524 -0.127)
							(mid -0.137521 -0.162921)
							(end -0.1016 -0.1778)
						)
						(arc
							(start 0.1016 -0.1778)
							(mid 0.137521 -0.162921)
							(end 0.1524 -0.127)
						)
					)
					(width 0)
					(fill yes)
				)
			)
		)
		(pad "2" smd custom
			(at 0 0.2794 270)
			(size 0.0762 0.0762)
			(layers "B.Cu" "B.Mask" "B.Paste")
			(net "GND")
			(options
				(clearance outline)
				(anchor circle)
			)
			(primitives
				(gr_poly
					(pts
						(arc
							(start 0.1524 0.127)
							(mid 0.137521 0.162921)
							(end 0.1016 0.1778)
						)
						(arc
							(start -0.1016 0.1778)
							(mid -0.137521 0.162921)
							(end -0.1524 0.127)
						)
						(arc
							(start -0.1524 -0.127)
							(mid -0.137521 -0.162921)
							(end -0.1016 -0.1778)
						)
						(arc
							(start 0.1016 -0.1778)
							(mid 0.137521 -0.162921)
							(end 0.1524 -0.127)
						)
					)
					(width 0)
					(fill yes)
				)
			)
		)
	)
	(footprint ""
		(layer "B.Cu")
		(at 53.28793 -76.761086)
		(property "Reference" "SC1280"
			(at 0 0 0)
			(layer "B.SilkS")
			(hide yes)
			(effects
				(font
					(size 1.27 1.27)
				)
				(justify mirror)
			)
		)
		(property "Value" "SCD01U50V2KX-1GP"
			(at -1.1811 -2.7051 0)
			(unlocked yes)
			(layer "B.Fab")
			(hide yes)
			(effects
				(font
					(size 1.016 1.016)
					(thickness 0.1524)
				)
				(justify mirror)
			)
		)
		(property "Device Type" "C402H22"
			(at -1.1811 -4.2291 0)
			(unlocked yes)
			(layer "B.Fab")
			(hide yes)
			(effects
				(font
					(size 1.016 1.016)
					(thickness 0.1524)
				)
				(justify mirror)
			)
		)
		(duplicate_pad_numbers_are_jumpers no)
		(fp_rect
			(start 0.4318 0.9525)
			(end -0.4318 -0.9525)
			(stroke
				(width 0)
				(type default)
			)
			(fill no)
			(layer "B.CrtYd")
		)
		(fp_rect
			(start 0.4318 0.9525)
			(end -0.4318 -0.9525)
			(stroke
				(width 0)
				(type default)
			)
			(fill no)
			(layer "B.Fab")
		)
		(pad "1" smd custom
			(at 0 -0.4445 180)
			(size 0.1524 0.1524)
			(layers "B.Cu" "B.Mask" "B.Paste")
			(net "SAS_EXP2CONN_RX_P_23")
			(options
				(clearance outline)
				(anchor circle)
			)
			(primitives
				(gr_poly
					(pts
						(arc
							(start 0.3048 0.2032)
							(mid 0.275042 0.275042)
							(end 0.2032 0.3048)
						)
						(arc
							(start -0.2032 0.3048)
							(mid -0.275042 0.275042)
							(end -0.3048 0.2032)
						)
						(arc
							(start -0.3048 -0.2032)
							(mid -0.275042 -0.275042)
							(end -0.2032 -0.3048)
						)
						(arc
							(start 0.2032 -0.3048)
							(mid 0.275042 -0.275042)
							(end 0.3048 -0.2032)
						)
					)
					(width 0)
					(fill yes)
				)
			)
		)
		(pad "2" smd custom
			(at 0 0.4445 180)
			(size 0.1524 0.1524)
			(layers "B.Cu" "B.Mask" "B.Paste")
			(net "MINI_RX_P_23")
			(options
				(clearance outline)
				(anchor circle)
			)
			(primitives
				(gr_poly
					(pts
						(arc
							(start 0.3048 0.2032)
							(mid 0.275042 0.275042)
							(end 0.2032 0.3048)
						)
						(arc
							(start -0.2032 0.3048)
							(mid -0.275042 0.275042)
							(end -0.3048 0.2032)
						)
						(arc
							(start -0.3048 -0.2032)
							(mid -0.275042 -0.275042)
							(end -0.2032 -0.3048)
						)
						(arc
							(start 0.2032 -0.3048)
							(mid 0.275042 -0.275042)
							(end 0.3048 -0.2032)
						)
					)
					(width 0)
					(fill yes)
				)
			)
		)
	)
	(footprint ""
		(layer "B.Cu")
		(at 290.449 -166.497)
		(property "Reference" "TP138"
			(at 0 0 0)
			(layer "B.SilkS")
			(hide yes)
			(effects
				(font
					(size 1.27 1.27)
				)
				(justify mirror)
			)
		)
		(property "Value" "TPAD28"
			(at -0.0127 -1.8034 0)
			(unlocked yes)
			(layer "B.Fab")
			(hide yes)
			(effects
				(font
					(size 1.016 1.016)
					(thickness 0.1524)
				)
				(justify mirror)
			)
		)
		(property "Device Type" "TPAD28"
			(at -0.0127 -3.3274 0)
			(unlocked yes)
			(layer "B.Fab")
			(hide yes)
			(effects
				(font
					(size 1.016 1.016)
					(thickness 0.1524)
				)
				(justify mirror)
			)
		)
		(duplicate_pad_numbers_are_jumpers no)
		(fp_poly
			(pts
				(arc
					(start 0.3556 0)
					(mid -0.3556 0)
					(end 0.3556 0)
				)
			)
			(stroke
				(width 0)
				(type default)
			)
			(fill no)
			(layer "B.CrtYd")
		)
		(fp_poly
			(pts
				(arc
					(start 0.6096 0)
					(mid -0.6096 0)
					(end 0.6096 0)
				)
			)
			(stroke
				(width 0)
				(type default)
			)
			(fill no)
			(layer "B.Fab")
		)
		(pad "1" smd circle
			(at 0 0 180)
			(size 0.7112 0.7112)
			(layers "B.Cu" "B.Mask" "B.Paste")
			(net "TP_BMC_GPIOE1")
		)
	)
	(footprint ""
		(layer "B.Cu")
		(at 116.821966 -32.639)
		(property "Reference" "STP137"
			(at 0 0 0)
			(layer "B.SilkS")
			(hide yes)
			(effects
				(font
					(size 1.27 1.27)
				)
				(justify mirror)
			)
		)
		(property "Value" "TPAD28"
			(at -0.0127 -1.8034 0)
			(unlocked yes)
			(layer "B.Fab")
			(hide yes)
			(effects
				(font
					(size 1.016 1.016)
					(thickness 0.1524)
				)
				(justify mirror)
			)
		)
		(property "Device Type" "TPAD28"
			(at -0.0127 -3.3274 0)
			(unlocked yes)
			(layer "B.Fab")
			(hide yes)
			(effects
				(font
					(size 1.016 1.016)
					(thickness 0.1524)
				)
				(justify mirror)
			)
		)
		(duplicate_pad_numbers_are_jumpers no)
		(fp_poly
			(pts
				(arc
					(start 0.3556 0)
					(mid -0.3556 0)
					(end 0.3556 0)
				)
			)
			(stroke
				(width 0)
				(type default)
			)
			(fill no)
			(layer "B.CrtYd")
		)
		(fp_poly
			(pts
				(arc
					(start 0.6096 0)
					(mid -0.6096 0)
					(end 0.6096 0)
				)
			)
			(stroke
				(width 0)
				(type default)
			)
			(fill no)
			(layer "B.Fab")
		)
		(pad "1" smd circle
			(at 0 0 180)
			(size 0.7112 0.7112)
			(layers "B.Cu" "B.Mask" "B.Paste")
			(net "IOC_GPIO_18")
		)
	)
	(footprint ""
		(layer "B.Cu")
		(at 318.008 -170.434 90)
		(property "Reference" "R301"
			(at 0 0 90)
			(layer "B.SilkS")
			(hide yes)
			(effects
				(font
					(size 1.27 1.27)
				)
				(justify mirror)
			)
		)
		(property "Value" "10KR2F-2-GP"
			(at -0.064008 -3.993896 90)
			(unlocked yes)
			(layer "B.Fab")
			(hide yes)
			(effects
				(font
					(size 1.016 1.016)
					(thickness 0.1524)
				)
				(justify mirror)
			)
		)
		(property "Device Type" "R402H16"
			(at -0.064008 -5.517896 90)
			(unlocked yes)
			(layer "B.Fab")
			(hide yes)
			(effects
				(font
					(size 1.016 1.016)
					(thickness 0.1524)
				)
				(justify mirror)
			)
		)
		(duplicate_pad_numbers_are_jumpers no)
		(fp_line
			(start 0.508 -0.9398)
			(end 0.508 0.9398)
			(stroke
				(width 0.1524)
				(type default)
			)
			(layer "B.SilkS")
		)
		(fp_line
			(start -0.508 -0.9398)
			(end 0.508 -0.9398)
			(stroke
				(width 0.1524)
				(type default)
			)
			(layer "B.SilkS")
		)
		(fp_rect
			(start 0.508 0.9398)
			(end -0.508 -0.9398)
			(stroke
				(width 0)
				(type default)
			)
			(fill no)
			(layer "B.CrtYd")
		)
		(fp_rect
			(start 0.508 0.9398)
			(end -0.508 -0.9398)
			(stroke
				(width 0)
				(type default)
			)
			(fill no)
			(layer "B.Fab")
		)
		(pad "1" smd custom
			(at 0 -0.4445 270)
			(size 0.1397 0.1397)
			(layers "B.Cu" "B.Mask" "B.Paste")
			(net "BMC0_ENTEST1")
			(options
				(clearance outline)
				(anchor circle)
			)
			(primitives
				(gr_poly
					(pts
						(arc
							(start -0.1778 0.2794)
							(mid -0.249642 0.249642)
							(end -0.2794 0.1778)
						)
						(arc
							(start -0.2794 -0.1778)
							(mid -0.249642 -0.249642)
							(end -0.1778 -0.2794)
						)
						(arc
							(start 0.1778 -0.2794)
							(mid 0.249642 -0.249642)
							(end 0.2794 -0.1778)
						)
						(arc
							(start 0.2794 0.1778)
							(mid 0.249642 0.249642)
							(end 0.1778 0.2794)
						)
					)
					(width 0)
					(fill yes)
				)
			)
		)
		(pad "2" smd custom
			(at 0 0.4445 270)
			(size 0.1397 0.1397)
			(layers "B.Cu" "B.Mask" "B.Paste")
			(net "GND")
			(options
				(clearance outline)
				(anchor circle)
			)
			(primitives
				(gr_poly
					(pts
						(arc
							(start -0.1778 0.2794)
							(mid -0.249642 0.249642)
							(end -0.2794 0.1778)
						)
						(arc
							(start -0.2794 -0.1778)
							(mid -0.249642 -0.249642)
							(end -0.1778 -0.2794)
						)
						(arc
							(start 0.1778 -0.2794)
							(mid 0.249642 -0.249642)
							(end 0.2794 -0.1778)
						)
						(arc
							(start 0.2794 0.1778)
							(mid 0.249642 0.249642)
							(end 0.1778 0.2794)
						)
					)
					(width 0)
					(fill yes)
				)
			)
		)
	)
	(footprint ""
		(layer "B.Cu")
		(at 113.29797 -94.615 90)
		(property "Reference" "SC1218"
			(at 0 0 90)
			(layer "B.SilkS")
			(hide yes)
			(effects
				(font
					(size 1.27 1.27)
				)
				(justify mirror)
			)
		)
		(property "Value" "SC1KP50V2KX-1GP"
			(at -1.1811 -2.7051 90)
			(unlocked yes)
			(layer "B.Fab")
			(hide yes)
			(effects
				(font
					(size 1.016 1.016)
					(thickness 0.1524)
				)
				(justify mirror)
			)
		)
		(property "Device Type" "C402H22"
			(at -1.1811 -4.2291 90)
			(unlocked yes)
			(layer "B.Fab")
			(hide yes)
			(effects
				(font
					(size 1.016 1.016)
					(thickness 0.1524)
				)
				(justify mirror)
			)
		)
		(duplicate_pad_numbers_are_jumpers no)
		(fp_rect
			(start 0.4318 0.9525)
			(end -0.4318 -0.9525)
			(stroke
				(width 0)
				(type default)
			)
			(fill no)
			(layer "B.CrtYd")
		)
		(fp_rect
			(start 0.4318 0.9525)
			(end -0.4318 -0.9525)
			(stroke
				(width 0)
				(type default)
			)
			(fill no)
			(layer "B.Fab")
		)
		(pad "1" smd custom
			(at 0 -0.4445 270)
			(size 0.1524 0.1524)
			(layers "B.Cu" "B.Mask" "B.Paste")
			(net "P0V9_E")
			(options
				(clearance outline)
				(anchor circle)
			)
			(primitives
				(gr_poly
					(pts
						(arc
							(start 0.3048 0.2032)
							(mid 0.275042 0.275042)
							(end 0.2032 0.3048)
						)
						(arc
							(start -0.2032 0.3048)
							(mid -0.275042 0.275042)
							(end -0.3048 0.2032)
						)
						(arc
							(start -0.3048 -0.2032)
							(mid -0.275042 -0.275042)
							(end -0.2032 -0.3048)
						)
						(arc
							(start 0.2032 -0.3048)
							(mid 0.275042 -0.275042)
							(end 0.3048 -0.2032)
						)
					)
					(width 0)
					(fill yes)
				)
			)
		)
		(pad "2" smd custom
			(at 0 0.4445 270)
			(size 0.1524 0.1524)
			(layers "B.Cu" "B.Mask" "B.Paste")
			(net "GND")
			(options
				(clearance outline)
				(anchor circle)
			)
			(primitives
				(gr_poly
					(pts
						(arc
							(start 0.3048 0.2032)
							(mid 0.275042 0.275042)
							(end 0.2032 0.3048)
						)
						(arc
							(start -0.2032 0.3048)
							(mid -0.275042 0.275042)
							(end -0.3048 0.2032)
						)
						(arc
							(start -0.3048 -0.2032)
							(mid -0.275042 -0.275042)
							(end -0.2032 -0.3048)
						)
						(arc
							(start 0.2032 -0.3048)
							(mid 0.275042 -0.275042)
							(end 0.3048 -0.2032)
						)
					)
					(width 0)
					(fill yes)
				)
			)
		)
	)
	(footprint ""
		(layer "B.Cu")
		(at 124.403612 -216.535 -90)
		(property "Reference" "SR1271"
			(at 0 0 90)
			(layer "B.SilkS")
			(hide yes)
			(effects
				(font
					(size 1.27 1.27)
				)
				(justify mirror)
			)
		)
		(property "Value" "0R2J-2-GP"
			(at -0.064008 -3.993896 270)
			(unlocked yes)
			(layer "B.Fab")
			(hide yes)
			(effects
				(font
					(size 1.016 1.016)
					(thickness 0.1524)
				)
				(justify mirror)
			)
		)
		(property "Device Type" "R402H16"
			(at -0.064008 -5.517896 270)
			(unlocked yes)
			(layer "B.Fab")
			(hide yes)
			(effects
				(font
					(size 1.016 1.016)
					(thickness 0.1524)
				)
				(justify mirror)
			)
		)
		(duplicate_pad_numbers_are_jumpers no)
		(fp_line
			(start -0.508 -0.9398)
			(end 0.508 -0.9398)
			(stroke
				(width 0.1524)
				(type default)
			)
			(layer "B.SilkS")
		)
		(fp_line
			(start 0.508 -0.9398)
			(end 0.508 0.9398)
			(stroke
				(width 0.1524)
				(type default)
			)
			(layer "B.SilkS")
		)
		(fp_rect
			(start 0.508 0.9398)
			(end -0.508 -0.9398)
			(stroke
				(width 0)
				(type default)
			)
			(fill no)
			(layer "B.CrtYd")
		)
		(fp_rect
			(start 0.508 0.9398)
			(end -0.508 -0.9398)
			(stroke
				(width 0)
				(type default)
			)
			(fill no)
			(layer "B.Fab")
		)
		(pad "1" smd custom
			(at 0 -0.4445 90)
			(size 0.1397 0.1397)
			(layers "B.Cu" "B.Mask" "B.Paste")
			(net "EXP_SCL_L_0")
			(options
				(clearance outline)
				(anchor circle)
			)
			(primitives
				(gr_poly
					(pts
						(arc
							(start -0.1778 0.2794)
							(mid -0.249642 0.249642)
							(end -0.2794 0.1778)
						)
						(arc
							(start -0.2794 -0.1778)
							(mid -0.249642 -0.249642)
							(end -0.1778 -0.2794)
						)
						(arc
							(start 0.1778 -0.2794)
							(mid 0.249642 -0.249642)
							(end 0.2794 -0.1778)
						)
						(arc
							(start 0.2794 0.1778)
							(mid 0.249642 0.249642)
							(end 0.1778 0.2794)
						)
					)
					(width 0)
					(fill yes)
				)
			)
		)
		(pad "2" smd custom
			(at 0 0.4445 90)
			(size 0.1397 0.1397)
			(layers "B.Cu" "B.Mask" "B.Paste")
			(net "REDV_I2C_SCL")
			(options
				(clearance outline)
				(anchor circle)
			)
			(primitives
				(gr_poly
					(pts
						(arc
							(start -0.1778 0.2794)
							(mid -0.249642 0.249642)
							(end -0.2794 0.1778)
						)
						(arc
							(start -0.2794 -0.1778)
							(mid -0.249642 -0.249642)
							(end -0.1778 -0.2794)
						)
						(arc
							(start 0.1778 -0.2794)
							(mid 0.249642 -0.249642)
							(end 0.2794 -0.1778)
						)
						(arc
							(start 0.2794 0.1778)
							(mid 0.249642 0.249642)
							(end 0.1778 0.2794)
						)
					)
					(width 0)
					(fill yes)
				)
			)
		)
	)
	(footprint ""
		(layer "B.Cu")
		(at 114.154966 -36.957)
		(property "Reference" "STP6"
			(at 0 0 0)
			(layer "B.SilkS")
			(hide yes)
			(effects
				(font
					(size 1.27 1.27)
				)
				(justify mirror)
			)
		)
		(property "Value" "TPAD28"
			(at -0.0127 -1.8034 0)
			(unlocked yes)
			(layer "B.Fab")
			(hide yes)
			(effects
				(font
					(size 1.016 1.016)
					(thickness 0.1524)
				)
				(justify mirror)
			)
		)
		(property "Device Type" "TPAD28"
			(at -0.0127 -3.3274 0)
			(unlocked yes)
			(layer "B.Fab")
			(hide yes)
			(effects
				(font
					(size 1.016 1.016)
					(thickness 0.1524)
				)
				(justify mirror)
			)
		)
		(duplicate_pad_numbers_are_jumpers no)
		(fp_poly
			(pts
				(arc
					(start 0.3556 0)
					(mid -0.3556 0)
					(end 0.3556 0)
				)
			)
			(stroke
				(width 0)
				(type default)
			)
			(fill no)
			(layer "B.CrtYd")
		)
		(fp_poly
			(pts
				(arc
					(start 0.6096 0)
					(mid -0.6096 0)
					(end 0.6096 0)
				)
			)
			(stroke
				(width 0)
				(type default)
			)
			(fill no)
			(layer "B.Fab")
		)
		(pad "1" smd circle
			(at 0 0 180)
			(size 0.7112 0.7112)
			(layers "B.Cu" "B.Mask" "B.Paste")
			(net "IOC_GPIO_27")
		)
	)
	(footprint ""
		(layer "B.Cu")
		(at 111.38916 -33.655)
		(property "Reference" "STP50"
			(at 0 0 0)
			(layer "B.SilkS")
			(hide yes)
			(effects
				(font
					(size 1.27 1.27)
				)
				(justify mirror)
			)
		)
		(property "Value" "TPAD28"
			(at -0.0127 -1.8034 0)
			(unlocked yes)
			(layer "B.Fab")
			(hide yes)
			(effects
				(font
					(size 1.016 1.016)
					(thickness 0.1524)
				)
				(justify mirror)
			)
		)
		(property "Device Type" "TPAD28"
			(at -0.0127 -3.3274 0)
			(unlocked yes)
			(layer "B.Fab")
			(hide yes)
			(effects
				(font
					(size 1.016 1.016)
					(thickness 0.1524)
				)
				(justify mirror)
			)
		)
		(duplicate_pad_numbers_are_jumpers no)
		(fp_poly
			(pts
				(arc
					(start 0.3556 0)
					(mid -0.3556 0)
					(end 0.3556 0)
				)
			)
			(stroke
				(width 0)
				(type default)
			)
			(fill no)
			(layer "B.CrtYd")
		)
		(fp_poly
			(pts
				(arc
					(start 0.6096 0)
					(mid -0.6096 0)
					(end 0.6096 0)
				)
			)
			(stroke
				(width 0)
				(type default)
			)
			(fill no)
			(layer "B.Fab")
		)
		(pad "1" smd circle
			(at 0 0 180)
			(size 0.7112 0.7112)
			(layers "B.Cu" "B.Mask" "B.Paste")
			(net "SPARE0")
		)
	)
	(footprint ""
		(layer "B.Cu")
		(at 114.84737 -90.8812 90)
		(property "Reference" "SC1248"
			(at 0 0 90)
			(layer "B.SilkS")
			(hide yes)
			(effects
				(font
					(size 1.27 1.27)
				)
				(justify mirror)
			)
		)
		(property "Value" "SCD1U6D3V1KX-GP"
			(at 2.8321 -1.7399 90)
			(unlocked yes)
			(layer "B.Fab")
			(hide yes)
			(effects
				(font
					(size 1.016 1.016)
					(thickness 0.1524)
				)
				(justify mirror)
			)
		)
		(property "Device Type" "C0201H13"
			(at 2.8321 -3.2639 90)
			(unlocked yes)
			(layer "B.Fab")
			(hide yes)
			(effects
				(font
					(size 1.016 1.016)
					(thickness 0.1524)
				)
				(justify mirror)
			)
		)
		(duplicate_pad_numbers_are_jumpers no)
		(fp_rect
			(start 0.2794 0.6477)
			(end -0.2794 -0.6477)
			(stroke
				(width 0)
				(type default)
			)
			(fill no)
			(layer "B.CrtYd")
		)
		(fp_rect
			(start 0.2794 0.6477)
			(end -0.2794 -0.6477)
			(stroke
				(width 0)
				(type default)
			)
			(fill no)
			(layer "B.Fab")
		)
		(pad "1" smd custom
			(at 0 -0.2794 270)
			(size 0.0762 0.0762)
			(layers "B.Cu" "B.Mask" "B.Paste")
			(net "P0V9_E")
			(options
				(clearance outline)
				(anchor circle)
			)
			(primitives
				(gr_poly
					(pts
						(arc
							(start 0.1524 0.127)
							(mid 0.137521 0.162921)
							(end 0.1016 0.1778)
						)
						(arc
							(start -0.1016 0.1778)
							(mid -0.137521 0.162921)
							(end -0.1524 0.127)
						)
						(arc
							(start -0.1524 -0.127)
							(mid -0.137521 -0.162921)
							(end -0.1016 -0.1778)
						)
						(arc
							(start 0.1016 -0.1778)
							(mid 0.137521 -0.162921)
							(end 0.1524 -0.127)
						)
					)
					(width 0)
					(fill yes)
				)
			)
		)
		(pad "2" smd custom
			(at 0 0.2794 270)
			(size 0.0762 0.0762)
			(layers "B.Cu" "B.Mask" "B.Paste")
			(net "GND")
			(options
				(clearance outline)
				(anchor circle)
			)
			(primitives
				(gr_poly
					(pts
						(arc
							(start 0.1524 0.127)
							(mid 0.137521 0.162921)
							(end 0.1016 0.1778)
						)
						(arc
							(start -0.1016 0.1778)
							(mid -0.137521 0.162921)
							(end -0.1524 0.127)
						)
						(arc
							(start -0.1524 -0.127)
							(mid -0.137521 -0.162921)
							(end -0.1016 -0.1778)
						)
						(arc
							(start 0.1016 -0.1778)
							(mid 0.137521 -0.162921)
							(end 0.1524 -0.127)
						)
					)
					(width 0)
					(fill yes)
				)
			)
		)
	)
	(footprint ""
		(layer "B.Cu")
		(at 342.921336 -71.797672)
		(property "Reference" "R265"
			(at 0 0 0)
			(layer "B.SilkS")
			(hide yes)
			(effects
				(font
					(size 1.27 1.27)
				)
				(justify mirror)
			)
		)
		(property "Value" "0R0402-PAD-1-GP"
			(at -0.064008 -3.993896 0)
			(unlocked yes)
			(layer "B.Fab")
			(hide yes)
			(effects
				(font
					(size 1.016 1.016)
					(thickness 0.1524)
				)
				(justify mirror)
			)
		)
		(property "Device Type" "0R0402-PAD"
			(at -0.064008 -5.517896 0)
			(unlocked yes)
			(layer "B.Fab")
			(hide yes)
			(effects
				(font
					(size 1.016 1.016)
					(thickness 0.1524)
				)
				(justify mirror)
			)
		)
		(duplicate_pad_numbers_are_jumpers no)
		(fp_line
			(start -0.508 -0.9398)
			(end 0.508 -0.9398)
			(stroke
				(width 0.1524)
				(type default)
			)
			(layer "B.SilkS")
		)
		(fp_line
			(start 0.508 -0.9398)
			(end 0.508 0.9398)
			(stroke
				(width 0.1524)
				(type default)
			)
			(layer "B.SilkS")
		)
		(fp_rect
			(start 0.508 0.9398)
			(end -0.508 -0.9398)
			(stroke
				(width 0)
				(type default)
			)
			(fill no)
			(layer "B.CrtYd")
		)
		(fp_rect
			(start 0.508 0.9398)
			(end -0.508 -0.9398)
			(stroke
				(width 0)
				(type default)
			)
			(fill no)
			(layer "B.Fab")
		)
		(pad "1" smd custom
			(at 0 -0.4445 180)
			(size 0.1397 0.1397)
			(layers "B.Cu" "B.Mask" "B.Paste")
			(net "P3V3_STBY")
			(options
				(clearance outline)
				(anchor circle)
			)
			(primitives
				(gr_poly
					(pts
						(xy -0.2794 -0.3683)
						(arc
							(start -0.2794 0.2667)
							(mid -0.249642 0.338542)
							(end -0.1778 0.3683)
						)
						(arc
							(start 0.1778 0.3683)
							(mid 0.249642 0.338542)
							(end 0.2794 0.2667)
						)
						(xy 0.2794 -0.3683)
					)
					(width 0)
					(fill yes)
				)
			)
		)
		(pad "2" smd custom
			(at 0 0.4445 180)
			(size 0.1397 0.1397)
			(layers "B.Cu" "B.Mask" "B.Paste")
			(net "FLA_WPN")
			(options
				(clearance outline)
				(anchor circle)
			)
			(primitives
				(gr_poly
					(pts
						(arc
							(start -0.1778 -0.3683)
							(mid -0.249642 -0.338542)
							(end -0.2794 -0.2667)
						)
						(xy -0.2794 0.3683) (xy 0.2794 0.3683)
						(arc
							(start 0.2794 -0.2667)
							(mid 0.249642 -0.338542)
							(end 0.1778 -0.3683)
						)
					)
					(width 0)
					(fill yes)
				)
			)
		)
	)
	(footprint ""
		(layer "B.Cu")
		(at 108.72216 -31.369)
		(property "Reference" "STP130"
			(at 0 0 0)
			(layer "B.SilkS")
			(hide yes)
			(effects
				(font
					(size 1.27 1.27)
				)
				(justify mirror)
			)
		)
		(property "Value" "TPAD28"
			(at -0.0127 -1.8034 0)
			(unlocked yes)
			(layer "B.Fab")
			(hide yes)
			(effects
				(font
					(size 1.016 1.016)
					(thickness 0.1524)
				)
				(justify mirror)
			)
		)
		(property "Device Type" "TPAD28"
			(at -0.0127 -3.3274 0)
			(unlocked yes)
			(layer "B.Fab")
			(hide yes)
			(effects
				(font
					(size 1.016 1.016)
					(thickness 0.1524)
				)
				(justify mirror)
			)
		)
		(duplicate_pad_numbers_are_jumpers no)
		(fp_poly
			(pts
				(arc
					(start 0.3556 0)
					(mid -0.3556 0)
					(end 0.3556 0)
				)
			)
			(stroke
				(width 0)
				(type default)
			)
			(fill no)
			(layer "B.CrtYd")
		)
		(fp_poly
			(pts
				(arc
					(start 0.6096 0)
					(mid -0.6096 0)
					(end 0.6096 0)
				)
			)
			(stroke
				(width 0)
				(type default)
			)
			(fill no)
			(layer "B.Fab")
		)
		(pad "1" smd circle
			(at 0 0 180)
			(size 0.7112 0.7112)
			(layers "B.Cu" "B.Mask" "B.Paste")
			(net "IOC_GPIO_13")
		)
	)
	(footprint ""
		(layer "B.Cu")
		(at 349.749872 -37.399722)
		(property "Reference" ""
			(at 0 0 0)
			(layer "B.SilkS")
			(hide yes)
			(effects
				(font
					(size 1.27 1.27)
				)
				(justify mirror)
			)
		)
		(property "Value" "*"
			(at 5.5753 -0.4572 0)
			(unlocked yes)
			(layer "B.Fab")
			(hide yes)
			(effects
				(font
					(size 1.016 1.016)
					(thickness 0.1524)
				)
				(justify mirror)
			)
		)
		(duplicate_pad_numbers_are_jumpers no)
		(fp_poly
			(pts
				(arc
					(start 4.3053 0)
					(mid -4.3053 0)
					(end 4.3053 0)
				)
			)
			(stroke
				(width 0)
				(type default)
			)
			(fill no)
			(layer "B.CrtYd")
		)
		(fp_poly
			(pts
				(arc
					(start 4.3053 0)
					(mid -4.3053 0)
					(end 4.3053 0)
				)
			)
			(stroke
				(width 0)
				(type default)
			)
			(fill no)
			(layer "B.Fab")
		)
		(pad "1" smd custom
			(at 2.95275 0 180)
			(size 2.000013 2.000013)
			(layers "B.Cu" "B.Mask" "B.Paste")
			(net "Net_55")
			(options
				(clearance outline)
				(anchor circle)
			)
			(primitives
				(gr_poly
					(pts
						(arc
							(start 4.0005 -0.00254)
							(mid -4.000501 0)
							(end 4.0005 0.00254)
						)
						(arc
							(start 1.905 0.00254)
							(mid -1.905002 0)
							(end 1.905 -0.00254)
						)
					)
					(width 0)
					(fill yes)
				)
			)
		)
	)
	(footprint ""
		(layer "B.Cu")
		(at 96.730566 -48.1584)
		(property "Reference" "SR680"
			(at 0 0 0)
			(layer "B.SilkS")
			(hide yes)
			(effects
				(font
					(size 1.27 1.27)
				)
				(justify mirror)
			)
		)
		(property "Value" "4K7R2F-GP"
			(at -0.064008 -3.993896 0)
			(unlocked yes)
			(layer "B.Fab")
			(hide yes)
			(effects
				(font
					(size 1.016 1.016)
					(thickness 0.1524)
				)
				(justify mirror)
			)
		)
		(property "Device Type" "R402H16"
			(at -0.064008 -5.517896 0)
			(unlocked yes)
			(layer "B.Fab")
			(hide yes)
			(effects
				(font
					(size 1.016 1.016)
					(thickness 0.1524)
				)
				(justify mirror)
			)
		)
		(duplicate_pad_numbers_are_jumpers no)
		(fp_line
			(start -0.508 -0.9398)
			(end 0.508 -0.9398)
			(stroke
				(width 0.1524)
				(type default)
			)
			(layer "B.SilkS")
		)
		(fp_line
			(start 0.508 -0.9398)
			(end 0.508 0.9398)
			(stroke
				(width 0.1524)
				(type default)
			)
			(layer "B.SilkS")
		)
		(fp_rect
			(start 0.508 0.9398)
			(end -0.508 -0.9398)
			(stroke
				(width 0)
				(type default)
			)
			(fill no)
			(layer "B.CrtYd")
		)
		(fp_rect
			(start 0.508 0.9398)
			(end -0.508 -0.9398)
			(stroke
				(width 0)
				(type default)
			)
			(fill no)
			(layer "B.Fab")
		)
		(pad "1" smd custom
			(at 0 -0.4445 180)
			(size 0.1397 0.1397)
			(layers "B.Cu" "B.Mask" "B.Paste")
			(net "P1V8_C")
			(options
				(clearance outline)
				(anchor circle)
			)
			(primitives
				(gr_poly
					(pts
						(arc
							(start -0.1778 0.2794)
							(mid -0.249642 0.249642)
							(end -0.2794 0.1778)
						)
						(arc
							(start -0.2794 -0.1778)
							(mid -0.249642 -0.249642)
							(end -0.1778 -0.2794)
						)
						(arc
							(start 0.1778 -0.2794)
							(mid 0.249642 -0.249642)
							(end 0.2794 -0.1778)
						)
						(arc
							(start 0.2794 0.1778)
							(mid 0.249642 0.249642)
							(end 0.1778 0.2794)
						)
					)
					(width 0)
					(fill yes)
				)
			)
		)
		(pad "2" smd custom
			(at 0 0.4445 180)
			(size 0.1397 0.1397)
			(layers "B.Cu" "B.Mask" "B.Paste")
			(net "ICE_SEL")
			(options
				(clearance outline)
				(anchor circle)
			)
			(primitives
				(gr_poly
					(pts
						(arc
							(start -0.1778 0.2794)
							(mid -0.249642 0.249642)
							(end -0.2794 0.1778)
						)
						(arc
							(start -0.2794 -0.1778)
							(mid -0.249642 -0.249642)
							(end -0.1778 -0.2794)
						)
						(arc
							(start 0.1778 -0.2794)
							(mid 0.249642 -0.249642)
							(end 0.2794 -0.1778)
						)
						(arc
							(start 0.2794 0.1778)
							(mid 0.249642 0.249642)
							(end 0.1778 0.2794)
						)
					)
					(width 0)
					(fill yes)
				)
			)
		)
	)
	(footprint ""
		(layer "B.Cu")
		(at 124.799852 -20.299934)
		(property "Reference" ""
			(at 0 0 0)
			(layer "B.SilkS")
			(hide yes)
			(effects
				(font
					(size 1.27 1.27)
				)
				(justify mirror)
			)
		)
		(property "Value" "*"
			(at 5.5753 -0.4572 0)
			(unlocked yes)
			(layer "B.Fab")
			(hide yes)
			(effects
				(font
					(size 1.016 1.016)
					(thickness 0.1524)
				)
				(justify mirror)
			)
		)
		(duplicate_pad_numbers_are_jumpers no)
		(fp_poly
			(pts
				(arc
					(start 4.3053 0)
					(mid -4.3053 0)
					(end 4.3053 0)
				)
			)
			(stroke
				(width 0)
				(type default)
			)
			(fill no)
			(layer "B.CrtYd")
		)
		(fp_poly
			(pts
				(arc
					(start 4.3053 0)
					(mid -4.3053 0)
					(end 4.3053 0)
				)
			)
			(stroke
				(width 0)
				(type default)
			)
			(fill no)
			(layer "B.Fab")
		)
		(pad "1" smd custom
			(at 2.95275 0 180)
			(size 2.000013 2.000013)
			(layers "B.Cu" "B.Mask" "B.Paste")
			(net "Net_49")
			(options
				(clearance outline)
				(anchor circle)
			)
			(primitives
				(gr_poly
					(pts
						(arc
							(start 4.0005 -0.00254)
							(mid -4.000501 0)
							(end 4.0005 0.00254)
						)
						(arc
							(start 1.905 0.00254)
							(mid -1.905002 0)
							(end 1.905 -0.00254)
						)
					)
					(width 0)
					(fill yes)
				)
			)
		)
	)
	(footprint ""
		(layer "B.Cu")
		(at 127.11557 -88.265 90)
		(property "Reference" "SC1175"
			(at 0 0 90)
			(layer "B.SilkS")
			(hide yes)
			(effects
				(font
					(size 1.27 1.27)
				)
				(justify mirror)
			)
		)
		(property "Value" "SCD1U16V2KX-3GP"
			(at -1.1811 -2.7051 90)
			(unlocked yes)
			(layer "B.Fab")
			(hide yes)
			(effects
				(font
					(size 1.016 1.016)
					(thickness 0.1524)
				)
				(justify mirror)
			)
		)
		(property "Device Type" "C402H22"
			(at -1.1811 -4.2291 90)
			(unlocked yes)
			(layer "B.Fab")
			(hide yes)
			(effects
				(font
					(size 1.016 1.016)
					(thickness 0.1524)
				)
				(justify mirror)
			)
		)
		(duplicate_pad_numbers_are_jumpers no)
		(fp_rect
			(start 0.4318 0.9525)
			(end -0.4318 -0.9525)
			(stroke
				(width 0)
				(type default)
			)
			(fill no)
			(layer "B.CrtYd")
		)
		(fp_rect
			(start 0.4318 0.9525)
			(end -0.4318 -0.9525)
			(stroke
				(width 0)
				(type default)
			)
			(fill no)
			(layer "B.Fab")
		)
		(pad "1" smd custom
			(at 0 -0.4445 270)
			(size 0.1524 0.1524)
			(layers "B.Cu" "B.Mask" "B.Paste")
			(net "GB_VDDA")
			(options
				(clearance outline)
				(anchor circle)
			)
			(primitives
				(gr_poly
					(pts
						(arc
							(start 0.3048 0.2032)
							(mid 0.275042 0.275042)
							(end 0.2032 0.3048)
						)
						(arc
							(start -0.2032 0.3048)
							(mid -0.275042 0.275042)
							(end -0.3048 0.2032)
						)
						(arc
							(start -0.3048 -0.2032)
							(mid -0.275042 -0.275042)
							(end -0.2032 -0.3048)
						)
						(arc
							(start 0.2032 -0.3048)
							(mid 0.275042 -0.275042)
							(end 0.3048 -0.2032)
						)
					)
					(width 0)
					(fill yes)
				)
			)
		)
		(pad "2" smd custom
			(at 0 0.4445 270)
			(size 0.1524 0.1524)
			(layers "B.Cu" "B.Mask" "B.Paste")
			(net "GND")
			(options
				(clearance outline)
				(anchor circle)
			)
			(primitives
				(gr_poly
					(pts
						(arc
							(start 0.3048 0.2032)
							(mid 0.275042 0.275042)
							(end 0.2032 0.3048)
						)
						(arc
							(start -0.2032 0.3048)
							(mid -0.275042 0.275042)
							(end -0.3048 0.2032)
						)
						(arc
							(start -0.3048 -0.2032)
							(mid -0.275042 -0.275042)
							(end -0.2032 -0.3048)
						)
						(arc
							(start 0.2032 -0.3048)
							(mid 0.275042 -0.275042)
							(end 0.3048 -0.2032)
						)
					)
					(width 0)
					(fill yes)
				)
			)
		)
	)
	(footprint ""
		(layer "B.Cu")
		(at 122.727212 -218.821)
		(property "Reference" "STP143"
			(at 0 0 0)
			(layer "B.SilkS")
			(hide yes)
			(effects
				(font
					(size 1.27 1.27)
				)
				(justify mirror)
			)
		)
		(property "Value" "TPAD32-GP"
			(at 0 -3.166364 0)
			(unlocked yes)
			(layer "B.Fab")
			(hide yes)
			(effects
				(font
					(size 1.016 1.016)
					(thickness 0.1524)
				)
				(justify mirror)
			)
		)
		(property "Device Type" "TPAD32"
			(at 0 -4.690618 0)
			(unlocked yes)
			(layer "B.Fab")
			(hide yes)
			(effects
				(font
					(size 1.016 1.016)
					(thickness 0.1524)
				)
				(justify mirror)
			)
		)
		(duplicate_pad_numbers_are_jumpers no)
		(fp_poly
			(pts
				(arc
					(start 0.4064 0)
					(mid -0.4064 0)
					(end 0.4064 0)
				)
			)
			(stroke
				(width 0)
				(type default)
			)
			(fill no)
			(layer "B.CrtYd")
		)
		(fp_poly
			(pts
				(arc
					(start 0.7112 0)
					(mid -0.7112 0)
					(end 0.7112 0)
				)
			)
			(stroke
				(width 0)
				(type default)
			)
			(fill no)
			(layer "B.Fab")
		)
		(pad "1" smd circle
			(at 0 0 180)
			(size 0.8128 0.8128)
			(layers "B.Cu" "B.Mask" "B.Paste")
			(net "REDV_PD#")
		)
	)
	(footprint ""
		(layer "B.Cu")
		(at 98.171 -91.9734)
		(property "Reference" "STP163"
			(at 0 0 0)
			(layer "B.SilkS")
			(hide yes)
			(effects
				(font
					(size 1.27 1.27)
				)
				(justify mirror)
			)
		)
		(property "Value" "TPAD28"
			(at -0.0127 -1.8034 0)
			(unlocked yes)
			(layer "B.Fab")
			(hide yes)
			(effects
				(font
					(size 1.016 1.016)
					(thickness 0.1524)
				)
				(justify mirror)
			)
		)
		(property "Device Type" "TPAD28"
			(at -0.0127 -3.3274 0)
			(unlocked yes)
			(layer "B.Fab")
			(hide yes)
			(effects
				(font
					(size 1.016 1.016)
					(thickness 0.1524)
				)
				(justify mirror)
			)
		)
		(duplicate_pad_numbers_are_jumpers no)
		(fp_poly
			(pts
				(arc
					(start 0.3556 0)
					(mid -0.3556 0)
					(end 0.3556 0)
				)
			)
			(stroke
				(width 0)
				(type default)
			)
			(fill no)
			(layer "B.CrtYd")
		)
		(fp_poly
			(pts
				(arc
					(start 0.6096 0)
					(mid -0.6096 0)
					(end 0.6096 0)
				)
			)
			(stroke
				(width 0)
				(type default)
			)
			(fill no)
			(layer "B.Fab")
		)
		(pad "1" smd circle
			(at 0 0 180)
			(size 0.7112 0.7112)
			(layers "B.Cu" "B.Mask" "B.Paste")
			(net "EXP_XM_ADDR_25")
		)
	)
	(footprint ""
		(layer "B.Cu")
		(at 111.29137 -98.1202 90)
		(property "Reference" "SC1254"
			(at 0 0 90)
			(layer "B.SilkS")
			(hide yes)
			(effects
				(font
					(size 1.27 1.27)
				)
				(justify mirror)
			)
		)
		(property "Value" "SCD1U6D3V1KX-GP"
			(at 2.8321 -1.7399 90)
			(unlocked yes)
			(layer "B.Fab")
			(hide yes)
			(effects
				(font
					(size 1.016 1.016)
					(thickness 0.1524)
				)
				(justify mirror)
			)
		)
		(property "Device Type" "C0201H13"
			(at 2.8321 -3.2639 90)
			(unlocked yes)
			(layer "B.Fab")
			(hide yes)
			(effects
				(font
					(size 1.016 1.016)
					(thickness 0.1524)
				)
				(justify mirror)
			)
		)
		(duplicate_pad_numbers_are_jumpers no)
		(fp_rect
			(start 0.2794 0.6477)
			(end -0.2794 -0.6477)
			(stroke
				(width 0)
				(type default)
			)
			(fill no)
			(layer "B.CrtYd")
		)
		(fp_rect
			(start 0.2794 0.6477)
			(end -0.2794 -0.6477)
			(stroke
				(width 0)
				(type default)
			)
			(fill no)
			(layer "B.Fab")
		)
		(pad "1" smd custom
			(at 0 -0.2794 270)
			(size 0.0762 0.0762)
			(layers "B.Cu" "B.Mask" "B.Paste")
			(net "P0V9_E")
			(options
				(clearance outline)
				(anchor circle)
			)
			(primitives
				(gr_poly
					(pts
						(arc
							(start 0.1524 0.127)
							(mid 0.137521 0.162921)
							(end 0.1016 0.1778)
						)
						(arc
							(start -0.1016 0.1778)
							(mid -0.137521 0.162921)
							(end -0.1524 0.127)
						)
						(arc
							(start -0.1524 -0.127)
							(mid -0.137521 -0.162921)
							(end -0.1016 -0.1778)
						)
						(arc
							(start 0.1016 -0.1778)
							(mid 0.137521 -0.162921)
							(end 0.1524 -0.127)
						)
					)
					(width 0)
					(fill yes)
				)
			)
		)
		(pad "2" smd custom
			(at 0 0.2794 270)
			(size 0.0762 0.0762)
			(layers "B.Cu" "B.Mask" "B.Paste")
			(net "GND")
			(options
				(clearance outline)
				(anchor circle)
			)
			(primitives
				(gr_poly
					(pts
						(arc
							(start 0.1524 0.127)
							(mid 0.137521 0.162921)
							(end 0.1016 0.1778)
						)
						(arc
							(start -0.1016 0.1778)
							(mid -0.137521 0.162921)
							(end -0.1524 0.127)
						)
						(arc
							(start -0.1524 -0.127)
							(mid -0.137521 -0.162921)
							(end -0.1016 -0.1778)
						)
						(arc
							(start 0.1016 -0.1778)
							(mid 0.137521 -0.162921)
							(end 0.1524 -0.127)
						)
					)
					(width 0)
					(fill yes)
				)
			)
		)
	)
	(footprint ""
		(layer "B.Cu")
		(at 103.359966 -48.26 90)
		(property "Reference" "SC1057"
			(at 0 0 90)
			(layer "B.SilkS")
			(hide yes)
			(effects
				(font
					(size 1.27 1.27)
				)
				(justify mirror)
			)
		)
		(property "Value" "SCD1U16V2KX-3GP"
			(at -1.1811 -2.7051 90)
			(unlocked yes)
			(layer "B.Fab")
			(hide yes)
			(effects
				(font
					(size 1.016 1.016)
					(thickness 0.1524)
				)
				(justify mirror)
			)
		)
		(property "Device Type" "C402H22"
			(at -1.1811 -4.2291 90)
			(unlocked yes)
			(layer "B.Fab")
			(hide yes)
			(effects
				(font
					(size 1.016 1.016)
					(thickness 0.1524)
				)
				(justify mirror)
			)
		)
		(duplicate_pad_numbers_are_jumpers no)
		(fp_rect
			(start 0.4318 0.9525)
			(end -0.4318 -0.9525)
			(stroke
				(width 0)
				(type default)
			)
			(fill no)
			(layer "B.CrtYd")
		)
		(fp_rect
			(start 0.4318 0.9525)
			(end -0.4318 -0.9525)
			(stroke
				(width 0)
				(type default)
			)
			(fill no)
			(layer "B.Fab")
		)
		(pad "1" smd custom
			(at 0 -0.4445 270)
			(size 0.1524 0.1524)
			(layers "B.Cu" "B.Mask" "B.Paste")
			(net "P0V955_C")
			(options
				(clearance outline)
				(anchor circle)
			)
			(primitives
				(gr_poly
					(pts
						(arc
							(start 0.3048 0.2032)
							(mid 0.275042 0.275042)
							(end 0.2032 0.3048)
						)
						(arc
							(start -0.2032 0.3048)
							(mid -0.275042 0.275042)
							(end -0.3048 0.2032)
						)
						(arc
							(start -0.3048 -0.2032)
							(mid -0.275042 -0.275042)
							(end -0.2032 -0.3048)
						)
						(arc
							(start 0.2032 -0.3048)
							(mid 0.275042 -0.275042)
							(end 0.3048 -0.2032)
						)
					)
					(width 0)
					(fill yes)
				)
			)
		)
		(pad "2" smd custom
			(at 0 0.4445 270)
			(size 0.1524 0.1524)
			(layers "B.Cu" "B.Mask" "B.Paste")
			(net "GND")
			(options
				(clearance outline)
				(anchor circle)
			)
			(primitives
				(gr_poly
					(pts
						(arc
							(start 0.3048 0.2032)
							(mid 0.275042 0.275042)
							(end 0.2032 0.3048)
						)
						(arc
							(start -0.2032 0.3048)
							(mid -0.275042 0.275042)
							(end -0.3048 0.2032)
						)
						(arc
							(start -0.3048 -0.2032)
							(mid -0.275042 -0.275042)
							(end -0.2032 -0.3048)
						)
						(arc
							(start 0.2032 -0.3048)
							(mid 0.275042 -0.275042)
							(end 0.3048 -0.2032)
						)
					)
					(width 0)
					(fill yes)
				)
			)
		)
	)
	(footprint ""
		(layer "B.Cu")
		(at 25.350216 -232.33888)
		(property "Reference" "R502"
			(at 0 0 0)
			(layer "B.SilkS")
			(hide yes)
			(effects
				(font
					(size 1.27 1.27)
				)
				(justify mirror)
			)
		)
		(property "Value" "0R2J-2-GP"
			(at -0.064008 -3.993896 0)
			(unlocked yes)
			(layer "B.Fab")
			(hide yes)
			(effects
				(font
					(size 1.016 1.016)
					(thickness 0.1524)
				)
				(justify mirror)
			)
		)
		(property "Device Type" "R402H16"
			(at -0.064008 -5.517896 0)
			(unlocked yes)
			(layer "B.Fab")
			(hide yes)
			(effects
				(font
					(size 1.016 1.016)
					(thickness 0.1524)
				)
				(justify mirror)
			)
		)
		(duplicate_pad_numbers_are_jumpers no)
		(fp_line
			(start -0.508 -0.9398)
			(end 0.508 -0.9398)
			(stroke
				(width 0.1524)
				(type default)
			)
			(layer "B.SilkS")
		)
		(fp_line
			(start 0.508 -0.9398)
			(end 0.508 0.9398)
			(stroke
				(width 0.1524)
				(type default)
			)
			(layer "B.SilkS")
		)
		(fp_rect
			(start 0.508 0.9398)
			(end -0.508 -0.9398)
			(stroke
				(width 0)
				(type default)
			)
			(fill no)
			(layer "B.CrtYd")
		)
		(fp_rect
			(start 0.508 0.9398)
			(end -0.508 -0.9398)
			(stroke
				(width 0)
				(type default)
			)
			(fill no)
			(layer "B.Fab")
		)
		(pad "1" smd custom
			(at 0 -0.4445 180)
			(size 0.1397 0.1397)
			(layers "B.Cu" "B.Mask" "B.Paste")
			(net "SAS_HDD_PWR0_PCIE")
			(options
				(clearance outline)
				(anchor circle)
			)
			(primitives
				(gr_poly
					(pts
						(arc
							(start -0.1778 0.2794)
							(mid -0.249642 0.249642)
							(end -0.2794 0.1778)
						)
						(arc
							(start -0.2794 -0.1778)
							(mid -0.249642 -0.249642)
							(end -0.1778 -0.2794)
						)
						(arc
							(start 0.1778 -0.2794)
							(mid 0.249642 -0.249642)
							(end 0.2794 -0.1778)
						)
						(arc
							(start 0.2794 0.1778)
							(mid 0.249642 0.249642)
							(end 0.1778 0.2794)
						)
					)
					(width 0)
					(fill yes)
				)
			)
		)
		(pad "2" smd custom
			(at 0 0.4445 180)
			(size 0.1397 0.1397)
			(layers "B.Cu" "B.Mask" "B.Paste")
			(net "SAS_HDD_PWR0")
			(options
				(clearance outline)
				(anchor circle)
			)
			(primitives
				(gr_poly
					(pts
						(arc
							(start -0.1778 0.2794)
							(mid -0.249642 0.249642)
							(end -0.2794 0.1778)
						)
						(arc
							(start -0.2794 -0.1778)
							(mid -0.249642 -0.249642)
							(end -0.1778 -0.2794)
						)
						(arc
							(start 0.1778 -0.2794)
							(mid 0.249642 -0.249642)
							(end 0.2794 -0.1778)
						)
						(arc
							(start 0.2794 0.1778)
							(mid 0.249642 0.249642)
							(end 0.1778 0.2794)
						)
					)
					(width 0)
					(fill yes)
				)
			)
		)
	)
	(footprint ""
		(layer "B.Cu")
		(at 103.359966 -46.609 90)
		(property "Reference" "SC1023"
			(at 0 0 90)
			(layer "B.SilkS")
			(hide yes)
			(effects
				(font
					(size 1.27 1.27)
				)
				(justify mirror)
			)
		)
		(property "Value" "SC1U10V2KX-4-GP"
			(at -1.1811 -2.7051 90)
			(unlocked yes)
			(layer "B.Fab")
			(hide yes)
			(effects
				(font
					(size 1.016 1.016)
					(thickness 0.1524)
				)
				(justify mirror)
			)
		)
		(property "Device Type" "C402H22"
			(at -1.1811 -4.2291 90)
			(unlocked yes)
			(layer "B.Fab")
			(hide yes)
			(effects
				(font
					(size 1.016 1.016)
					(thickness 0.1524)
				)
				(justify mirror)
			)
		)
		(duplicate_pad_numbers_are_jumpers no)
		(fp_rect
			(start 0.4318 0.9525)
			(end -0.4318 -0.9525)
			(stroke
				(width 0)
				(type default)
			)
			(fill no)
			(layer "B.CrtYd")
		)
		(fp_rect
			(start 0.4318 0.9525)
			(end -0.4318 -0.9525)
			(stroke
				(width 0)
				(type default)
			)
			(fill no)
			(layer "B.Fab")
		)
		(pad "1" smd custom
			(at 0 -0.4445 270)
			(size 0.1524 0.1524)
			(layers "B.Cu" "B.Mask" "B.Paste")
			(net "P0V955_C")
			(options
				(clearance outline)
				(anchor circle)
			)
			(primitives
				(gr_poly
					(pts
						(arc
							(start 0.3048 0.2032)
							(mid 0.275042 0.275042)
							(end 0.2032 0.3048)
						)
						(arc
							(start -0.2032 0.3048)
							(mid -0.275042 0.275042)
							(end -0.3048 0.2032)
						)
						(arc
							(start -0.3048 -0.2032)
							(mid -0.275042 -0.275042)
							(end -0.2032 -0.3048)
						)
						(arc
							(start 0.2032 -0.3048)
							(mid 0.275042 -0.275042)
							(end 0.3048 -0.2032)
						)
					)
					(width 0)
					(fill yes)
				)
			)
		)
		(pad "2" smd custom
			(at 0 0.4445 270)
			(size 0.1524 0.1524)
			(layers "B.Cu" "B.Mask" "B.Paste")
			(net "GND")
			(options
				(clearance outline)
				(anchor circle)
			)
			(primitives
				(gr_poly
					(pts
						(arc
							(start 0.3048 0.2032)
							(mid 0.275042 0.275042)
							(end 0.2032 0.3048)
						)
						(arc
							(start -0.2032 0.3048)
							(mid -0.275042 0.275042)
							(end -0.3048 0.2032)
						)
						(arc
							(start -0.3048 -0.2032)
							(mid -0.275042 -0.275042)
							(end -0.2032 -0.3048)
						)
						(arc
							(start 0.2032 -0.3048)
							(mid 0.275042 -0.275042)
							(end 0.3048 -0.2032)
						)
					)
					(width 0)
					(fill yes)
				)
			)
		)
	)
	(footprint ""
		(layer "B.Cu")
		(at 303.8094 -182.6514)
		(property "Reference" "TP103"
			(at 0 0 0)
			(layer "B.SilkS")
			(hide yes)
			(effects
				(font
					(size 1.27 1.27)
				)
				(justify mirror)
			)
		)
		(property "Value" "TPAD28"
			(at -0.0127 -1.8034 0)
			(unlocked yes)
			(layer "B.Fab")
			(hide yes)
			(effects
				(font
					(size 1.016 1.016)
					(thickness 0.1524)
				)
				(justify mirror)
			)
		)
		(property "Device Type" "TPAD28"
			(at -0.0127 -3.3274 0)
			(unlocked yes)
			(layer "B.Fab")
			(hide yes)
			(effects
				(font
					(size 1.016 1.016)
					(thickness 0.1524)
				)
				(justify mirror)
			)
		)
		(duplicate_pad_numbers_are_jumpers no)
		(fp_poly
			(pts
				(arc
					(start 0.3556 0)
					(mid -0.3556 0)
					(end 0.3556 0)
				)
			)
			(stroke
				(width 0)
				(type default)
			)
			(fill no)
			(layer "B.CrtYd")
		)
		(fp_poly
			(pts
				(arc
					(start 0.6096 0)
					(mid -0.6096 0)
					(end 0.6096 0)
				)
			)
			(stroke
				(width 0)
				(type default)
			)
			(fill no)
			(layer "B.Fab")
		)
		(pad "1" smd circle
			(at 0 0 180)
			(size 0.7112 0.7112)
			(layers "B.Cu" "B.Mask" "B.Paste")
			(net "TP_BMC_GPIOL4")
		)
	)
	(footprint ""
		(layer "B.Cu")
		(at 110.88116 -35.306 90)
		(property "Reference" "SC995"
			(at 0 0 90)
			(layer "B.SilkS")
			(hide yes)
			(effects
				(font
					(size 1.27 1.27)
				)
				(justify mirror)
			)
		)
		(property "Value" "SCD1U16V2KX-3GP"
			(at -1.1811 -2.7051 90)
			(unlocked yes)
			(layer "B.Fab")
			(hide yes)
			(effects
				(font
					(size 1.016 1.016)
					(thickness 0.1524)
				)
				(justify mirror)
			)
		)
		(property "Device Type" "C402H22"
			(at -1.1811 -4.2291 90)
			(unlocked yes)
			(layer "B.Fab")
			(hide yes)
			(effects
				(font
					(size 1.016 1.016)
					(thickness 0.1524)
				)
				(justify mirror)
			)
		)
		(duplicate_pad_numbers_are_jumpers no)
		(fp_rect
			(start 0.4318 0.9525)
			(end -0.4318 -0.9525)
			(stroke
				(width 0)
				(type default)
			)
			(fill no)
			(layer "B.CrtYd")
		)
		(fp_rect
			(start 0.4318 0.9525)
			(end -0.4318 -0.9525)
			(stroke
				(width 0)
				(type default)
			)
			(fill no)
			(layer "B.Fab")
		)
		(pad "1" smd custom
			(at 0 -0.4445 270)
			(size 0.1524 0.1524)
			(layers "B.Cu" "B.Mask" "B.Paste")
			(net "P1V8_C")
			(options
				(clearance outline)
				(anchor circle)
			)
			(primitives
				(gr_poly
					(pts
						(arc
							(start 0.3048 0.2032)
							(mid 0.275042 0.275042)
							(end 0.2032 0.3048)
						)
						(arc
							(start -0.2032 0.3048)
							(mid -0.275042 0.275042)
							(end -0.3048 0.2032)
						)
						(arc
							(start -0.3048 -0.2032)
							(mid -0.275042 -0.275042)
							(end -0.2032 -0.3048)
						)
						(arc
							(start 0.2032 -0.3048)
							(mid 0.275042 -0.275042)
							(end 0.3048 -0.2032)
						)
					)
					(width 0)
					(fill yes)
				)
			)
		)
		(pad "2" smd custom
			(at 0 0.4445 270)
			(size 0.1524 0.1524)
			(layers "B.Cu" "B.Mask" "B.Paste")
			(net "GND")
			(options
				(clearance outline)
				(anchor circle)
			)
			(primitives
				(gr_poly
					(pts
						(arc
							(start 0.3048 0.2032)
							(mid 0.275042 0.275042)
							(end 0.2032 0.3048)
						)
						(arc
							(start -0.2032 0.3048)
							(mid -0.275042 0.275042)
							(end -0.3048 0.2032)
						)
						(arc
							(start -0.3048 -0.2032)
							(mid -0.275042 -0.275042)
							(end -0.2032 -0.3048)
						)
						(arc
							(start 0.2032 -0.3048)
							(mid 0.275042 -0.275042)
							(end 0.3048 -0.2032)
						)
					)
					(width 0)
					(fill yes)
				)
			)
		)
	)
	(footprint ""
		(layer "B.Cu")
		(at 340.110318 -133.353048 90)
		(property "Reference" "R555"
			(at 0 0 90)
			(layer "B.SilkS")
			(hide yes)
			(effects
				(font
					(size 1.27 1.27)
				)
				(justify mirror)
			)
		)
		(property "Value" "0R3J-0-U-GP"
			(at 0.0254 -2.5146 90)
			(unlocked yes)
			(layer "B.Fab")
			(hide yes)
			(effects
				(font
					(size 1.016 1.016)
					(thickness 0.1524)
				)
				(justify mirror)
			)
		)
		(property "Device Type" "R603H22"
			(at 0.0254 -4.0386 90)
			(unlocked yes)
			(layer "B.Fab")
			(hide yes)
			(effects
				(font
					(size 1.016 1.016)
					(thickness 0.1524)
				)
				(justify mirror)
			)
		)
		(duplicate_pad_numbers_are_jumpers no)
		(fp_line
			(start 0.4826 0)
			(end 0.2032 0)
			(stroke
				(width 0.2032)
				(type default)
			)
			(layer "B.SilkS")
		)
		(fp_line
			(start -0.2032 0)
			(end -0.4826 0)
			(stroke
				(width 0.2032)
				(type default)
			)
			(layer "B.SilkS")
		)
		(fp_rect
			(start 0.5842 1.3335)
			(end -0.5842 -1.3335)
			(stroke
				(width 0)
				(type default)
			)
			(fill no)
			(layer "B.CrtYd")
		)
		(fp_rect
			(start 0.5842 1.3335)
			(end -0.5842 -1.3335)
			(stroke
				(width 0)
				(type default)
			)
			(fill no)
			(layer "B.Fab")
		)
		(pad "1" smd custom
			(at 0 -0.762 270)
			(size 0.2159 0.2159)
			(layers "B.Cu" "B.Mask" "B.Paste")
			(net "USB_P0_DP")
			(options
				(clearance outline)
				(anchor circle)
			)
			(primitives
				(gr_poly
					(pts
						(arc
							(start -0.3302 0.4318)
							(mid -0.402042 0.402042)
							(end -0.4318 0.3302)
						)
						(arc
							(start -0.4318 -0.3302)
							(mid -0.402042 -0.402042)
							(end -0.3302 -0.4318)
						)
						(arc
							(start 0.3302 -0.4318)
							(mid 0.402042 -0.402042)
							(end 0.4318 -0.3302)
						)
						(arc
							(start 0.4318 0.3302)
							(mid 0.402042 0.402042)
							(end 0.3302 0.4318)
						)
					)
					(width 0)
					(fill yes)
				)
			)
		)
		(pad "2" smd custom
			(at 0 0.762 270)
			(size 0.2159 0.2159)
			(layers "B.Cu" "B.Mask" "B.Paste")
			(net "USB_DP_R")
			(options
				(clearance outline)
				(anchor circle)
			)
			(primitives
				(gr_poly
					(pts
						(arc
							(start -0.3302 0.4318)
							(mid -0.402042 0.402042)
							(end -0.4318 0.3302)
						)
						(arc
							(start -0.4318 -0.3302)
							(mid -0.402042 -0.402042)
							(end -0.3302 -0.4318)
						)
						(arc
							(start 0.3302 -0.4318)
							(mid 0.402042 -0.402042)
							(end 0.4318 -0.3302)
						)
						(arc
							(start 0.4318 0.3302)
							(mid 0.402042 0.402042)
							(end 0.3302 0.4318)
						)
					)
					(width 0)
					(fill yes)
				)
			)
		)
	)
	(footprint ""
		(layer "B.Cu")
		(at 124.568966 -33.401)
		(property "Reference" "SC931"
			(at 0 0 0)
			(layer "B.SilkS")
			(hide yes)
			(effects
				(font
					(size 1.27 1.27)
				)
				(justify mirror)
			)
		)
		(property "Value" "SC22U6D3V5MX-2GP"
			(at 0.0762 -6.1214 0)
			(unlocked yes)
			(layer "B.Fab")
			(hide yes)
			(effects
				(font
					(size 1.016 1.016)
					(thickness 0.1524)
				)
				(justify mirror)
			)
		)
		(property "Device Type" "C805H58"
			(at 0.0762 -8.1534 0)
			(unlocked yes)
			(layer "B.Fab")
			(hide yes)
			(effects
				(font
					(size 1.016 1.016)
					(thickness 0.1524)
				)
				(justify mirror)
			)
		)
		(duplicate_pad_numbers_are_jumpers no)
		(fp_line
			(start -0.635 0)
			(end 0.635 0)
			(stroke
				(width 0.508)
				(type default)
			)
			(layer "B.SilkS")
		)
		(fp_rect
			(start 0.9652 1.778)
			(end -0.9652 -1.778)
			(stroke
				(width 0)
				(type default)
			)
			(fill no)
			(layer "B.CrtYd")
		)
		(fp_poly
			(pts
				(xy 0.9652 -1.778) (xy -0.9652 -1.778) (xy -0.9652 1.778) (xy 0.9652 1.778)
			)
			(stroke
				(width 0)
				(type default)
			)
			(fill no)
			(layer "B.Fab")
		)
		(pad "1" smd rect
			(at 0 -0.9652 180)
			(size 1.397 1.143)
			(layers "B.Cu" "B.Mask" "B.Paste")
			(net "PLL_VDD")
		)
		(pad "2" smd rect
			(at 0 0.9652 180)
			(size 1.397 1.143)
			(layers "B.Cu" "B.Mask" "B.Paste")
			(net "GND")
		)
	)
	(footprint ""
		(layer "B.Cu")
		(at 286.4612 -166.675816)
		(property "Reference" "TP183"
			(at 0 0 0)
			(layer "B.SilkS")
			(hide yes)
			(effects
				(font
					(size 1.27 1.27)
				)
				(justify mirror)
			)
		)
		(property "Value" "TPAD28"
			(at -0.0127 -1.8034 0)
			(unlocked yes)
			(layer "B.Fab")
			(hide yes)
			(effects
				(font
					(size 1.016 1.016)
					(thickness 0.1524)
				)
				(justify mirror)
			)
		)
		(property "Device Type" "TPAD28"
			(at -0.0127 -3.3274 0)
			(unlocked yes)
			(layer "B.Fab")
			(hide yes)
			(effects
				(font
					(size 1.016 1.016)
					(thickness 0.1524)
				)
				(justify mirror)
			)
		)
		(duplicate_pad_numbers_are_jumpers no)
		(fp_poly
			(pts
				(arc
					(start 0.3556 0)
					(mid -0.3556 0)
					(end 0.3556 0)
				)
			)
			(stroke
				(width 0)
				(type default)
			)
			(fill no)
			(layer "B.CrtYd")
		)
		(fp_poly
			(pts
				(arc
					(start 0.6096 0)
					(mid -0.6096 0)
					(end 0.6096 0)
				)
			)
			(stroke
				(width 0)
				(type default)
			)
			(fill no)
			(layer "B.Fab")
		)
		(pad "1" smd circle
			(at 0 0 180)
			(size 0.7112 0.7112)
			(layers "B.Cu" "B.Mask" "B.Paste")
			(net "TP_BMC_GPIOF7")
		)
	)
	(footprint ""
		(layer "B.Cu")
		(at 69.514212 -244.856)
		(property "Reference" "C298"
			(at 0 0 0)
			(layer "B.SilkS")
			(hide yes)
			(effects
				(font
					(size 1.27 1.27)
				)
				(justify mirror)
			)
		)
		(property "Value" "SCD1U25V2KX-2-GP"
			(at -1.1811 -2.7051 0)
			(unlocked yes)
			(layer "B.Fab")
			(hide yes)
			(effects
				(font
					(size 1.016 1.016)
					(thickness 0.1524)
				)
				(justify mirror)
			)
		)
		(property "Device Type" "C402H22"
			(at -1.1811 -4.2291 0)
			(unlocked yes)
			(layer "B.Fab")
			(hide yes)
			(effects
				(font
					(size 1.016 1.016)
					(thickness 0.1524)
				)
				(justify mirror)
			)
		)
		(duplicate_pad_numbers_are_jumpers no)
		(fp_rect
			(start 0.4318 0.9525)
			(end -0.4318 -0.9525)
			(stroke
				(width 0)
				(type default)
			)
			(fill no)
			(layer "B.CrtYd")
		)
		(fp_rect
			(start 0.4318 0.9525)
			(end -0.4318 -0.9525)
			(stroke
				(width 0)
				(type default)
			)
			(fill no)
			(layer "B.Fab")
		)
		(pad "1" smd custom
			(at 0 -0.4445 180)
			(size 0.1524 0.1524)
			(layers "B.Cu" "B.Mask" "B.Paste")
			(net "P12V_PCIE")
			(options
				(clearance outline)
				(anchor circle)
			)
			(primitives
				(gr_poly
					(pts
						(arc
							(start 0.3048 0.2032)
							(mid 0.275042 0.275042)
							(end 0.2032 0.3048)
						)
						(arc
							(start -0.2032 0.3048)
							(mid -0.275042 0.275042)
							(end -0.3048 0.2032)
						)
						(arc
							(start -0.3048 -0.2032)
							(mid -0.275042 -0.275042)
							(end -0.2032 -0.3048)
						)
						(arc
							(start 0.2032 -0.3048)
							(mid 0.275042 -0.275042)
							(end 0.3048 -0.2032)
						)
					)
					(width 0)
					(fill yes)
				)
			)
		)
		(pad "2" smd custom
			(at 0 0.4445 180)
			(size 0.1524 0.1524)
			(layers "B.Cu" "B.Mask" "B.Paste")
			(net "GND")
			(options
				(clearance outline)
				(anchor circle)
			)
			(primitives
				(gr_poly
					(pts
						(arc
							(start 0.3048 0.2032)
							(mid 0.275042 0.275042)
							(end 0.2032 0.3048)
						)
						(arc
							(start -0.2032 0.3048)
							(mid -0.275042 0.275042)
							(end -0.3048 0.2032)
						)
						(arc
							(start -0.3048 -0.2032)
							(mid -0.275042 -0.275042)
							(end -0.2032 -0.3048)
						)
						(arc
							(start 0.2032 -0.3048)
							(mid 0.275042 -0.275042)
							(end 0.3048 -0.2032)
						)
					)
					(width 0)
					(fill yes)
				)
			)
		)
	)
	(footprint ""
		(layer "B.Cu")
		(at 307.086 -160.655 180)
		(property "Reference" "R465"
			(at 0 0 0)
			(layer "B.SilkS")
			(hide yes)
			(effects
				(font
					(size 1.27 1.27)
				)
				(justify mirror)
			)
		)
		(property "Value" "0R2J-2-GP"
			(at -0.064008 -3.993896 180)
			(unlocked yes)
			(layer "B.Fab")
			(hide yes)
			(effects
				(font
					(size 1.016 1.016)
					(thickness 0.1524)
				)
				(justify mirror)
			)
		)
		(property "Device Type" "R402H16"
			(at -0.064008 -5.517896 180)
			(unlocked yes)
			(layer "B.Fab")
			(hide yes)
			(effects
				(font
					(size 1.016 1.016)
					(thickness 0.1524)
				)
				(justify mirror)
			)
		)
		(duplicate_pad_numbers_are_jumpers no)
		(fp_line
			(start 0.508 -0.9398)
			(end 0.508 0.9398)
			(stroke
				(width 0.1524)
				(type default)
			)
			(layer "B.SilkS")
		)
		(fp_line
			(start -0.508 -0.9398)
			(end 0.508 -0.9398)
			(stroke
				(width 0.1524)
				(type default)
			)
			(layer "B.SilkS")
		)
		(fp_rect
			(start 0.508 0.9398)
			(end -0.508 -0.9398)
			(stroke
				(width 0)
				(type default)
			)
			(fill no)
			(layer "B.CrtYd")
		)
		(fp_rect
			(start 0.508 0.9398)
			(end -0.508 -0.9398)
			(stroke
				(width 0)
				(type default)
			)
			(fill no)
			(layer "B.Fab")
		)
		(pad "1" smd custom
			(at 0 -0.4445)
			(size 0.1397 0.1397)
			(layers "B.Cu" "B.Mask" "B.Paste")
			(net "BMC_I2C_SCL_9")
			(options
				(clearance outline)
				(anchor circle)
			)
			(primitives
				(gr_poly
					(pts
						(arc
							(start -0.1778 0.2794)
							(mid -0.249642 0.249642)
							(end -0.2794 0.1778)
						)
						(arc
							(start -0.2794 -0.1778)
							(mid -0.249642 -0.249642)
							(end -0.1778 -0.2794)
						)
						(arc
							(start 0.1778 -0.2794)
							(mid 0.249642 -0.249642)
							(end 0.2794 -0.1778)
						)
						(arc
							(start 0.2794 0.1778)
							(mid 0.249642 0.249642)
							(end 0.1778 0.2794)
						)
					)
					(width 0)
					(fill yes)
				)
			)
		)
		(pad "2" smd custom
			(at 0 0.4445)
			(size 0.1397 0.1397)
			(layers "B.Cu" "B.Mask" "B.Paste")
			(net "BMC0_SMB9_CLK")
			(options
				(clearance outline)
				(anchor circle)
			)
			(primitives
				(gr_poly
					(pts
						(arc
							(start -0.1778 0.2794)
							(mid -0.249642 0.249642)
							(end -0.2794 0.1778)
						)
						(arc
							(start -0.2794 -0.1778)
							(mid -0.249642 -0.249642)
							(end -0.1778 -0.2794)
						)
						(arc
							(start 0.1778 -0.2794)
							(mid 0.249642 -0.249642)
							(end 0.2794 -0.1778)
						)
						(arc
							(start 0.2794 0.1778)
							(mid 0.249642 0.249642)
							(end 0.1778 0.2794)
						)
					)
					(width 0)
					(fill yes)
				)
			)
		)
	)
	(footprint ""
		(layer "B.Cu")
		(at 15.571216 -170.10888 90)
		(property "Reference" "SC1111"
			(at 0 0 90)
			(layer "B.SilkS")
			(hide yes)
			(effects
				(font
					(size 1.27 1.27)
				)
				(justify mirror)
			)
		)
		(property "Value" "SCD1U16V2KX-3GP"
			(at -1.1811 -2.7051 90)
			(unlocked yes)
			(layer "B.Fab")
			(hide yes)
			(effects
				(font
					(size 1.016 1.016)
					(thickness 0.1524)
				)
				(justify mirror)
			)
		)
		(property "Device Type" "C402H22"
			(at -1.1811 -4.2291 90)
			(unlocked yes)
			(layer "B.Fab")
			(hide yes)
			(effects
				(font
					(size 1.016 1.016)
					(thickness 0.1524)
				)
				(justify mirror)
			)
		)
		(duplicate_pad_numbers_are_jumpers no)
		(fp_rect
			(start 0.4318 0.9525)
			(end -0.4318 -0.9525)
			(stroke
				(width 0)
				(type default)
			)
			(fill no)
			(layer "B.CrtYd")
		)
		(fp_rect
			(start 0.4318 0.9525)
			(end -0.4318 -0.9525)
			(stroke
				(width 0)
				(type default)
			)
			(fill no)
			(layer "B.Fab")
		)
		(pad "1" smd custom
			(at 0 -0.4445 270)
			(size 0.1524 0.1524)
			(layers "B.Cu" "B.Mask" "B.Paste")
			(net "P1V8_E")
			(options
				(clearance outline)
				(anchor circle)
			)
			(primitives
				(gr_poly
					(pts
						(arc
							(start 0.3048 0.2032)
							(mid 0.275042 0.275042)
							(end 0.2032 0.3048)
						)
						(arc
							(start -0.2032 0.3048)
							(mid -0.275042 0.275042)
							(end -0.3048 0.2032)
						)
						(arc
							(start -0.3048 -0.2032)
							(mid -0.275042 -0.275042)
							(end -0.2032 -0.3048)
						)
						(arc
							(start 0.2032 -0.3048)
							(mid 0.275042 -0.275042)
							(end 0.3048 -0.2032)
						)
					)
					(width 0)
					(fill yes)
				)
			)
		)
		(pad "2" smd custom
			(at 0 0.4445 270)
			(size 0.1524 0.1524)
			(layers "B.Cu" "B.Mask" "B.Paste")
			(net "GND")
			(options
				(clearance outline)
				(anchor circle)
			)
			(primitives
				(gr_poly
					(pts
						(arc
							(start 0.3048 0.2032)
							(mid 0.275042 0.275042)
							(end 0.2032 0.3048)
						)
						(arc
							(start -0.2032 0.3048)
							(mid -0.275042 0.275042)
							(end -0.3048 0.2032)
						)
						(arc
							(start -0.3048 -0.2032)
							(mid -0.275042 -0.275042)
							(end -0.2032 -0.3048)
						)
						(arc
							(start 0.2032 -0.3048)
							(mid 0.275042 -0.275042)
							(end 0.3048 -0.2032)
						)
					)
					(width 0)
					(fill yes)
				)
			)
		)
	)
	(footprint ""
		(layer "B.Cu")
		(at 318.008 -164.338 -90)
		(property "Reference" "R245"
			(at 0 0 90)
			(layer "B.SilkS")
			(hide yes)
			(effects
				(font
					(size 1.27 1.27)
				)
				(justify mirror)
			)
		)
		(property "Value" "0R2J-2-GP"
			(at -0.064008 -3.993896 270)
			(unlocked yes)
			(layer "B.Fab")
			(hide yes)
			(effects
				(font
					(size 1.016 1.016)
					(thickness 0.1524)
				)
				(justify mirror)
			)
		)
		(property "Device Type" "R402H16"
			(at -0.064008 -5.517896 270)
			(unlocked yes)
			(layer "B.Fab")
			(hide yes)
			(effects
				(font
					(size 1.016 1.016)
					(thickness 0.1524)
				)
				(justify mirror)
			)
		)
		(duplicate_pad_numbers_are_jumpers no)
		(fp_line
			(start -0.508 -0.9398)
			(end 0.508 -0.9398)
			(stroke
				(width 0.1524)
				(type default)
			)
			(layer "B.SilkS")
		)
		(fp_line
			(start 0.508 -0.9398)
			(end 0.508 0.9398)
			(stroke
				(width 0.1524)
				(type default)
			)
			(layer "B.SilkS")
		)
		(fp_rect
			(start 0.508 0.9398)
			(end -0.508 -0.9398)
			(stroke
				(width 0)
				(type default)
			)
			(fill no)
			(layer "B.CrtYd")
		)
		(fp_rect
			(start 0.508 0.9398)
			(end -0.508 -0.9398)
			(stroke
				(width 0)
				(type default)
			)
			(fill no)
			(layer "B.Fab")
		)
		(pad "1" smd custom
			(at 0 -0.4445 90)
			(size 0.1397 0.1397)
			(layers "B.Cu" "B.Mask" "B.Paste")
			(net "NIC_SMBUS_SDA")
			(options
				(clearance outline)
				(anchor circle)
			)
			(primitives
				(gr_poly
					(pts
						(arc
							(start -0.1778 0.2794)
							(mid -0.249642 0.249642)
							(end -0.2794 0.1778)
						)
						(arc
							(start -0.2794 -0.1778)
							(mid -0.249642 -0.249642)
							(end -0.1778 -0.2794)
						)
						(arc
							(start 0.1778 -0.2794)
							(mid 0.249642 -0.249642)
							(end 0.2794 -0.1778)
						)
						(arc
							(start 0.2794 0.1778)
							(mid 0.249642 0.249642)
							(end 0.1778 0.2794)
						)
					)
					(width 0)
					(fill yes)
				)
			)
		)
		(pad "2" smd custom
			(at 0 0.4445 90)
			(size 0.1397 0.1397)
			(layers "B.Cu" "B.Mask" "B.Paste")
			(net "BMC0_SMB4_DAT")
			(options
				(clearance outline)
				(anchor circle)
			)
			(primitives
				(gr_poly
					(pts
						(arc
							(start -0.1778 0.2794)
							(mid -0.249642 0.249642)
							(end -0.2794 0.1778)
						)
						(arc
							(start -0.2794 -0.1778)
							(mid -0.249642 -0.249642)
							(end -0.1778 -0.2794)
						)
						(arc
							(start 0.1778 -0.2794)
							(mid 0.249642 -0.249642)
							(end 0.2794 -0.1778)
						)
						(arc
							(start 0.2794 0.1778)
							(mid 0.249642 0.249642)
							(end 0.1778 0.2794)
						)
					)
					(width 0)
					(fill yes)
				)
			)
		)
	)
	(footprint ""
		(layer "B.Cu")
		(at 118.688612 -222.885 180)
		(property "Reference" "SR887"
			(at 0 0 0)
			(layer "B.SilkS")
			(hide yes)
			(effects
				(font
					(size 1.27 1.27)
				)
				(justify mirror)
			)
		)
		(property "Value" "0R2J-2-GP"
			(at -0.064008 -3.993896 180)
			(unlocked yes)
			(layer "B.Fab")
			(hide yes)
			(effects
				(font
					(size 1.016 1.016)
					(thickness 0.1524)
				)
				(justify mirror)
			)
		)
		(property "Device Type" "R402H16"
			(at -0.064008 -5.517896 180)
			(unlocked yes)
			(layer "B.Fab")
			(hide yes)
			(effects
				(font
					(size 1.016 1.016)
					(thickness 0.1524)
				)
				(justify mirror)
			)
		)
		(duplicate_pad_numbers_are_jumpers no)
		(fp_line
			(start 0.508 -0.9398)
			(end 0.508 0.9398)
			(stroke
				(width 0.1524)
				(type default)
			)
			(layer "B.SilkS")
		)
		(fp_line
			(start -0.508 -0.9398)
			(end 0.508 -0.9398)
			(stroke
				(width 0.1524)
				(type default)
			)
			(layer "B.SilkS")
		)
		(fp_rect
			(start 0.508 0.9398)
			(end -0.508 -0.9398)
			(stroke
				(width 0)
				(type default)
			)
			(fill no)
			(layer "B.CrtYd")
		)
		(fp_rect
			(start 0.508 0.9398)
			(end -0.508 -0.9398)
			(stroke
				(width 0)
				(type default)
			)
			(fill no)
			(layer "B.Fab")
		)
		(pad "1" smd custom
			(at 0 -0.4445)
			(size 0.1397 0.1397)
			(layers "B.Cu" "B.Mask" "B.Paste")
			(net "SAS_GF_EXP_RX_DP7")
			(options
				(clearance outline)
				(anchor circle)
			)
			(primitives
				(gr_poly
					(pts
						(arc
							(start -0.1778 0.2794)
							(mid -0.249642 0.249642)
							(end -0.2794 0.1778)
						)
						(arc
							(start -0.2794 -0.1778)
							(mid -0.249642 -0.249642)
							(end -0.1778 -0.2794)
						)
						(arc
							(start 0.1778 -0.2794)
							(mid 0.249642 -0.249642)
							(end 0.2794 -0.1778)
						)
						(arc
							(start 0.2794 0.1778)
							(mid 0.249642 0.249642)
							(end 0.1778 0.2794)
						)
					)
					(width 0)
					(fill yes)
				)
			)
		)
		(pad "2" smd custom
			(at 0 0.4445)
			(size 0.1397 0.1397)
			(layers "B.Cu" "B.Mask" "B.Paste")
			(net "REDV_RX7_P")
			(options
				(clearance outline)
				(anchor circle)
			)
			(primitives
				(gr_poly
					(pts
						(arc
							(start -0.1778 0.2794)
							(mid -0.249642 0.249642)
							(end -0.2794 0.1778)
						)
						(arc
							(start -0.2794 -0.1778)
							(mid -0.249642 -0.249642)
							(end -0.1778 -0.2794)
						)
						(arc
							(start 0.1778 -0.2794)
							(mid 0.249642 -0.249642)
							(end 0.2794 -0.1778)
						)
						(arc
							(start 0.2794 0.1778)
							(mid 0.249642 0.249642)
							(end 0.1778 0.2794)
						)
					)
					(width 0)
					(fill yes)
				)
			)
		)
	)
	(footprint ""
		(layer "B.Cu")
		(at 167.630348 -118.354856 -90)
		(property "Reference" "PC184"
			(at 0 0 90)
			(layer "B.SilkS")
			(hide yes)
			(effects
				(font
					(size 1.27 1.27)
				)
				(justify mirror)
			)
		)
		(property "Value" "SC4D7U25V5KX-1-GP"
			(at 0.0762 -6.1214 270)
			(unlocked yes)
			(layer "B.Fab")
			(hide yes)
			(effects
				(font
					(size 1.016 1.016)
					(thickness 0.1524)
				)
				(justify mirror)
			)
		)
		(property "Device Type" "C805H58"
			(at 0.0762 -8.1534 270)
			(unlocked yes)
			(layer "B.Fab")
			(hide yes)
			(effects
				(font
					(size 1.016 1.016)
					(thickness 0.1524)
				)
				(justify mirror)
			)
		)
		(duplicate_pad_numbers_are_jumpers no)
		(fp_line
			(start -0.635 0)
			(end 0.635 0)
			(stroke
				(width 0.508)
				(type default)
			)
			(layer "B.SilkS")
		)
		(fp_rect
			(start 0.9652 1.778)
			(end -0.9652 -1.778)
			(stroke
				(width 0)
				(type default)
			)
			(fill no)
			(layer "B.CrtYd")
		)
		(fp_poly
			(pts
				(xy 0.9652 -1.778) (xy -0.9652 -1.778) (xy -0.9652 1.778) (xy 0.9652 1.778)
			)
			(stroke
				(width 0)
				(type default)
			)
			(fill no)
			(layer "B.Fab")
		)
		(pad "1" smd rect
			(at 0 -0.9652 90)
			(size 1.397 1.143)
			(layers "B.Cu" "B.Mask" "B.Paste")
			(net "P0V9_E_VDD")
		)
		(pad "2" smd rect
			(at 0 0.9652 90)
			(size 1.397 1.143)
			(layers "B.Cu" "B.Mask" "B.Paste")
			(net "GND")
		)
	)
	(footprint ""
		(layer "B.Cu")
		(at 130.537966 -31.877 90)
		(property "Reference" "SQ3"
			(at 0 0 90)
			(layer "B.SilkS")
			(hide yes)
			(effects
				(font
					(size 1.27 1.27)
				)
				(justify mirror)
			)
		)
		(property "Value" "2N7002A-7-GP"
			(at -0.127 -8.9662 90)
			(unlocked yes)
			(layer "B.Fab")
			(hide yes)
			(effects
				(font
					(size 1.016 1.016)
					(thickness 0.1524)
				)
				(justify mirror)
			)
		)
		(property "Device Type" "SOT23DGS2D4H48"
			(at -0.127 -10.4902 90)
			(unlocked yes)
			(layer "B.Fab")
			(hide yes)
			(effects
				(font
					(size 1.016 1.016)
					(thickness 0.1524)
				)
				(justify mirror)
			)
		)
		(duplicate_pad_numbers_are_jumpers no)
		(fp_line
			(start 1.651 -1.778)
			(end 1.651 1.778)
			(stroke
				(width 0.1524)
				(type default)
			)
			(layer "B.SilkS")
		)
		(fp_line
			(start -1.651 -1.778)
			(end 1.651 -1.778)
			(stroke
				(width 0.1524)
				(type default)
			)
			(layer "B.SilkS")
		)
		(fp_line
			(start 1.651 1.778)
			(end -1.651 1.778)
			(stroke
				(width 0.1524)
				(type default)
			)
			(layer "B.SilkS")
		)
		(fp_line
			(start -1.651 1.778)
			(end -1.651 -1.778)
			(stroke
				(width 0.1524)
				(type default)
			)
			(layer "B.SilkS")
		)
		(fp_poly
			(pts
				(xy 1.778 1.8796) (xy 1.778 -1.8796) (xy -1.778 -1.8796) (xy -1.778 1.8796)
			)
			(stroke
				(width 0)
				(type default)
			)
			(fill no)
			(layer "B.CrtYd")
		)
		(fp_poly
			(pts
				(xy 1.778 1.8796) (xy 1.778 -1.8796) (xy -1.778 -1.8796) (xy -1.778 1.8796)
			)
			(stroke
				(width 0)
				(type default)
			)
			(fill no)
			(layer "B.Fab")
		)
		(pad "D" smd custom
			(at 0 -0.9525 270)
			(size 0.1905 0.1905)
			(layers "B.Cu" "B.Mask" "B.Paste")
			(net "SYS_RST")
			(options
				(clearance outline)
				(anchor circle)
			)
			(primitives
				(gr_poly
					(pts
						(arc
							(start -0.1778 -0.5715)
							(mid -0.321484 -0.511984)
							(end -0.381 -0.3683)
						)
						(arc
							(start -0.381 0.3683)
							(mid -0.321484 0.511984)
							(end -0.1778 0.5715)
						)
						(arc
							(start 0.1778 0.5715)
							(mid 0.321484 0.511984)
							(end 0.381 0.3683)
						)
						(arc
							(start 0.381 -0.3683)
							(mid 0.321484 -0.511984)
							(end 0.1778 -0.5715)
						)
					)
					(width 0)
					(fill yes)
				)
			)
		)
		(pad "G" smd custom
			(at 0.98425 0.9525 270)
			(size 0.1905 0.1905)
			(layers "B.Cu" "B.Mask" "B.Paste")
			(net "P3V3_STBY_B")
			(options
				(clearance outline)
				(anchor circle)
			)
			(primitives
				(gr_poly
					(pts
						(arc
							(start -0.1778 -0.5715)
							(mid -0.321484 -0.511984)
							(end -0.381 -0.3683)
						)
						(arc
							(start -0.381 0.3683)
							(mid -0.321484 0.511984)
							(end -0.1778 0.5715)
						)
						(arc
							(start 0.1778 0.5715)
							(mid 0.321484 0.511984)
							(end 0.381 0.3683)
						)
						(arc
							(start 0.381 -0.3683)
							(mid 0.321484 -0.511984)
							(end 0.1778 -0.5715)
						)
					)
					(width 0)
					(fill yes)
				)
			)
		)
		(pad "S" smd custom
			(at -0.98425 0.9525 270)
			(size 0.1905 0.1905)
			(layers "B.Cu" "B.Mask" "B.Paste")
			(net "GND")
			(options
				(clearance outline)
				(anchor circle)
			)
			(primitives
				(gr_poly
					(pts
						(arc
							(start -0.1778 -0.5715)
							(mid -0.321484 -0.511984)
							(end -0.381 -0.3683)
						)
						(arc
							(start -0.381 0.3683)
							(mid -0.321484 0.511984)
							(end -0.1778 0.5715)
						)
						(arc
							(start 0.1778 0.5715)
							(mid 0.321484 0.511984)
							(end 0.381 0.3683)
						)
						(arc
							(start 0.381 -0.3683)
							(mid 0.321484 -0.511984)
							(end 0.1778 -0.5715)
						)
					)
					(width 0)
					(fill yes)
				)
			)
		)
	)
	(footprint ""
		(layer "B.Cu")
		(at 328.295 -103.505 180)
		(property "Reference" "PC30"
			(at 0 0 0)
			(layer "B.SilkS")
			(hide yes)
			(effects
				(font
					(size 1.27 1.27)
				)
				(justify mirror)
			)
		)
		(property "Value" "SCD1U25V2KX-2-GP"
			(at -1.1811 -2.7051 180)
			(unlocked yes)
			(layer "B.Fab")
			(hide yes)
			(effects
				(font
					(size 1.016 1.016)
					(thickness 0.1524)
				)
				(justify mirror)
			)
		)
		(property "Device Type" "C402H22"
			(at -1.1811 -4.2291 180)
			(unlocked yes)
			(layer "B.Fab")
			(hide yes)
			(effects
				(font
					(size 1.016 1.016)
					(thickness 0.1524)
				)
				(justify mirror)
			)
		)
		(duplicate_pad_numbers_are_jumpers no)
		(fp_rect
			(start 0.4318 0.9525)
			(end -0.4318 -0.9525)
			(stroke
				(width 0)
				(type default)
			)
			(fill no)
			(layer "B.CrtYd")
		)
		(fp_rect
			(start 0.4318 0.9525)
			(end -0.4318 -0.9525)
			(stroke
				(width 0)
				(type default)
			)
			(fill no)
			(layer "B.Fab")
		)
		(pad "1" smd custom
			(at 0 -0.4445)
			(size 0.1524 0.1524)
			(layers "B.Cu" "B.Mask" "B.Paste")
			(net "P3V3_STBY")
			(options
				(clearance outline)
				(anchor circle)
			)
			(primitives
				(gr_poly
					(pts
						(arc
							(start 0.3048 0.2032)
							(mid 0.275042 0.275042)
							(end 0.2032 0.3048)
						)
						(arc
							(start -0.2032 0.3048)
							(mid -0.275042 0.275042)
							(end -0.3048 0.2032)
						)
						(arc
							(start -0.3048 -0.2032)
							(mid -0.275042 -0.275042)
							(end -0.2032 -0.3048)
						)
						(arc
							(start 0.2032 -0.3048)
							(mid 0.275042 -0.275042)
							(end 0.3048 -0.2032)
						)
					)
					(width 0)
					(fill yes)
				)
			)
		)
		(pad "2" smd custom
			(at 0 0.4445)
			(size 0.1524 0.1524)
			(layers "B.Cu" "B.Mask" "B.Paste")
			(net "P3V3_STBY_LL_R")
			(options
				(clearance outline)
				(anchor circle)
			)
			(primitives
				(gr_poly
					(pts
						(arc
							(start 0.3048 0.2032)
							(mid 0.275042 0.275042)
							(end 0.2032 0.3048)
						)
						(arc
							(start -0.2032 0.3048)
							(mid -0.275042 0.275042)
							(end -0.3048 0.2032)
						)
						(arc
							(start -0.3048 -0.2032)
							(mid -0.275042 -0.275042)
							(end -0.2032 -0.3048)
						)
						(arc
							(start 0.2032 -0.3048)
							(mid 0.275042 -0.275042)
							(end 0.3048 -0.2032)
						)
					)
					(width 0)
					(fill yes)
				)
			)
		)
	)
	(footprint ""
		(layer "B.Cu")
		(at 96.901 -230.124 -90)
		(property "Reference" "R667"
			(at 0 0 90)
			(layer "B.SilkS")
			(hide yes)
			(effects
				(font
					(size 1.27 1.27)
				)
				(justify mirror)
			)
		)
		(property "Value" "0R2J-2-GP"
			(at -0.064008 -3.993896 270)
			(unlocked yes)
			(layer "B.Fab")
			(hide yes)
			(effects
				(font
					(size 1.016 1.016)
					(thickness 0.1524)
				)
				(justify mirror)
			)
		)
		(property "Device Type" "R402H16"
			(at -0.064008 -5.517896 270)
			(unlocked yes)
			(layer "B.Fab")
			(hide yes)
			(effects
				(font
					(size 1.016 1.016)
					(thickness 0.1524)
				)
				(justify mirror)
			)
		)
		(duplicate_pad_numbers_are_jumpers no)
		(fp_line
			(start -0.508 -0.9398)
			(end 0.508 -0.9398)
			(stroke
				(width 0.1524)
				(type default)
			)
			(layer "B.SilkS")
		)
		(fp_line
			(start 0.508 -0.9398)
			(end 0.508 0.9398)
			(stroke
				(width 0.1524)
				(type default)
			)
			(layer "B.SilkS")
		)
		(fp_rect
			(start 0.508 0.9398)
			(end -0.508 -0.9398)
			(stroke
				(width 0)
				(type default)
			)
			(fill no)
			(layer "B.CrtYd")
		)
		(fp_rect
			(start 0.508 0.9398)
			(end -0.508 -0.9398)
			(stroke
				(width 0)
				(type default)
			)
			(fill no)
			(layer "B.Fab")
		)
		(pad "1" smd custom
			(at 0 -0.4445 90)
			(size 0.1397 0.1397)
			(layers "B.Cu" "B.Mask" "B.Paste")
			(net "SAS_FAULT_LED10")
			(options
				(clearance outline)
				(anchor circle)
			)
			(primitives
				(gr_poly
					(pts
						(arc
							(start -0.1778 0.2794)
							(mid -0.249642 0.249642)
							(end -0.2794 0.1778)
						)
						(arc
							(start -0.2794 -0.1778)
							(mid -0.249642 -0.249642)
							(end -0.1778 -0.2794)
						)
						(arc
							(start 0.1778 -0.2794)
							(mid 0.249642 -0.249642)
							(end 0.2794 -0.1778)
						)
						(arc
							(start 0.2794 0.1778)
							(mid 0.249642 0.249642)
							(end 0.1778 0.2794)
						)
					)
					(width 0)
					(fill yes)
				)
			)
		)
		(pad "2" smd custom
			(at 0 0.4445 90)
			(size 0.1397 0.1397)
			(layers "B.Cu" "B.Mask" "B.Paste")
			(net "SAS_HDD_LED_10")
			(options
				(clearance outline)
				(anchor circle)
			)
			(primitives
				(gr_poly
					(pts
						(arc
							(start -0.1778 0.2794)
							(mid -0.249642 0.249642)
							(end -0.2794 0.1778)
						)
						(arc
							(start -0.2794 -0.1778)
							(mid -0.249642 -0.249642)
							(end -0.1778 -0.2794)
						)
						(arc
							(start 0.1778 -0.2794)
							(mid 0.249642 -0.249642)
							(end 0.2794 -0.1778)
						)
						(arc
							(start 0.2794 0.1778)
							(mid 0.249642 0.249642)
							(end 0.1778 0.2794)
						)
					)
					(width 0)
					(fill yes)
				)
			)
		)
	)
	(footprint ""
		(layer "B.Cu")
		(at 318.008 -175.641 -90)
		(property "Reference" "R280"
			(at 0 0 90)
			(layer "B.SilkS")
			(hide yes)
			(effects
				(font
					(size 1.27 1.27)
				)
				(justify mirror)
			)
		)
		(property "Value" "0R2J-2-GP"
			(at -0.064008 -3.993896 270)
			(unlocked yes)
			(layer "B.Fab")
			(hide yes)
			(effects
				(font
					(size 1.016 1.016)
					(thickness 0.1524)
				)
				(justify mirror)
			)
		)
		(property "Device Type" "R402H16"
			(at -0.064008 -5.517896 270)
			(unlocked yes)
			(layer "B.Fab")
			(hide yes)
			(effects
				(font
					(size 1.016 1.016)
					(thickness 0.1524)
				)
				(justify mirror)
			)
		)
		(duplicate_pad_numbers_are_jumpers no)
		(fp_line
			(start -0.508 -0.9398)
			(end 0.508 -0.9398)
			(stroke
				(width 0.1524)
				(type default)
			)
			(layer "B.SilkS")
		)
		(fp_line
			(start 0.508 -0.9398)
			(end 0.508 0.9398)
			(stroke
				(width 0.1524)
				(type default)
			)
			(layer "B.SilkS")
		)
		(fp_rect
			(start 0.508 0.9398)
			(end -0.508 -0.9398)
			(stroke
				(width 0)
				(type default)
			)
			(fill no)
			(layer "B.CrtYd")
		)
		(fp_rect
			(start 0.508 0.9398)
			(end -0.508 -0.9398)
			(stroke
				(width 0)
				(type default)
			)
			(fill no)
			(layer "B.Fab")
		)
		(pad "1" smd custom
			(at 0 -0.4445 90)
			(size 0.1397 0.1397)
			(layers "B.Cu" "B.Mask" "B.Paste")
			(net "BMC_TXD5")
			(options
				(clearance outline)
				(anchor circle)
			)
			(primitives
				(gr_poly
					(pts
						(arc
							(start -0.1778 0.2794)
							(mid -0.249642 0.249642)
							(end -0.2794 0.1778)
						)
						(arc
							(start -0.2794 -0.1778)
							(mid -0.249642 -0.249642)
							(end -0.1778 -0.2794)
						)
						(arc
							(start 0.1778 -0.2794)
							(mid 0.249642 -0.249642)
							(end 0.2794 -0.1778)
						)
						(arc
							(start 0.2794 0.1778)
							(mid 0.249642 0.249642)
							(end 0.1778 0.2794)
						)
					)
					(width 0)
					(fill yes)
				)
			)
		)
		(pad "2" smd custom
			(at 0 0.4445 90)
			(size 0.1397 0.1397)
			(layers "B.Cu" "B.Mask" "B.Paste")
			(net "BMC_TXD5_R")
			(options
				(clearance outline)
				(anchor circle)
			)
			(primitives
				(gr_poly
					(pts
						(arc
							(start -0.1778 0.2794)
							(mid -0.249642 0.249642)
							(end -0.2794 0.1778)
						)
						(arc
							(start -0.2794 -0.1778)
							(mid -0.249642 -0.249642)
							(end -0.1778 -0.2794)
						)
						(arc
							(start 0.1778 -0.2794)
							(mid 0.249642 -0.249642)
							(end 0.2794 -0.1778)
						)
						(arc
							(start 0.2794 0.1778)
							(mid 0.249642 0.249642)
							(end 0.1778 0.2794)
						)
					)
					(width 0)
					(fill yes)
				)
			)
		)
	)
	(footprint ""
		(layer "B.Cu")
		(at 199.898 -102.489)
		(property "Reference" "PC233"
			(at 0 0 0)
			(layer "B.SilkS")
			(hide yes)
			(effects
				(font
					(size 1.27 1.27)
				)
				(justify mirror)
			)
		)
		(property "Value" "SCD1U50V3KX-GP"
			(at 0 -2.8194 0)
			(unlocked yes)
			(layer "B.Fab")
			(hide yes)
			(effects
				(font
					(size 1.016 1.016)
					(thickness 0.1524)
				)
				(justify mirror)
			)
		)
		(property "Device Type" "C603H36"
			(at 0 -4.3434 0)
			(unlocked yes)
			(layer "B.Fab")
			(hide yes)
			(effects
				(font
					(size 1.016 1.016)
					(thickness 0.1524)
				)
				(justify mirror)
			)
		)
		(duplicate_pad_numbers_are_jumpers no)
		(fp_line
			(start -0.508 0)
			(end 0.508 0)
			(stroke
				(width 0.2032)
				(type default)
			)
			(layer "B.SilkS")
		)
		(fp_rect
			(start 0.5842 1.3335)
			(end -0.5842 -1.3335)
			(stroke
				(width 0)
				(type default)
			)
			(fill no)
			(layer "B.CrtYd")
		)
		(fp_rect
			(start 0.5842 1.3335)
			(end -0.5842 -1.3335)
			(stroke
				(width 0)
				(type default)
			)
			(fill no)
			(layer "B.Fab")
		)
		(pad "1" smd custom
			(at 0 -0.762 180)
			(size 0.2159 0.2159)
			(layers "B.Cu" "B.Mask" "B.Paste")
			(net "P1V5_E_VFB_R")
			(options
				(clearance outline)
				(anchor circle)
			)
			(primitives
				(gr_poly
					(pts
						(arc
							(start -0.3302 0.4318)
							(mid -0.402042 0.402042)
							(end -0.4318 0.3302)
						)
						(arc
							(start -0.4318 -0.3302)
							(mid -0.402042 -0.402042)
							(end -0.3302 -0.4318)
						)
						(arc
							(start 0.3302 -0.4318)
							(mid 0.402042 -0.402042)
							(end 0.4318 -0.3302)
						)
						(arc
							(start 0.4318 0.3302)
							(mid 0.402042 0.402042)
							(end 0.3302 0.4318)
						)
					)
					(width 0)
					(fill yes)
				)
			)
		)
		(pad "2" smd custom
			(at 0 0.762 180)
			(size 0.2159 0.2159)
			(layers "B.Cu" "B.Mask" "B.Paste")
			(net "P1V5_E")
			(options
				(clearance outline)
				(anchor circle)
			)
			(primitives
				(gr_poly
					(pts
						(arc
							(start -0.3302 0.4318)
							(mid -0.402042 0.402042)
							(end -0.4318 0.3302)
						)
						(arc
							(start -0.4318 -0.3302)
							(mid -0.402042 -0.402042)
							(end -0.3302 -0.4318)
						)
						(arc
							(start 0.3302 -0.4318)
							(mid 0.402042 -0.402042)
							(end 0.4318 -0.3302)
						)
						(arc
							(start 0.4318 0.3302)
							(mid 0.402042 0.402042)
							(end 0.3302 0.4318)
						)
					)
					(width 0)
					(fill yes)
				)
			)
		)
	)
	(footprint ""
		(layer "B.Cu")
		(at 102.343966 -40.386)
		(property "Reference" "SC1062"
			(at 0 0 0)
			(layer "B.SilkS")
			(hide yes)
			(effects
				(font
					(size 1.27 1.27)
				)
				(justify mirror)
			)
		)
		(property "Value" "SCD1U16V2KX-3GP"
			(at -1.1811 -2.7051 0)
			(unlocked yes)
			(layer "B.Fab")
			(hide yes)
			(effects
				(font
					(size 1.016 1.016)
					(thickness 0.1524)
				)
				(justify mirror)
			)
		)
		(property "Device Type" "C402H22"
			(at -1.1811 -4.2291 0)
			(unlocked yes)
			(layer "B.Fab")
			(hide yes)
			(effects
				(font
					(size 1.016 1.016)
					(thickness 0.1524)
				)
				(justify mirror)
			)
		)
		(duplicate_pad_numbers_are_jumpers no)
		(fp_rect
			(start 0.4318 0.9525)
			(end -0.4318 -0.9525)
			(stroke
				(width 0)
				(type default)
			)
			(fill no)
			(layer "B.CrtYd")
		)
		(fp_rect
			(start 0.4318 0.9525)
			(end -0.4318 -0.9525)
			(stroke
				(width 0)
				(type default)
			)
			(fill no)
			(layer "B.Fab")
		)
		(pad "1" smd custom
			(at 0 -0.4445 180)
			(size 0.1524 0.1524)
			(layers "B.Cu" "B.Mask" "B.Paste")
			(net "P0V955_C")
			(options
				(clearance outline)
				(anchor circle)
			)
			(primitives
				(gr_poly
					(pts
						(arc
							(start 0.3048 0.2032)
							(mid 0.275042 0.275042)
							(end 0.2032 0.3048)
						)
						(arc
							(start -0.2032 0.3048)
							(mid -0.275042 0.275042)
							(end -0.3048 0.2032)
						)
						(arc
							(start -0.3048 -0.2032)
							(mid -0.275042 -0.275042)
							(end -0.2032 -0.3048)
						)
						(arc
							(start 0.2032 -0.3048)
							(mid 0.275042 -0.275042)
							(end 0.3048 -0.2032)
						)
					)
					(width 0)
					(fill yes)
				)
			)
		)
		(pad "2" smd custom
			(at 0 0.4445 180)
			(size 0.1524 0.1524)
			(layers "B.Cu" "B.Mask" "B.Paste")
			(net "GND")
			(options
				(clearance outline)
				(anchor circle)
			)
			(primitives
				(gr_poly
					(pts
						(arc
							(start 0.3048 0.2032)
							(mid 0.275042 0.275042)
							(end 0.2032 0.3048)
						)
						(arc
							(start -0.2032 0.3048)
							(mid -0.275042 0.275042)
							(end -0.3048 0.2032)
						)
						(arc
							(start -0.3048 -0.2032)
							(mid -0.275042 -0.275042)
							(end -0.2032 -0.3048)
						)
						(arc
							(start 0.2032 -0.3048)
							(mid 0.275042 -0.275042)
							(end 0.3048 -0.2032)
						)
					)
					(width 0)
					(fill yes)
				)
			)
		)
	)
	(footprint ""
		(layer "B.Cu")
		(at 117.38737 -79.9084 -90)
		(property "Reference" "SL13"
			(at 0 0 90)
			(layer "B.SilkS")
			(hide yes)
			(effects
				(font
					(size 1.27 1.27)
				)
				(justify mirror)
			)
		)
		(property "Value" "MPZ2012S601AT-GP"
			(at 0 -4.2418 270)
			(unlocked yes)
			(layer "B.Fab")
			(hide yes)
			(effects
				(font
					(size 1.016 1.016)
					(thickness 0.1524)
				)
				(justify mirror)
			)
		)
		(property "Device Type" "L805H42"
			(at 0 -5.7912 270)
			(unlocked yes)
			(layer "B.Fab")
			(hide yes)
			(effects
				(font
					(size 1.016 1.016)
					(thickness 0.1524)
				)
				(justify mirror)
			)
		)
		(duplicate_pad_numbers_are_jumpers no)
		(fp_line
			(start -0.889 1.7018)
			(end 0.889 1.7018)
			(stroke
				(width 0.1524)
				(type default)
			)
			(layer "B.SilkS")
		)
		(fp_line
			(start 0.889 1.7018)
			(end 0.889 -1.7018)
			(stroke
				(width 0.1524)
				(type default)
			)
			(layer "B.SilkS")
		)
		(fp_line
			(start -0.889 -1.7018)
			(end -0.889 1.7018)
			(stroke
				(width 0.1524)
				(type default)
			)
			(layer "B.SilkS")
		)
		(fp_line
			(start 0.889 -1.7018)
			(end -0.889 -1.7018)
			(stroke
				(width 0.1524)
				(type default)
			)
			(layer "B.SilkS")
		)
		(fp_rect
			(start 0.9652 1.778)
			(end -0.9652 -1.778)
			(stroke
				(width 0)
				(type default)
			)
			(fill no)
			(layer "B.CrtYd")
		)
		(fp_rect
			(start 0.9652 1.778)
			(end -0.9652 -1.778)
			(stroke
				(width 0)
				(type default)
			)
			(fill no)
			(layer "B.Fab")
		)
		(pad "1" smd rect
			(at 0 -0.9652 90)
			(size 1.397 1.143)
			(layers "B.Cu" "B.Mask" "B.Paste")
			(net "XTAL_VDDA18")
		)
		(pad "2" smd rect
			(at 0 0.9652 90)
			(size 1.397 1.143)
			(layers "B.Cu" "B.Mask" "B.Paste")
			(net "P1V8_E")
		)
	)
	(footprint ""
		(layer "B.Cu")
		(at 351.663 -81.534 180)
		(property "Reference" "R266"
			(at 0 0 0)
			(layer "B.SilkS")
			(hide yes)
			(effects
				(font
					(size 1.27 1.27)
				)
				(justify mirror)
			)
		)
		(property "Value" "2K2R2J-2-GP"
			(at -0.064008 -3.993896 180)
			(unlocked yes)
			(layer "B.Fab")
			(hide yes)
			(effects
				(font
					(size 1.016 1.016)
					(thickness 0.1524)
				)
				(justify mirror)
			)
		)
		(property "Device Type" "R402H16"
			(at -0.064008 -5.517896 180)
			(unlocked yes)
			(layer "B.Fab")
			(hide yes)
			(effects
				(font
					(size 1.016 1.016)
					(thickness 0.1524)
				)
				(justify mirror)
			)
		)
		(duplicate_pad_numbers_are_jumpers no)
		(fp_line
			(start 0.508 -0.9398)
			(end 0.508 0.9398)
			(stroke
				(width 0.1524)
				(type default)
			)
			(layer "B.SilkS")
		)
		(fp_line
			(start -0.508 -0.9398)
			(end 0.508 -0.9398)
			(stroke
				(width 0.1524)
				(type default)
			)
			(layer "B.SilkS")
		)
		(fp_rect
			(start 0.508 0.9398)
			(end -0.508 -0.9398)
			(stroke
				(width 0)
				(type default)
			)
			(fill no)
			(layer "B.CrtYd")
		)
		(fp_rect
			(start 0.508 0.9398)
			(end -0.508 -0.9398)
			(stroke
				(width 0)
				(type default)
			)
			(fill no)
			(layer "B.Fab")
		)
		(pad "1" smd custom
			(at 0 -0.4445)
			(size 0.1397 0.1397)
			(layers "B.Cu" "B.Mask" "B.Paste")
			(net "P3V3_STBY")
			(options
				(clearance outline)
				(anchor circle)
			)
			(primitives
				(gr_poly
					(pts
						(arc
							(start -0.1778 0.2794)
							(mid -0.249642 0.249642)
							(end -0.2794 0.1778)
						)
						(arc
							(start -0.2794 -0.1778)
							(mid -0.249642 -0.249642)
							(end -0.1778 -0.2794)
						)
						(arc
							(start 0.1778 -0.2794)
							(mid 0.249642 -0.249642)
							(end 0.2794 -0.1778)
						)
						(arc
							(start 0.2794 0.1778)
							(mid 0.249642 0.249642)
							(end 0.1778 0.2794)
						)
					)
					(width 0)
					(fill yes)
				)
			)
		)
		(pad "2" smd custom
			(at 0 0.4445)
			(size 0.1397 0.1397)
			(layers "B.Cu" "B.Mask" "B.Paste")
			(net "PU_IBMC_BT_HOLD_N")
			(options
				(clearance outline)
				(anchor circle)
			)
			(primitives
				(gr_poly
					(pts
						(arc
							(start -0.1778 0.2794)
							(mid -0.249642 0.249642)
							(end -0.2794 0.1778)
						)
						(arc
							(start -0.2794 -0.1778)
							(mid -0.249642 -0.249642)
							(end -0.1778 -0.2794)
						)
						(arc
							(start 0.1778 -0.2794)
							(mid 0.249642 -0.249642)
							(end 0.2794 -0.1778)
						)
						(arc
							(start 0.2794 0.1778)
							(mid 0.249642 0.249642)
							(end 0.1778 0.2794)
						)
					)
					(width 0)
					(fill yes)
				)
			)
		)
	)
	(footprint ""
		(layer "B.Cu")
		(at 309.118 -50.927 180)
		(property "Reference" "C277"
			(at 0 0 0)
			(layer "B.SilkS")
			(hide yes)
			(effects
				(font
					(size 1.27 1.27)
				)
				(justify mirror)
			)
		)
		(property "Value" "SCD1U25V2KX-2-GP"
			(at -1.1811 -2.7051 180)
			(unlocked yes)
			(layer "B.Fab")
			(hide yes)
			(effects
				(font
					(size 1.016 1.016)
					(thickness 0.1524)
				)
				(justify mirror)
			)
		)
		(property "Device Type" "C402H22"
			(at -1.1811 -4.2291 180)
			(unlocked yes)
			(layer "B.Fab")
			(hide yes)
			(effects
				(font
					(size 1.016 1.016)
					(thickness 0.1524)
				)
				(justify mirror)
			)
		)
		(duplicate_pad_numbers_are_jumpers no)
		(fp_rect
			(start 0.4318 0.9525)
			(end -0.4318 -0.9525)
			(stroke
				(width 0)
				(type default)
			)
			(fill no)
			(layer "B.CrtYd")
		)
		(fp_rect
			(start 0.4318 0.9525)
			(end -0.4318 -0.9525)
			(stroke
				(width 0)
				(type default)
			)
			(fill no)
			(layer "B.Fab")
		)
		(pad "1" smd custom
			(at 0 -0.4445)
			(size 0.1524 0.1524)
			(layers "B.Cu" "B.Mask" "B.Paste")
			(net "P12V")
			(options
				(clearance outline)
				(anchor circle)
			)
			(primitives
				(gr_poly
					(pts
						(arc
							(start 0.3048 0.2032)
							(mid 0.275042 0.275042)
							(end 0.2032 0.3048)
						)
						(arc
							(start -0.2032 0.3048)
							(mid -0.275042 0.275042)
							(end -0.3048 0.2032)
						)
						(arc
							(start -0.3048 -0.2032)
							(mid -0.275042 -0.275042)
							(end -0.2032 -0.3048)
						)
						(arc
							(start 0.2032 -0.3048)
							(mid 0.275042 -0.275042)
							(end 0.3048 -0.2032)
						)
					)
					(width 0)
					(fill yes)
				)
			)
		)
		(pad "2" smd custom
			(at 0 0.4445)
			(size 0.1524 0.1524)
			(layers "B.Cu" "B.Mask" "B.Paste")
			(net "GND")
			(options
				(clearance outline)
				(anchor circle)
			)
			(primitives
				(gr_poly
					(pts
						(arc
							(start 0.3048 0.2032)
							(mid 0.275042 0.275042)
							(end 0.2032 0.3048)
						)
						(arc
							(start -0.2032 0.3048)
							(mid -0.275042 0.275042)
							(end -0.3048 0.2032)
						)
						(arc
							(start -0.3048 -0.2032)
							(mid -0.275042 -0.275042)
							(end -0.2032 -0.3048)
						)
						(arc
							(start 0.2032 -0.3048)
							(mid 0.275042 -0.275042)
							(end 0.3048 -0.2032)
						)
					)
					(width 0)
					(fill yes)
				)
			)
		)
	)
	(footprint ""
		(layer "B.Cu")
		(at 12.19708 -231.822752)
		(property "Reference" "R513"
			(at 0 0 0)
			(layer "B.SilkS")
			(hide yes)
			(effects
				(font
					(size 1.27 1.27)
				)
				(justify mirror)
			)
		)
		(property "Value" "0R2J-2-GP"
			(at -0.064008 -3.993896 0)
			(unlocked yes)
			(layer "B.Fab")
			(hide yes)
			(effects
				(font
					(size 1.016 1.016)
					(thickness 0.1524)
				)
				(justify mirror)
			)
		)
		(property "Device Type" "R402H16"
			(at -0.064008 -5.517896 0)
			(unlocked yes)
			(layer "B.Fab")
			(hide yes)
			(effects
				(font
					(size 1.016 1.016)
					(thickness 0.1524)
				)
				(justify mirror)
			)
		)
		(duplicate_pad_numbers_are_jumpers no)
		(fp_line
			(start -0.508 -0.9398)
			(end 0.508 -0.9398)
			(stroke
				(width 0.1524)
				(type default)
			)
			(layer "B.SilkS")
		)
		(fp_line
			(start 0.508 -0.9398)
			(end 0.508 0.9398)
			(stroke
				(width 0.1524)
				(type default)
			)
			(layer "B.SilkS")
		)
		(fp_rect
			(start 0.508 0.9398)
			(end -0.508 -0.9398)
			(stroke
				(width 0)
				(type default)
			)
			(fill no)
			(layer "B.CrtYd")
		)
		(fp_rect
			(start 0.508 0.9398)
			(end -0.508 -0.9398)
			(stroke
				(width 0)
				(type default)
			)
			(fill no)
			(layer "B.Fab")
		)
		(pad "1" smd custom
			(at 0 -0.4445 180)
			(size 0.1397 0.1397)
			(layers "B.Cu" "B.Mask" "B.Paste")
			(net "SAS_HDD_PWR11_PCIE")
			(options
				(clearance outline)
				(anchor circle)
			)
			(primitives
				(gr_poly
					(pts
						(arc
							(start -0.1778 0.2794)
							(mid -0.249642 0.249642)
							(end -0.2794 0.1778)
						)
						(arc
							(start -0.2794 -0.1778)
							(mid -0.249642 -0.249642)
							(end -0.1778 -0.2794)
						)
						(arc
							(start 0.1778 -0.2794)
							(mid 0.249642 -0.249642)
							(end 0.2794 -0.1778)
						)
						(arc
							(start 0.2794 0.1778)
							(mid 0.249642 0.249642)
							(end 0.1778 0.2794)
						)
					)
					(width 0)
					(fill yes)
				)
			)
		)
		(pad "2" smd custom
			(at 0 0.4445 180)
			(size 0.1397 0.1397)
			(layers "B.Cu" "B.Mask" "B.Paste")
			(net "SAS_HDD_PWR11")
			(options
				(clearance outline)
				(anchor circle)
			)
			(primitives
				(gr_poly
					(pts
						(arc
							(start -0.1778 0.2794)
							(mid -0.249642 0.249642)
							(end -0.2794 0.1778)
						)
						(arc
							(start -0.2794 -0.1778)
							(mid -0.249642 -0.249642)
							(end -0.1778 -0.2794)
						)
						(arc
							(start 0.1778 -0.2794)
							(mid 0.249642 -0.249642)
							(end 0.2794 -0.1778)
						)
						(arc
							(start 0.2794 0.1778)
							(mid 0.249642 0.249642)
							(end 0.1778 0.2794)
						)
					)
					(width 0)
					(fill yes)
				)
			)
		)
	)
	(footprint ""
		(layer "B.Cu")
		(at 119.996966 -38.989 -90)
		(property "Reference" "SR621"
			(at 0 0 90)
			(layer "B.SilkS")
			(hide yes)
			(effects
				(font
					(size 1.27 1.27)
				)
				(justify mirror)
			)
		)
		(property "Value" "2K2R2F-GP"
			(at -0.064008 -3.993896 270)
			(unlocked yes)
			(layer "B.Fab")
			(hide yes)
			(effects
				(font
					(size 1.016 1.016)
					(thickness 0.1524)
				)
				(justify mirror)
			)
		)
		(property "Device Type" "R402H16"
			(at -0.064008 -5.517896 270)
			(unlocked yes)
			(layer "B.Fab")
			(hide yes)
			(effects
				(font
					(size 1.016 1.016)
					(thickness 0.1524)
				)
				(justify mirror)
			)
		)
		(duplicate_pad_numbers_are_jumpers no)
		(fp_line
			(start -0.508 -0.9398)
			(end 0.508 -0.9398)
			(stroke
				(width 0.1524)
				(type default)
			)
			(layer "B.SilkS")
		)
		(fp_line
			(start 0.508 -0.9398)
			(end 0.508 0.9398)
			(stroke
				(width 0.1524)
				(type default)
			)
			(layer "B.SilkS")
		)
		(fp_rect
			(start 0.508 0.9398)
			(end -0.508 -0.9398)
			(stroke
				(width 0)
				(type default)
			)
			(fill no)
			(layer "B.CrtYd")
		)
		(fp_rect
			(start 0.508 0.9398)
			(end -0.508 -0.9398)
			(stroke
				(width 0)
				(type default)
			)
			(fill no)
			(layer "B.Fab")
		)
		(pad "1" smd custom
			(at 0 -0.4445 90)
			(size 0.1397 0.1397)
			(layers "B.Cu" "B.Mask" "B.Paste")
			(net "P1V8_C")
			(options
				(clearance outline)
				(anchor circle)
			)
			(primitives
				(gr_poly
					(pts
						(arc
							(start -0.1778 0.2794)
							(mid -0.249642 0.249642)
							(end -0.2794 0.1778)
						)
						(arc
							(start -0.2794 -0.1778)
							(mid -0.249642 -0.249642)
							(end -0.1778 -0.2794)
						)
						(arc
							(start 0.1778 -0.2794)
							(mid 0.249642 -0.249642)
							(end 0.2794 -0.1778)
						)
						(arc
							(start 0.2794 0.1778)
							(mid 0.249642 0.249642)
							(end 0.1778 0.2794)
						)
					)
					(width 0)
					(fill yes)
				)
			)
		)
		(pad "2" smd custom
			(at 0 0.4445 90)
			(size 0.1397 0.1397)
			(layers "B.Cu" "B.Mask" "B.Paste")
			(net "IOC_SDA_2")
			(options
				(clearance outline)
				(anchor circle)
			)
			(primitives
				(gr_poly
					(pts
						(arc
							(start -0.1778 0.2794)
							(mid -0.249642 0.249642)
							(end -0.2794 0.1778)
						)
						(arc
							(start -0.2794 -0.1778)
							(mid -0.249642 -0.249642)
							(end -0.1778 -0.2794)
						)
						(arc
							(start 0.1778 -0.2794)
							(mid 0.249642 -0.249642)
							(end 0.2794 -0.1778)
						)
						(arc
							(start 0.2794 0.1778)
							(mid 0.249642 0.249642)
							(end 0.1778 0.2794)
						)
					)
					(width 0)
					(fill yes)
				)
			)
		)
	)
	(footprint ""
		(layer "B.Cu")
		(at 344.551 -115.824 -90)
		(property "Reference" "PC19"
			(at 0 0 90)
			(layer "B.SilkS")
			(hide yes)
			(effects
				(font
					(size 1.27 1.27)
				)
				(justify mirror)
			)
		)
		(property "Value" "SC1KP50V2KX-1GP"
			(at -1.1811 -2.7051 270)
			(unlocked yes)
			(layer "B.Fab")
			(hide yes)
			(effects
				(font
					(size 1.016 1.016)
					(thickness 0.1524)
				)
				(justify mirror)
			)
		)
		(property "Device Type" "C402H22"
			(at -1.1811 -4.2291 270)
			(unlocked yes)
			(layer "B.Fab")
			(hide yes)
			(effects
				(font
					(size 1.016 1.016)
					(thickness 0.1524)
				)
				(justify mirror)
			)
		)
		(duplicate_pad_numbers_are_jumpers no)
		(fp_rect
			(start 0.4318 0.9525)
			(end -0.4318 -0.9525)
			(stroke
				(width 0)
				(type default)
			)
			(fill no)
			(layer "B.CrtYd")
		)
		(fp_rect
			(start 0.4318 0.9525)
			(end -0.4318 -0.9525)
			(stroke
				(width 0)
				(type default)
			)
			(fill no)
			(layer "B.Fab")
		)
		(pad "1" smd custom
			(at 0 -0.4445 90)
			(size 0.1524 0.1524)
			(layers "B.Cu" "B.Mask" "B.Paste")
			(net "P5V_STBY_VFB_R")
			(options
				(clearance outline)
				(anchor circle)
			)
			(primitives
				(gr_poly
					(pts
						(arc
							(start 0.3048 0.2032)
							(mid 0.275042 0.275042)
							(end 0.2032 0.3048)
						)
						(arc
							(start -0.2032 0.3048)
							(mid -0.275042 0.275042)
							(end -0.3048 0.2032)
						)
						(arc
							(start -0.3048 -0.2032)
							(mid -0.275042 -0.275042)
							(end -0.2032 -0.3048)
						)
						(arc
							(start 0.2032 -0.3048)
							(mid 0.275042 -0.275042)
							(end 0.3048 -0.2032)
						)
					)
					(width 0)
					(fill yes)
				)
			)
		)
		(pad "2" smd custom
			(at 0 0.4445 90)
			(size 0.1524 0.1524)
			(layers "B.Cu" "B.Mask" "B.Paste")
			(net "P5V_STBY_VFB")
			(options
				(clearance outline)
				(anchor circle)
			)
			(primitives
				(gr_poly
					(pts
						(arc
							(start 0.3048 0.2032)
							(mid 0.275042 0.275042)
							(end 0.2032 0.3048)
						)
						(arc
							(start -0.2032 0.3048)
							(mid -0.275042 0.275042)
							(end -0.3048 0.2032)
						)
						(arc
							(start -0.3048 -0.2032)
							(mid -0.275042 -0.275042)
							(end -0.2032 -0.3048)
						)
						(arc
							(start 0.2032 -0.3048)
							(mid 0.275042 -0.275042)
							(end 0.3048 -0.2032)
						)
					)
					(width 0)
					(fill yes)
				)
			)
		)
	)
	(footprint ""
		(layer "B.Cu")
		(at 86.614 -29.09316 180)
		(property "Reference" "SR585"
			(at 0 0 0)
			(layer "B.SilkS")
			(hide yes)
			(effects
				(font
					(size 1.27 1.27)
				)
				(justify mirror)
			)
		)
		(property "Value" "51R2F-2-GP"
			(at -0.064008 -3.993896 180)
			(unlocked yes)
			(layer "B.Fab")
			(hide yes)
			(effects
				(font
					(size 1.016 1.016)
					(thickness 0.1524)
				)
				(justify mirror)
			)
		)
		(property "Device Type" "R402H16"
			(at -0.064008 -5.517896 180)
			(unlocked yes)
			(layer "B.Fab")
			(hide yes)
			(effects
				(font
					(size 1.016 1.016)
					(thickness 0.1524)
				)
				(justify mirror)
			)
		)
		(duplicate_pad_numbers_are_jumpers no)
		(fp_line
			(start 0.508 -0.9398)
			(end 0.508 0.9398)
			(stroke
				(width 0.1524)
				(type default)
			)
			(layer "B.SilkS")
		)
		(fp_line
			(start -0.508 -0.9398)
			(end 0.508 -0.9398)
			(stroke
				(width 0.1524)
				(type default)
			)
			(layer "B.SilkS")
		)
		(fp_rect
			(start 0.508 0.9398)
			(end -0.508 -0.9398)
			(stroke
				(width 0)
				(type default)
			)
			(fill no)
			(layer "B.CrtYd")
		)
		(fp_rect
			(start 0.508 0.9398)
			(end -0.508 -0.9398)
			(stroke
				(width 0)
				(type default)
			)
			(fill no)
			(layer "B.Fab")
		)
		(pad "1" smd custom
			(at 0 -0.4445)
			(size 0.1397 0.1397)
			(layers "B.Cu" "B.Mask" "B.Paste")
			(net "GND")
			(options
				(clearance outline)
				(anchor circle)
			)
			(primitives
				(gr_poly
					(pts
						(arc
							(start -0.1778 0.2794)
							(mid -0.249642 0.249642)
							(end -0.2794 0.1778)
						)
						(arc
							(start -0.2794 -0.1778)
							(mid -0.249642 -0.249642)
							(end -0.1778 -0.2794)
						)
						(arc
							(start 0.1778 -0.2794)
							(mid 0.249642 -0.249642)
							(end 0.2794 -0.1778)
						)
						(arc
							(start 0.2794 0.1778)
							(mid 0.249642 0.249642)
							(end 0.1778 0.2794)
						)
					)
					(width 0)
					(fill yes)
				)
			)
		)
		(pad "2" smd custom
			(at 0 0.4445)
			(size 0.1397 0.1397)
			(layers "B.Cu" "B.Mask" "B.Paste")
			(net "CK_100M_EXP_SAS")
			(options
				(clearance outline)
				(anchor circle)
			)
			(primitives
				(gr_poly
					(pts
						(arc
							(start -0.1778 0.2794)
							(mid -0.249642 0.249642)
							(end -0.2794 0.1778)
						)
						(arc
							(start -0.2794 -0.1778)
							(mid -0.249642 -0.249642)
							(end -0.1778 -0.2794)
						)
						(arc
							(start 0.1778 -0.2794)
							(mid 0.249642 -0.249642)
							(end 0.2794 -0.1778)
						)
						(arc
							(start 0.2794 0.1778)
							(mid 0.249642 0.249642)
							(end 0.1778 0.2794)
						)
					)
					(width 0)
					(fill yes)
				)
			)
		)
	)
	(footprint ""
		(layer "B.Cu")
		(at 101.454966 -44.958 -90)
		(property "Reference" "SC1025"
			(at 0 0 90)
			(layer "B.SilkS")
			(hide yes)
			(effects
				(font
					(size 1.27 1.27)
				)
				(justify mirror)
			)
		)
		(property "Value" "SC1U10V2KX-4-GP"
			(at -1.1811 -2.7051 270)
			(unlocked yes)
			(layer "B.Fab")
			(hide yes)
			(effects
				(font
					(size 1.016 1.016)
					(thickness 0.1524)
				)
				(justify mirror)
			)
		)
		(property "Device Type" "C402H22"
			(at -1.1811 -4.2291 270)
			(unlocked yes)
			(layer "B.Fab")
			(hide yes)
			(effects
				(font
					(size 1.016 1.016)
					(thickness 0.1524)
				)
				(justify mirror)
			)
		)
		(duplicate_pad_numbers_are_jumpers no)
		(fp_rect
			(start 0.4318 0.9525)
			(end -0.4318 -0.9525)
			(stroke
				(width 0)
				(type default)
			)
			(fill no)
			(layer "B.CrtYd")
		)
		(fp_rect
			(start 0.4318 0.9525)
			(end -0.4318 -0.9525)
			(stroke
				(width 0)
				(type default)
			)
			(fill no)
			(layer "B.Fab")
		)
		(pad "1" smd custom
			(at 0 -0.4445 90)
			(size 0.1524 0.1524)
			(layers "B.Cu" "B.Mask" "B.Paste")
			(net "P0V955_C")
			(options
				(clearance outline)
				(anchor circle)
			)
			(primitives
				(gr_poly
					(pts
						(arc
							(start 0.3048 0.2032)
							(mid 0.275042 0.275042)
							(end 0.2032 0.3048)
						)
						(arc
							(start -0.2032 0.3048)
							(mid -0.275042 0.275042)
							(end -0.3048 0.2032)
						)
						(arc
							(start -0.3048 -0.2032)
							(mid -0.275042 -0.275042)
							(end -0.2032 -0.3048)
						)
						(arc
							(start 0.2032 -0.3048)
							(mid 0.275042 -0.275042)
							(end 0.3048 -0.2032)
						)
					)
					(width 0)
					(fill yes)
				)
			)
		)
		(pad "2" smd custom
			(at 0 0.4445 90)
			(size 0.1524 0.1524)
			(layers "B.Cu" "B.Mask" "B.Paste")
			(net "GND")
			(options
				(clearance outline)
				(anchor circle)
			)
			(primitives
				(gr_poly
					(pts
						(arc
							(start 0.3048 0.2032)
							(mid 0.275042 0.275042)
							(end 0.2032 0.3048)
						)
						(arc
							(start -0.2032 0.3048)
							(mid -0.275042 0.275042)
							(end -0.3048 0.2032)
						)
						(arc
							(start -0.3048 -0.2032)
							(mid -0.275042 -0.275042)
							(end -0.2032 -0.3048)
						)
						(arc
							(start 0.2032 -0.3048)
							(mid 0.275042 -0.275042)
							(end 0.3048 -0.2032)
						)
					)
					(width 0)
					(fill yes)
				)
			)
		)
	)
	(footprint ""
		(layer "B.Cu")
		(at 303.8983 -177.42408 90)
		(property "Reference" "C219"
			(at 0 0 90)
			(layer "B.SilkS")
			(hide yes)
			(effects
				(font
					(size 1.27 1.27)
				)
				(justify mirror)
			)
		)
		(property "Value" "SC1U10V3KX-4GP-U"
			(at 0 -2.8194 90)
			(unlocked yes)
			(layer "B.Fab")
			(hide yes)
			(effects
				(font
					(size 1.016 1.016)
					(thickness 0.1524)
				)
				(justify mirror)
			)
		)
		(property "Device Type" "C603H36"
			(at 0 -4.3434 90)
			(unlocked yes)
			(layer "B.Fab")
			(hide yes)
			(effects
				(font
					(size 1.016 1.016)
					(thickness 0.1524)
				)
				(justify mirror)
			)
		)
		(duplicate_pad_numbers_are_jumpers no)
		(fp_line
			(start -0.508 0)
			(end 0.508 0)
			(stroke
				(width 0.2032)
				(type default)
			)
			(layer "B.SilkS")
		)
		(fp_rect
			(start 0.5842 1.3335)
			(end -0.5842 -1.3335)
			(stroke
				(width 0)
				(type default)
			)
			(fill no)
			(layer "B.CrtYd")
		)
		(fp_rect
			(start 0.5842 1.3335)
			(end -0.5842 -1.3335)
			(stroke
				(width 0)
				(type default)
			)
			(fill no)
			(layer "B.Fab")
		)
		(pad "1" smd custom
			(at 0 -0.762 270)
			(size 0.2159 0.2159)
			(layers "B.Cu" "B.Mask" "B.Paste")
			(net "P3V3_STBY")
			(options
				(clearance outline)
				(anchor circle)
			)
			(primitives
				(gr_poly
					(pts
						(arc
							(start -0.3302 0.4318)
							(mid -0.402042 0.402042)
							(end -0.4318 0.3302)
						)
						(arc
							(start -0.4318 -0.3302)
							(mid -0.402042 -0.402042)
							(end -0.3302 -0.4318)
						)
						(arc
							(start 0.3302 -0.4318)
							(mid 0.402042 -0.402042)
							(end 0.4318 -0.3302)
						)
						(arc
							(start 0.4318 0.3302)
							(mid 0.402042 0.402042)
							(end 0.3302 0.4318)
						)
					)
					(width 0)
					(fill yes)
				)
			)
		)
		(pad "2" smd custom
			(at 0 0.762 270)
			(size 0.2159 0.2159)
			(layers "B.Cu" "B.Mask" "B.Paste")
			(net "GND")
			(options
				(clearance outline)
				(anchor circle)
			)
			(primitives
				(gr_poly
					(pts
						(arc
							(start -0.3302 0.4318)
							(mid -0.402042 0.402042)
							(end -0.4318 0.3302)
						)
						(arc
							(start -0.4318 -0.3302)
							(mid -0.402042 -0.402042)
							(end -0.3302 -0.4318)
						)
						(arc
							(start 0.3302 -0.4318)
							(mid 0.402042 -0.402042)
							(end 0.4318 -0.3302)
						)
						(arc
							(start 0.4318 0.3302)
							(mid 0.402042 0.402042)
							(end 0.3302 0.4318)
						)
					)
					(width 0)
					(fill yes)
				)
			)
		)
	)
	(footprint ""
		(layer "B.Cu")
		(at 78.982062 -57.874408 -90)
		(property "Reference" "SC924"
			(at 0 0 90)
			(layer "B.SilkS")
			(hide yes)
			(effects
				(font
					(size 1.27 1.27)
				)
				(justify mirror)
			)
		)
		(property "Value" "SC10U6D3V5KX-4GP"
			(at 0.0762 -6.1214 270)
			(unlocked yes)
			(layer "B.Fab")
			(hide yes)
			(effects
				(font
					(size 1.016 1.016)
					(thickness 0.1524)
				)
				(justify mirror)
			)
		)
		(property "Device Type" "C805H58"
			(at 0.0762 -8.1534 270)
			(unlocked yes)
			(layer "B.Fab")
			(hide yes)
			(effects
				(font
					(size 1.016 1.016)
					(thickness 0.1524)
				)
				(justify mirror)
			)
		)
		(duplicate_pad_numbers_are_jumpers no)
		(fp_line
			(start -0.635 0)
			(end 0.635 0)
			(stroke
				(width 0.508)
				(type default)
			)
			(layer "B.SilkS")
		)
		(fp_rect
			(start 0.9652 1.778)
			(end -0.9652 -1.778)
			(stroke
				(width 0)
				(type default)
			)
			(fill no)
			(layer "B.CrtYd")
		)
		(fp_poly
			(pts
				(xy 0.9652 -1.778) (xy -0.9652 -1.778) (xy -0.9652 1.778) (xy 0.9652 1.778)
			)
			(stroke
				(width 0)
				(type default)
			)
			(fill no)
			(layer "B.Fab")
		)
		(pad "1" smd rect
			(at 0 -0.9652 90)
			(size 1.397 1.143)
			(layers "B.Cu" "B.Mask" "B.Paste")
			(net "VDDA_SAS_REF_CLK")
		)
		(pad "2" smd rect
			(at 0 0.9652 90)
			(size 1.397 1.143)
			(layers "B.Cu" "B.Mask" "B.Paste")
			(net "GND")
		)
	)
	(footprint ""
		(layer "B.Cu")
		(at 112.91316 -31.115)
		(property "Reference" "STP139"
			(at 0 0 0)
			(layer "B.SilkS")
			(hide yes)
			(effects
				(font
					(size 1.27 1.27)
				)
				(justify mirror)
			)
		)
		(property "Value" "TPAD28"
			(at -0.0127 -1.8034 0)
			(unlocked yes)
			(layer "B.Fab")
			(hide yes)
			(effects
				(font
					(size 1.016 1.016)
					(thickness 0.1524)
				)
				(justify mirror)
			)
		)
		(property "Device Type" "TPAD28"
			(at -0.0127 -3.3274 0)
			(unlocked yes)
			(layer "B.Fab")
			(hide yes)
			(effects
				(font
					(size 1.016 1.016)
					(thickness 0.1524)
				)
				(justify mirror)
			)
		)
		(duplicate_pad_numbers_are_jumpers no)
		(fp_poly
			(pts
				(arc
					(start 0.3556 0)
					(mid -0.3556 0)
					(end 0.3556 0)
				)
			)
			(stroke
				(width 0)
				(type default)
			)
			(fill no)
			(layer "B.CrtYd")
		)
		(fp_poly
			(pts
				(arc
					(start 0.6096 0)
					(mid -0.6096 0)
					(end 0.6096 0)
				)
			)
			(stroke
				(width 0)
				(type default)
			)
			(fill no)
			(layer "B.Fab")
		)
		(pad "1" smd circle
			(at 0 0 180)
			(size 0.7112 0.7112)
			(layers "B.Cu" "B.Mask" "B.Paste")
			(net "IOC_GPIO_19")
		)
	)
	(footprint ""
		(layer "B.Cu")
		(at 319.913 -165.354 90)
		(property "Reference" "R314"
			(at 0 0 90)
			(layer "B.SilkS")
			(hide yes)
			(effects
				(font
					(size 1.27 1.27)
				)
				(justify mirror)
			)
		)
		(property "Value" "4K7R2F-GP"
			(at -0.064008 -3.993896 90)
			(unlocked yes)
			(layer "B.Fab")
			(hide yes)
			(effects
				(font
					(size 1.016 1.016)
					(thickness 0.1524)
				)
				(justify mirror)
			)
		)
		(property "Device Type" "R402H16"
			(at -0.064008 -5.517896 90)
			(unlocked yes)
			(layer "B.Fab")
			(hide yes)
			(effects
				(font
					(size 1.016 1.016)
					(thickness 0.1524)
				)
				(justify mirror)
			)
		)
		(duplicate_pad_numbers_are_jumpers no)
		(fp_line
			(start 0.508 -0.9398)
			(end 0.508 0.9398)
			(stroke
				(width 0.1524)
				(type default)
			)
			(layer "B.SilkS")
		)
		(fp_line
			(start -0.508 -0.9398)
			(end 0.508 -0.9398)
			(stroke
				(width 0.1524)
				(type default)
			)
			(layer "B.SilkS")
		)
		(fp_rect
			(start 0.508 0.9398)
			(end -0.508 -0.9398)
			(stroke
				(width 0)
				(type default)
			)
			(fill no)
			(layer "B.CrtYd")
		)
		(fp_rect
			(start 0.508 0.9398)
			(end -0.508 -0.9398)
			(stroke
				(width 0)
				(type default)
			)
			(fill no)
			(layer "B.Fab")
		)
		(pad "1" smd custom
			(at 0 -0.4445 270)
			(size 0.1397 0.1397)
			(layers "B.Cu" "B.Mask" "B.Paste")
			(net "BMC_I2C_D_SDA")
			(options
				(clearance outline)
				(anchor circle)
			)
			(primitives
				(gr_poly
					(pts
						(arc
							(start -0.1778 0.2794)
							(mid -0.249642 0.249642)
							(end -0.2794 0.1778)
						)
						(arc
							(start -0.2794 -0.1778)
							(mid -0.249642 -0.249642)
							(end -0.1778 -0.2794)
						)
						(arc
							(start 0.1778 -0.2794)
							(mid 0.249642 -0.249642)
							(end 0.2794 -0.1778)
						)
						(arc
							(start 0.2794 0.1778)
							(mid 0.249642 0.249642)
							(end 0.1778 0.2794)
						)
					)
					(width 0)
					(fill yes)
				)
			)
		)
		(pad "2" smd custom
			(at 0 0.4445 270)
			(size 0.1397 0.1397)
			(layers "B.Cu" "B.Mask" "B.Paste")
			(net "P3V3_STBY")
			(options
				(clearance outline)
				(anchor circle)
			)
			(primitives
				(gr_poly
					(pts
						(arc
							(start -0.1778 0.2794)
							(mid -0.249642 0.249642)
							(end -0.2794 0.1778)
						)
						(arc
							(start -0.2794 -0.1778)
							(mid -0.249642 -0.249642)
							(end -0.1778 -0.2794)
						)
						(arc
							(start 0.1778 -0.2794)
							(mid 0.249642 -0.249642)
							(end 0.2794 -0.1778)
						)
						(arc
							(start 0.2794 0.1778)
							(mid 0.249642 0.249642)
							(end 0.1778 0.2794)
						)
					)
					(width 0)
					(fill yes)
				)
			)
		)
	)
	(footprint ""
		(layer "B.Cu")
		(at 117.61597 -81.915)
		(property "Reference" "STP112"
			(at 0 0 0)
			(layer "B.SilkS")
			(hide yes)
			(effects
				(font
					(size 1.27 1.27)
				)
				(justify mirror)
			)
		)
		(property "Value" "TPAD28"
			(at -0.0127 -1.8034 0)
			(unlocked yes)
			(layer "B.Fab")
			(hide yes)
			(effects
				(font
					(size 1.016 1.016)
					(thickness 0.1524)
				)
				(justify mirror)
			)
		)
		(property "Device Type" "TPAD28"
			(at -0.0127 -3.3274 0)
			(unlocked yes)
			(layer "B.Fab")
			(hide yes)
			(effects
				(font
					(size 1.016 1.016)
					(thickness 0.1524)
				)
				(justify mirror)
			)
		)
		(duplicate_pad_numbers_are_jumpers no)
		(fp_poly
			(pts
				(arc
					(start 0.3556 0)
					(mid -0.3556 0)
					(end 0.3556 0)
				)
			)
			(stroke
				(width 0)
				(type default)
			)
			(fill no)
			(layer "B.CrtYd")
		)
		(fp_poly
			(pts
				(arc
					(start 0.6096 0)
					(mid -0.6096 0)
					(end 0.6096 0)
				)
			)
			(stroke
				(width 0)
				(type default)
			)
			(fill no)
			(layer "B.Fab")
		)
		(pad "1" smd circle
			(at 0 0 180)
			(size 0.7112 0.7112)
			(layers "B.Cu" "B.Mask" "B.Paste")
			(net "TEST_MUX_45")
		)
	)
	(footprint ""
		(layer "B.Cu")
		(at 113.80597 -79.121)
		(property "Reference" "STP68"
			(at 0 0 0)
			(layer "B.SilkS")
			(hide yes)
			(effects
				(font
					(size 1.27 1.27)
				)
				(justify mirror)
			)
		)
		(property "Value" "TPAD28"
			(at -0.0127 -1.8034 0)
			(unlocked yes)
			(layer "B.Fab")
			(hide yes)
			(effects
				(font
					(size 1.016 1.016)
					(thickness 0.1524)
				)
				(justify mirror)
			)
		)
		(property "Device Type" "TPAD28"
			(at -0.0127 -3.3274 0)
			(unlocked yes)
			(layer "B.Fab")
			(hide yes)
			(effects
				(font
					(size 1.016 1.016)
					(thickness 0.1524)
				)
				(justify mirror)
			)
		)
		(duplicate_pad_numbers_are_jumpers no)
		(fp_poly
			(pts
				(arc
					(start 0.3556 0)
					(mid -0.3556 0)
					(end 0.3556 0)
				)
			)
			(stroke
				(width 0)
				(type default)
			)
			(fill no)
			(layer "B.CrtYd")
		)
		(fp_poly
			(pts
				(arc
					(start 0.6096 0)
					(mid -0.6096 0)
					(end 0.6096 0)
				)
			)
			(stroke
				(width 0)
				(type default)
			)
			(fill no)
			(layer "B.Fab")
		)
		(pad "1" smd circle
			(at 0 0 180)
			(size 0.7112 0.7112)
			(layers "B.Cu" "B.Mask" "B.Paste")
			(net "EXP_TEST_MUX30")
		)
	)
	(footprint ""
		(layer "B.Cu")
		(at 107.42676 -33.782)
		(property "Reference" "STP77"
			(at 0 0 0)
			(layer "B.SilkS")
			(hide yes)
			(effects
				(font
					(size 1.27 1.27)
				)
				(justify mirror)
			)
		)
		(property "Value" "TPAD28"
			(at -0.0127 -1.8034 0)
			(unlocked yes)
			(layer "B.Fab")
			(hide yes)
			(effects
				(font
					(size 1.016 1.016)
					(thickness 0.1524)
				)
				(justify mirror)
			)
		)
		(property "Device Type" "TPAD28"
			(at -0.0127 -3.3274 0)
			(unlocked yes)
			(layer "B.Fab")
			(hide yes)
			(effects
				(font
					(size 1.016 1.016)
					(thickness 0.1524)
				)
				(justify mirror)
			)
		)
		(duplicate_pad_numbers_are_jumpers no)
		(fp_poly
			(pts
				(arc
					(start 0.3556 0)
					(mid -0.3556 0)
					(end 0.3556 0)
				)
			)
			(stroke
				(width 0)
				(type default)
			)
			(fill no)
			(layer "B.CrtYd")
		)
		(fp_poly
			(pts
				(arc
					(start 0.6096 0)
					(mid -0.6096 0)
					(end 0.6096 0)
				)
			)
			(stroke
				(width 0)
				(type default)
			)
			(fill no)
			(layer "B.Fab")
		)
		(pad "1" smd circle
			(at 0 0 180)
			(size 0.7112 0.7112)
			(layers "B.Cu" "B.Mask" "B.Paste")
			(net "IOC_GPIO_2")
		)
	)
	(footprint ""
		(layer "B.Cu")
		(at 114.56797 -98.425 180)
		(property "Reference" "SC1220"
			(at 0 0 0)
			(layer "B.SilkS")
			(hide yes)
			(effects
				(font
					(size 1.27 1.27)
				)
				(justify mirror)
			)
		)
		(property "Value" "SC1KP50V2KX-1GP"
			(at -1.1811 -2.7051 180)
			(unlocked yes)
			(layer "B.Fab")
			(hide yes)
			(effects
				(font
					(size 1.016 1.016)
					(thickness 0.1524)
				)
				(justify mirror)
			)
		)
		(property "Device Type" "C402H22"
			(at -1.1811 -4.2291 180)
			(unlocked yes)
			(layer "B.Fab")
			(hide yes)
			(effects
				(font
					(size 1.016 1.016)
					(thickness 0.1524)
				)
				(justify mirror)
			)
		)
		(duplicate_pad_numbers_are_jumpers no)
		(fp_rect
			(start 0.4318 0.9525)
			(end -0.4318 -0.9525)
			(stroke
				(width 0)
				(type default)
			)
			(fill no)
			(layer "B.CrtYd")
		)
		(fp_rect
			(start 0.4318 0.9525)
			(end -0.4318 -0.9525)
			(stroke
				(width 0)
				(type default)
			)
			(fill no)
			(layer "B.Fab")
		)
		(pad "1" smd custom
			(at 0 -0.4445)
			(size 0.1524 0.1524)
			(layers "B.Cu" "B.Mask" "B.Paste")
			(net "P0V9_E")
			(options
				(clearance outline)
				(anchor circle)
			)
			(primitives
				(gr_poly
					(pts
						(arc
							(start 0.3048 0.2032)
							(mid 0.275042 0.275042)
							(end 0.2032 0.3048)
						)
						(arc
							(start -0.2032 0.3048)
							(mid -0.275042 0.275042)
							(end -0.3048 0.2032)
						)
						(arc
							(start -0.3048 -0.2032)
							(mid -0.275042 -0.275042)
							(end -0.2032 -0.3048)
						)
						(arc
							(start 0.2032 -0.3048)
							(mid 0.275042 -0.275042)
							(end 0.3048 -0.2032)
						)
					)
					(width 0)
					(fill yes)
				)
			)
		)
		(pad "2" smd custom
			(at 0 0.4445)
			(size 0.1524 0.1524)
			(layers "B.Cu" "B.Mask" "B.Paste")
			(net "GND")
			(options
				(clearance outline)
				(anchor circle)
			)
			(primitives
				(gr_poly
					(pts
						(arc
							(start 0.3048 0.2032)
							(mid 0.275042 0.275042)
							(end 0.2032 0.3048)
						)
						(arc
							(start -0.2032 0.3048)
							(mid -0.275042 0.275042)
							(end -0.3048 0.2032)
						)
						(arc
							(start -0.3048 -0.2032)
							(mid -0.275042 -0.275042)
							(end -0.2032 -0.3048)
						)
						(arc
							(start 0.2032 -0.3048)
							(mid 0.275042 -0.275042)
							(end 0.3048 -0.2032)
						)
					)
					(width 0)
					(fill yes)
				)
			)
		)
	)
	(footprint ""
		(layer "B.Cu")
		(at 310.007 -50.927 180)
		(property "Reference" "C279"
			(at 0 0 0)
			(layer "B.SilkS")
			(hide yes)
			(effects
				(font
					(size 1.27 1.27)
				)
				(justify mirror)
			)
		)
		(property "Value" "SCD1U25V2KX-2-GP"
			(at -1.1811 -2.7051 180)
			(unlocked yes)
			(layer "B.Fab")
			(hide yes)
			(effects
				(font
					(size 1.016 1.016)
					(thickness 0.1524)
				)
				(justify mirror)
			)
		)
		(property "Device Type" "C402H22"
			(at -1.1811 -4.2291 180)
			(unlocked yes)
			(layer "B.Fab")
			(hide yes)
			(effects
				(font
					(size 1.016 1.016)
					(thickness 0.1524)
				)
				(justify mirror)
			)
		)
		(duplicate_pad_numbers_are_jumpers no)
		(fp_rect
			(start 0.4318 0.9525)
			(end -0.4318 -0.9525)
			(stroke
				(width 0)
				(type default)
			)
			(fill no)
			(layer "B.CrtYd")
		)
		(fp_rect
			(start 0.4318 0.9525)
			(end -0.4318 -0.9525)
			(stroke
				(width 0)
				(type default)
			)
			(fill no)
			(layer "B.Fab")
		)
		(pad "1" smd custom
			(at 0 -0.4445)
			(size 0.1524 0.1524)
			(layers "B.Cu" "B.Mask" "B.Paste")
			(net "P12V")
			(options
				(clearance outline)
				(anchor circle)
			)
			(primitives
				(gr_poly
					(pts
						(arc
							(start 0.3048 0.2032)
							(mid 0.275042 0.275042)
							(end 0.2032 0.3048)
						)
						(arc
							(start -0.2032 0.3048)
							(mid -0.275042 0.275042)
							(end -0.3048 0.2032)
						)
						(arc
							(start -0.3048 -0.2032)
							(mid -0.275042 -0.275042)
							(end -0.2032 -0.3048)
						)
						(arc
							(start 0.2032 -0.3048)
							(mid 0.275042 -0.275042)
							(end 0.3048 -0.2032)
						)
					)
					(width 0)
					(fill yes)
				)
			)
		)
		(pad "2" smd custom
			(at 0 0.4445)
			(size 0.1524 0.1524)
			(layers "B.Cu" "B.Mask" "B.Paste")
			(net "GND")
			(options
				(clearance outline)
				(anchor circle)
			)
			(primitives
				(gr_poly
					(pts
						(arc
							(start 0.3048 0.2032)
							(mid 0.275042 0.275042)
							(end 0.2032 0.3048)
						)
						(arc
							(start -0.2032 0.3048)
							(mid -0.275042 0.275042)
							(end -0.3048 0.2032)
						)
						(arc
							(start -0.3048 -0.2032)
							(mid -0.275042 -0.275042)
							(end -0.2032 -0.3048)
						)
						(arc
							(start 0.2032 -0.3048)
							(mid 0.275042 -0.275042)
							(end 0.3048 -0.2032)
						)
					)
					(width 0)
					(fill yes)
				)
			)
		)
	)
	(footprint ""
		(layer "B.Cu")
		(at 286.41294 -168.56964)
		(property "Reference" "TP118"
			(at 0 0 0)
			(layer "B.SilkS")
			(hide yes)
			(effects
				(font
					(size 1.27 1.27)
				)
				(justify mirror)
			)
		)
		(property "Value" "TPAD28"
			(at -0.0127 -1.8034 0)
			(unlocked yes)
			(layer "B.Fab")
			(hide yes)
			(effects
				(font
					(size 1.016 1.016)
					(thickness 0.1524)
				)
				(justify mirror)
			)
		)
		(property "Device Type" "TPAD28"
			(at -0.0127 -3.3274 0)
			(unlocked yes)
			(layer "B.Fab")
			(hide yes)
			(effects
				(font
					(size 1.016 1.016)
					(thickness 0.1524)
				)
				(justify mirror)
			)
		)
		(duplicate_pad_numbers_are_jumpers no)
		(fp_poly
			(pts
				(arc
					(start 0.3556 0)
					(mid -0.3556 0)
					(end 0.3556 0)
				)
			)
			(stroke
				(width 0)
				(type default)
			)
			(fill no)
			(layer "B.CrtYd")
		)
		(fp_poly
			(pts
				(arc
					(start 0.6096 0)
					(mid -0.6096 0)
					(end 0.6096 0)
				)
			)
			(stroke
				(width 0)
				(type default)
			)
			(fill no)
			(layer "B.Fab")
		)
		(pad "1" smd circle
			(at 0 0 180)
			(size 0.7112 0.7112)
			(layers "B.Cu" "B.Mask" "B.Paste")
			(net "TP_BMC_GPIOF0")
		)
	)
	(footprint ""
		(layer "B.Cu")
		(at 100.08616 -31.623)
		(property "Reference" "SC870"
			(at 0 0 0)
			(layer "B.SilkS")
			(hide yes)
			(effects
				(font
					(size 1.27 1.27)
				)
				(justify mirror)
			)
		)
		(property "Value" "SCD22U6D3V1MX-1-GP"
			(at 2.8321 -1.7399 0)
			(unlocked yes)
			(layer "B.Fab")
			(hide yes)
			(effects
				(font
					(size 1.016 1.016)
					(thickness 0.1524)
				)
				(justify mirror)
			)
		)
		(property "Device Type" "C0201H13"
			(at 2.8321 -3.2639 0)
			(unlocked yes)
			(layer "B.Fab")
			(hide yes)
			(effects
				(font
					(size 1.016 1.016)
					(thickness 0.1524)
				)
				(justify mirror)
			)
		)
		(duplicate_pad_numbers_are_jumpers no)
		(fp_rect
			(start 0.2794 0.6477)
			(end -0.2794 -0.6477)
			(stroke
				(width 0)
				(type default)
			)
			(fill no)
			(layer "B.CrtYd")
		)
		(fp_rect
			(start 0.2794 0.6477)
			(end -0.2794 -0.6477)
			(stroke
				(width 0)
				(type default)
			)
			(fill no)
			(layer "B.Fab")
		)
		(pad "1" smd custom
			(at 0 -0.2794 180)
			(size 0.0762 0.0762)
			(layers "B.Cu" "B.Mask" "B.Paste")
			(net "PCIE_SAS_C_CPU_RX_N4")
			(options
				(clearance outline)
				(anchor circle)
			)
			(primitives
				(gr_poly
					(pts
						(arc
							(start 0.1524 0.127)
							(mid 0.137521 0.162921)
							(end 0.1016 0.1778)
						)
						(arc
							(start -0.1016 0.1778)
							(mid -0.137521 0.162921)
							(end -0.1524 0.127)
						)
						(arc
							(start -0.1524 -0.127)
							(mid -0.137521 -0.162921)
							(end -0.1016 -0.1778)
						)
						(arc
							(start 0.1016 -0.1778)
							(mid 0.137521 -0.162921)
							(end 0.1524 -0.127)
						)
					)
					(width 0)
					(fill yes)
				)
			)
		)
		(pad "2" smd custom
			(at 0 0.2794 180)
			(size 0.0762 0.0762)
			(layers "B.Cu" "B.Mask" "B.Paste")
			(net "PCIE_SAS_CPU_RX_N4")
			(options
				(clearance outline)
				(anchor circle)
			)
			(primitives
				(gr_poly
					(pts
						(arc
							(start 0.1524 0.127)
							(mid 0.137521 0.162921)
							(end 0.1016 0.1778)
						)
						(arc
							(start -0.1016 0.1778)
							(mid -0.137521 0.162921)
							(end -0.1524 0.127)
						)
						(arc
							(start -0.1524 -0.127)
							(mid -0.137521 -0.162921)
							(end -0.1016 -0.1778)
						)
						(arc
							(start 0.1016 -0.1778)
							(mid 0.137521 -0.162921)
							(end 0.1524 -0.127)
						)
					)
					(width 0)
					(fill yes)
				)
			)
		)
	)
	(footprint ""
		(layer "B.Cu")
		(at 290.059872 -176.729136 90)
		(property "Reference" "C210"
			(at 0 0 90)
			(layer "B.SilkS")
			(hide yes)
			(effects
				(font
					(size 1.27 1.27)
				)
				(justify mirror)
			)
		)
		(property "Value" "SC1U6D3V3KX-2GP"
			(at 0 -2.8194 90)
			(unlocked yes)
			(layer "B.Fab")
			(hide yes)
			(effects
				(font
					(size 1.016 1.016)
					(thickness 0.1524)
				)
				(justify mirror)
			)
		)
		(property "Device Type" "C603H36"
			(at 0 -4.3434 90)
			(unlocked yes)
			(layer "B.Fab")
			(hide yes)
			(effects
				(font
					(size 1.016 1.016)
					(thickness 0.1524)
				)
				(justify mirror)
			)
		)
		(duplicate_pad_numbers_are_jumpers no)
		(fp_line
			(start -0.508 0)
			(end 0.508 0)
			(stroke
				(width 0.2032)
				(type default)
			)
			(layer "B.SilkS")
		)
		(fp_rect
			(start 0.5842 1.3335)
			(end -0.5842 -1.3335)
			(stroke
				(width 0)
				(type default)
			)
			(fill no)
			(layer "B.CrtYd")
		)
		(fp_rect
			(start 0.5842 1.3335)
			(end -0.5842 -1.3335)
			(stroke
				(width 0)
				(type default)
			)
			(fill no)
			(layer "B.Fab")
		)
		(pad "1" smd custom
			(at 0 -0.762 270)
			(size 0.2159 0.2159)
			(layers "B.Cu" "B.Mask" "B.Paste")
			(net "P3V3_STBY")
			(options
				(clearance outline)
				(anchor circle)
			)
			(primitives
				(gr_poly
					(pts
						(arc
							(start -0.3302 0.4318)
							(mid -0.402042 0.402042)
							(end -0.4318 0.3302)
						)
						(arc
							(start -0.4318 -0.3302)
							(mid -0.402042 -0.402042)
							(end -0.3302 -0.4318)
						)
						(arc
							(start 0.3302 -0.4318)
							(mid 0.402042 -0.402042)
							(end 0.4318 -0.3302)
						)
						(arc
							(start 0.4318 0.3302)
							(mid 0.402042 0.402042)
							(end 0.3302 0.4318)
						)
					)
					(width 0)
					(fill yes)
				)
			)
		)
		(pad "2" smd custom
			(at 0 0.762 270)
			(size 0.2159 0.2159)
			(layers "B.Cu" "B.Mask" "B.Paste")
			(net "GND")
			(options
				(clearance outline)
				(anchor circle)
			)
			(primitives
				(gr_poly
					(pts
						(arc
							(start -0.3302 0.4318)
							(mid -0.402042 0.402042)
							(end -0.4318 0.3302)
						)
						(arc
							(start -0.4318 -0.3302)
							(mid -0.402042 -0.402042)
							(end -0.3302 -0.4318)
						)
						(arc
							(start 0.3302 -0.4318)
							(mid 0.402042 -0.402042)
							(end 0.4318 -0.3302)
						)
						(arc
							(start 0.4318 0.3302)
							(mid 0.402042 0.402042)
							(end 0.3302 0.4318)
						)
					)
					(width 0)
					(fill yes)
				)
			)
		)
	)
	(footprint ""
		(layer "B.Cu")
		(at 120.91797 -85.979 -90)
		(property "Reference" "SC1193"
			(at 0 0 90)
			(layer "B.SilkS")
			(hide yes)
			(effects
				(font
					(size 1.27 1.27)
				)
				(justify mirror)
			)
		)
		(property "Value" "SCD1U6D3V1KX-GP"
			(at 2.8321 -1.7399 270)
			(unlocked yes)
			(layer "B.Fab")
			(hide yes)
			(effects
				(font
					(size 1.016 1.016)
					(thickness 0.1524)
				)
				(justify mirror)
			)
		)
		(property "Device Type" "C0201H13"
			(at 2.8321 -3.2639 270)
			(unlocked yes)
			(layer "B.Fab")
			(hide yes)
			(effects
				(font
					(size 1.016 1.016)
					(thickness 0.1524)
				)
				(justify mirror)
			)
		)
		(duplicate_pad_numbers_are_jumpers no)
		(fp_rect
			(start 0.2794 0.6477)
			(end -0.2794 -0.6477)
			(stroke
				(width 0)
				(type default)
			)
			(fill no)
			(layer "B.CrtYd")
		)
		(fp_rect
			(start 0.2794 0.6477)
			(end -0.2794 -0.6477)
			(stroke
				(width 0)
				(type default)
			)
			(fill no)
			(layer "B.Fab")
		)
		(pad "1" smd custom
			(at 0 -0.2794 90)
			(size 0.0762 0.0762)
			(layers "B.Cu" "B.Mask" "B.Paste")
			(net "GB_VDDA")
			(options
				(clearance outline)
				(anchor circle)
			)
			(primitives
				(gr_poly
					(pts
						(arc
							(start 0.1524 0.127)
							(mid 0.137521 0.162921)
							(end 0.1016 0.1778)
						)
						(arc
							(start -0.1016 0.1778)
							(mid -0.137521 0.162921)
							(end -0.1524 0.127)
						)
						(arc
							(start -0.1524 -0.127)
							(mid -0.137521 -0.162921)
							(end -0.1016 -0.1778)
						)
						(arc
							(start 0.1016 -0.1778)
							(mid 0.137521 -0.162921)
							(end 0.1524 -0.127)
						)
					)
					(width 0)
					(fill yes)
				)
			)
		)
		(pad "2" smd custom
			(at 0 0.2794 90)
			(size 0.0762 0.0762)
			(layers "B.Cu" "B.Mask" "B.Paste")
			(net "GND")
			(options
				(clearance outline)
				(anchor circle)
			)
			(primitives
				(gr_poly
					(pts
						(arc
							(start 0.1524 0.127)
							(mid 0.137521 0.162921)
							(end 0.1016 0.1778)
						)
						(arc
							(start -0.1016 0.1778)
							(mid -0.137521 0.162921)
							(end -0.1524 0.127)
						)
						(arc
							(start -0.1524 -0.127)
							(mid -0.137521 -0.162921)
							(end -0.1016 -0.1778)
						)
						(arc
							(start 0.1016 -0.1778)
							(mid 0.137521 -0.162921)
							(end 0.1524 -0.127)
						)
					)
					(width 0)
					(fill yes)
				)
			)
		)
	)
	(footprint ""
		(layer "B.Cu")
		(at 79.502 -23.114)
		(property "Reference" "SR932"
			(at 0 0 0)
			(layer "B.SilkS")
			(hide yes)
			(effects
				(font
					(size 1.27 1.27)
				)
				(justify mirror)
			)
		)
		(property "Value" "4K7R2F-GP"
			(at -0.064008 -3.993896 0)
			(unlocked yes)
			(layer "B.Fab")
			(hide yes)
			(effects
				(font
					(size 1.016 1.016)
					(thickness 0.1524)
				)
				(justify mirror)
			)
		)
		(property "Device Type" "R402H16"
			(at -0.064008 -5.517896 0)
			(unlocked yes)
			(layer "B.Fab")
			(hide yes)
			(effects
				(font
					(size 1.016 1.016)
					(thickness 0.1524)
				)
				(justify mirror)
			)
		)
		(duplicate_pad_numbers_are_jumpers no)
		(fp_line
			(start -0.508 -0.9398)
			(end 0.508 -0.9398)
			(stroke
				(width 0.1524)
				(type default)
			)
			(layer "B.SilkS")
		)
		(fp_line
			(start 0.508 -0.9398)
			(end 0.508 0.9398)
			(stroke
				(width 0.1524)
				(type default)
			)
			(layer "B.SilkS")
		)
		(fp_rect
			(start 0.508 0.9398)
			(end -0.508 -0.9398)
			(stroke
				(width 0)
				(type default)
			)
			(fill no)
			(layer "B.CrtYd")
		)
		(fp_rect
			(start 0.508 0.9398)
			(end -0.508 -0.9398)
			(stroke
				(width 0)
				(type default)
			)
			(fill no)
			(layer "B.Fab")
		)
		(pad "1" smd custom
			(at 0 -0.4445 180)
			(size 0.1397 0.1397)
			(layers "B.Cu" "B.Mask" "B.Paste")
			(net "P3V3_STBY")
			(options
				(clearance outline)
				(anchor circle)
			)
			(primitives
				(gr_poly
					(pts
						(arc
							(start -0.1778 0.2794)
							(mid -0.249642 0.249642)
							(end -0.2794 0.1778)
						)
						(arc
							(start -0.2794 -0.1778)
							(mid -0.249642 -0.249642)
							(end -0.1778 -0.2794)
						)
						(arc
							(start 0.1778 -0.2794)
							(mid 0.249642 -0.249642)
							(end 0.2794 -0.1778)
						)
						(arc
							(start 0.2794 0.1778)
							(mid 0.249642 0.249642)
							(end 0.1778 0.2794)
						)
					)
					(width 0)
					(fill yes)
				)
			)
		)
		(pad "2" smd custom
			(at 0 0.4445 180)
			(size 0.1397 0.1397)
			(layers "B.Cu" "B.Mask" "B.Paste")
			(net "PG_STAT_P0V955_C")
			(options
				(clearance outline)
				(anchor circle)
			)
			(primitives
				(gr_poly
					(pts
						(arc
							(start -0.1778 0.2794)
							(mid -0.249642 0.249642)
							(end -0.2794 0.1778)
						)
						(arc
							(start -0.2794 -0.1778)
							(mid -0.249642 -0.249642)
							(end -0.1778 -0.2794)
						)
						(arc
							(start 0.1778 -0.2794)
							(mid 0.249642 -0.249642)
							(end 0.2794 -0.1778)
						)
						(arc
							(start 0.2794 0.1778)
							(mid 0.249642 0.249642)
							(end 0.1778 0.2794)
						)
					)
					(width 0)
					(fill yes)
				)
			)
		)
	)
	(footprint ""
		(layer "B.Cu")
		(at 88.91397 -137.795 90)
		(property "Reference" "SC1119"
			(at 0 0 90)
			(layer "B.SilkS")
			(hide yes)
			(effects
				(font
					(size 1.27 1.27)
				)
				(justify mirror)
			)
		)
		(property "Value" "SCD1U16V2KX-3GP"
			(at -1.1811 -2.7051 90)
			(unlocked yes)
			(layer "B.Fab")
			(hide yes)
			(effects
				(font
					(size 1.016 1.016)
					(thickness 0.1524)
				)
				(justify mirror)
			)
		)
		(property "Device Type" "C402H22"
			(at -1.1811 -4.2291 90)
			(unlocked yes)
			(layer "B.Fab")
			(hide yes)
			(effects
				(font
					(size 1.016 1.016)
					(thickness 0.1524)
				)
				(justify mirror)
			)
		)
		(duplicate_pad_numbers_are_jumpers no)
		(fp_rect
			(start 0.4318 0.9525)
			(end -0.4318 -0.9525)
			(stroke
				(width 0)
				(type default)
			)
			(fill no)
			(layer "B.CrtYd")
		)
		(fp_rect
			(start 0.4318 0.9525)
			(end -0.4318 -0.9525)
			(stroke
				(width 0)
				(type default)
			)
			(fill no)
			(layer "B.Fab")
		)
		(pad "1" smd custom
			(at 0 -0.4445 270)
			(size 0.1524 0.1524)
			(layers "B.Cu" "B.Mask" "B.Paste")
			(net "P3V3_STBY")
			(options
				(clearance outline)
				(anchor circle)
			)
			(primitives
				(gr_poly
					(pts
						(arc
							(start 0.3048 0.2032)
							(mid 0.275042 0.275042)
							(end 0.2032 0.3048)
						)
						(arc
							(start -0.2032 0.3048)
							(mid -0.275042 0.275042)
							(end -0.3048 0.2032)
						)
						(arc
							(start -0.3048 -0.2032)
							(mid -0.275042 -0.275042)
							(end -0.2032 -0.3048)
						)
						(arc
							(start 0.2032 -0.3048)
							(mid 0.275042 -0.275042)
							(end 0.3048 -0.2032)
						)
					)
					(width 0)
					(fill yes)
				)
			)
		)
		(pad "2" smd custom
			(at 0 0.4445 270)
			(size 0.1524 0.1524)
			(layers "B.Cu" "B.Mask" "B.Paste")
			(net "GND")
			(options
				(clearance outline)
				(anchor circle)
			)
			(primitives
				(gr_poly
					(pts
						(arc
							(start 0.3048 0.2032)
							(mid 0.275042 0.275042)
							(end 0.2032 0.3048)
						)
						(arc
							(start -0.2032 0.3048)
							(mid -0.275042 0.275042)
							(end -0.3048 0.2032)
						)
						(arc
							(start -0.3048 -0.2032)
							(mid -0.275042 -0.275042)
							(end -0.2032 -0.3048)
						)
						(arc
							(start 0.2032 -0.3048)
							(mid 0.275042 -0.275042)
							(end 0.3048 -0.2032)
						)
					)
					(width 0)
					(fill yes)
				)
			)
		)
	)
	(footprint ""
		(layer "B.Cu")
		(at 100.838 -239.395)
		(property "Reference" "SR844"
			(at 0 0 0)
			(layer "B.SilkS")
			(hide yes)
			(effects
				(font
					(size 1.27 1.27)
				)
				(justify mirror)
			)
		)
		(property "Value" "4K7R2F-GP"
			(at -0.064008 -3.993896 0)
			(unlocked yes)
			(layer "B.Fab")
			(hide yes)
			(effects
				(font
					(size 1.016 1.016)
					(thickness 0.1524)
				)
				(justify mirror)
			)
		)
		(property "Device Type" "R402H16"
			(at -0.064008 -5.517896 0)
			(unlocked yes)
			(layer "B.Fab")
			(hide yes)
			(effects
				(font
					(size 1.016 1.016)
					(thickness 0.1524)
				)
				(justify mirror)
			)
		)
		(duplicate_pad_numbers_are_jumpers no)
		(fp_line
			(start -0.508 -0.9398)
			(end 0.508 -0.9398)
			(stroke
				(width 0.1524)
				(type default)
			)
			(layer "B.SilkS")
		)
		(fp_line
			(start 0.508 -0.9398)
			(end 0.508 0.9398)
			(stroke
				(width 0.1524)
				(type default)
			)
			(layer "B.SilkS")
		)
		(fp_rect
			(start 0.508 0.9398)
			(end -0.508 -0.9398)
			(stroke
				(width 0)
				(type default)
			)
			(fill no)
			(layer "B.CrtYd")
		)
		(fp_rect
			(start 0.508 0.9398)
			(end -0.508 -0.9398)
			(stroke
				(width 0)
				(type default)
			)
			(fill no)
			(layer "B.Fab")
		)
		(pad "1" smd custom
			(at 0 -0.4445 180)
			(size 0.1397 0.1397)
			(layers "B.Cu" "B.Mask" "B.Paste")
			(net "SAS_FAULT_LED1")
			(options
				(clearance outline)
				(anchor circle)
			)
			(primitives
				(gr_poly
					(pts
						(arc
							(start -0.1778 0.2794)
							(mid -0.249642 0.249642)
							(end -0.2794 0.1778)
						)
						(arc
							(start -0.2794 -0.1778)
							(mid -0.249642 -0.249642)
							(end -0.1778 -0.2794)
						)
						(arc
							(start 0.1778 -0.2794)
							(mid 0.249642 -0.249642)
							(end 0.2794 -0.1778)
						)
						(arc
							(start 0.2794 0.1778)
							(mid 0.249642 0.249642)
							(end 0.1778 0.2794)
						)
					)
					(width 0)
					(fill yes)
				)
			)
		)
		(pad "2" smd custom
			(at 0 0.4445 180)
			(size 0.1397 0.1397)
			(layers "B.Cu" "B.Mask" "B.Paste")
			(net "P3V3_STBY")
			(options
				(clearance outline)
				(anchor circle)
			)
			(primitives
				(gr_poly
					(pts
						(arc
							(start -0.1778 0.2794)
							(mid -0.249642 0.249642)
							(end -0.2794 0.1778)
						)
						(arc
							(start -0.2794 -0.1778)
							(mid -0.249642 -0.249642)
							(end -0.1778 -0.2794)
						)
						(arc
							(start 0.1778 -0.2794)
							(mid 0.249642 -0.249642)
							(end 0.2794 -0.1778)
						)
						(arc
							(start 0.2794 0.1778)
							(mid 0.249642 0.249642)
							(end 0.1778 0.2794)
						)
					)
					(width 0)
					(fill yes)
				)
			)
		)
	)
	(footprint ""
		(layer "B.Cu")
		(at 90.932 -3.429)
		(property "Reference" "SC1051"
			(at 0 0 0)
			(layer "B.SilkS")
			(hide yes)
			(effects
				(font
					(size 1.27 1.27)
				)
				(justify mirror)
			)
		)
		(property "Value" "SCD1U16V2KX-3GP"
			(at -1.1811 -2.7051 0)
			(unlocked yes)
			(layer "B.Fab")
			(hide yes)
			(effects
				(font
					(size 1.016 1.016)
					(thickness 0.1524)
				)
				(justify mirror)
			)
		)
		(property "Device Type" "C402H22"
			(at -1.1811 -4.2291 0)
			(unlocked yes)
			(layer "B.Fab")
			(hide yes)
			(effects
				(font
					(size 1.016 1.016)
					(thickness 0.1524)
				)
				(justify mirror)
			)
		)
		(duplicate_pad_numbers_are_jumpers no)
		(fp_rect
			(start 0.4318 0.9525)
			(end -0.4318 -0.9525)
			(stroke
				(width 0)
				(type default)
			)
			(fill no)
			(layer "B.CrtYd")
		)
		(fp_rect
			(start 0.4318 0.9525)
			(end -0.4318 -0.9525)
			(stroke
				(width 0)
				(type default)
			)
			(fill no)
			(layer "B.Fab")
		)
		(pad "1" smd custom
			(at 0 -0.4445 180)
			(size 0.1524 0.1524)
			(layers "B.Cu" "B.Mask" "B.Paste")
			(net "P0V955_C")
			(options
				(clearance outline)
				(anchor circle)
			)
			(primitives
				(gr_poly
					(pts
						(arc
							(start 0.3048 0.2032)
							(mid 0.275042 0.275042)
							(end 0.2032 0.3048)
						)
						(arc
							(start -0.2032 0.3048)
							(mid -0.275042 0.275042)
							(end -0.3048 0.2032)
						)
						(arc
							(start -0.3048 -0.2032)
							(mid -0.275042 -0.275042)
							(end -0.2032 -0.3048)
						)
						(arc
							(start 0.2032 -0.3048)
							(mid 0.275042 -0.275042)
							(end 0.3048 -0.2032)
						)
					)
					(width 0)
					(fill yes)
				)
			)
		)
		(pad "2" smd custom
			(at 0 0.4445 180)
			(size 0.1524 0.1524)
			(layers "B.Cu" "B.Mask" "B.Paste")
			(net "GND")
			(options
				(clearance outline)
				(anchor circle)
			)
			(primitives
				(gr_poly
					(pts
						(arc
							(start 0.3048 0.2032)
							(mid 0.275042 0.275042)
							(end 0.2032 0.3048)
						)
						(arc
							(start -0.2032 0.3048)
							(mid -0.275042 0.275042)
							(end -0.3048 0.2032)
						)
						(arc
							(start -0.3048 -0.2032)
							(mid -0.275042 -0.275042)
							(end -0.2032 -0.3048)
						)
						(arc
							(start 0.2032 -0.3048)
							(mid 0.275042 -0.275042)
							(end 0.3048 -0.2032)
						)
					)
					(width 0)
					(fill yes)
				)
			)
		)
	)
	(footprint ""
		(layer "B.Cu")
		(at 24.596344 -176.276762 90)
		(property "Reference" "SC1112"
			(at 0 0 90)
			(layer "B.SilkS")
			(hide yes)
			(effects
				(font
					(size 1.27 1.27)
				)
				(justify mirror)
			)
		)
		(property "Value" "SCD1U16V2KX-3GP"
			(at -1.1811 -2.7051 90)
			(unlocked yes)
			(layer "B.Fab")
			(hide yes)
			(effects
				(font
					(size 1.016 1.016)
					(thickness 0.1524)
				)
				(justify mirror)
			)
		)
		(property "Device Type" "C402H22"
			(at -1.1811 -4.2291 90)
			(unlocked yes)
			(layer "B.Fab")
			(hide yes)
			(effects
				(font
					(size 1.016 1.016)
					(thickness 0.1524)
				)
				(justify mirror)
			)
		)
		(duplicate_pad_numbers_are_jumpers no)
		(fp_rect
			(start 0.4318 0.9525)
			(end -0.4318 -0.9525)
			(stroke
				(width 0)
				(type default)
			)
			(fill no)
			(layer "B.CrtYd")
		)
		(fp_rect
			(start 0.4318 0.9525)
			(end -0.4318 -0.9525)
			(stroke
				(width 0)
				(type default)
			)
			(fill no)
			(layer "B.Fab")
		)
		(pad "1" smd custom
			(at 0 -0.4445 270)
			(size 0.1524 0.1524)
			(layers "B.Cu" "B.Mask" "B.Paste")
			(net "P3V3_STBY")
			(options
				(clearance outline)
				(anchor circle)
			)
			(primitives
				(gr_poly
					(pts
						(arc
							(start 0.3048 0.2032)
							(mid 0.275042 0.275042)
							(end 0.2032 0.3048)
						)
						(arc
							(start -0.2032 0.3048)
							(mid -0.275042 0.275042)
							(end -0.3048 0.2032)
						)
						(arc
							(start -0.3048 -0.2032)
							(mid -0.275042 -0.275042)
							(end -0.2032 -0.3048)
						)
						(arc
							(start 0.2032 -0.3048)
							(mid 0.275042 -0.275042)
							(end 0.3048 -0.2032)
						)
					)
					(width 0)
					(fill yes)
				)
			)
		)
		(pad "2" smd custom
			(at 0 0.4445 270)
			(size 0.1524 0.1524)
			(layers "B.Cu" "B.Mask" "B.Paste")
			(net "GND")
			(options
				(clearance outline)
				(anchor circle)
			)
			(primitives
				(gr_poly
					(pts
						(arc
							(start 0.3048 0.2032)
							(mid 0.275042 0.275042)
							(end 0.2032 0.3048)
						)
						(arc
							(start -0.2032 0.3048)
							(mid -0.275042 0.275042)
							(end -0.3048 0.2032)
						)
						(arc
							(start -0.3048 -0.2032)
							(mid -0.275042 -0.275042)
							(end -0.2032 -0.3048)
						)
						(arc
							(start 0.2032 -0.3048)
							(mid 0.275042 -0.275042)
							(end 0.3048 -0.2032)
						)
					)
					(width 0)
					(fill yes)
				)
			)
		)
	)
	(footprint ""
		(layer "B.Cu")
		(at 180.013864 -33.854136 90)
		(property "Reference" "C230"
			(at 0 0 90)
			(layer "B.SilkS")
			(hide yes)
			(effects
				(font
					(size 1.27 1.27)
				)
				(justify mirror)
			)
		)
		(property "Value" "SCD1U16V2KX-3GP"
			(at -1.1811 -2.7051 90)
			(unlocked yes)
			(layer "B.Fab")
			(hide yes)
			(effects
				(font
					(size 1.016 1.016)
					(thickness 0.1524)
				)
				(justify mirror)
			)
		)
		(property "Device Type" "C402H22"
			(at -1.1811 -4.2291 90)
			(unlocked yes)
			(layer "B.Fab")
			(hide yes)
			(effects
				(font
					(size 1.016 1.016)
					(thickness 0.1524)
				)
				(justify mirror)
			)
		)
		(duplicate_pad_numbers_are_jumpers no)
		(fp_rect
			(start 0.4318 0.9525)
			(end -0.4318 -0.9525)
			(stroke
				(width 0)
				(type default)
			)
			(fill no)
			(layer "B.CrtYd")
		)
		(fp_rect
			(start 0.4318 0.9525)
			(end -0.4318 -0.9525)
			(stroke
				(width 0)
				(type default)
			)
			(fill no)
			(layer "B.Fab")
		)
		(pad "1" smd custom
			(at 0 -0.4445 270)
			(size 0.1524 0.1524)
			(layers "B.Cu" "B.Mask" "B.Paste")
			(net "P3V3_STBY")
			(options
				(clearance outline)
				(anchor circle)
			)
			(primitives
				(gr_poly
					(pts
						(arc
							(start 0.3048 0.2032)
							(mid 0.275042 0.275042)
							(end 0.2032 0.3048)
						)
						(arc
							(start -0.2032 0.3048)
							(mid -0.275042 0.275042)
							(end -0.3048 0.2032)
						)
						(arc
							(start -0.3048 -0.2032)
							(mid -0.275042 -0.275042)
							(end -0.2032 -0.3048)
						)
						(arc
							(start 0.2032 -0.3048)
							(mid 0.275042 -0.275042)
							(end 0.3048 -0.2032)
						)
					)
					(width 0)
					(fill yes)
				)
			)
		)
		(pad "2" smd custom
			(at 0 0.4445 270)
			(size 0.1524 0.1524)
			(layers "B.Cu" "B.Mask" "B.Paste")
			(net "GND")
			(options
				(clearance outline)
				(anchor circle)
			)
			(primitives
				(gr_poly
					(pts
						(arc
							(start 0.3048 0.2032)
							(mid 0.275042 0.275042)
							(end 0.2032 0.3048)
						)
						(arc
							(start -0.2032 0.3048)
							(mid -0.275042 0.275042)
							(end -0.3048 0.2032)
						)
						(arc
							(start -0.3048 -0.2032)
							(mid -0.275042 -0.275042)
							(end -0.2032 -0.3048)
						)
						(arc
							(start 0.2032 -0.3048)
							(mid 0.275042 -0.275042)
							(end 0.3048 -0.2032)
						)
					)
					(width 0)
					(fill yes)
				)
			)
		)
	)
	(footprint ""
		(layer "B.Cu")
		(at 98.787966 -43.307 -90)
		(property "Reference" "SC1030"
			(at 0 0 90)
			(layer "B.SilkS")
			(hide yes)
			(effects
				(font
					(size 1.27 1.27)
				)
				(justify mirror)
			)
		)
		(property "Value" "SC1KP50V2KX-1GP"
			(at -1.1811 -2.7051 270)
			(unlocked yes)
			(layer "B.Fab")
			(hide yes)
			(effects
				(font
					(size 1.016 1.016)
					(thickness 0.1524)
				)
				(justify mirror)
			)
		)
		(property "Device Type" "C402H22"
			(at -1.1811 -4.2291 270)
			(unlocked yes)
			(layer "B.Fab")
			(hide yes)
			(effects
				(font
					(size 1.016 1.016)
					(thickness 0.1524)
				)
				(justify mirror)
			)
		)
		(duplicate_pad_numbers_are_jumpers no)
		(fp_rect
			(start 0.4318 0.9525)
			(end -0.4318 -0.9525)
			(stroke
				(width 0)
				(type default)
			)
			(fill no)
			(layer "B.CrtYd")
		)
		(fp_rect
			(start 0.4318 0.9525)
			(end -0.4318 -0.9525)
			(stroke
				(width 0)
				(type default)
			)
			(fill no)
			(layer "B.Fab")
		)
		(pad "1" smd custom
			(at 0 -0.4445 90)
			(size 0.1524 0.1524)
			(layers "B.Cu" "B.Mask" "B.Paste")
			(net "P0V955_C")
			(options
				(clearance outline)
				(anchor circle)
			)
			(primitives
				(gr_poly
					(pts
						(arc
							(start 0.3048 0.2032)
							(mid 0.275042 0.275042)
							(end 0.2032 0.3048)
						)
						(arc
							(start -0.2032 0.3048)
							(mid -0.275042 0.275042)
							(end -0.3048 0.2032)
						)
						(arc
							(start -0.3048 -0.2032)
							(mid -0.275042 -0.275042)
							(end -0.2032 -0.3048)
						)
						(arc
							(start 0.2032 -0.3048)
							(mid 0.275042 -0.275042)
							(end 0.3048 -0.2032)
						)
					)
					(width 0)
					(fill yes)
				)
			)
		)
		(pad "2" smd custom
			(at 0 0.4445 90)
			(size 0.1524 0.1524)
			(layers "B.Cu" "B.Mask" "B.Paste")
			(net "GND")
			(options
				(clearance outline)
				(anchor circle)
			)
			(primitives
				(gr_poly
					(pts
						(arc
							(start 0.3048 0.2032)
							(mid 0.275042 0.275042)
							(end 0.2032 0.3048)
						)
						(arc
							(start -0.2032 0.3048)
							(mid -0.275042 0.275042)
							(end -0.3048 0.2032)
						)
						(arc
							(start -0.3048 -0.2032)
							(mid -0.275042 -0.275042)
							(end -0.2032 -0.3048)
						)
						(arc
							(start 0.2032 -0.3048)
							(mid 0.275042 -0.275042)
							(end 0.3048 -0.2032)
						)
					)
					(width 0)
					(fill yes)
				)
			)
		)
	)
	(footprint ""
		(layer "B.Cu")
		(at 30.430216 -232.33888)
		(property "Reference" "R507"
			(at 0 0 0)
			(layer "B.SilkS")
			(hide yes)
			(effects
				(font
					(size 1.27 1.27)
				)
				(justify mirror)
			)
		)
		(property "Value" "0R2J-2-GP"
			(at -0.064008 -3.993896 0)
			(unlocked yes)
			(layer "B.Fab")
			(hide yes)
			(effects
				(font
					(size 1.016 1.016)
					(thickness 0.1524)
				)
				(justify mirror)
			)
		)
		(property "Device Type" "R402H16"
			(at -0.064008 -5.517896 0)
			(unlocked yes)
			(layer "B.Fab")
			(hide yes)
			(effects
				(font
					(size 1.016 1.016)
					(thickness 0.1524)
				)
				(justify mirror)
			)
		)
		(duplicate_pad_numbers_are_jumpers no)
		(fp_line
			(start -0.508 -0.9398)
			(end 0.508 -0.9398)
			(stroke
				(width 0.1524)
				(type default)
			)
			(layer "B.SilkS")
		)
		(fp_line
			(start 0.508 -0.9398)
			(end 0.508 0.9398)
			(stroke
				(width 0.1524)
				(type default)
			)
			(layer "B.SilkS")
		)
		(fp_rect
			(start 0.508 0.9398)
			(end -0.508 -0.9398)
			(stroke
				(width 0)
				(type default)
			)
			(fill no)
			(layer "B.CrtYd")
		)
		(fp_rect
			(start 0.508 0.9398)
			(end -0.508 -0.9398)
			(stroke
				(width 0)
				(type default)
			)
			(fill no)
			(layer "B.Fab")
		)
		(pad "1" smd custom
			(at 0 -0.4445 180)
			(size 0.1397 0.1397)
			(layers "B.Cu" "B.Mask" "B.Paste")
			(net "SAS_HDD_PWR5_PCIE")
			(options
				(clearance outline)
				(anchor circle)
			)
			(primitives
				(gr_poly
					(pts
						(arc
							(start -0.1778 0.2794)
							(mid -0.249642 0.249642)
							(end -0.2794 0.1778)
						)
						(arc
							(start -0.2794 -0.1778)
							(mid -0.249642 -0.249642)
							(end -0.1778 -0.2794)
						)
						(arc
							(start 0.1778 -0.2794)
							(mid 0.249642 -0.249642)
							(end 0.2794 -0.1778)
						)
						(arc
							(start 0.2794 0.1778)
							(mid 0.249642 0.249642)
							(end 0.1778 0.2794)
						)
					)
					(width 0)
					(fill yes)
				)
			)
		)
		(pad "2" smd custom
			(at 0 0.4445 180)
			(size 0.1397 0.1397)
			(layers "B.Cu" "B.Mask" "B.Paste")
			(net "SAS_HDD_PWR5")
			(options
				(clearance outline)
				(anchor circle)
			)
			(primitives
				(gr_poly
					(pts
						(arc
							(start -0.1778 0.2794)
							(mid -0.249642 0.249642)
							(end -0.2794 0.1778)
						)
						(arc
							(start -0.2794 -0.1778)
							(mid -0.249642 -0.249642)
							(end -0.1778 -0.2794)
						)
						(arc
							(start 0.1778 -0.2794)
							(mid 0.249642 -0.249642)
							(end 0.2794 -0.1778)
						)
						(arc
							(start 0.2794 0.1778)
							(mid 0.249642 0.249642)
							(end 0.1778 0.2794)
						)
					)
					(width 0)
					(fill yes)
				)
			)
		)
	)
	(footprint ""
		(layer "B.Cu")
		(at 101.86797 -96.901 -90)
		(property "Reference" "STP86"
			(at 0 0 90)
			(layer "B.SilkS")
			(hide yes)
			(effects
				(font
					(size 1.27 1.27)
				)
				(justify mirror)
			)
		)
		(property "Value" "TPAD28"
			(at -0.0127 -1.8034 270)
			(unlocked yes)
			(layer "B.Fab")
			(hide yes)
			(effects
				(font
					(size 1.016 1.016)
					(thickness 0.1524)
				)
				(justify mirror)
			)
		)
		(property "Device Type" "TPAD28"
			(at -0.0127 -3.3274 270)
			(unlocked yes)
			(layer "B.Fab")
			(hide yes)
			(effects
				(font
					(size 1.016 1.016)
					(thickness 0.1524)
				)
				(justify mirror)
			)
		)
		(duplicate_pad_numbers_are_jumpers no)
		(fp_poly
			(pts
				(arc
					(start 0 -0.3556)
					(mid 0 0.3556)
					(end 0 -0.3556)
				)
			)
			(stroke
				(width 0)
				(type default)
			)
			(fill no)
			(layer "B.CrtYd")
		)
		(fp_poly
			(pts
				(arc
					(start 0 -0.6096)
					(mid 0 0.6096)
					(end 0 -0.6096)
				)
			)
			(stroke
				(width 0)
				(type default)
			)
			(fill no)
			(layer "B.Fab")
		)
		(pad "1" smd circle
			(at 0 0 90)
			(size 0.7112 0.7112)
			(layers "B.Cu" "B.Mask" "B.Paste")
			(net "EXP_PWM_OUT0")
		)
	)
	(footprint ""
		(layer "B.Cu")
		(at 123.171966 -33.528)
		(property "Reference" "SC934"
			(at 0 0 0)
			(layer "B.SilkS")
			(hide yes)
			(effects
				(font
					(size 1.27 1.27)
				)
				(justify mirror)
			)
		)
		(property "Value" "SCD1U6D3V1KX-GP"
			(at 2.8321 -1.7399 0)
			(unlocked yes)
			(layer "B.Fab")
			(hide yes)
			(effects
				(font
					(size 1.016 1.016)
					(thickness 0.1524)
				)
				(justify mirror)
			)
		)
		(property "Device Type" "C0201H13"
			(at 2.8321 -3.2639 0)
			(unlocked yes)
			(layer "B.Fab")
			(hide yes)
			(effects
				(font
					(size 1.016 1.016)
					(thickness 0.1524)
				)
				(justify mirror)
			)
		)
		(duplicate_pad_numbers_are_jumpers no)
		(fp_rect
			(start 0.2794 0.6477)
			(end -0.2794 -0.6477)
			(stroke
				(width 0)
				(type default)
			)
			(fill no)
			(layer "B.CrtYd")
		)
		(fp_rect
			(start 0.2794 0.6477)
			(end -0.2794 -0.6477)
			(stroke
				(width 0)
				(type default)
			)
			(fill no)
			(layer "B.Fab")
		)
		(pad "1" smd custom
			(at 0 -0.2794 180)
			(size 0.0762 0.0762)
			(layers "B.Cu" "B.Mask" "B.Paste")
			(net "PLL_VDD")
			(options
				(clearance outline)
				(anchor circle)
			)
			(primitives
				(gr_poly
					(pts
						(arc
							(start 0.1524 0.127)
							(mid 0.137521 0.162921)
							(end 0.1016 0.1778)
						)
						(arc
							(start -0.1016 0.1778)
							(mid -0.137521 0.162921)
							(end -0.1524 0.127)
						)
						(arc
							(start -0.1524 -0.127)
							(mid -0.137521 -0.162921)
							(end -0.1016 -0.1778)
						)
						(arc
							(start 0.1016 -0.1778)
							(mid 0.137521 -0.162921)
							(end 0.1524 -0.127)
						)
					)
					(width 0)
					(fill yes)
				)
			)
		)
		(pad "2" smd custom
			(at 0 0.2794 180)
			(size 0.0762 0.0762)
			(layers "B.Cu" "B.Mask" "B.Paste")
			(net "GND")
			(options
				(clearance outline)
				(anchor circle)
			)
			(primitives
				(gr_poly
					(pts
						(arc
							(start 0.1524 0.127)
							(mid 0.137521 0.162921)
							(end 0.1016 0.1778)
						)
						(arc
							(start -0.1016 0.1778)
							(mid -0.137521 0.162921)
							(end -0.1524 0.127)
						)
						(arc
							(start -0.1524 -0.127)
							(mid -0.137521 -0.162921)
							(end -0.1016 -0.1778)
						)
						(arc
							(start 0.1016 -0.1778)
							(mid 0.137521 -0.162921)
							(end 0.1524 -0.127)
						)
					)
					(width 0)
					(fill yes)
				)
			)
		)
	)
	(footprint ""
		(layer "B.Cu")
		(at 18.281904 -100.400866)
		(property "Reference" "C135"
			(at 0 0 0)
			(layer "B.SilkS")
			(hide yes)
			(effects
				(font
					(size 1.27 1.27)
				)
				(justify mirror)
			)
		)
		(property "Value" "SCD01U50V2KX-1GP"
			(at -1.1811 -2.7051 0)
			(unlocked yes)
			(layer "B.Fab")
			(hide yes)
			(effects
				(font
					(size 1.016 1.016)
					(thickness 0.1524)
				)
				(justify mirror)
			)
		)
		(property "Device Type" "C402H22"
			(at -1.1811 -4.2291 0)
			(unlocked yes)
			(layer "B.Fab")
			(hide yes)
			(effects
				(font
					(size 1.016 1.016)
					(thickness 0.1524)
				)
				(justify mirror)
			)
		)
		(duplicate_pad_numbers_are_jumpers no)
		(fp_rect
			(start 0.4318 0.9525)
			(end -0.4318 -0.9525)
			(stroke
				(width 0)
				(type default)
			)
			(fill no)
			(layer "B.CrtYd")
		)
		(fp_rect
			(start 0.4318 0.9525)
			(end -0.4318 -0.9525)
			(stroke
				(width 0)
				(type default)
			)
			(fill no)
			(layer "B.Fab")
		)
		(pad "1" smd custom
			(at 0 -0.4445 180)
			(size 0.1524 0.1524)
			(layers "B.Cu" "B.Mask" "B.Paste")
			(net "IOC_SAS_RX_P7")
			(options
				(clearance outline)
				(anchor circle)
			)
			(primitives
				(gr_poly
					(pts
						(arc
							(start 0.3048 0.2032)
							(mid 0.275042 0.275042)
							(end 0.2032 0.3048)
						)
						(arc
							(start -0.2032 0.3048)
							(mid -0.275042 0.275042)
							(end -0.3048 0.2032)
						)
						(arc
							(start -0.3048 -0.2032)
							(mid -0.275042 -0.275042)
							(end -0.2032 -0.3048)
						)
						(arc
							(start 0.2032 -0.3048)
							(mid 0.275042 -0.275042)
							(end 0.3048 -0.2032)
						)
					)
					(width 0)
					(fill yes)
				)
			)
		)
		(pad "2" smd custom
			(at 0 0.4445 180)
			(size 0.1524 0.1524)
			(layers "B.Cu" "B.Mask" "B.Paste")
			(net "SAS_EXT_CONN_RX19_P")
			(options
				(clearance outline)
				(anchor circle)
			)
			(primitives
				(gr_poly
					(pts
						(arc
							(start 0.3048 0.2032)
							(mid 0.275042 0.275042)
							(end 0.2032 0.3048)
						)
						(arc
							(start -0.2032 0.3048)
							(mid -0.275042 0.275042)
							(end -0.3048 0.2032)
						)
						(arc
							(start -0.3048 -0.2032)
							(mid -0.275042 -0.275042)
							(end -0.2032 -0.3048)
						)
						(arc
							(start 0.2032 -0.3048)
							(mid 0.275042 -0.275042)
							(end 0.3048 -0.2032)
						)
					)
					(width 0)
					(fill yes)
				)
			)
		)
	)
	(footprint ""
		(layer "B.Cu")
		(at 124.403612 -218.821 -90)
		(property "Reference" "SR909"
			(at 0 0 90)
			(layer "B.SilkS")
			(hide yes)
			(effects
				(font
					(size 1.27 1.27)
				)
				(justify mirror)
			)
		)
		(property "Value" "4K7R2F-GP"
			(at -0.064008 -3.993896 270)
			(unlocked yes)
			(layer "B.Fab")
			(hide yes)
			(effects
				(font
					(size 1.016 1.016)
					(thickness 0.1524)
				)
				(justify mirror)
			)
		)
		(property "Device Type" "R402H16"
			(at -0.064008 -5.517896 270)
			(unlocked yes)
			(layer "B.Fab")
			(hide yes)
			(effects
				(font
					(size 1.016 1.016)
					(thickness 0.1524)
				)
				(justify mirror)
			)
		)
		(duplicate_pad_numbers_are_jumpers no)
		(fp_line
			(start -0.508 -0.9398)
			(end 0.508 -0.9398)
			(stroke
				(width 0.1524)
				(type default)
			)
			(layer "B.SilkS")
		)
		(fp_line
			(start 0.508 -0.9398)
			(end 0.508 0.9398)
			(stroke
				(width 0.1524)
				(type default)
			)
			(layer "B.SilkS")
		)
		(fp_rect
			(start 0.508 0.9398)
			(end -0.508 -0.9398)
			(stroke
				(width 0)
				(type default)
			)
			(fill no)
			(layer "B.CrtYd")
		)
		(fp_rect
			(start 0.508 0.9398)
			(end -0.508 -0.9398)
			(stroke
				(width 0)
				(type default)
			)
			(fill no)
			(layer "B.Fab")
		)
		(pad "1" smd custom
			(at 0 -0.4445 90)
			(size 0.1397 0.1397)
			(layers "B.Cu" "B.Mask" "B.Paste")
			(net "P1V26_STBY")
			(options
				(clearance outline)
				(anchor circle)
			)
			(primitives
				(gr_poly
					(pts
						(arc
							(start -0.1778 0.2794)
							(mid -0.249642 0.249642)
							(end -0.2794 0.1778)
						)
						(arc
							(start -0.2794 -0.1778)
							(mid -0.249642 -0.249642)
							(end -0.1778 -0.2794)
						)
						(arc
							(start 0.1778 -0.2794)
							(mid 0.249642 -0.249642)
							(end 0.2794 -0.1778)
						)
						(arc
							(start 0.2794 0.1778)
							(mid 0.249642 0.249642)
							(end 0.1778 0.2794)
						)
					)
					(width 0)
					(fill yes)
				)
			)
		)
		(pad "2" smd custom
			(at 0 0.4445 90)
			(size 0.1397 0.1397)
			(layers "B.Cu" "B.Mask" "B.Paste")
			(net "REDV_PD#")
			(options
				(clearance outline)
				(anchor circle)
			)
			(primitives
				(gr_poly
					(pts
						(arc
							(start -0.1778 0.2794)
							(mid -0.249642 0.249642)
							(end -0.2794 0.1778)
						)
						(arc
							(start -0.2794 -0.1778)
							(mid -0.249642 -0.249642)
							(end -0.1778 -0.2794)
						)
						(arc
							(start 0.1778 -0.2794)
							(mid 0.249642 -0.249642)
							(end 0.2794 -0.1778)
						)
						(arc
							(start 0.2794 0.1778)
							(mid 0.249642 0.249642)
							(end 0.1778 0.2794)
						)
					)
					(width 0)
					(fill yes)
				)
			)
		)
	)
	(footprint ""
		(layer "B.Cu")
		(at 99.549966 -40.64)
		(property "Reference" "SC1018"
			(at 0 0 0)
			(layer "B.SilkS")
			(hide yes)
			(effects
				(font
					(size 1.27 1.27)
				)
				(justify mirror)
			)
		)
		(property "Value" "SC10U6D3V5KX-4GP"
			(at 0.0762 -6.1214 0)
			(unlocked yes)
			(layer "B.Fab")
			(hide yes)
			(effects
				(font
					(size 1.016 1.016)
					(thickness 0.1524)
				)
				(justify mirror)
			)
		)
		(property "Device Type" "C805H58"
			(at 0.0762 -8.1534 0)
			(unlocked yes)
			(layer "B.Fab")
			(hide yes)
			(effects
				(font
					(size 1.016 1.016)
					(thickness 0.1524)
				)
				(justify mirror)
			)
		)
		(duplicate_pad_numbers_are_jumpers no)
		(fp_line
			(start -0.635 0)
			(end 0.635 0)
			(stroke
				(width 0.508)
				(type default)
			)
			(layer "B.SilkS")
		)
		(fp_rect
			(start 0.9652 1.778)
			(end -0.9652 -1.778)
			(stroke
				(width 0)
				(type default)
			)
			(fill no)
			(layer "B.CrtYd")
		)
		(fp_poly
			(pts
				(xy 0.9652 -1.778) (xy -0.9652 -1.778) (xy -0.9652 1.778) (xy 0.9652 1.778)
			)
			(stroke
				(width 0)
				(type default)
			)
			(fill no)
			(layer "B.Fab")
		)
		(pad "1" smd rect
			(at 0 -0.9652 180)
			(size 1.397 1.143)
			(layers "B.Cu" "B.Mask" "B.Paste")
			(net "P0V955_C")
		)
		(pad "2" smd rect
			(at 0 0.9652 180)
			(size 1.397 1.143)
			(layers "B.Cu" "B.Mask" "B.Paste")
			(net "GND")
		)
	)
	(footprint ""
		(layer "B.Cu")
		(at 274.193 -172.593 90)
		(property "Reference" "R241"
			(at 0 0 90)
			(layer "B.SilkS")
			(hide yes)
			(effects
				(font
					(size 1.27 1.27)
				)
				(justify mirror)
			)
		)
		(property "Value" "0R2J-2-GP"
			(at -0.064008 -3.993896 90)
			(unlocked yes)
			(layer "B.Fab")
			(hide yes)
			(effects
				(font
					(size 1.016 1.016)
					(thickness 0.1524)
				)
				(justify mirror)
			)
		)
		(property "Device Type" "R402H16"
			(at -0.064008 -5.517896 90)
			(unlocked yes)
			(layer "B.Fab")
			(hide yes)
			(effects
				(font
					(size 1.016 1.016)
					(thickness 0.1524)
				)
				(justify mirror)
			)
		)
		(duplicate_pad_numbers_are_jumpers no)
		(fp_line
			(start 0.508 -0.9398)
			(end 0.508 0.9398)
			(stroke
				(width 0.1524)
				(type default)
			)
			(layer "B.SilkS")
		)
		(fp_line
			(start -0.508 -0.9398)
			(end 0.508 -0.9398)
			(stroke
				(width 0.1524)
				(type default)
			)
			(layer "B.SilkS")
		)
		(fp_rect
			(start 0.508 0.9398)
			(end -0.508 -0.9398)
			(stroke
				(width 0)
				(type default)
			)
			(fill no)
			(layer "B.CrtYd")
		)
		(fp_rect
			(start 0.508 0.9398)
			(end -0.508 -0.9398)
			(stroke
				(width 0)
				(type default)
			)
			(fill no)
			(layer "B.Fab")
		)
		(pad "1" smd custom
			(at 0 -0.4445 270)
			(size 0.1397 0.1397)
			(layers "B.Cu" "B.Mask" "B.Paste")
			(net "BMC_10G_SDA_2")
			(options
				(clearance outline)
				(anchor circle)
			)
			(primitives
				(gr_poly
					(pts
						(arc
							(start -0.1778 0.2794)
							(mid -0.249642 0.249642)
							(end -0.2794 0.1778)
						)
						(arc
							(start -0.2794 -0.1778)
							(mid -0.249642 -0.249642)
							(end -0.1778 -0.2794)
						)
						(arc
							(start 0.1778 -0.2794)
							(mid 0.249642 -0.249642)
							(end 0.2794 -0.1778)
						)
						(arc
							(start 0.2794 0.1778)
							(mid 0.249642 0.249642)
							(end 0.1778 0.2794)
						)
					)
					(width 0)
					(fill yes)
				)
			)
		)
		(pad "2" smd custom
			(at 0 0.4445 270)
			(size 0.1397 0.1397)
			(layers "B.Cu" "B.Mask" "B.Paste")
			(net "BMC0_SMB2_DAT")
			(options
				(clearance outline)
				(anchor circle)
			)
			(primitives
				(gr_poly
					(pts
						(arc
							(start -0.1778 0.2794)
							(mid -0.249642 0.249642)
							(end -0.2794 0.1778)
						)
						(arc
							(start -0.2794 -0.1778)
							(mid -0.249642 -0.249642)
							(end -0.1778 -0.2794)
						)
						(arc
							(start 0.1778 -0.2794)
							(mid 0.249642 -0.249642)
							(end 0.2794 -0.1778)
						)
						(arc
							(start 0.2794 0.1778)
							(mid 0.249642 0.249642)
							(end 0.1778 0.2794)
						)
					)
					(width 0)
					(fill yes)
				)
			)
		)
	)
	(footprint ""
		(layer "B.Cu")
		(at 158.877 -89.154)
		(property "Reference" "PC179"
			(at 0 0 0)
			(layer "B.SilkS")
			(hide yes)
			(effects
				(font
					(size 1.27 1.27)
				)
				(justify mirror)
			)
		)
		(property "Value" "SC22U6D3V3MX-1-GP"
			(at 0 -2.8194 0)
			(unlocked yes)
			(layer "B.Fab")
			(hide yes)
			(effects
				(font
					(size 1.016 1.016)
					(thickness 0.1524)
				)
				(justify mirror)
			)
		)
		(property "Device Type" "C603H40"
			(at 0 -4.3434 0)
			(unlocked yes)
			(layer "B.Fab")
			(hide yes)
			(effects
				(font
					(size 1.016 1.016)
					(thickness 0.1524)
				)
				(justify mirror)
			)
		)
		(duplicate_pad_numbers_are_jumpers no)
		(fp_line
			(start -0.508 0)
			(end 0.508 0)
			(stroke
				(width 0.2032)
				(type default)
			)
			(layer "B.SilkS")
		)
		(fp_rect
			(start 0.5842 1.3335)
			(end -0.5842 -1.3335)
			(stroke
				(width 0)
				(type default)
			)
			(fill no)
			(layer "B.CrtYd")
		)
		(fp_rect
			(start 0.5842 1.3335)
			(end -0.5842 -1.3335)
			(stroke
				(width 0)
				(type default)
			)
			(fill no)
			(layer "B.Fab")
		)
		(pad "1" smd custom
			(at 0 -0.762 180)
			(size 0.2159 0.2159)
			(layers "B.Cu" "B.Mask" "B.Paste")
			(net "P0V9_E")
			(options
				(clearance outline)
				(anchor circle)
			)
			(primitives
				(gr_poly
					(pts
						(arc
							(start -0.3302 0.4318)
							(mid -0.402042 0.402042)
							(end -0.4318 0.3302)
						)
						(arc
							(start -0.4318 -0.3302)
							(mid -0.402042 -0.402042)
							(end -0.3302 -0.4318)
						)
						(arc
							(start 0.3302 -0.4318)
							(mid 0.402042 -0.402042)
							(end 0.4318 -0.3302)
						)
						(arc
							(start 0.4318 0.3302)
							(mid 0.402042 0.402042)
							(end 0.3302 0.4318)
						)
					)
					(width 0)
					(fill yes)
				)
			)
		)
		(pad "2" smd custom
			(at 0 0.762 180)
			(size 0.2159 0.2159)
			(layers "B.Cu" "B.Mask" "B.Paste")
			(net "GND")
			(options
				(clearance outline)
				(anchor circle)
			)
			(primitives
				(gr_poly
					(pts
						(arc
							(start -0.3302 0.4318)
							(mid -0.402042 0.402042)
							(end -0.4318 0.3302)
						)
						(arc
							(start -0.4318 -0.3302)
							(mid -0.402042 -0.402042)
							(end -0.3302 -0.4318)
						)
						(arc
							(start 0.3302 -0.4318)
							(mid 0.402042 -0.402042)
							(end 0.4318 -0.3302)
						)
						(arc
							(start 0.4318 0.3302)
							(mid 0.402042 0.402042)
							(end 0.3302 0.4318)
						)
					)
					(width 0)
					(fill yes)
				)
			)
		)
	)
	(footprint ""
		(layer "B.Cu")
		(at 107.2388 -40.3352)
		(property "Reference" "SC1049"
			(at 0 0 0)
			(layer "B.SilkS")
			(hide yes)
			(effects
				(font
					(size 1.27 1.27)
				)
				(justify mirror)
			)
		)
		(property "Value" "SCD1U16V2KX-3GP"
			(at -1.1811 -2.7051 0)
			(unlocked yes)
			(layer "B.Fab")
			(hide yes)
			(effects
				(font
					(size 1.016 1.016)
					(thickness 0.1524)
				)
				(justify mirror)
			)
		)
		(property "Device Type" "C402H22"
			(at -1.1811 -4.2291 0)
			(unlocked yes)
			(layer "B.Fab")
			(hide yes)
			(effects
				(font
					(size 1.016 1.016)
					(thickness 0.1524)
				)
				(justify mirror)
			)
		)
		(duplicate_pad_numbers_are_jumpers no)
		(fp_rect
			(start 0.4318 0.9525)
			(end -0.4318 -0.9525)
			(stroke
				(width 0)
				(type default)
			)
			(fill no)
			(layer "B.CrtYd")
		)
		(fp_rect
			(start 0.4318 0.9525)
			(end -0.4318 -0.9525)
			(stroke
				(width 0)
				(type default)
			)
			(fill no)
			(layer "B.Fab")
		)
		(pad "1" smd custom
			(at 0 -0.4445 180)
			(size 0.1524 0.1524)
			(layers "B.Cu" "B.Mask" "B.Paste")
			(net "P0V955_C")
			(options
				(clearance outline)
				(anchor circle)
			)
			(primitives
				(gr_poly
					(pts
						(arc
							(start 0.3048 0.2032)
							(mid 0.275042 0.275042)
							(end 0.2032 0.3048)
						)
						(arc
							(start -0.2032 0.3048)
							(mid -0.275042 0.275042)
							(end -0.3048 0.2032)
						)
						(arc
							(start -0.3048 -0.2032)
							(mid -0.275042 -0.275042)
							(end -0.2032 -0.3048)
						)
						(arc
							(start 0.2032 -0.3048)
							(mid 0.275042 -0.275042)
							(end 0.3048 -0.2032)
						)
					)
					(width 0)
					(fill yes)
				)
			)
		)
		(pad "2" smd custom
			(at 0 0.4445 180)
			(size 0.1524 0.1524)
			(layers "B.Cu" "B.Mask" "B.Paste")
			(net "GND")
			(options
				(clearance outline)
				(anchor circle)
			)
			(primitives
				(gr_poly
					(pts
						(arc
							(start 0.3048 0.2032)
							(mid 0.275042 0.275042)
							(end 0.2032 0.3048)
						)
						(arc
							(start -0.2032 0.3048)
							(mid -0.275042 0.275042)
							(end -0.3048 0.2032)
						)
						(arc
							(start -0.3048 -0.2032)
							(mid -0.275042 -0.275042)
							(end -0.2032 -0.3048)
						)
						(arc
							(start 0.2032 -0.3048)
							(mid 0.275042 -0.275042)
							(end 0.3048 -0.2032)
						)
					)
					(width 0)
					(fill yes)
				)
			)
		)
	)
	(footprint ""
		(layer "B.Cu")
		(at 44.52493 -77.650086)
		(property "Reference" "SC1276"
			(at 0 0 0)
			(layer "B.SilkS")
			(hide yes)
			(effects
				(font
					(size 1.27 1.27)
				)
				(justify mirror)
			)
		)
		(property "Value" "SCD01U50V2KX-1GP"
			(at -1.1811 -2.7051 0)
			(unlocked yes)
			(layer "B.Fab")
			(hide yes)
			(effects
				(font
					(size 1.016 1.016)
					(thickness 0.1524)
				)
				(justify mirror)
			)
		)
		(property "Device Type" "C402H22"
			(at -1.1811 -4.2291 0)
			(unlocked yes)
			(layer "B.Fab")
			(hide yes)
			(effects
				(font
					(size 1.016 1.016)
					(thickness 0.1524)
				)
				(justify mirror)
			)
		)
		(duplicate_pad_numbers_are_jumpers no)
		(fp_rect
			(start 0.4318 0.9525)
			(end -0.4318 -0.9525)
			(stroke
				(width 0)
				(type default)
			)
			(fill no)
			(layer "B.CrtYd")
		)
		(fp_rect
			(start 0.4318 0.9525)
			(end -0.4318 -0.9525)
			(stroke
				(width 0)
				(type default)
			)
			(fill no)
			(layer "B.Fab")
		)
		(pad "1" smd custom
			(at 0 -0.4445 180)
			(size 0.1524 0.1524)
			(layers "B.Cu" "B.Mask" "B.Paste")
			(net "SAS_EXP2CONN_RX_P_21")
			(options
				(clearance outline)
				(anchor circle)
			)
			(primitives
				(gr_poly
					(pts
						(arc
							(start 0.3048 0.2032)
							(mid 0.275042 0.275042)
							(end 0.2032 0.3048)
						)
						(arc
							(start -0.2032 0.3048)
							(mid -0.275042 0.275042)
							(end -0.3048 0.2032)
						)
						(arc
							(start -0.3048 -0.2032)
							(mid -0.275042 -0.275042)
							(end -0.2032 -0.3048)
						)
						(arc
							(start 0.2032 -0.3048)
							(mid 0.275042 -0.275042)
							(end 0.3048 -0.2032)
						)
					)
					(width 0)
					(fill yes)
				)
			)
		)
		(pad "2" smd custom
			(at 0 0.4445 180)
			(size 0.1524 0.1524)
			(layers "B.Cu" "B.Mask" "B.Paste")
			(net "MINI_RX_P_21")
			(options
				(clearance outline)
				(anchor circle)
			)
			(primitives
				(gr_poly
					(pts
						(arc
							(start 0.3048 0.2032)
							(mid 0.275042 0.275042)
							(end 0.2032 0.3048)
						)
						(arc
							(start -0.2032 0.3048)
							(mid -0.275042 0.275042)
							(end -0.3048 0.2032)
						)
						(arc
							(start -0.3048 -0.2032)
							(mid -0.275042 -0.275042)
							(end -0.2032 -0.3048)
						)
						(arc
							(start 0.2032 -0.3048)
							(mid 0.275042 -0.275042)
							(end 0.3048 -0.2032)
						)
					)
					(width 0)
					(fill yes)
				)
			)
		)
	)
	(footprint ""
		(layer "B.Cu")
		(at 288.925 -166.243 180)
		(property "Reference" "R253"
			(at 0 0 0)
			(layer "B.SilkS")
			(hide yes)
			(effects
				(font
					(size 1.27 1.27)
				)
				(justify mirror)
			)
		)
		(property "Value" "0R2J-2-GP"
			(at -0.064008 -3.993896 180)
			(unlocked yes)
			(layer "B.Fab")
			(hide yes)
			(effects
				(font
					(size 1.016 1.016)
					(thickness 0.1524)
				)
				(justify mirror)
			)
		)
		(property "Device Type" "R402H16"
			(at -0.064008 -5.517896 180)
			(unlocked yes)
			(layer "B.Fab")
			(hide yes)
			(effects
				(font
					(size 1.016 1.016)
					(thickness 0.1524)
				)
				(justify mirror)
			)
		)
		(duplicate_pad_numbers_are_jumpers no)
		(fp_line
			(start 0.508 -0.9398)
			(end 0.508 0.9398)
			(stroke
				(width 0.1524)
				(type default)
			)
			(layer "B.SilkS")
		)
		(fp_line
			(start -0.508 -0.9398)
			(end 0.508 -0.9398)
			(stroke
				(width 0.1524)
				(type default)
			)
			(layer "B.SilkS")
		)
		(fp_rect
			(start 0.508 0.9398)
			(end -0.508 -0.9398)
			(stroke
				(width 0)
				(type default)
			)
			(fill no)
			(layer "B.CrtYd")
		)
		(fp_rect
			(start 0.508 0.9398)
			(end -0.508 -0.9398)
			(stroke
				(width 0)
				(type default)
			)
			(fill no)
			(layer "B.Fab")
		)
		(pad "1" smd custom
			(at 0 -0.4445)
			(size 0.1397 0.1397)
			(layers "B.Cu" "B.Mask" "B.Paste")
			(net "PMU_PLTRST_N")
			(options
				(clearance outline)
				(anchor circle)
			)
			(primitives
				(gr_poly
					(pts
						(arc
							(start -0.1778 0.2794)
							(mid -0.249642 0.249642)
							(end -0.2794 0.1778)
						)
						(arc
							(start -0.2794 -0.1778)
							(mid -0.249642 -0.249642)
							(end -0.1778 -0.2794)
						)
						(arc
							(start 0.1778 -0.2794)
							(mid 0.249642 -0.249642)
							(end 0.2794 -0.1778)
						)
						(arc
							(start 0.2794 0.1778)
							(mid 0.249642 0.249642)
							(end 0.1778 0.2794)
						)
					)
					(width 0)
					(fill yes)
				)
			)
		)
		(pad "2" smd custom
			(at 0 0.4445)
			(size 0.1397 0.1397)
			(layers "B.Cu" "B.Mask" "B.Paste")
			(net "BMC0_PMU_PLTRST_N_BMC")
			(options
				(clearance outline)
				(anchor circle)
			)
			(primitives
				(gr_poly
					(pts
						(arc
							(start -0.1778 0.2794)
							(mid -0.249642 0.249642)
							(end -0.2794 0.1778)
						)
						(arc
							(start -0.2794 -0.1778)
							(mid -0.249642 -0.249642)
							(end -0.1778 -0.2794)
						)
						(arc
							(start 0.1778 -0.2794)
							(mid 0.249642 -0.249642)
							(end 0.2794 -0.1778)
						)
						(arc
							(start 0.2794 0.1778)
							(mid 0.249642 0.249642)
							(end 0.1778 0.2794)
						)
					)
					(width 0)
					(fill yes)
				)
			)
		)
	)
	(footprint ""
		(layer "B.Cu")
		(at 109.20476 -38.9382)
		(property "Reference" "SR665"
			(at 0 0 0)
			(layer "B.SilkS")
			(hide yes)
			(effects
				(font
					(size 1.27 1.27)
				)
				(justify mirror)
			)
		)
		(property "Value" "10KR2F-2-GP"
			(at -0.064008 -3.993896 0)
			(unlocked yes)
			(layer "B.Fab")
			(hide yes)
			(effects
				(font
					(size 1.016 1.016)
					(thickness 0.1524)
				)
				(justify mirror)
			)
		)
		(property "Device Type" "R402H16"
			(at -0.064008 -5.517896 0)
			(unlocked yes)
			(layer "B.Fab")
			(hide yes)
			(effects
				(font
					(size 1.016 1.016)
					(thickness 0.1524)
				)
				(justify mirror)
			)
		)
		(duplicate_pad_numbers_are_jumpers no)
		(fp_line
			(start -0.508 -0.9398)
			(end 0.508 -0.9398)
			(stroke
				(width 0.1524)
				(type default)
			)
			(layer "B.SilkS")
		)
		(fp_line
			(start 0.508 -0.9398)
			(end 0.508 0.9398)
			(stroke
				(width 0.1524)
				(type default)
			)
			(layer "B.SilkS")
		)
		(fp_rect
			(start 0.508 0.9398)
			(end -0.508 -0.9398)
			(stroke
				(width 0)
				(type default)
			)
			(fill no)
			(layer "B.CrtYd")
		)
		(fp_rect
			(start 0.508 0.9398)
			(end -0.508 -0.9398)
			(stroke
				(width 0)
				(type default)
			)
			(fill no)
			(layer "B.Fab")
		)
		(pad "1" smd custom
			(at 0 -0.4445 180)
			(size 0.1397 0.1397)
			(layers "B.Cu" "B.Mask" "B.Paste")
			(net "P1V8_C")
			(options
				(clearance outline)
				(anchor circle)
			)
			(primitives
				(gr_poly
					(pts
						(arc
							(start -0.1778 0.2794)
							(mid -0.249642 0.249642)
							(end -0.2794 0.1778)
						)
						(arc
							(start -0.2794 -0.1778)
							(mid -0.249642 -0.249642)
							(end -0.1778 -0.2794)
						)
						(arc
							(start 0.1778 -0.2794)
							(mid 0.249642 -0.249642)
							(end 0.2794 -0.1778)
						)
						(arc
							(start 0.2794 0.1778)
							(mid 0.249642 0.249642)
							(end 0.1778 0.2794)
						)
					)
					(width 0)
					(fill yes)
				)
			)
		)
		(pad "2" smd custom
			(at 0 0.4445 180)
			(size 0.1397 0.1397)
			(layers "B.Cu" "B.Mask" "B.Paste")
			(net "SYS_DBMODE0")
			(options
				(clearance outline)
				(anchor circle)
			)
			(primitives
				(gr_poly
					(pts
						(arc
							(start -0.1778 0.2794)
							(mid -0.249642 0.249642)
							(end -0.2794 0.1778)
						)
						(arc
							(start -0.2794 -0.1778)
							(mid -0.249642 -0.249642)
							(end -0.1778 -0.2794)
						)
						(arc
							(start 0.1778 -0.2794)
							(mid 0.249642 -0.249642)
							(end 0.2794 -0.1778)
						)
						(arc
							(start 0.2794 0.1778)
							(mid 0.249642 0.249642)
							(end 0.1778 0.2794)
						)
					)
					(width 0)
					(fill yes)
				)
			)
		)
	)
	(footprint ""
		(layer "B.Cu")
		(at 186.363864 -33.981136)
		(property "Reference" "C229"
			(at 0 0 0)
			(layer "B.SilkS")
			(hide yes)
			(effects
				(font
					(size 1.27 1.27)
				)
				(justify mirror)
			)
		)
		(property "Value" "SCD1U16V2KX-3GP"
			(at -1.1811 -2.7051 0)
			(unlocked yes)
			(layer "B.Fab")
			(hide yes)
			(effects
				(font
					(size 1.016 1.016)
					(thickness 0.1524)
				)
				(justify mirror)
			)
		)
		(property "Device Type" "C402H22"
			(at -1.1811 -4.2291 0)
			(unlocked yes)
			(layer "B.Fab")
			(hide yes)
			(effects
				(font
					(size 1.016 1.016)
					(thickness 0.1524)
				)
				(justify mirror)
			)
		)
		(duplicate_pad_numbers_are_jumpers no)
		(fp_rect
			(start 0.4318 0.9525)
			(end -0.4318 -0.9525)
			(stroke
				(width 0)
				(type default)
			)
			(fill no)
			(layer "B.CrtYd")
		)
		(fp_rect
			(start 0.4318 0.9525)
			(end -0.4318 -0.9525)
			(stroke
				(width 0)
				(type default)
			)
			(fill no)
			(layer "B.Fab")
		)
		(pad "1" smd custom
			(at 0 -0.4445 180)
			(size 0.1524 0.1524)
			(layers "B.Cu" "B.Mask" "B.Paste")
			(net "P3V3_STBY")
			(options
				(clearance outline)
				(anchor circle)
			)
			(primitives
				(gr_poly
					(pts
						(arc
							(start 0.3048 0.2032)
							(mid 0.275042 0.275042)
							(end 0.2032 0.3048)
						)
						(arc
							(start -0.2032 0.3048)
							(mid -0.275042 0.275042)
							(end -0.3048 0.2032)
						)
						(arc
							(start -0.3048 -0.2032)
							(mid -0.275042 -0.275042)
							(end -0.2032 -0.3048)
						)
						(arc
							(start 0.2032 -0.3048)
							(mid 0.275042 -0.275042)
							(end 0.3048 -0.2032)
						)
					)
					(width 0)
					(fill yes)
				)
			)
		)
		(pad "2" smd custom
			(at 0 0.4445 180)
			(size 0.1524 0.1524)
			(layers "B.Cu" "B.Mask" "B.Paste")
			(net "GND")
			(options
				(clearance outline)
				(anchor circle)
			)
			(primitives
				(gr_poly
					(pts
						(arc
							(start 0.3048 0.2032)
							(mid 0.275042 0.275042)
							(end 0.2032 0.3048)
						)
						(arc
							(start -0.2032 0.3048)
							(mid -0.275042 0.275042)
							(end -0.3048 0.2032)
						)
						(arc
							(start -0.3048 -0.2032)
							(mid -0.275042 -0.275042)
							(end -0.2032 -0.3048)
						)
						(arc
							(start 0.2032 -0.3048)
							(mid 0.275042 -0.275042)
							(end 0.3048 -0.2032)
						)
					)
					(width 0)
					(fill yes)
				)
			)
		)
	)
	(footprint ""
		(layer "B.Cu")
		(at 300.863 -185.547)
		(property "Reference" "TP145"
			(at 0 0 0)
			(layer "B.SilkS")
			(hide yes)
			(effects
				(font
					(size 1.27 1.27)
				)
				(justify mirror)
			)
		)
		(property "Value" "TPAD28"
			(at -0.0127 -1.8034 0)
			(unlocked yes)
			(layer "B.Fab")
			(hide yes)
			(effects
				(font
					(size 1.016 1.016)
					(thickness 0.1524)
				)
				(justify mirror)
			)
		)
		(property "Device Type" "TPAD28"
			(at -0.0127 -3.3274 0)
			(unlocked yes)
			(layer "B.Fab")
			(hide yes)
			(effects
				(font
					(size 1.016 1.016)
					(thickness 0.1524)
				)
				(justify mirror)
			)
		)
		(duplicate_pad_numbers_are_jumpers no)
		(fp_poly
			(pts
				(arc
					(start 0.3556 0)
					(mid -0.3556 0)
					(end 0.3556 0)
				)
			)
			(stroke
				(width 0)
				(type default)
			)
			(fill no)
			(layer "B.CrtYd")
		)
		(fp_poly
			(pts
				(arc
					(start 0.6096 0)
					(mid -0.6096 0)
					(end 0.6096 0)
				)
			)
			(stroke
				(width 0)
				(type default)
			)
			(fill no)
			(layer "B.Fab")
		)
		(pad "1" smd circle
			(at 0 0 180)
			(size 0.7112 0.7112)
			(layers "B.Cu" "B.Mask" "B.Paste")
			(net "TP_BMC0_TACH8")
		)
	)
	(footprint ""
		(layer "B.Cu")
		(at 21.739352 -216.726008 -90)
		(property "Reference" "SC634"
			(at 0 0 90)
			(layer "B.SilkS")
			(hide yes)
			(effects
				(font
					(size 1.27 1.27)
				)
				(justify mirror)
			)
		)
		(property "Value" "SCD1U16V2KX-3GP"
			(at -1.1811 -2.7051 270)
			(unlocked yes)
			(layer "B.Fab")
			(hide yes)
			(effects
				(font
					(size 1.016 1.016)
					(thickness 0.1524)
				)
				(justify mirror)
			)
		)
		(property "Device Type" "C402H22"
			(at -1.1811 -4.2291 270)
			(unlocked yes)
			(layer "B.Fab")
			(hide yes)
			(effects
				(font
					(size 1.016 1.016)
					(thickness 0.1524)
				)
				(justify mirror)
			)
		)
		(duplicate_pad_numbers_are_jumpers no)
		(fp_rect
			(start 0.4318 0.9525)
			(end -0.4318 -0.9525)
			(stroke
				(width 0)
				(type default)
			)
			(fill no)
			(layer "B.CrtYd")
		)
		(fp_rect
			(start 0.4318 0.9525)
			(end -0.4318 -0.9525)
			(stroke
				(width 0)
				(type default)
			)
			(fill no)
			(layer "B.Fab")
		)
		(pad "1" smd custom
			(at 0 -0.4445 90)
			(size 0.1524 0.1524)
			(layers "B.Cu" "B.Mask" "B.Paste")
			(net "P3V3_STBY")
			(options
				(clearance outline)
				(anchor circle)
			)
			(primitives
				(gr_poly
					(pts
						(arc
							(start 0.3048 0.2032)
							(mid 0.275042 0.275042)
							(end 0.2032 0.3048)
						)
						(arc
							(start -0.2032 0.3048)
							(mid -0.275042 0.275042)
							(end -0.3048 0.2032)
						)
						(arc
							(start -0.3048 -0.2032)
							(mid -0.275042 -0.275042)
							(end -0.2032 -0.3048)
						)
						(arc
							(start 0.2032 -0.3048)
							(mid 0.275042 -0.275042)
							(end 0.3048 -0.2032)
						)
					)
					(width 0)
					(fill yes)
				)
			)
		)
		(pad "2" smd custom
			(at 0 0.4445 90)
			(size 0.1524 0.1524)
			(layers "B.Cu" "B.Mask" "B.Paste")
			(net "GND")
			(options
				(clearance outline)
				(anchor circle)
			)
			(primitives
				(gr_poly
					(pts
						(arc
							(start 0.3048 0.2032)
							(mid 0.275042 0.275042)
							(end 0.2032 0.3048)
						)
						(arc
							(start -0.2032 0.3048)
							(mid -0.275042 0.275042)
							(end -0.3048 0.2032)
						)
						(arc
							(start -0.3048 -0.2032)
							(mid -0.275042 -0.275042)
							(end -0.2032 -0.3048)
						)
						(arc
							(start 0.2032 -0.3048)
							(mid 0.275042 -0.275042)
							(end 0.3048 -0.2032)
						)
					)
					(width 0)
					(fill yes)
				)
			)
		)
	)
	(footprint ""
		(layer "B.Cu")
		(at 30.811216 -203.38288 -90)
		(property "Reference" "C320"
			(at 0 0 90)
			(layer "B.SilkS")
			(hide yes)
			(effects
				(font
					(size 1.27 1.27)
				)
				(justify mirror)
			)
		)
		(property "Value" "SC1U10V2KX-4-GP"
			(at -1.1811 -2.7051 270)
			(unlocked yes)
			(layer "B.Fab")
			(hide yes)
			(effects
				(font
					(size 1.016 1.016)
					(thickness 0.1524)
				)
				(justify mirror)
			)
		)
		(property "Device Type" "C402H22"
			(at -1.1811 -4.2291 270)
			(unlocked yes)
			(layer "B.Fab")
			(hide yes)
			(effects
				(font
					(size 1.016 1.016)
					(thickness 0.1524)
				)
				(justify mirror)
			)
		)
		(duplicate_pad_numbers_are_jumpers no)
		(fp_rect
			(start 0.4318 0.9525)
			(end -0.4318 -0.9525)
			(stroke
				(width 0)
				(type default)
			)
			(fill no)
			(layer "B.CrtYd")
		)
		(fp_rect
			(start 0.4318 0.9525)
			(end -0.4318 -0.9525)
			(stroke
				(width 0)
				(type default)
			)
			(fill no)
			(layer "B.Fab")
		)
		(pad "1" smd custom
			(at 0 -0.4445 90)
			(size 0.1524 0.1524)
			(layers "B.Cu" "B.Mask" "B.Paste")
			(net "P3V3_STBY")
			(options
				(clearance outline)
				(anchor circle)
			)
			(primitives
				(gr_poly
					(pts
						(arc
							(start 0.3048 0.2032)
							(mid 0.275042 0.275042)
							(end 0.2032 0.3048)
						)
						(arc
							(start -0.2032 0.3048)
							(mid -0.275042 0.275042)
							(end -0.3048 0.2032)
						)
						(arc
							(start -0.3048 -0.2032)
							(mid -0.275042 -0.275042)
							(end -0.2032 -0.3048)
						)
						(arc
							(start 0.2032 -0.3048)
							(mid 0.275042 -0.275042)
							(end 0.3048 -0.2032)
						)
					)
					(width 0)
					(fill yes)
				)
			)
		)
		(pad "2" smd custom
			(at 0 0.4445 90)
			(size 0.1524 0.1524)
			(layers "B.Cu" "B.Mask" "B.Paste")
			(net "GND")
			(options
				(clearance outline)
				(anchor circle)
			)
			(primitives
				(gr_poly
					(pts
						(arc
							(start 0.3048 0.2032)
							(mid 0.275042 0.275042)
							(end 0.2032 0.3048)
						)
						(arc
							(start -0.2032 0.3048)
							(mid -0.275042 0.275042)
							(end -0.3048 0.2032)
						)
						(arc
							(start -0.3048 -0.2032)
							(mid -0.275042 -0.275042)
							(end -0.2032 -0.3048)
						)
						(arc
							(start 0.2032 -0.3048)
							(mid 0.275042 -0.275042)
							(end 0.3048 -0.2032)
						)
					)
					(width 0)
					(fill yes)
				)
			)
		)
	)
	(footprint ""
		(layer "B.Cu")
		(at 110.657386 -56.734456)
		(property "Reference" "STP158"
			(at 0 0 0)
			(layer "B.SilkS")
			(hide yes)
			(effects
				(font
					(size 1.27 1.27)
				)
				(justify mirror)
			)
		)
		(property "Value" "TPAD28"
			(at -0.0127 -1.8034 0)
			(unlocked yes)
			(layer "B.Fab")
			(hide yes)
			(effects
				(font
					(size 1.016 1.016)
					(thickness 0.1524)
				)
				(justify mirror)
			)
		)
		(property "Device Type" "TPAD28"
			(at -0.0127 -3.3274 0)
			(unlocked yes)
			(layer "B.Fab")
			(hide yes)
			(effects
				(font
					(size 1.016 1.016)
					(thickness 0.1524)
				)
				(justify mirror)
			)
		)
		(duplicate_pad_numbers_are_jumpers no)
		(fp_poly
			(pts
				(arc
					(start 0.3556 0)
					(mid -0.3556 0)
					(end 0.3556 0)
				)
			)
			(stroke
				(width 0)
				(type default)
			)
			(fill no)
			(layer "B.CrtYd")
		)
		(fp_poly
			(pts
				(arc
					(start 0.6096 0)
					(mid -0.6096 0)
					(end 0.6096 0)
				)
			)
			(stroke
				(width 0)
				(type default)
			)
			(fill no)
			(layer "B.Fab")
		)
		(pad "1" smd circle
			(at 0 0 180)
			(size 0.7112 0.7112)
			(layers "B.Cu" "B.Mask" "B.Paste")
			(net "XM_WP")
		)
	)
	(footprint ""
		(layer "B.Cu")
		(at 274.193 -173.609 90)
		(property "Reference" "R332"
			(at 0 0 90)
			(layer "B.SilkS")
			(hide yes)
			(effects
				(font
					(size 1.27 1.27)
				)
				(justify mirror)
			)
		)
		(property "Value" "0R2J-2-GP"
			(at -0.064008 -3.993896 90)
			(unlocked yes)
			(layer "B.Fab")
			(hide yes)
			(effects
				(font
					(size 1.016 1.016)
					(thickness 0.1524)
				)
				(justify mirror)
			)
		)
		(property "Device Type" "R402H16"
			(at -0.064008 -5.517896 90)
			(unlocked yes)
			(layer "B.Fab")
			(hide yes)
			(effects
				(font
					(size 1.016 1.016)
					(thickness 0.1524)
				)
				(justify mirror)
			)
		)
		(duplicate_pad_numbers_are_jumpers no)
		(fp_line
			(start 0.508 -0.9398)
			(end 0.508 0.9398)
			(stroke
				(width 0.1524)
				(type default)
			)
			(layer "B.SilkS")
		)
		(fp_line
			(start -0.508 -0.9398)
			(end 0.508 -0.9398)
			(stroke
				(width 0.1524)
				(type default)
			)
			(layer "B.SilkS")
		)
		(fp_rect
			(start 0.508 0.9398)
			(end -0.508 -0.9398)
			(stroke
				(width 0)
				(type default)
			)
			(fill no)
			(layer "B.CrtYd")
		)
		(fp_rect
			(start 0.508 0.9398)
			(end -0.508 -0.9398)
			(stroke
				(width 0)
				(type default)
			)
			(fill no)
			(layer "B.Fab")
		)
		(pad "1" smd custom
			(at 0 -0.4445 270)
			(size 0.1397 0.1397)
			(layers "B.Cu" "B.Mask" "B.Paste")
			(net "SAS_SEB_PEER_PRSNT_BMC")
			(options
				(clearance outline)
				(anchor circle)
			)
			(primitives
				(gr_poly
					(pts
						(arc
							(start -0.1778 0.2794)
							(mid -0.249642 0.249642)
							(end -0.2794 0.1778)
						)
						(arc
							(start -0.2794 -0.1778)
							(mid -0.249642 -0.249642)
							(end -0.1778 -0.2794)
						)
						(arc
							(start 0.1778 -0.2794)
							(mid 0.249642 -0.249642)
							(end 0.2794 -0.1778)
						)
						(arc
							(start 0.2794 0.1778)
							(mid 0.249642 0.249642)
							(end 0.1778 0.2794)
						)
					)
					(width 0)
					(fill yes)
				)
			)
		)
		(pad "2" smd custom
			(at 0 0.4445 270)
			(size 0.1397 0.1397)
			(layers "B.Cu" "B.Mask" "B.Paste")
			(net "MB0_PRESNET#")
			(options
				(clearance outline)
				(anchor circle)
			)
			(primitives
				(gr_poly
					(pts
						(arc
							(start -0.1778 0.2794)
							(mid -0.249642 0.249642)
							(end -0.2794 0.1778)
						)
						(arc
							(start -0.2794 -0.1778)
							(mid -0.249642 -0.249642)
							(end -0.1778 -0.2794)
						)
						(arc
							(start 0.1778 -0.2794)
							(mid 0.249642 -0.249642)
							(end 0.2794 -0.1778)
						)
						(arc
							(start 0.2794 0.1778)
							(mid 0.249642 0.249642)
							(end 0.1778 0.2794)
						)
					)
					(width 0)
					(fill yes)
				)
			)
		)
	)
	(footprint ""
		(layer "B.Cu")
		(at 103.432356 -50.3047 180)
		(property "Reference" "SC1038"
			(at 0 0 0)
			(layer "B.SilkS")
			(hide yes)
			(effects
				(font
					(size 1.27 1.27)
				)
				(justify mirror)
			)
		)
		(property "Value" "SCD1U16V2KX-3GP"
			(at -1.1811 -2.7051 180)
			(unlocked yes)
			(layer "B.Fab")
			(hide yes)
			(effects
				(font
					(size 1.016 1.016)
					(thickness 0.1524)
				)
				(justify mirror)
			)
		)
		(property "Device Type" "C402H22"
			(at -1.1811 -4.2291 180)
			(unlocked yes)
			(layer "B.Fab")
			(hide yes)
			(effects
				(font
					(size 1.016 1.016)
					(thickness 0.1524)
				)
				(justify mirror)
			)
		)
		(duplicate_pad_numbers_are_jumpers no)
		(fp_rect
			(start 0.4318 0.9525)
			(end -0.4318 -0.9525)
			(stroke
				(width 0)
				(type default)
			)
			(fill no)
			(layer "B.CrtYd")
		)
		(fp_rect
			(start 0.4318 0.9525)
			(end -0.4318 -0.9525)
			(stroke
				(width 0)
				(type default)
			)
			(fill no)
			(layer "B.Fab")
		)
		(pad "1" smd custom
			(at 0 -0.4445)
			(size 0.1524 0.1524)
			(layers "B.Cu" "B.Mask" "B.Paste")
			(net "P0V955_C")
			(options
				(clearance outline)
				(anchor circle)
			)
			(primitives
				(gr_poly
					(pts
						(arc
							(start 0.3048 0.2032)
							(mid 0.275042 0.275042)
							(end 0.2032 0.3048)
						)
						(arc
							(start -0.2032 0.3048)
							(mid -0.275042 0.275042)
							(end -0.3048 0.2032)
						)
						(arc
							(start -0.3048 -0.2032)
							(mid -0.275042 -0.275042)
							(end -0.2032 -0.3048)
						)
						(arc
							(start 0.2032 -0.3048)
							(mid 0.275042 -0.275042)
							(end 0.3048 -0.2032)
						)
					)
					(width 0)
					(fill yes)
				)
			)
		)
		(pad "2" smd custom
			(at 0 0.4445)
			(size 0.1524 0.1524)
			(layers "B.Cu" "B.Mask" "B.Paste")
			(net "GND")
			(options
				(clearance outline)
				(anchor circle)
			)
			(primitives
				(gr_poly
					(pts
						(arc
							(start 0.3048 0.2032)
							(mid 0.275042 0.275042)
							(end 0.2032 0.3048)
						)
						(arc
							(start -0.2032 0.3048)
							(mid -0.275042 0.275042)
							(end -0.3048 0.2032)
						)
						(arc
							(start -0.3048 -0.2032)
							(mid -0.275042 -0.275042)
							(end -0.2032 -0.3048)
						)
						(arc
							(start 0.2032 -0.3048)
							(mid 0.275042 -0.275042)
							(end 0.3048 -0.2032)
						)
					)
					(width 0)
					(fill yes)
				)
			)
		)
	)
	(footprint ""
		(layer "B.Cu")
		(at 109.97057 -91.27998 -90)
		(property "Reference" "SC1250"
			(at 0 0 90)
			(layer "B.SilkS")
			(hide yes)
			(effects
				(font
					(size 1.27 1.27)
				)
				(justify mirror)
			)
		)
		(property "Value" "SCD1U6D3V1KX-GP"
			(at 2.8321 -1.7399 270)
			(unlocked yes)
			(layer "B.Fab")
			(hide yes)
			(effects
				(font
					(size 1.016 1.016)
					(thickness 0.1524)
				)
				(justify mirror)
			)
		)
		(property "Device Type" "C0201H13"
			(at 2.8321 -3.2639 270)
			(unlocked yes)
			(layer "B.Fab")
			(hide yes)
			(effects
				(font
					(size 1.016 1.016)
					(thickness 0.1524)
				)
				(justify mirror)
			)
		)
		(duplicate_pad_numbers_are_jumpers no)
		(fp_rect
			(start 0.2794 0.6477)
			(end -0.2794 -0.6477)
			(stroke
				(width 0)
				(type default)
			)
			(fill no)
			(layer "B.CrtYd")
		)
		(fp_rect
			(start 0.2794 0.6477)
			(end -0.2794 -0.6477)
			(stroke
				(width 0)
				(type default)
			)
			(fill no)
			(layer "B.Fab")
		)
		(pad "1" smd custom
			(at 0 -0.2794 90)
			(size 0.0762 0.0762)
			(layers "B.Cu" "B.Mask" "B.Paste")
			(net "P0V9_E")
			(options
				(clearance outline)
				(anchor circle)
			)
			(primitives
				(gr_poly
					(pts
						(arc
							(start 0.1524 0.127)
							(mid 0.137521 0.162921)
							(end 0.1016 0.1778)
						)
						(arc
							(start -0.1016 0.1778)
							(mid -0.137521 0.162921)
							(end -0.1524 0.127)
						)
						(arc
							(start -0.1524 -0.127)
							(mid -0.137521 -0.162921)
							(end -0.1016 -0.1778)
						)
						(arc
							(start 0.1016 -0.1778)
							(mid 0.137521 -0.162921)
							(end 0.1524 -0.127)
						)
					)
					(width 0)
					(fill yes)
				)
			)
		)
		(pad "2" smd custom
			(at 0 0.2794 90)
			(size 0.0762 0.0762)
			(layers "B.Cu" "B.Mask" "B.Paste")
			(net "GND")
			(options
				(clearance outline)
				(anchor circle)
			)
			(primitives
				(gr_poly
					(pts
						(arc
							(start 0.1524 0.127)
							(mid 0.137521 0.162921)
							(end 0.1016 0.1778)
						)
						(arc
							(start -0.1016 0.1778)
							(mid -0.137521 0.162921)
							(end -0.1524 0.127)
						)
						(arc
							(start -0.1524 -0.127)
							(mid -0.137521 -0.162921)
							(end -0.1016 -0.1778)
						)
						(arc
							(start 0.1016 -0.1778)
							(mid 0.137521 -0.162921)
							(end 0.1524 -0.127)
						)
					)
					(width 0)
					(fill yes)
				)
			)
		)
	)
	(footprint ""
		(layer "B.Cu")
		(at 116.059966 -36.322)
		(property "Reference" "STP135"
			(at 0 0 0)
			(layer "B.SilkS")
			(hide yes)
			(effects
				(font
					(size 1.27 1.27)
				)
				(justify mirror)
			)
		)
		(property "Value" "TPAD28"
			(at -0.0127 -1.8034 0)
			(unlocked yes)
			(layer "B.Fab")
			(hide yes)
			(effects
				(font
					(size 1.016 1.016)
					(thickness 0.1524)
				)
				(justify mirror)
			)
		)
		(property "Device Type" "TPAD28"
			(at -0.0127 -3.3274 0)
			(unlocked yes)
			(layer "B.Fab")
			(hide yes)
			(effects
				(font
					(size 1.016 1.016)
					(thickness 0.1524)
				)
				(justify mirror)
			)
		)
		(duplicate_pad_numbers_are_jumpers no)
		(fp_poly
			(pts
				(arc
					(start 0.3556 0)
					(mid -0.3556 0)
					(end 0.3556 0)
				)
			)
			(stroke
				(width 0)
				(type default)
			)
			(fill no)
			(layer "B.CrtYd")
		)
		(fp_poly
			(pts
				(arc
					(start 0.6096 0)
					(mid -0.6096 0)
					(end 0.6096 0)
				)
			)
			(stroke
				(width 0)
				(type default)
			)
			(fill no)
			(layer "B.Fab")
		)
		(pad "1" smd circle
			(at 0 0 180)
			(size 0.7112 0.7112)
			(layers "B.Cu" "B.Mask" "B.Paste")
			(net "IOC_GPIO_17")
		)
	)
	(footprint ""
		(layer "B.Cu")
		(at 15.833344 -176.149762 90)
		(property "Reference" "SC1115"
			(at 0 0 90)
			(layer "B.SilkS")
			(hide yes)
			(effects
				(font
					(size 1.27 1.27)
				)
				(justify mirror)
			)
		)
		(property "Value" "SCD1U16V2KX-3GP"
			(at -1.1811 -2.7051 90)
			(unlocked yes)
			(layer "B.Fab")
			(hide yes)
			(effects
				(font
					(size 1.016 1.016)
					(thickness 0.1524)
				)
				(justify mirror)
			)
		)
		(property "Device Type" "C402H22"
			(at -1.1811 -4.2291 90)
			(unlocked yes)
			(layer "B.Fab")
			(hide yes)
			(effects
				(font
					(size 1.016 1.016)
					(thickness 0.1524)
				)
				(justify mirror)
			)
		)
		(duplicate_pad_numbers_are_jumpers no)
		(fp_rect
			(start 0.4318 0.9525)
			(end -0.4318 -0.9525)
			(stroke
				(width 0)
				(type default)
			)
			(fill no)
			(layer "B.CrtYd")
		)
		(fp_rect
			(start 0.4318 0.9525)
			(end -0.4318 -0.9525)
			(stroke
				(width 0)
				(type default)
			)
			(fill no)
			(layer "B.Fab")
		)
		(pad "1" smd custom
			(at 0 -0.4445 270)
			(size 0.1524 0.1524)
			(layers "B.Cu" "B.Mask" "B.Paste")
			(net "P3V3_STBY")
			(options
				(clearance outline)
				(anchor circle)
			)
			(primitives
				(gr_poly
					(pts
						(arc
							(start 0.3048 0.2032)
							(mid 0.275042 0.275042)
							(end 0.2032 0.3048)
						)
						(arc
							(start -0.2032 0.3048)
							(mid -0.275042 0.275042)
							(end -0.3048 0.2032)
						)
						(arc
							(start -0.3048 -0.2032)
							(mid -0.275042 -0.275042)
							(end -0.2032 -0.3048)
						)
						(arc
							(start 0.2032 -0.3048)
							(mid 0.275042 -0.275042)
							(end 0.3048 -0.2032)
						)
					)
					(width 0)
					(fill yes)
				)
			)
		)
		(pad "2" smd custom
			(at 0 0.4445 270)
			(size 0.1524 0.1524)
			(layers "B.Cu" "B.Mask" "B.Paste")
			(net "GND")
			(options
				(clearance outline)
				(anchor circle)
			)
			(primitives
				(gr_poly
					(pts
						(arc
							(start 0.3048 0.2032)
							(mid 0.275042 0.275042)
							(end 0.2032 0.3048)
						)
						(arc
							(start -0.2032 0.3048)
							(mid -0.275042 0.275042)
							(end -0.3048 0.2032)
						)
						(arc
							(start -0.3048 -0.2032)
							(mid -0.275042 -0.275042)
							(end -0.2032 -0.3048)
						)
						(arc
							(start 0.2032 -0.3048)
							(mid 0.275042 -0.275042)
							(end 0.3048 -0.2032)
						)
					)
					(width 0)
					(fill yes)
				)
			)
		)
	)
	(footprint ""
		(layer "B.Cu")
		(at 120.015 -36.703 -90)
		(property "Reference" "SR624"
			(at 0 0 90)
			(layer "B.SilkS")
			(hide yes)
			(effects
				(font
					(size 1.27 1.27)
				)
				(justify mirror)
			)
		)
		(property "Value" "2K2R2F-GP"
			(at -0.064008 -3.993896 270)
			(unlocked yes)
			(layer "B.Fab")
			(hide yes)
			(effects
				(font
					(size 1.016 1.016)
					(thickness 0.1524)
				)
				(justify mirror)
			)
		)
		(property "Device Type" "R402H16"
			(at -0.064008 -5.517896 270)
			(unlocked yes)
			(layer "B.Fab")
			(hide yes)
			(effects
				(font
					(size 1.016 1.016)
					(thickness 0.1524)
				)
				(justify mirror)
			)
		)
		(duplicate_pad_numbers_are_jumpers no)
		(fp_line
			(start -0.508 -0.9398)
			(end 0.508 -0.9398)
			(stroke
				(width 0.1524)
				(type default)
			)
			(layer "B.SilkS")
		)
		(fp_line
			(start 0.508 -0.9398)
			(end 0.508 0.9398)
			(stroke
				(width 0.1524)
				(type default)
			)
			(layer "B.SilkS")
		)
		(fp_rect
			(start 0.508 0.9398)
			(end -0.508 -0.9398)
			(stroke
				(width 0)
				(type default)
			)
			(fill no)
			(layer "B.CrtYd")
		)
		(fp_rect
			(start 0.508 0.9398)
			(end -0.508 -0.9398)
			(stroke
				(width 0)
				(type default)
			)
			(fill no)
			(layer "B.Fab")
		)
		(pad "1" smd custom
			(at 0 -0.4445 90)
			(size 0.1397 0.1397)
			(layers "B.Cu" "B.Mask" "B.Paste")
			(net "P1V8_C")
			(options
				(clearance outline)
				(anchor circle)
			)
			(primitives
				(gr_poly
					(pts
						(arc
							(start -0.1778 0.2794)
							(mid -0.249642 0.249642)
							(end -0.2794 0.1778)
						)
						(arc
							(start -0.2794 -0.1778)
							(mid -0.249642 -0.249642)
							(end -0.1778 -0.2794)
						)
						(arc
							(start 0.1778 -0.2794)
							(mid 0.249642 -0.249642)
							(end 0.2794 -0.1778)
						)
						(arc
							(start 0.2794 0.1778)
							(mid 0.249642 0.249642)
							(end 0.1778 0.2794)
						)
					)
					(width 0)
					(fill yes)
				)
			)
		)
		(pad "2" smd custom
			(at 0 0.4445 90)
			(size 0.1397 0.1397)
			(layers "B.Cu" "B.Mask" "B.Paste")
			(net "IOC_SCL_4")
			(options
				(clearance outline)
				(anchor circle)
			)
			(primitives
				(gr_poly
					(pts
						(arc
							(start -0.1778 0.2794)
							(mid -0.249642 0.249642)
							(end -0.2794 0.1778)
						)
						(arc
							(start -0.2794 -0.1778)
							(mid -0.249642 -0.249642)
							(end -0.1778 -0.2794)
						)
						(arc
							(start 0.1778 -0.2794)
							(mid 0.249642 -0.249642)
							(end 0.2794 -0.1778)
						)
						(arc
							(start 0.2794 0.1778)
							(mid 0.249642 0.249642)
							(end 0.1778 0.2794)
						)
					)
					(width 0)
					(fill yes)
				)
			)
		)
	)
	(footprint ""
		(layer "B.Cu")
		(at 299.212 -178.1302 -90)
		(property "Reference" "C208"
			(at 0 0 90)
			(layer "B.SilkS")
			(hide yes)
			(effects
				(font
					(size 1.27 1.27)
				)
				(justify mirror)
			)
		)
		(property "Value" "SC1U10V2KX-1GP"
			(at -1.1811 -2.7051 270)
			(unlocked yes)
			(layer "B.Fab")
			(hide yes)
			(effects
				(font
					(size 1.016 1.016)
					(thickness 0.1524)
				)
				(justify mirror)
			)
		)
		(property "Device Type" "C402H22"
			(at -1.1811 -4.2291 270)
			(unlocked yes)
			(layer "B.Fab")
			(hide yes)
			(effects
				(font
					(size 1.016 1.016)
					(thickness 0.1524)
				)
				(justify mirror)
			)
		)
		(duplicate_pad_numbers_are_jumpers no)
		(fp_rect
			(start 0.4318 0.9525)
			(end -0.4318 -0.9525)
			(stroke
				(width 0)
				(type default)
			)
			(fill no)
			(layer "B.CrtYd")
		)
		(fp_rect
			(start 0.4318 0.9525)
			(end -0.4318 -0.9525)
			(stroke
				(width 0)
				(type default)
			)
			(fill no)
			(layer "B.Fab")
		)
		(pad "1" smd custom
			(at 0 -0.4445 90)
			(size 0.1524 0.1524)
			(layers "B.Cu" "B.Mask" "B.Paste")
			(net "P3V3_STBY")
			(options
				(clearance outline)
				(anchor circle)
			)
			(primitives
				(gr_poly
					(pts
						(arc
							(start 0.3048 0.2032)
							(mid 0.275042 0.275042)
							(end 0.2032 0.3048)
						)
						(arc
							(start -0.2032 0.3048)
							(mid -0.275042 0.275042)
							(end -0.3048 0.2032)
						)
						(arc
							(start -0.3048 -0.2032)
							(mid -0.275042 -0.275042)
							(end -0.2032 -0.3048)
						)
						(arc
							(start 0.2032 -0.3048)
							(mid 0.275042 -0.275042)
							(end 0.3048 -0.2032)
						)
					)
					(width 0)
					(fill yes)
				)
			)
		)
		(pad "2" smd custom
			(at 0 0.4445 90)
			(size 0.1524 0.1524)
			(layers "B.Cu" "B.Mask" "B.Paste")
			(net "GND")
			(options
				(clearance outline)
				(anchor circle)
			)
			(primitives
				(gr_poly
					(pts
						(arc
							(start 0.3048 0.2032)
							(mid 0.275042 0.275042)
							(end 0.2032 0.3048)
						)
						(arc
							(start -0.2032 0.3048)
							(mid -0.275042 0.275042)
							(end -0.3048 0.2032)
						)
						(arc
							(start -0.3048 -0.2032)
							(mid -0.275042 -0.275042)
							(end -0.2032 -0.3048)
						)
						(arc
							(start 0.2032 -0.3048)
							(mid 0.275042 -0.275042)
							(end 0.3048 -0.2032)
						)
					)
					(width 0)
					(fill yes)
				)
			)
		)
	)
	(footprint ""
		(layer "B.Cu")
		(at 109.23016 -32.639)
		(property "Reference" "STP46"
			(at 0 0 0)
			(layer "B.SilkS")
			(hide yes)
			(effects
				(font
					(size 1.27 1.27)
				)
				(justify mirror)
			)
		)
		(property "Value" "TPAD28"
			(at -0.0127 -1.8034 0)
			(unlocked yes)
			(layer "B.Fab")
			(hide yes)
			(effects
				(font
					(size 1.016 1.016)
					(thickness 0.1524)
				)
				(justify mirror)
			)
		)
		(property "Device Type" "TPAD28"
			(at -0.0127 -3.3274 0)
			(unlocked yes)
			(layer "B.Fab")
			(hide yes)
			(effects
				(font
					(size 1.016 1.016)
					(thickness 0.1524)
				)
				(justify mirror)
			)
		)
		(duplicate_pad_numbers_are_jumpers no)
		(fp_poly
			(pts
				(arc
					(start 0.3556 0)
					(mid -0.3556 0)
					(end 0.3556 0)
				)
			)
			(stroke
				(width 0)
				(type default)
			)
			(fill no)
			(layer "B.CrtYd")
		)
		(fp_poly
			(pts
				(arc
					(start 0.6096 0)
					(mid -0.6096 0)
					(end 0.6096 0)
				)
			)
			(stroke
				(width 0)
				(type default)
			)
			(fill no)
			(layer "B.Fab")
		)
		(pad "1" smd circle
			(at 0 0 180)
			(size 0.7112 0.7112)
			(layers "B.Cu" "B.Mask" "B.Paste")
			(net "IOC_GPIO_6")
		)
	)
	(footprint ""
		(layer "B.Cu")
		(at 324.358 -182.372)
		(property "Reference" "R5762"
			(at 0 0 0)
			(layer "B.SilkS")
			(hide yes)
			(effects
				(font
					(size 1.27 1.27)
				)
				(justify mirror)
			)
		)
		(property "Value" "1KR2F-3-GP"
			(at -0.064008 -3.993896 0)
			(unlocked yes)
			(layer "B.Fab")
			(hide yes)
			(effects
				(font
					(size 1.016 1.016)
					(thickness 0.1524)
				)
				(justify mirror)
			)
		)
		(property "Device Type" "R402H16"
			(at -0.064008 -5.517896 0)
			(unlocked yes)
			(layer "B.Fab")
			(hide yes)
			(effects
				(font
					(size 1.016 1.016)
					(thickness 0.1524)
				)
				(justify mirror)
			)
		)
		(duplicate_pad_numbers_are_jumpers no)
		(fp_line
			(start -0.508 -0.9398)
			(end 0.508 -0.9398)
			(stroke
				(width 0.1524)
				(type default)
			)
			(layer "B.SilkS")
		)
		(fp_line
			(start 0.508 -0.9398)
			(end 0.508 0.9398)
			(stroke
				(width 0.1524)
				(type default)
			)
			(layer "B.SilkS")
		)
		(fp_rect
			(start 0.508 0.9398)
			(end -0.508 -0.9398)
			(stroke
				(width 0)
				(type default)
			)
			(fill no)
			(layer "B.CrtYd")
		)
		(fp_rect
			(start 0.508 0.9398)
			(end -0.508 -0.9398)
			(stroke
				(width 0)
				(type default)
			)
			(fill no)
			(layer "B.Fab")
		)
		(pad "1" smd custom
			(at 0 -0.4445 180)
			(size 0.1397 0.1397)
			(layers "B.Cu" "B.Mask" "B.Paste")
			(net "ADC_P0V955_C")
			(options
				(clearance outline)
				(anchor circle)
			)
			(primitives
				(gr_poly
					(pts
						(arc
							(start -0.1778 0.2794)
							(mid -0.249642 0.249642)
							(end -0.2794 0.1778)
						)
						(arc
							(start -0.2794 -0.1778)
							(mid -0.249642 -0.249642)
							(end -0.1778 -0.2794)
						)
						(arc
							(start 0.1778 -0.2794)
							(mid 0.249642 -0.249642)
							(end 0.2794 -0.1778)
						)
						(arc
							(start 0.2794 0.1778)
							(mid 0.249642 0.249642)
							(end 0.1778 0.2794)
						)
					)
					(width 0)
					(fill yes)
				)
			)
		)
		(pad "2" smd custom
			(at 0 0.4445 180)
			(size 0.1397 0.1397)
			(layers "B.Cu" "B.Mask" "B.Paste")
			(net "GND")
			(options
				(clearance outline)
				(anchor circle)
			)
			(primitives
				(gr_poly
					(pts
						(arc
							(start -0.1778 0.2794)
							(mid -0.249642 0.249642)
							(end -0.2794 0.1778)
						)
						(arc
							(start -0.2794 -0.1778)
							(mid -0.249642 -0.249642)
							(end -0.1778 -0.2794)
						)
						(arc
							(start 0.1778 -0.2794)
							(mid 0.249642 -0.249642)
							(end 0.2794 -0.1778)
						)
						(arc
							(start 0.2794 0.1778)
							(mid 0.249642 0.249642)
							(end 0.1778 0.2794)
						)
					)
					(width 0)
					(fill yes)
				)
			)
		)
	)
	(footprint ""
		(layer "B.Cu")
		(at 100.21697 -108.204)
		(property "Reference" "TP264"
			(at 0 0 0)
			(layer "B.SilkS")
			(hide yes)
			(effects
				(font
					(size 1.27 1.27)
				)
				(justify mirror)
			)
		)
		(property "Value" "TPAD28"
			(at -0.0127 -1.8034 0)
			(unlocked yes)
			(layer "B.Fab")
			(hide yes)
			(effects
				(font
					(size 1.016 1.016)
					(thickness 0.1524)
				)
				(justify mirror)
			)
		)
		(property "Device Type" "TPAD28"
			(at -0.0127 -3.3274 0)
			(unlocked yes)
			(layer "B.Fab")
			(hide yes)
			(effects
				(font
					(size 1.016 1.016)
					(thickness 0.1524)
				)
				(justify mirror)
			)
		)
		(duplicate_pad_numbers_are_jumpers no)
		(fp_poly
			(pts
				(arc
					(start 0.3556 0)
					(mid -0.3556 0)
					(end 0.3556 0)
				)
			)
			(stroke
				(width 0)
				(type default)
			)
			(fill no)
			(layer "B.CrtYd")
		)
		(fp_poly
			(pts
				(arc
					(start 0.6096 0)
					(mid -0.6096 0)
					(end 0.6096 0)
				)
			)
			(stroke
				(width 0)
				(type default)
			)
			(fill no)
			(layer "B.Fab")
		)
		(pad "1" smd circle
			(at 0 0 180)
			(size 0.7112 0.7112)
			(layers "B.Cu" "B.Mask" "B.Paste")
			(net "SIO_D_OUT")
		)
	)
	(footprint ""
		(layer "B.Cu")
		(at 162.814 -120.396)
		(property "Reference" "SR858"
			(at 0 0 0)
			(layer "B.SilkS")
			(hide yes)
			(effects
				(font
					(size 1.27 1.27)
				)
				(justify mirror)
			)
		)
		(property "Value" "0R2J-2-GP"
			(at -0.064008 -3.993896 0)
			(unlocked yes)
			(layer "B.Fab")
			(hide yes)
			(effects
				(font
					(size 1.016 1.016)
					(thickness 0.1524)
				)
				(justify mirror)
			)
		)
		(property "Device Type" "R402H16"
			(at -0.064008 -5.517896 0)
			(unlocked yes)
			(layer "B.Fab")
			(hide yes)
			(effects
				(font
					(size 1.016 1.016)
					(thickness 0.1524)
				)
				(justify mirror)
			)
		)
		(duplicate_pad_numbers_are_jumpers no)
		(fp_line
			(start -0.508 -0.9398)
			(end 0.508 -0.9398)
			(stroke
				(width 0.1524)
				(type default)
			)
			(layer "B.SilkS")
		)
		(fp_line
			(start 0.508 -0.9398)
			(end 0.508 0.9398)
			(stroke
				(width 0.1524)
				(type default)
			)
			(layer "B.SilkS")
		)
		(fp_rect
			(start 0.508 0.9398)
			(end -0.508 -0.9398)
			(stroke
				(width 0)
				(type default)
			)
			(fill no)
			(layer "B.CrtYd")
		)
		(fp_rect
			(start 0.508 0.9398)
			(end -0.508 -0.9398)
			(stroke
				(width 0)
				(type default)
			)
			(fill no)
			(layer "B.Fab")
		)
		(pad "1" smd custom
			(at 0 -0.4445 180)
			(size 0.1397 0.1397)
			(layers "B.Cu" "B.Mask" "B.Paste")
			(net "EXP_RESET_MR_N")
			(options
				(clearance outline)
				(anchor circle)
			)
			(primitives
				(gr_poly
					(pts
						(arc
							(start -0.1778 0.2794)
							(mid -0.249642 0.249642)
							(end -0.2794 0.1778)
						)
						(arc
							(start -0.2794 -0.1778)
							(mid -0.249642 -0.249642)
							(end -0.1778 -0.2794)
						)
						(arc
							(start 0.1778 -0.2794)
							(mid 0.249642 -0.249642)
							(end 0.2794 -0.1778)
						)
						(arc
							(start 0.2794 0.1778)
							(mid 0.249642 0.249642)
							(end 0.1778 0.2794)
						)
					)
					(width 0)
					(fill yes)
				)
			)
		)
		(pad "2" smd custom
			(at 0 0.4445 180)
			(size 0.1397 0.1397)
			(layers "B.Cu" "B.Mask" "B.Paste")
			(net "EXP_RST")
			(options
				(clearance outline)
				(anchor circle)
			)
			(primitives
				(gr_poly
					(pts
						(arc
							(start -0.1778 0.2794)
							(mid -0.249642 0.249642)
							(end -0.2794 0.1778)
						)
						(arc
							(start -0.2794 -0.1778)
							(mid -0.249642 -0.249642)
							(end -0.1778 -0.2794)
						)
						(arc
							(start 0.1778 -0.2794)
							(mid 0.249642 -0.249642)
							(end 0.2794 -0.1778)
						)
						(arc
							(start 0.2794 0.1778)
							(mid 0.249642 0.249642)
							(end 0.1778 0.2794)
						)
					)
					(width 0)
					(fill yes)
				)
			)
		)
	)
	(footprint ""
		(layer "B.Cu")
		(at 110.50397 -72.644 180)
		(property "Reference" "SR731"
			(at 0 0 0)
			(layer "B.SilkS")
			(hide yes)
			(effects
				(font
					(size 1.27 1.27)
				)
				(justify mirror)
			)
		)
		(property "Value" "150R2F-1-GP"
			(at -0.064008 -3.993896 180)
			(unlocked yes)
			(layer "B.Fab")
			(hide yes)
			(effects
				(font
					(size 1.016 1.016)
					(thickness 0.1524)
				)
				(justify mirror)
			)
		)
		(property "Device Type" "R402H16"
			(at -0.064008 -5.517896 180)
			(unlocked yes)
			(layer "B.Fab")
			(hide yes)
			(effects
				(font
					(size 1.016 1.016)
					(thickness 0.1524)
				)
				(justify mirror)
			)
		)
		(duplicate_pad_numbers_are_jumpers no)
		(fp_line
			(start 0.508 -0.9398)
			(end 0.508 0.9398)
			(stroke
				(width 0.1524)
				(type default)
			)
			(layer "B.SilkS")
		)
		(fp_line
			(start -0.508 -0.9398)
			(end 0.508 -0.9398)
			(stroke
				(width 0.1524)
				(type default)
			)
			(layer "B.SilkS")
		)
		(fp_rect
			(start 0.508 0.9398)
			(end -0.508 -0.9398)
			(stroke
				(width 0)
				(type default)
			)
			(fill no)
			(layer "B.CrtYd")
		)
		(fp_rect
			(start 0.508 0.9398)
			(end -0.508 -0.9398)
			(stroke
				(width 0)
				(type default)
			)
			(fill no)
			(layer "B.Fab")
		)
		(pad "1" smd custom
			(at 0 -0.4445)
			(size 0.1397 0.1397)
			(layers "B.Cu" "B.Mask" "B.Paste")
			(net "P3V3_STBY")
			(options
				(clearance outline)
				(anchor circle)
			)
			(primitives
				(gr_poly
					(pts
						(arc
							(start -0.1778 0.2794)
							(mid -0.249642 0.249642)
							(end -0.2794 0.1778)
						)
						(arc
							(start -0.2794 -0.1778)
							(mid -0.249642 -0.249642)
							(end -0.1778 -0.2794)
						)
						(arc
							(start 0.1778 -0.2794)
							(mid 0.249642 -0.249642)
							(end 0.2794 -0.1778)
						)
						(arc
							(start 0.2794 0.1778)
							(mid 0.249642 0.249642)
							(end 0.1778 0.2794)
						)
					)
					(width 0)
					(fill yes)
				)
			)
		)
		(pad "2" smd custom
			(at 0 0.4445)
			(size 0.1397 0.1397)
			(layers "B.Cu" "B.Mask" "B.Paste")
			(net "EXP_HW_LED_R")
			(options
				(clearance outline)
				(anchor circle)
			)
			(primitives
				(gr_poly
					(pts
						(arc
							(start -0.1778 0.2794)
							(mid -0.249642 0.249642)
							(end -0.2794 0.1778)
						)
						(arc
							(start -0.2794 -0.1778)
							(mid -0.249642 -0.249642)
							(end -0.1778 -0.2794)
						)
						(arc
							(start 0.1778 -0.2794)
							(mid 0.249642 -0.249642)
							(end 0.2794 -0.1778)
						)
						(arc
							(start 0.2794 0.1778)
							(mid 0.249642 0.249642)
							(end 0.1778 0.2794)
						)
					)
					(width 0)
					(fill yes)
				)
			)
		)
	)
	(footprint ""
		(layer "B.Cu")
		(at 110.725966 -45.0596 -90)
		(property "Reference" "SC990"
			(at 0 0 90)
			(layer "B.SilkS")
			(hide yes)
			(effects
				(font
					(size 1.27 1.27)
				)
				(justify mirror)
			)
		)
		(property "Value" "SCD1U16V2KX-3GP"
			(at -1.1811 -2.7051 270)
			(unlocked yes)
			(layer "B.Fab")
			(hide yes)
			(effects
				(font
					(size 1.016 1.016)
					(thickness 0.1524)
				)
				(justify mirror)
			)
		)
		(property "Device Type" "C402H22"
			(at -1.1811 -4.2291 270)
			(unlocked yes)
			(layer "B.Fab")
			(hide yes)
			(effects
				(font
					(size 1.016 1.016)
					(thickness 0.1524)
				)
				(justify mirror)
			)
		)
		(duplicate_pad_numbers_are_jumpers no)
		(fp_rect
			(start 0.4318 0.9525)
			(end -0.4318 -0.9525)
			(stroke
				(width 0)
				(type default)
			)
			(fill no)
			(layer "B.CrtYd")
		)
		(fp_rect
			(start 0.4318 0.9525)
			(end -0.4318 -0.9525)
			(stroke
				(width 0)
				(type default)
			)
			(fill no)
			(layer "B.Fab")
		)
		(pad "1" smd custom
			(at 0 -0.4445 90)
			(size 0.1524 0.1524)
			(layers "B.Cu" "B.Mask" "B.Paste")
			(net "P1V8_C")
			(options
				(clearance outline)
				(anchor circle)
			)
			(primitives
				(gr_poly
					(pts
						(arc
							(start 0.3048 0.2032)
							(mid 0.275042 0.275042)
							(end 0.2032 0.3048)
						)
						(arc
							(start -0.2032 0.3048)
							(mid -0.275042 0.275042)
							(end -0.3048 0.2032)
						)
						(arc
							(start -0.3048 -0.2032)
							(mid -0.275042 -0.275042)
							(end -0.2032 -0.3048)
						)
						(arc
							(start 0.2032 -0.3048)
							(mid 0.275042 -0.275042)
							(end 0.3048 -0.2032)
						)
					)
					(width 0)
					(fill yes)
				)
			)
		)
		(pad "2" smd custom
			(at 0 0.4445 90)
			(size 0.1524 0.1524)
			(layers "B.Cu" "B.Mask" "B.Paste")
			(net "GND")
			(options
				(clearance outline)
				(anchor circle)
			)
			(primitives
				(gr_poly
					(pts
						(arc
							(start 0.3048 0.2032)
							(mid 0.275042 0.275042)
							(end 0.2032 0.3048)
						)
						(arc
							(start -0.2032 0.3048)
							(mid -0.275042 0.275042)
							(end -0.3048 0.2032)
						)
						(arc
							(start -0.3048 -0.2032)
							(mid -0.275042 -0.275042)
							(end -0.2032 -0.3048)
						)
						(arc
							(start 0.2032 -0.3048)
							(mid 0.275042 -0.275042)
							(end 0.3048 -0.2032)
						)
					)
					(width 0)
					(fill yes)
				)
			)
		)
	)
	(footprint ""
		(layer "B.Cu")
		(at 287.782 -166.878)
		(property "Reference" "TP134"
			(at 0 0 0)
			(layer "B.SilkS")
			(hide yes)
			(effects
				(font
					(size 1.27 1.27)
				)
				(justify mirror)
			)
		)
		(property "Value" "TPAD28"
			(at -0.0127 -1.8034 0)
			(unlocked yes)
			(layer "B.Fab")
			(hide yes)
			(effects
				(font
					(size 1.016 1.016)
					(thickness 0.1524)
				)
				(justify mirror)
			)
		)
		(property "Device Type" "TPAD28"
			(at -0.0127 -3.3274 0)
			(unlocked yes)
			(layer "B.Fab")
			(hide yes)
			(effects
				(font
					(size 1.016 1.016)
					(thickness 0.1524)
				)
				(justify mirror)
			)
		)
		(duplicate_pad_numbers_are_jumpers no)
		(fp_poly
			(pts
				(arc
					(start 0.3556 0)
					(mid -0.3556 0)
					(end 0.3556 0)
				)
			)
			(stroke
				(width 0)
				(type default)
			)
			(fill no)
			(layer "B.CrtYd")
		)
		(fp_poly
			(pts
				(arc
					(start 0.6096 0)
					(mid -0.6096 0)
					(end 0.6096 0)
				)
			)
			(stroke
				(width 0)
				(type default)
			)
			(fill no)
			(layer "B.Fab")
		)
		(pad "1" smd circle
			(at 0 0 180)
			(size 0.7112 0.7112)
			(layers "B.Cu" "B.Mask" "B.Paste")
			(net "TP_BMC_GPIOF3")
		)
	)
	(footprint ""
		(layer "B.Cu")
		(at 333.375 -154.813 180)
		(property "Reference" "C3"
			(at 0 0 0)
			(layer "B.SilkS")
			(hide yes)
			(effects
				(font
					(size 1.27 1.27)
				)
				(justify mirror)
			)
		)
		(property "Value" "SCD1U16V2KX-3GP"
			(at -1.1811 -2.7051 180)
			(unlocked yes)
			(layer "B.Fab")
			(hide yes)
			(effects
				(font
					(size 1.016 1.016)
					(thickness 0.1524)
				)
				(justify mirror)
			)
		)
		(property "Device Type" "C402H22"
			(at -1.1811 -4.2291 180)
			(unlocked yes)
			(layer "B.Fab")
			(hide yes)
			(effects
				(font
					(size 1.016 1.016)
					(thickness 0.1524)
				)
				(justify mirror)
			)
		)
		(duplicate_pad_numbers_are_jumpers no)
		(fp_rect
			(start 0.4318 0.9525)
			(end -0.4318 -0.9525)
			(stroke
				(width 0)
				(type default)
			)
			(fill no)
			(layer "B.CrtYd")
		)
		(fp_rect
			(start 0.4318 0.9525)
			(end -0.4318 -0.9525)
			(stroke
				(width 0)
				(type default)
			)
			(fill no)
			(layer "B.Fab")
		)
		(pad "1" smd custom
			(at 0 -0.4445)
			(size 0.1524 0.1524)
			(layers "B.Cu" "B.Mask" "B.Paste")
			(net "P3V3_STBY")
			(options
				(clearance outline)
				(anchor circle)
			)
			(primitives
				(gr_poly
					(pts
						(arc
							(start 0.3048 0.2032)
							(mid 0.275042 0.275042)
							(end 0.2032 0.3048)
						)
						(arc
							(start -0.2032 0.3048)
							(mid -0.275042 0.275042)
							(end -0.3048 0.2032)
						)
						(arc
							(start -0.3048 -0.2032)
							(mid -0.275042 -0.275042)
							(end -0.2032 -0.3048)
						)
						(arc
							(start 0.2032 -0.3048)
							(mid 0.275042 -0.275042)
							(end 0.3048 -0.2032)
						)
					)
					(width 0)
					(fill yes)
				)
			)
		)
		(pad "2" smd custom
			(at 0 0.4445)
			(size 0.1524 0.1524)
			(layers "B.Cu" "B.Mask" "B.Paste")
			(net "GND")
			(options
				(clearance outline)
				(anchor circle)
			)
			(primitives
				(gr_poly
					(pts
						(arc
							(start 0.3048 0.2032)
							(mid 0.275042 0.275042)
							(end 0.2032 0.3048)
						)
						(arc
							(start -0.2032 0.3048)
							(mid -0.275042 0.275042)
							(end -0.3048 0.2032)
						)
						(arc
							(start -0.3048 -0.2032)
							(mid -0.275042 -0.275042)
							(end -0.2032 -0.3048)
						)
						(arc
							(start 0.2032 -0.3048)
							(mid 0.275042 -0.275042)
							(end 0.3048 -0.2032)
						)
					)
					(width 0)
					(fill yes)
				)
			)
		)
	)
	(footprint ""
		(layer "B.Cu")
		(at 129.521966 -34.29 -90)
		(property "Reference" "SR713"
			(at 0 0 90)
			(layer "B.SilkS")
			(hide yes)
			(effects
				(font
					(size 1.27 1.27)
				)
				(justify mirror)
			)
		)
		(property "Value" "10R2F-L-GP"
			(at -0.064008 -3.993896 270)
			(unlocked yes)
			(layer "B.Fab")
			(hide yes)
			(effects
				(font
					(size 1.016 1.016)
					(thickness 0.1524)
				)
				(justify mirror)
			)
		)
		(property "Device Type" "R402H14"
			(at -0.064008 -5.517896 270)
			(unlocked yes)
			(layer "B.Fab")
			(hide yes)
			(effects
				(font
					(size 1.016 1.016)
					(thickness 0.1524)
				)
				(justify mirror)
			)
		)
		(duplicate_pad_numbers_are_jumpers no)
		(fp_line
			(start -0.508 -0.9398)
			(end 0.508 -0.9398)
			(stroke
				(width 0.1524)
				(type default)
			)
			(layer "B.SilkS")
		)
		(fp_line
			(start 0.508 -0.9398)
			(end 0.508 0.9398)
			(stroke
				(width 0.1524)
				(type default)
			)
			(layer "B.SilkS")
		)
		(fp_rect
			(start 0.508 0.9398)
			(end -0.508 -0.9398)
			(stroke
				(width 0)
				(type default)
			)
			(fill no)
			(layer "B.CrtYd")
		)
		(fp_rect
			(start 0.508 0.9398)
			(end -0.508 -0.9398)
			(stroke
				(width 0)
				(type default)
			)
			(fill no)
			(layer "B.Fab")
		)
		(pad "1" smd custom
			(at 0 -0.4445 90)
			(size 0.1397 0.1397)
			(layers "B.Cu" "B.Mask" "B.Paste")
			(net "P1V8_C")
			(options
				(clearance outline)
				(anchor circle)
			)
			(primitives
				(gr_poly
					(pts
						(arc
							(start -0.1778 0.2794)
							(mid -0.249642 0.249642)
							(end -0.2794 0.1778)
						)
						(arc
							(start -0.2794 -0.1778)
							(mid -0.249642 -0.249642)
							(end -0.1778 -0.2794)
						)
						(arc
							(start 0.1778 -0.2794)
							(mid 0.249642 -0.249642)
							(end 0.2794 -0.1778)
						)
						(arc
							(start 0.2794 0.1778)
							(mid 0.249642 0.249642)
							(end 0.1778 0.2794)
						)
					)
					(width 0)
					(fill yes)
				)
			)
		)
		(pad "2" smd custom
			(at 0 0.4445 90)
			(size 0.1397 0.1397)
			(layers "B.Cu" "B.Mask" "B.Paste")
			(net "PLL_VDD")
			(options
				(clearance outline)
				(anchor circle)
			)
			(primitives
				(gr_poly
					(pts
						(arc
							(start -0.1778 0.2794)
							(mid -0.249642 0.249642)
							(end -0.2794 0.1778)
						)
						(arc
							(start -0.2794 -0.1778)
							(mid -0.249642 -0.249642)
							(end -0.1778 -0.2794)
						)
						(arc
							(start 0.1778 -0.2794)
							(mid 0.249642 -0.249642)
							(end 0.2794 -0.1778)
						)
						(arc
							(start 0.2794 0.1778)
							(mid 0.249642 0.249642)
							(end 0.1778 0.2794)
						)
					)
					(width 0)
					(fill yes)
				)
			)
		)
	)
	(footprint ""
		(layer "B.Cu")
		(at 124.34697 -109.093 180)
		(property "Reference" "SC1173"
			(at 0 0 0)
			(layer "B.SilkS")
			(hide yes)
			(effects
				(font
					(size 1.27 1.27)
				)
				(justify mirror)
			)
		)
		(property "Value" "SCD1U16V2KX-3GP"
			(at -1.1811 -2.7051 180)
			(unlocked yes)
			(layer "B.Fab")
			(hide yes)
			(effects
				(font
					(size 1.016 1.016)
					(thickness 0.1524)
				)
				(justify mirror)
			)
		)
		(property "Device Type" "C402H22"
			(at -1.1811 -4.2291 180)
			(unlocked yes)
			(layer "B.Fab")
			(hide yes)
			(effects
				(font
					(size 1.016 1.016)
					(thickness 0.1524)
				)
				(justify mirror)
			)
		)
		(duplicate_pad_numbers_are_jumpers no)
		(fp_rect
			(start 0.4318 0.9525)
			(end -0.4318 -0.9525)
			(stroke
				(width 0)
				(type default)
			)
			(fill no)
			(layer "B.CrtYd")
		)
		(fp_rect
			(start 0.4318 0.9525)
			(end -0.4318 -0.9525)
			(stroke
				(width 0)
				(type default)
			)
			(fill no)
			(layer "B.Fab")
		)
		(pad "1" smd custom
			(at 0 -0.4445)
			(size 0.1524 0.1524)
			(layers "B.Cu" "B.Mask" "B.Paste")
			(net "GB_VDDA")
			(options
				(clearance outline)
				(anchor circle)
			)
			(primitives
				(gr_poly
					(pts
						(arc
							(start 0.3048 0.2032)
							(mid 0.275042 0.275042)
							(end 0.2032 0.3048)
						)
						(arc
							(start -0.2032 0.3048)
							(mid -0.275042 0.275042)
							(end -0.3048 0.2032)
						)
						(arc
							(start -0.3048 -0.2032)
							(mid -0.275042 -0.275042)
							(end -0.2032 -0.3048)
						)
						(arc
							(start 0.2032 -0.3048)
							(mid 0.275042 -0.275042)
							(end 0.3048 -0.2032)
						)
					)
					(width 0)
					(fill yes)
				)
			)
		)
		(pad "2" smd custom
			(at 0 0.4445)
			(size 0.1524 0.1524)
			(layers "B.Cu" "B.Mask" "B.Paste")
			(net "GND")
			(options
				(clearance outline)
				(anchor circle)
			)
			(primitives
				(gr_poly
					(pts
						(arc
							(start 0.3048 0.2032)
							(mid 0.275042 0.275042)
							(end 0.2032 0.3048)
						)
						(arc
							(start -0.2032 0.3048)
							(mid -0.275042 0.275042)
							(end -0.3048 0.2032)
						)
						(arc
							(start -0.3048 -0.2032)
							(mid -0.275042 -0.275042)
							(end -0.2032 -0.3048)
						)
						(arc
							(start 0.2032 -0.3048)
							(mid 0.275042 -0.275042)
							(end 0.3048 -0.2032)
						)
					)
					(width 0)
					(fill yes)
				)
			)
		)
	)
	(footprint ""
		(layer "B.Cu")
		(at 110.852966 -49.784 -90)
		(property "Reference" "SC992"
			(at 0 0 90)
			(layer "B.SilkS")
			(hide yes)
			(effects
				(font
					(size 1.27 1.27)
				)
				(justify mirror)
			)
		)
		(property "Value" "SCD1U16V2KX-3GP"
			(at -1.1811 -2.7051 270)
			(unlocked yes)
			(layer "B.Fab")
			(hide yes)
			(effects
				(font
					(size 1.016 1.016)
					(thickness 0.1524)
				)
				(justify mirror)
			)
		)
		(property "Device Type" "C402H22"
			(at -1.1811 -4.2291 270)
			(unlocked yes)
			(layer "B.Fab")
			(hide yes)
			(effects
				(font
					(size 1.016 1.016)
					(thickness 0.1524)
				)
				(justify mirror)
			)
		)
		(duplicate_pad_numbers_are_jumpers no)
		(fp_rect
			(start 0.4318 0.9525)
			(end -0.4318 -0.9525)
			(stroke
				(width 0)
				(type default)
			)
			(fill no)
			(layer "B.CrtYd")
		)
		(fp_rect
			(start 0.4318 0.9525)
			(end -0.4318 -0.9525)
			(stroke
				(width 0)
				(type default)
			)
			(fill no)
			(layer "B.Fab")
		)
		(pad "1" smd custom
			(at 0 -0.4445 90)
			(size 0.1524 0.1524)
			(layers "B.Cu" "B.Mask" "B.Paste")
			(net "P1V8_C")
			(options
				(clearance outline)
				(anchor circle)
			)
			(primitives
				(gr_poly
					(pts
						(arc
							(start 0.3048 0.2032)
							(mid 0.275042 0.275042)
							(end 0.2032 0.3048)
						)
						(arc
							(start -0.2032 0.3048)
							(mid -0.275042 0.275042)
							(end -0.3048 0.2032)
						)
						(arc
							(start -0.3048 -0.2032)
							(mid -0.275042 -0.275042)
							(end -0.2032 -0.3048)
						)
						(arc
							(start 0.2032 -0.3048)
							(mid 0.275042 -0.275042)
							(end 0.3048 -0.2032)
						)
					)
					(width 0)
					(fill yes)
				)
			)
		)
		(pad "2" smd custom
			(at 0 0.4445 90)
			(size 0.1524 0.1524)
			(layers "B.Cu" "B.Mask" "B.Paste")
			(net "GND")
			(options
				(clearance outline)
				(anchor circle)
			)
			(primitives
				(gr_poly
					(pts
						(arc
							(start 0.3048 0.2032)
							(mid 0.275042 0.275042)
							(end 0.2032 0.3048)
						)
						(arc
							(start -0.2032 0.3048)
							(mid -0.275042 0.275042)
							(end -0.3048 0.2032)
						)
						(arc
							(start -0.3048 -0.2032)
							(mid -0.275042 -0.275042)
							(end -0.2032 -0.3048)
						)
						(arc
							(start 0.2032 -0.3048)
							(mid 0.275042 -0.275042)
							(end 0.3048 -0.2032)
						)
					)
					(width 0)
					(fill yes)
				)
			)
		)
	)
	(footprint ""
		(layer "B.Cu")
		(at 86.087966 -51.181 90)
		(property "Reference" "SC969"
			(at 0 0 90)
			(layer "B.SilkS")
			(hide yes)
			(effects
				(font
					(size 1.27 1.27)
				)
				(justify mirror)
			)
		)
		(property "Value" "SC1U10V2KX-4-GP"
			(at -1.1811 -2.7051 90)
			(unlocked yes)
			(layer "B.Fab")
			(hide yes)
			(effects
				(font
					(size 1.016 1.016)
					(thickness 0.1524)
				)
				(justify mirror)
			)
		)
		(property "Device Type" "C402H22"
			(at -1.1811 -4.2291 90)
			(unlocked yes)
			(layer "B.Fab")
			(hide yes)
			(effects
				(font
					(size 1.016 1.016)
					(thickness 0.1524)
				)
				(justify mirror)
			)
		)
		(duplicate_pad_numbers_are_jumpers no)
		(fp_rect
			(start 0.4318 0.9525)
			(end -0.4318 -0.9525)
			(stroke
				(width 0)
				(type default)
			)
			(fill no)
			(layer "B.CrtYd")
		)
		(fp_rect
			(start 0.4318 0.9525)
			(end -0.4318 -0.9525)
			(stroke
				(width 0)
				(type default)
			)
			(fill no)
			(layer "B.Fab")
		)
		(pad "1" smd custom
			(at 0 -0.4445 270)
			(size 0.1524 0.1524)
			(layers "B.Cu" "B.Mask" "B.Paste")
			(net "P1V8_C")
			(options
				(clearance outline)
				(anchor circle)
			)
			(primitives
				(gr_poly
					(pts
						(arc
							(start 0.3048 0.2032)
							(mid 0.275042 0.275042)
							(end 0.2032 0.3048)
						)
						(arc
							(start -0.2032 0.3048)
							(mid -0.275042 0.275042)
							(end -0.3048 0.2032)
						)
						(arc
							(start -0.3048 -0.2032)
							(mid -0.275042 -0.275042)
							(end -0.2032 -0.3048)
						)
						(arc
							(start 0.2032 -0.3048)
							(mid 0.275042 -0.275042)
							(end 0.3048 -0.2032)
						)
					)
					(width 0)
					(fill yes)
				)
			)
		)
		(pad "2" smd custom
			(at 0 0.4445 270)
			(size 0.1524 0.1524)
			(layers "B.Cu" "B.Mask" "B.Paste")
			(net "GND")
			(options
				(clearance outline)
				(anchor circle)
			)
			(primitives
				(gr_poly
					(pts
						(arc
							(start 0.3048 0.2032)
							(mid 0.275042 0.275042)
							(end 0.2032 0.3048)
						)
						(arc
							(start -0.2032 0.3048)
							(mid -0.275042 0.275042)
							(end -0.3048 0.2032)
						)
						(arc
							(start -0.3048 -0.2032)
							(mid -0.275042 -0.275042)
							(end -0.2032 -0.3048)
						)
						(arc
							(start 0.2032 -0.3048)
							(mid 0.275042 -0.275042)
							(end 0.3048 -0.2032)
						)
					)
					(width 0)
					(fill yes)
				)
			)
		)
	)
	(footprint ""
		(layer "B.Cu")
		(at 310.896 -182.499 90)
		(property "Reference" "SR852"
			(at 0 0 90)
			(layer "B.SilkS")
			(hide yes)
			(effects
				(font
					(size 1.27 1.27)
				)
				(justify mirror)
			)
		)
		(property "Value" "4K75R2F-1-GP"
			(at -0.064008 -3.993896 90)
			(unlocked yes)
			(layer "B.Fab")
			(hide yes)
			(effects
				(font
					(size 1.016 1.016)
					(thickness 0.1524)
				)
				(justify mirror)
			)
		)
		(property "Device Type" "R402H16"
			(at -0.064008 -5.517896 90)
			(unlocked yes)
			(layer "B.Fab")
			(hide yes)
			(effects
				(font
					(size 1.016 1.016)
					(thickness 0.1524)
				)
				(justify mirror)
			)
		)
		(duplicate_pad_numbers_are_jumpers no)
		(fp_line
			(start 0.508 -0.9398)
			(end 0.508 0.9398)
			(stroke
				(width 0.1524)
				(type default)
			)
			(layer "B.SilkS")
		)
		(fp_line
			(start -0.508 -0.9398)
			(end 0.508 -0.9398)
			(stroke
				(width 0.1524)
				(type default)
			)
			(layer "B.SilkS")
		)
		(fp_rect
			(start 0.508 0.9398)
			(end -0.508 -0.9398)
			(stroke
				(width 0)
				(type default)
			)
			(fill no)
			(layer "B.CrtYd")
		)
		(fp_rect
			(start 0.508 0.9398)
			(end -0.508 -0.9398)
			(stroke
				(width 0)
				(type default)
			)
			(fill no)
			(layer "B.Fab")
		)
		(pad "1" smd custom
			(at 0 -0.4445 270)
			(size 0.1397 0.1397)
			(layers "B.Cu" "B.Mask" "B.Paste")
			(net "BMC_FW_DET_BOARD_VER_0")
			(options
				(clearance outline)
				(anchor circle)
			)
			(primitives
				(gr_poly
					(pts
						(arc
							(start -0.1778 0.2794)
							(mid -0.249642 0.249642)
							(end -0.2794 0.1778)
						)
						(arc
							(start -0.2794 -0.1778)
							(mid -0.249642 -0.249642)
							(end -0.1778 -0.2794)
						)
						(arc
							(start 0.1778 -0.2794)
							(mid 0.249642 -0.249642)
							(end 0.2794 -0.1778)
						)
						(arc
							(start 0.2794 0.1778)
							(mid 0.249642 0.249642)
							(end 0.1778 0.2794)
						)
					)
					(width 0)
					(fill yes)
				)
			)
		)
		(pad "2" smd custom
			(at 0 0.4445 270)
			(size 0.1397 0.1397)
			(layers "B.Cu" "B.Mask" "B.Paste")
			(net "GND")
			(options
				(clearance outline)
				(anchor circle)
			)
			(primitives
				(gr_poly
					(pts
						(arc
							(start -0.1778 0.2794)
							(mid -0.249642 0.249642)
							(end -0.2794 0.1778)
						)
						(arc
							(start -0.2794 -0.1778)
							(mid -0.249642 -0.249642)
							(end -0.1778 -0.2794)
						)
						(arc
							(start 0.1778 -0.2794)
							(mid 0.249642 -0.249642)
							(end 0.2794 -0.1778)
						)
						(arc
							(start 0.2794 0.1778)
							(mid 0.249642 0.249642)
							(end 0.1778 0.2794)
						)
					)
					(width 0)
					(fill yes)
				)
			)
		)
	)
	(footprint ""
		(layer "B.Cu")
		(at 263.525 -35.814 90)
		(property "Reference" "PR48"
			(at 0 0 90)
			(layer "B.SilkS")
			(hide yes)
			(effects
				(font
					(size 1.27 1.27)
				)
				(justify mirror)
			)
		)
		(property "Value" "475KR2F-GP"
			(at -0.064008 -3.993896 90)
			(unlocked yes)
			(layer "B.Fab")
			(hide yes)
			(effects
				(font
					(size 1.016 1.016)
					(thickness 0.1524)
				)
				(justify mirror)
			)
		)
		(property "Device Type" "R402H16"
			(at -0.064008 -5.517896 90)
			(unlocked yes)
			(layer "B.Fab")
			(hide yes)
			(effects
				(font
					(size 1.016 1.016)
					(thickness 0.1524)
				)
				(justify mirror)
			)
		)
		(duplicate_pad_numbers_are_jumpers no)
		(fp_line
			(start 0.508 -0.9398)
			(end 0.508 0.9398)
			(stroke
				(width 0.1524)
				(type default)
			)
			(layer "B.SilkS")
		)
		(fp_line
			(start -0.508 -0.9398)
			(end 0.508 -0.9398)
			(stroke
				(width 0.1524)
				(type default)
			)
			(layer "B.SilkS")
		)
		(fp_rect
			(start 0.508 0.9398)
			(end -0.508 -0.9398)
			(stroke
				(width 0)
				(type default)
			)
			(fill no)
			(layer "B.CrtYd")
		)
		(fp_rect
			(start 0.508 0.9398)
			(end -0.508 -0.9398)
			(stroke
				(width 0)
				(type default)
			)
			(fill no)
			(layer "B.Fab")
		)
		(pad "1" smd custom
			(at 0 -0.4445 270)
			(size 0.1397 0.1397)
			(layers "B.Cu" "B.Mask" "B.Paste")
			(net "P1V8_STBY_MODE")
			(options
				(clearance outline)
				(anchor circle)
			)
			(primitives
				(gr_poly
					(pts
						(arc
							(start -0.1778 0.2794)
							(mid -0.249642 0.249642)
							(end -0.2794 0.1778)
						)
						(arc
							(start -0.2794 -0.1778)
							(mid -0.249642 -0.249642)
							(end -0.1778 -0.2794)
						)
						(arc
							(start 0.1778 -0.2794)
							(mid 0.249642 -0.249642)
							(end 0.2794 -0.1778)
						)
						(arc
							(start 0.2794 0.1778)
							(mid 0.249642 0.249642)
							(end 0.1778 0.2794)
						)
					)
					(width 0)
					(fill yes)
				)
			)
		)
		(pad "2" smd custom
			(at 0 0.4445 270)
			(size 0.1397 0.1397)
			(layers "B.Cu" "B.Mask" "B.Paste")
			(net "P1V8_STBY_PG")
			(options
				(clearance outline)
				(anchor circle)
			)
			(primitives
				(gr_poly
					(pts
						(arc
							(start -0.1778 0.2794)
							(mid -0.249642 0.249642)
							(end -0.2794 0.1778)
						)
						(arc
							(start -0.2794 -0.1778)
							(mid -0.249642 -0.249642)
							(end -0.1778 -0.2794)
						)
						(arc
							(start 0.1778 -0.2794)
							(mid 0.249642 -0.249642)
							(end 0.2794 -0.1778)
						)
						(arc
							(start 0.2794 0.1778)
							(mid 0.249642 0.249642)
							(end 0.1778 0.2794)
						)
					)
					(width 0)
					(fill yes)
				)
			)
		)
	)
	(footprint ""
		(layer "B.Cu")
		(at 298.069 -173.482)
		(property "Reference" "TP179"
			(at 0 0 0)
			(layer "B.SilkS")
			(hide yes)
			(effects
				(font
					(size 1.27 1.27)
				)
				(justify mirror)
			)
		)
		(property "Value" "TPAD28"
			(at 0.0127 -1.6637 0)
			(unlocked yes)
			(layer "B.Fab")
			(hide yes)
			(effects
				(font
					(size 1.016 1.016)
					(thickness 0.1524)
				)
				(justify mirror)
			)
		)
		(property "Device Type" "TPAD28"
			(at 0.0127 -3.1877 0)
			(unlocked yes)
			(layer "B.Fab")
			(hide yes)
			(effects
				(font
					(size 1.016 1.016)
					(thickness 0.1524)
				)
				(justify mirror)
			)
		)
		(duplicate_pad_numbers_are_jumpers no)
		(fp_poly
			(pts
				(arc
					(start 0.3556 0)
					(mid -0.3556 0)
					(end 0.3556 0)
				)
			)
			(stroke
				(width 0)
				(type default)
			)
			(fill no)
			(layer "B.CrtYd")
		)
		(fp_poly
			(pts
				(arc
					(start 0.6096 0)
					(mid -0.6096 0)
					(end 0.6096 0)
				)
			)
			(stroke
				(width 0)
				(type default)
			)
			(fill no)
			(layer "B.Fab")
		)
		(pad "1" smd circle
			(at 0 0 180)
			(size 0.7112 0.7112)
			(layers "B.Cu" "B.Mask" "B.Paste")
			(net "BMC0_JTAG_RTCK")
		)
	)
	(footprint ""
		(layer "B.Cu")
		(at 111.195612 -222.885 180)
		(property "Reference" "SR894"
			(at 0 0 0)
			(layer "B.SilkS")
			(hide yes)
			(effects
				(font
					(size 1.27 1.27)
				)
				(justify mirror)
			)
		)
		(property "Value" "0R2J-2-GP"
			(at -0.064008 -3.993896 180)
			(unlocked yes)
			(layer "B.Fab")
			(hide yes)
			(effects
				(font
					(size 1.016 1.016)
					(thickness 0.1524)
				)
				(justify mirror)
			)
		)
		(property "Device Type" "R402H16"
			(at -0.064008 -5.517896 180)
			(unlocked yes)
			(layer "B.Fab")
			(hide yes)
			(effects
				(font
					(size 1.016 1.016)
					(thickness 0.1524)
				)
				(justify mirror)
			)
		)
		(duplicate_pad_numbers_are_jumpers no)
		(fp_line
			(start 0.508 -0.9398)
			(end 0.508 0.9398)
			(stroke
				(width 0.1524)
				(type default)
			)
			(layer "B.SilkS")
		)
		(fp_line
			(start -0.508 -0.9398)
			(end 0.508 -0.9398)
			(stroke
				(width 0.1524)
				(type default)
			)
			(layer "B.SilkS")
		)
		(fp_rect
			(start 0.508 0.9398)
			(end -0.508 -0.9398)
			(stroke
				(width 0)
				(type default)
			)
			(fill no)
			(layer "B.CrtYd")
		)
		(fp_rect
			(start 0.508 0.9398)
			(end -0.508 -0.9398)
			(stroke
				(width 0)
				(type default)
			)
			(fill no)
			(layer "B.Fab")
		)
		(pad "1" smd custom
			(at 0 -0.4445)
			(size 0.1397 0.1397)
			(layers "B.Cu" "B.Mask" "B.Paste")
			(net "SAS_GF_EXP_RX_DP8")
			(options
				(clearance outline)
				(anchor circle)
			)
			(primitives
				(gr_poly
					(pts
						(arc
							(start -0.1778 0.2794)
							(mid -0.249642 0.249642)
							(end -0.2794 0.1778)
						)
						(arc
							(start -0.2794 -0.1778)
							(mid -0.249642 -0.249642)
							(end -0.1778 -0.2794)
						)
						(arc
							(start 0.1778 -0.2794)
							(mid 0.249642 -0.249642)
							(end 0.2794 -0.1778)
						)
						(arc
							(start 0.2794 0.1778)
							(mid 0.249642 0.249642)
							(end 0.1778 0.2794)
						)
					)
					(width 0)
					(fill yes)
				)
			)
		)
		(pad "2" smd custom
			(at 0 0.4445)
			(size 0.1397 0.1397)
			(layers "B.Cu" "B.Mask" "B.Paste")
			(net "REDV_RX8_P")
			(options
				(clearance outline)
				(anchor circle)
			)
			(primitives
				(gr_poly
					(pts
						(arc
							(start -0.1778 0.2794)
							(mid -0.249642 0.249642)
							(end -0.2794 0.1778)
						)
						(arc
							(start -0.2794 -0.1778)
							(mid -0.249642 -0.249642)
							(end -0.1778 -0.2794)
						)
						(arc
							(start 0.1778 -0.2794)
							(mid 0.249642 -0.249642)
							(end 0.2794 -0.1778)
						)
						(arc
							(start 0.2794 0.1778)
							(mid 0.249642 0.249642)
							(end 0.1778 0.2794)
						)
					)
					(width 0)
					(fill yes)
				)
			)
		)
	)
	(footprint ""
		(layer "B.Cu")
		(at 98.1202 -41.402)
		(property "Reference" "SC1048"
			(at 0 0 0)
			(layer "B.SilkS")
			(hide yes)
			(effects
				(font
					(size 1.27 1.27)
				)
				(justify mirror)
			)
		)
		(property "Value" "SCD1U16V2KX-3GP"
			(at -1.1811 -2.7051 0)
			(unlocked yes)
			(layer "B.Fab")
			(hide yes)
			(effects
				(font
					(size 1.016 1.016)
					(thickness 0.1524)
				)
				(justify mirror)
			)
		)
		(property "Device Type" "C402H22"
			(at -1.1811 -4.2291 0)
			(unlocked yes)
			(layer "B.Fab")
			(hide yes)
			(effects
				(font
					(size 1.016 1.016)
					(thickness 0.1524)
				)
				(justify mirror)
			)
		)
		(duplicate_pad_numbers_are_jumpers no)
		(fp_rect
			(start 0.4318 0.9525)
			(end -0.4318 -0.9525)
			(stroke
				(width 0)
				(type default)
			)
			(fill no)
			(layer "B.CrtYd")
		)
		(fp_rect
			(start 0.4318 0.9525)
			(end -0.4318 -0.9525)
			(stroke
				(width 0)
				(type default)
			)
			(fill no)
			(layer "B.Fab")
		)
		(pad "1" smd custom
			(at 0 -0.4445 180)
			(size 0.1524 0.1524)
			(layers "B.Cu" "B.Mask" "B.Paste")
			(net "P0V955_C")
			(options
				(clearance outline)
				(anchor circle)
			)
			(primitives
				(gr_poly
					(pts
						(arc
							(start 0.3048 0.2032)
							(mid 0.275042 0.275042)
							(end 0.2032 0.3048)
						)
						(arc
							(start -0.2032 0.3048)
							(mid -0.275042 0.275042)
							(end -0.3048 0.2032)
						)
						(arc
							(start -0.3048 -0.2032)
							(mid -0.275042 -0.275042)
							(end -0.2032 -0.3048)
						)
						(arc
							(start 0.2032 -0.3048)
							(mid 0.275042 -0.275042)
							(end 0.3048 -0.2032)
						)
					)
					(width 0)
					(fill yes)
				)
			)
		)
		(pad "2" smd custom
			(at 0 0.4445 180)
			(size 0.1524 0.1524)
			(layers "B.Cu" "B.Mask" "B.Paste")
			(net "GND")
			(options
				(clearance outline)
				(anchor circle)
			)
			(primitives
				(gr_poly
					(pts
						(arc
							(start 0.3048 0.2032)
							(mid 0.275042 0.275042)
							(end 0.2032 0.3048)
						)
						(arc
							(start -0.2032 0.3048)
							(mid -0.275042 0.275042)
							(end -0.3048 0.2032)
						)
						(arc
							(start -0.3048 -0.2032)
							(mid -0.275042 -0.275042)
							(end -0.2032 -0.3048)
						)
						(arc
							(start 0.2032 -0.3048)
							(mid 0.275042 -0.275042)
							(end 0.3048 -0.2032)
						)
					)
					(width 0)
					(fill yes)
				)
			)
		)
	)
	(footprint ""
		(layer "B.Cu")
		(at 274.193 -169.545 90)
		(property "Reference" "R240"
			(at 0 0 90)
			(layer "B.SilkS")
			(hide yes)
			(effects
				(font
					(size 1.27 1.27)
				)
				(justify mirror)
			)
		)
		(property "Value" "0R2J-2-GP"
			(at -0.064008 -3.993896 90)
			(unlocked yes)
			(layer "B.Fab")
			(hide yes)
			(effects
				(font
					(size 1.016 1.016)
					(thickness 0.1524)
				)
				(justify mirror)
			)
		)
		(property "Device Type" "R402H16"
			(at -0.064008 -5.517896 90)
			(unlocked yes)
			(layer "B.Fab")
			(hide yes)
			(effects
				(font
					(size 1.016 1.016)
					(thickness 0.1524)
				)
				(justify mirror)
			)
		)
		(duplicate_pad_numbers_are_jumpers no)
		(fp_line
			(start 0.508 -0.9398)
			(end 0.508 0.9398)
			(stroke
				(width 0.1524)
				(type default)
			)
			(layer "B.SilkS")
		)
		(fp_line
			(start -0.508 -0.9398)
			(end 0.508 -0.9398)
			(stroke
				(width 0.1524)
				(type default)
			)
			(layer "B.SilkS")
		)
		(fp_rect
			(start 0.508 0.9398)
			(end -0.508 -0.9398)
			(stroke
				(width 0)
				(type default)
			)
			(fill no)
			(layer "B.CrtYd")
		)
		(fp_rect
			(start 0.508 0.9398)
			(end -0.508 -0.9398)
			(stroke
				(width 0)
				(type default)
			)
			(fill no)
			(layer "B.Fab")
		)
		(pad "1" smd custom
			(at 0 -0.4445 270)
			(size 0.1397 0.1397)
			(layers "B.Cu" "B.Mask" "B.Paste")
			(net "BMC_10G_SCL_2")
			(options
				(clearance outline)
				(anchor circle)
			)
			(primitives
				(gr_poly
					(pts
						(arc
							(start -0.1778 0.2794)
							(mid -0.249642 0.249642)
							(end -0.2794 0.1778)
						)
						(arc
							(start -0.2794 -0.1778)
							(mid -0.249642 -0.249642)
							(end -0.1778 -0.2794)
						)
						(arc
							(start 0.1778 -0.2794)
							(mid 0.249642 -0.249642)
							(end 0.2794 -0.1778)
						)
						(arc
							(start 0.2794 0.1778)
							(mid 0.249642 0.249642)
							(end 0.1778 0.2794)
						)
					)
					(width 0)
					(fill yes)
				)
			)
		)
		(pad "2" smd custom
			(at 0 0.4445 270)
			(size 0.1397 0.1397)
			(layers "B.Cu" "B.Mask" "B.Paste")
			(net "BMC0_SMB2_CLK")
			(options
				(clearance outline)
				(anchor circle)
			)
			(primitives
				(gr_poly
					(pts
						(arc
							(start -0.1778 0.2794)
							(mid -0.249642 0.249642)
							(end -0.2794 0.1778)
						)
						(arc
							(start -0.2794 -0.1778)
							(mid -0.249642 -0.249642)
							(end -0.1778 -0.2794)
						)
						(arc
							(start 0.1778 -0.2794)
							(mid 0.249642 -0.249642)
							(end 0.2794 -0.1778)
						)
						(arc
							(start 0.2794 0.1778)
							(mid 0.249642 0.249642)
							(end 0.1778 0.2794)
						)
					)
					(width 0)
					(fill yes)
				)
			)
		)
	)
	(footprint ""
		(layer "B.Cu")
		(at 87.916766 -47.8028)
		(property "Reference" "STP3"
			(at 0 0 0)
			(layer "B.SilkS")
			(hide yes)
			(effects
				(font
					(size 1.27 1.27)
				)
				(justify mirror)
			)
		)
		(property "Value" "TPAD28"
			(at -0.0127 -1.8034 0)
			(unlocked yes)
			(layer "B.Fab")
			(hide yes)
			(effects
				(font
					(size 1.016 1.016)
					(thickness 0.1524)
				)
				(justify mirror)
			)
		)
		(property "Device Type" "TPAD28"
			(at -0.0127 -3.3274 0)
			(unlocked yes)
			(layer "B.Fab")
			(hide yes)
			(effects
				(font
					(size 1.016 1.016)
					(thickness 0.1524)
				)
				(justify mirror)
			)
		)
		(duplicate_pad_numbers_are_jumpers no)
		(fp_poly
			(pts
				(arc
					(start 0.3556 0)
					(mid -0.3556 0)
					(end 0.3556 0)
				)
			)
			(stroke
				(width 0)
				(type default)
			)
			(fill no)
			(layer "B.CrtYd")
		)
		(fp_poly
			(pts
				(arc
					(start 0.6096 0)
					(mid -0.6096 0)
					(end 0.6096 0)
				)
			)
			(stroke
				(width 0)
				(type default)
			)
			(fill no)
			(layer "B.Fab")
		)
		(pad "1" smd circle
			(at 0 0 180)
			(size 0.7112 0.7112)
			(layers "B.Cu" "B.Mask" "B.Paste")
			(net "SIO_CLK_0")
		)
	)
	(footprint ""
		(layer "B.Cu")
		(at 319.405 -181.737 -90)
		(property "Reference" "R5772"
			(at 0 0 90)
			(layer "B.SilkS")
			(hide yes)
			(effects
				(font
					(size 1.27 1.27)
				)
				(justify mirror)
			)
		)
		(property "Value" "1KR2F-3-GP"
			(at -0.064008 -3.993896 270)
			(unlocked yes)
			(layer "B.Fab")
			(hide yes)
			(effects
				(font
					(size 1.016 1.016)
					(thickness 0.1524)
				)
				(justify mirror)
			)
		)
		(property "Device Type" "R402H16"
			(at -0.064008 -5.517896 270)
			(unlocked yes)
			(layer "B.Fab")
			(hide yes)
			(effects
				(font
					(size 1.016 1.016)
					(thickness 0.1524)
				)
				(justify mirror)
			)
		)
		(duplicate_pad_numbers_are_jumpers no)
		(fp_line
			(start -0.508 -0.9398)
			(end 0.508 -0.9398)
			(stroke
				(width 0.1524)
				(type default)
			)
			(layer "B.SilkS")
		)
		(fp_line
			(start 0.508 -0.9398)
			(end 0.508 0.9398)
			(stroke
				(width 0.1524)
				(type default)
			)
			(layer "B.SilkS")
		)
		(fp_rect
			(start 0.508 0.9398)
			(end -0.508 -0.9398)
			(stroke
				(width 0)
				(type default)
			)
			(fill no)
			(layer "B.CrtYd")
		)
		(fp_rect
			(start 0.508 0.9398)
			(end -0.508 -0.9398)
			(stroke
				(width 0)
				(type default)
			)
			(fill no)
			(layer "B.Fab")
		)
		(pad "1" smd custom
			(at 0 -0.4445 90)
			(size 0.1397 0.1397)
			(layers "B.Cu" "B.Mask" "B.Paste")
			(net "P1V5_E")
			(options
				(clearance outline)
				(anchor circle)
			)
			(primitives
				(gr_poly
					(pts
						(arc
							(start -0.1778 0.2794)
							(mid -0.249642 0.249642)
							(end -0.2794 0.1778)
						)
						(arc
							(start -0.2794 -0.1778)
							(mid -0.249642 -0.249642)
							(end -0.1778 -0.2794)
						)
						(arc
							(start 0.1778 -0.2794)
							(mid 0.249642 -0.249642)
							(end 0.2794 -0.1778)
						)
						(arc
							(start 0.2794 0.1778)
							(mid 0.249642 0.249642)
							(end 0.1778 0.2794)
						)
					)
					(width 0)
					(fill yes)
				)
			)
		)
		(pad "2" smd custom
			(at 0 0.4445 90)
			(size 0.1397 0.1397)
			(layers "B.Cu" "B.Mask" "B.Paste")
			(net "ADC_P1V5_E")
			(options
				(clearance outline)
				(anchor circle)
			)
			(primitives
				(gr_poly
					(pts
						(arc
							(start -0.1778 0.2794)
							(mid -0.249642 0.249642)
							(end -0.2794 0.1778)
						)
						(arc
							(start -0.2794 -0.1778)
							(mid -0.249642 -0.249642)
							(end -0.1778 -0.2794)
						)
						(arc
							(start 0.1778 -0.2794)
							(mid 0.249642 -0.249642)
							(end 0.2794 -0.1778)
						)
						(arc
							(start 0.2794 0.1778)
							(mid 0.249642 0.249642)
							(end 0.1778 0.2794)
						)
					)
					(width 0)
					(fill yes)
				)
			)
		)
	)
	(footprint ""
		(layer "B.Cu")
		(at 318.008 -179.705 -90)
		(property "Reference" "R321"
			(at 0 0 90)
			(layer "B.SilkS")
			(hide yes)
			(effects
				(font
					(size 1.27 1.27)
				)
				(justify mirror)
			)
		)
		(property "Value" "0R2J-2-GP"
			(at -0.064008 -3.993896 270)
			(unlocked yes)
			(layer "B.Fab")
			(hide yes)
			(effects
				(font
					(size 1.016 1.016)
					(thickness 0.1524)
				)
				(justify mirror)
			)
		)
		(property "Device Type" "R402H16"
			(at -0.064008 -5.517896 270)
			(unlocked yes)
			(layer "B.Fab")
			(hide yes)
			(effects
				(font
					(size 1.016 1.016)
					(thickness 0.1524)
				)
				(justify mirror)
			)
		)
		(duplicate_pad_numbers_are_jumpers no)
		(fp_line
			(start -0.508 -0.9398)
			(end 0.508 -0.9398)
			(stroke
				(width 0.1524)
				(type default)
			)
			(layer "B.SilkS")
		)
		(fp_line
			(start 0.508 -0.9398)
			(end 0.508 0.9398)
			(stroke
				(width 0.1524)
				(type default)
			)
			(layer "B.SilkS")
		)
		(fp_rect
			(start 0.508 0.9398)
			(end -0.508 -0.9398)
			(stroke
				(width 0)
				(type default)
			)
			(fill no)
			(layer "B.CrtYd")
		)
		(fp_rect
			(start 0.508 0.9398)
			(end -0.508 -0.9398)
			(stroke
				(width 0)
				(type default)
			)
			(fill no)
			(layer "B.Fab")
		)
		(pad "1" smd custom
			(at 0 -0.4445 90)
			(size 0.1397 0.1397)
			(layers "B.Cu" "B.Mask" "B.Paste")
			(net "ADC_P0V955_C")
			(options
				(clearance outline)
				(anchor circle)
			)
			(primitives
				(gr_poly
					(pts
						(arc
							(start -0.1778 0.2794)
							(mid -0.249642 0.249642)
							(end -0.2794 0.1778)
						)
						(arc
							(start -0.2794 -0.1778)
							(mid -0.249642 -0.249642)
							(end -0.1778 -0.2794)
						)
						(arc
							(start 0.1778 -0.2794)
							(mid 0.249642 -0.249642)
							(end 0.2794 -0.1778)
						)
						(arc
							(start 0.2794 0.1778)
							(mid 0.249642 0.249642)
							(end 0.1778 0.2794)
						)
					)
					(width 0)
					(fill yes)
				)
			)
		)
		(pad "2" smd custom
			(at 0 0.4445 90)
			(size 0.1397 0.1397)
			(layers "B.Cu" "B.Mask" "B.Paste")
			(net "ADC_P0V955_C_BMC")
			(options
				(clearance outline)
				(anchor circle)
			)
			(primitives
				(gr_poly
					(pts
						(arc
							(start -0.1778 0.2794)
							(mid -0.249642 0.249642)
							(end -0.2794 0.1778)
						)
						(arc
							(start -0.2794 -0.1778)
							(mid -0.249642 -0.249642)
							(end -0.1778 -0.2794)
						)
						(arc
							(start 0.1778 -0.2794)
							(mid 0.249642 -0.249642)
							(end 0.2794 -0.1778)
						)
						(arc
							(start 0.2794 0.1778)
							(mid 0.249642 0.249642)
							(end 0.1778 0.2794)
						)
					)
					(width 0)
					(fill yes)
				)
			)
		)
	)
	(footprint ""
		(layer "B.Cu")
		(at 101.454966 -40.386)
		(property "Reference" "SC1060"
			(at 0 0 0)
			(layer "B.SilkS")
			(hide yes)
			(effects
				(font
					(size 1.27 1.27)
				)
				(justify mirror)
			)
		)
		(property "Value" "SCD1U16V2KX-3GP"
			(at -1.1811 -2.7051 0)
			(unlocked yes)
			(layer "B.Fab")
			(hide yes)
			(effects
				(font
					(size 1.016 1.016)
					(thickness 0.1524)
				)
				(justify mirror)
			)
		)
		(property "Device Type" "C402H22"
			(at -1.1811 -4.2291 0)
			(unlocked yes)
			(layer "B.Fab")
			(hide yes)
			(effects
				(font
					(size 1.016 1.016)
					(thickness 0.1524)
				)
				(justify mirror)
			)
		)
		(duplicate_pad_numbers_are_jumpers no)
		(fp_rect
			(start 0.4318 0.9525)
			(end -0.4318 -0.9525)
			(stroke
				(width 0)
				(type default)
			)
			(fill no)
			(layer "B.CrtYd")
		)
		(fp_rect
			(start 0.4318 0.9525)
			(end -0.4318 -0.9525)
			(stroke
				(width 0)
				(type default)
			)
			(fill no)
			(layer "B.Fab")
		)
		(pad "1" smd custom
			(at 0 -0.4445 180)
			(size 0.1524 0.1524)
			(layers "B.Cu" "B.Mask" "B.Paste")
			(net "P0V955_C")
			(options
				(clearance outline)
				(anchor circle)
			)
			(primitives
				(gr_poly
					(pts
						(arc
							(start 0.3048 0.2032)
							(mid 0.275042 0.275042)
							(end 0.2032 0.3048)
						)
						(arc
							(start -0.2032 0.3048)
							(mid -0.275042 0.275042)
							(end -0.3048 0.2032)
						)
						(arc
							(start -0.3048 -0.2032)
							(mid -0.275042 -0.275042)
							(end -0.2032 -0.3048)
						)
						(arc
							(start 0.2032 -0.3048)
							(mid 0.275042 -0.275042)
							(end 0.3048 -0.2032)
						)
					)
					(width 0)
					(fill yes)
				)
			)
		)
		(pad "2" smd custom
			(at 0 0.4445 180)
			(size 0.1524 0.1524)
			(layers "B.Cu" "B.Mask" "B.Paste")
			(net "GND")
			(options
				(clearance outline)
				(anchor circle)
			)
			(primitives
				(gr_poly
					(pts
						(arc
							(start 0.3048 0.2032)
							(mid 0.275042 0.275042)
							(end 0.2032 0.3048)
						)
						(arc
							(start -0.2032 0.3048)
							(mid -0.275042 0.275042)
							(end -0.3048 0.2032)
						)
						(arc
							(start -0.3048 -0.2032)
							(mid -0.275042 -0.275042)
							(end -0.2032 -0.3048)
						)
						(arc
							(start 0.2032 -0.3048)
							(mid 0.275042 -0.275042)
							(end 0.3048 -0.2032)
						)
					)
					(width 0)
					(fill yes)
				)
			)
		)
	)
	(footprint ""
		(layer "B.Cu")
		(at 302.45304 -182.7403)
		(property "Reference" "TP101"
			(at 0 0 0)
			(layer "B.SilkS")
			(hide yes)
			(effects
				(font
					(size 1.27 1.27)
				)
				(justify mirror)
			)
		)
		(property "Value" "TPAD28"
			(at -0.0127 -1.8034 0)
			(unlocked yes)
			(layer "B.Fab")
			(hide yes)
			(effects
				(font
					(size 1.016 1.016)
					(thickness 0.1524)
				)
				(justify mirror)
			)
		)
		(property "Device Type" "TPAD28"
			(at -0.0127 -3.3274 0)
			(unlocked yes)
			(layer "B.Fab")
			(hide yes)
			(effects
				(font
					(size 1.016 1.016)
					(thickness 0.1524)
				)
				(justify mirror)
			)
		)
		(duplicate_pad_numbers_are_jumpers no)
		(fp_poly
			(pts
				(arc
					(start 0.3556 0)
					(mid -0.3556 0)
					(end 0.3556 0)
				)
			)
			(stroke
				(width 0)
				(type default)
			)
			(fill no)
			(layer "B.CrtYd")
		)
		(fp_poly
			(pts
				(arc
					(start 0.6096 0)
					(mid -0.6096 0)
					(end 0.6096 0)
				)
			)
			(stroke
				(width 0)
				(type default)
			)
			(fill no)
			(layer "B.Fab")
		)
		(pad "1" smd circle
			(at 0 0 180)
			(size 0.7112 0.7112)
			(layers "B.Cu" "B.Mask" "B.Paste")
			(net "TP_BMC_GPIOL2")
		)
	)
	(footprint ""
		(layer "B.Cu")
		(at 110.804706 -53.05298 -90)
		(property "Reference" "SC1007"
			(at 0 0 90)
			(layer "B.SilkS")
			(hide yes)
			(effects
				(font
					(size 1.27 1.27)
				)
				(justify mirror)
			)
		)
		(property "Value" "SCD1U16V2KX-3GP"
			(at -1.1811 -2.7051 270)
			(unlocked yes)
			(layer "B.Fab")
			(hide yes)
			(effects
				(font
					(size 1.016 1.016)
					(thickness 0.1524)
				)
				(justify mirror)
			)
		)
		(property "Device Type" "C402H22"
			(at -1.1811 -4.2291 270)
			(unlocked yes)
			(layer "B.Fab")
			(hide yes)
			(effects
				(font
					(size 1.016 1.016)
					(thickness 0.1524)
				)
				(justify mirror)
			)
		)
		(duplicate_pad_numbers_are_jumpers no)
		(fp_rect
			(start 0.4318 0.9525)
			(end -0.4318 -0.9525)
			(stroke
				(width 0)
				(type default)
			)
			(fill no)
			(layer "B.CrtYd")
		)
		(fp_rect
			(start 0.4318 0.9525)
			(end -0.4318 -0.9525)
			(stroke
				(width 0)
				(type default)
			)
			(fill no)
			(layer "B.Fab")
		)
		(pad "1" smd custom
			(at 0 -0.4445 90)
			(size 0.1524 0.1524)
			(layers "B.Cu" "B.Mask" "B.Paste")
			(net "P1V8_C")
			(options
				(clearance outline)
				(anchor circle)
			)
			(primitives
				(gr_poly
					(pts
						(arc
							(start 0.3048 0.2032)
							(mid 0.275042 0.275042)
							(end 0.2032 0.3048)
						)
						(arc
							(start -0.2032 0.3048)
							(mid -0.275042 0.275042)
							(end -0.3048 0.2032)
						)
						(arc
							(start -0.3048 -0.2032)
							(mid -0.275042 -0.275042)
							(end -0.2032 -0.3048)
						)
						(arc
							(start 0.2032 -0.3048)
							(mid 0.275042 -0.275042)
							(end 0.3048 -0.2032)
						)
					)
					(width 0)
					(fill yes)
				)
			)
		)
		(pad "2" smd custom
			(at 0 0.4445 90)
			(size 0.1524 0.1524)
			(layers "B.Cu" "B.Mask" "B.Paste")
			(net "GND")
			(options
				(clearance outline)
				(anchor circle)
			)
			(primitives
				(gr_poly
					(pts
						(arc
							(start 0.3048 0.2032)
							(mid 0.275042 0.275042)
							(end 0.2032 0.3048)
						)
						(arc
							(start -0.2032 0.3048)
							(mid -0.275042 0.275042)
							(end -0.3048 0.2032)
						)
						(arc
							(start -0.3048 -0.2032)
							(mid -0.275042 -0.275042)
							(end -0.2032 -0.3048)
						)
						(arc
							(start 0.2032 -0.3048)
							(mid 0.275042 -0.275042)
							(end 0.3048 -0.2032)
						)
					)
					(width 0)
					(fill yes)
				)
			)
		)
	)
	(footprint ""
		(layer "B.Cu")
		(at 276.729952 -165.248336 90)
		(property "Reference" "R236"
			(at 0 0 90)
			(layer "B.SilkS")
			(hide yes)
			(effects
				(font
					(size 1.27 1.27)
				)
				(justify mirror)
			)
		)
		(property "Value" "100KR2F-L1-GP"
			(at -0.064008 -3.993896 90)
			(unlocked yes)
			(layer "B.Fab")
			(hide yes)
			(effects
				(font
					(size 1.016 1.016)
					(thickness 0.1524)
				)
				(justify mirror)
			)
		)
		(property "Device Type" "R402H16"
			(at -0.064008 -5.517896 90)
			(unlocked yes)
			(layer "B.Fab")
			(hide yes)
			(effects
				(font
					(size 1.016 1.016)
					(thickness 0.1524)
				)
				(justify mirror)
			)
		)
		(duplicate_pad_numbers_are_jumpers no)
		(fp_line
			(start 0.508 -0.9398)
			(end 0.508 0.9398)
			(stroke
				(width 0.1524)
				(type default)
			)
			(layer "B.SilkS")
		)
		(fp_line
			(start -0.508 -0.9398)
			(end 0.508 -0.9398)
			(stroke
				(width 0.1524)
				(type default)
			)
			(layer "B.SilkS")
		)
		(fp_rect
			(start 0.508 0.9398)
			(end -0.508 -0.9398)
			(stroke
				(width 0)
				(type default)
			)
			(fill no)
			(layer "B.CrtYd")
		)
		(fp_rect
			(start 0.508 0.9398)
			(end -0.508 -0.9398)
			(stroke
				(width 0)
				(type default)
			)
			(fill no)
			(layer "B.Fab")
		)
		(pad "1" smd custom
			(at 0 -0.4445 270)
			(size 0.1397 0.1397)
			(layers "B.Cu" "B.Mask" "B.Paste")
			(net "GND")
			(options
				(clearance outline)
				(anchor circle)
			)
			(primitives
				(gr_poly
					(pts
						(arc
							(start -0.1778 0.2794)
							(mid -0.249642 0.249642)
							(end -0.2794 0.1778)
						)
						(arc
							(start -0.2794 -0.1778)
							(mid -0.249642 -0.249642)
							(end -0.1778 -0.2794)
						)
						(arc
							(start 0.1778 -0.2794)
							(mid 0.249642 -0.249642)
							(end 0.2794 -0.1778)
						)
						(arc
							(start 0.2794 0.1778)
							(mid 0.249642 0.249642)
							(end 0.1778 0.2794)
						)
					)
					(width 0)
					(fill yes)
				)
			)
		)
		(pad "2" smd custom
			(at 0 0.4445 270)
			(size 0.1397 0.1397)
			(layers "B.Cu" "B.Mask" "B.Paste")
			(net "TP_BMC0_LPC_LAD2")
			(options
				(clearance outline)
				(anchor circle)
			)
			(primitives
				(gr_poly
					(pts
						(arc
							(start -0.1778 0.2794)
							(mid -0.249642 0.249642)
							(end -0.2794 0.1778)
						)
						(arc
							(start -0.2794 -0.1778)
							(mid -0.249642 -0.249642)
							(end -0.1778 -0.2794)
						)
						(arc
							(start 0.1778 -0.2794)
							(mid 0.249642 -0.249642)
							(end 0.2794 -0.1778)
						)
						(arc
							(start 0.2794 0.1778)
							(mid 0.249642 0.249642)
							(end 0.1778 0.2794)
						)
					)
					(width 0)
					(fill yes)
				)
			)
		)
	)
	(footprint ""
		(layer "B.Cu")
		(at 197.739 -247.142 90)
		(property "Reference" "R626"
			(at 0 0 90)
			(layer "B.SilkS")
			(hide yes)
			(effects
				(font
					(size 1.27 1.27)
				)
				(justify mirror)
			)
		)
		(property "Value" "27KR2F-L-GP"
			(at -0.064008 -3.993896 90)
			(unlocked yes)
			(layer "B.Fab")
			(hide yes)
			(effects
				(font
					(size 1.016 1.016)
					(thickness 0.1524)
				)
				(justify mirror)
			)
		)
		(property "Device Type" "R402H16"
			(at -0.064008 -5.517896 90)
			(unlocked yes)
			(layer "B.Fab")
			(hide yes)
			(effects
				(font
					(size 1.016 1.016)
					(thickness 0.1524)
				)
				(justify mirror)
			)
		)
		(duplicate_pad_numbers_are_jumpers no)
		(fp_line
			(start 0.508 -0.9398)
			(end 0.508 0.9398)
			(stroke
				(width 0.1524)
				(type default)
			)
			(layer "B.SilkS")
		)
		(fp_line
			(start -0.508 -0.9398)
			(end 0.508 -0.9398)
			(stroke
				(width 0.1524)
				(type default)
			)
			(layer "B.SilkS")
		)
		(fp_rect
			(start 0.508 0.9398)
			(end -0.508 -0.9398)
			(stroke
				(width 0)
				(type default)
			)
			(fill no)
			(layer "B.CrtYd")
		)
		(fp_rect
			(start 0.508 0.9398)
			(end -0.508 -0.9398)
			(stroke
				(width 0)
				(type default)
			)
			(fill no)
			(layer "B.Fab")
		)
		(pad "1" smd custom
			(at 0 -0.4445 270)
			(size 0.1397 0.1397)
			(layers "B.Cu" "B.Mask" "B.Paste")
			(net "P12V_PCIE")
			(options
				(clearance outline)
				(anchor circle)
			)
			(primitives
				(gr_poly
					(pts
						(arc
							(start -0.1778 0.2794)
							(mid -0.249642 0.249642)
							(end -0.2794 0.1778)
						)
						(arc
							(start -0.2794 -0.1778)
							(mid -0.249642 -0.249642)
							(end -0.1778 -0.2794)
						)
						(arc
							(start 0.1778 -0.2794)
							(mid 0.249642 -0.249642)
							(end 0.2794 -0.1778)
						)
						(arc
							(start 0.2794 0.1778)
							(mid 0.249642 0.249642)
							(end 0.1778 0.2794)
						)
					)
					(width 0)
					(fill yes)
				)
			)
		)
		(pad "2" smd custom
			(at 0 0.4445 270)
			(size 0.1397 0.1397)
			(layers "B.Cu" "B.Mask" "B.Paste")
			(net "PCIE_MATED#_B")
			(options
				(clearance outline)
				(anchor circle)
			)
			(primitives
				(gr_poly
					(pts
						(arc
							(start -0.1778 0.2794)
							(mid -0.249642 0.249642)
							(end -0.2794 0.1778)
						)
						(arc
							(start -0.2794 -0.1778)
							(mid -0.249642 -0.249642)
							(end -0.1778 -0.2794)
						)
						(arc
							(start 0.1778 -0.2794)
							(mid 0.249642 -0.249642)
							(end 0.2794 -0.1778)
						)
						(arc
							(start 0.2794 0.1778)
							(mid 0.249642 0.249642)
							(end 0.1778 0.2794)
						)
					)
					(width 0)
					(fill yes)
				)
			)
		)
	)
	(footprint ""
		(layer "B.Cu")
		(at 49.60493 -78.158086)
		(property "Reference" "TP189"
			(at 0 0 0)
			(layer "B.SilkS")
			(hide yes)
			(effects
				(font
					(size 1.27 1.27)
				)
				(justify mirror)
			)
		)
		(property "Value" "TPAD32-GP"
			(at 0 -3.166364 0)
			(unlocked yes)
			(layer "B.Fab")
			(hide yes)
			(effects
				(font
					(size 1.016 1.016)
					(thickness 0.1524)
				)
				(justify mirror)
			)
		)
		(property "Device Type" "TPAD32"
			(at 0 -4.690618 0)
			(unlocked yes)
			(layer "B.Fab")
			(hide yes)
			(effects
				(font
					(size 1.016 1.016)
					(thickness 0.1524)
				)
				(justify mirror)
			)
		)
		(duplicate_pad_numbers_are_jumpers no)
		(fp_poly
			(pts
				(arc
					(start 0.4064 0)
					(mid -0.4064 0)
					(end 0.4064 0)
				)
			)
			(stroke
				(width 0)
				(type default)
			)
			(fill no)
			(layer "B.CrtYd")
		)
		(fp_poly
			(pts
				(arc
					(start 0.7112 0)
					(mid -0.7112 0)
					(end 0.7112 0)
				)
			)
			(stroke
				(width 0)
				(type default)
			)
			(fill no)
			(layer "B.Fab")
		)
		(pad "1" smd circle
			(at 0 0 180)
			(size 0.8128 0.8128)
			(layers "B.Cu" "B.Mask" "B.Paste")
			(net "INT_CONN_A_SB4")
		)
	)
	(footprint ""
		(layer "B.Cu")
		(at 113.662206 -41.19626)
		(property "Reference" "STP24"
			(at 0 0 0)
			(layer "B.SilkS")
			(hide yes)
			(effects
				(font
					(size 1.27 1.27)
				)
				(justify mirror)
			)
		)
		(property "Value" "TPAD28"
			(at -0.0127 -1.8034 0)
			(unlocked yes)
			(layer "B.Fab")
			(hide yes)
			(effects
				(font
					(size 1.016 1.016)
					(thickness 0.1524)
				)
				(justify mirror)
			)
		)
		(property "Device Type" "TPAD28"
			(at -0.0127 -3.3274 0)
			(unlocked yes)
			(layer "B.Fab")
			(hide yes)
			(effects
				(font
					(size 1.016 1.016)
					(thickness 0.1524)
				)
				(justify mirror)
			)
		)
		(duplicate_pad_numbers_are_jumpers no)
		(fp_poly
			(pts
				(arc
					(start 0.3556 0)
					(mid -0.3556 0)
					(end 0.3556 0)
				)
			)
			(stroke
				(width 0)
				(type default)
			)
			(fill no)
			(layer "B.CrtYd")
		)
		(fp_poly
			(pts
				(arc
					(start 0.6096 0)
					(mid -0.6096 0)
					(end 0.6096 0)
				)
			)
			(stroke
				(width 0)
				(type default)
			)
			(fill no)
			(layer "B.Fab")
		)
		(pad "1" smd circle
			(at 0 0 180)
			(size 0.7112 0.7112)
			(layers "B.Cu" "B.Mask" "B.Paste")
			(net "IOC_GPIO_38")
		)
	)
	(footprint ""
		(layer "B.Cu")
		(at 95.739966 -52.578)
		(property "Reference" "SC978"
			(at 0 0 0)
			(layer "B.SilkS")
			(hide yes)
			(effects
				(font
					(size 1.27 1.27)
				)
				(justify mirror)
			)
		)
		(property "Value" "SCD1U16V2KX-3GP"
			(at -1.1811 -2.7051 0)
			(unlocked yes)
			(layer "B.Fab")
			(hide yes)
			(effects
				(font
					(size 1.016 1.016)
					(thickness 0.1524)
				)
				(justify mirror)
			)
		)
		(property "Device Type" "C402H22"
			(at -1.1811 -4.2291 0)
			(unlocked yes)
			(layer "B.Fab")
			(hide yes)
			(effects
				(font
					(size 1.016 1.016)
					(thickness 0.1524)
				)
				(justify mirror)
			)
		)
		(duplicate_pad_numbers_are_jumpers no)
		(fp_rect
			(start 0.4318 0.9525)
			(end -0.4318 -0.9525)
			(stroke
				(width 0)
				(type default)
			)
			(fill no)
			(layer "B.CrtYd")
		)
		(fp_rect
			(start 0.4318 0.9525)
			(end -0.4318 -0.9525)
			(stroke
				(width 0)
				(type default)
			)
			(fill no)
			(layer "B.Fab")
		)
		(pad "1" smd custom
			(at 0 -0.4445 180)
			(size 0.1524 0.1524)
			(layers "B.Cu" "B.Mask" "B.Paste")
			(net "P1V8_C")
			(options
				(clearance outline)
				(anchor circle)
			)
			(primitives
				(gr_poly
					(pts
						(arc
							(start 0.3048 0.2032)
							(mid 0.275042 0.275042)
							(end 0.2032 0.3048)
						)
						(arc
							(start -0.2032 0.3048)
							(mid -0.275042 0.275042)
							(end -0.3048 0.2032)
						)
						(arc
							(start -0.3048 -0.2032)
							(mid -0.275042 -0.275042)
							(end -0.2032 -0.3048)
						)
						(arc
							(start 0.2032 -0.3048)
							(mid 0.275042 -0.275042)
							(end 0.3048 -0.2032)
						)
					)
					(width 0)
					(fill yes)
				)
			)
		)
		(pad "2" smd custom
			(at 0 0.4445 180)
			(size 0.1524 0.1524)
			(layers "B.Cu" "B.Mask" "B.Paste")
			(net "GND")
			(options
				(clearance outline)
				(anchor circle)
			)
			(primitives
				(gr_poly
					(pts
						(arc
							(start 0.3048 0.2032)
							(mid 0.275042 0.275042)
							(end 0.2032 0.3048)
						)
						(arc
							(start -0.2032 0.3048)
							(mid -0.275042 0.275042)
							(end -0.3048 0.2032)
						)
						(arc
							(start -0.3048 -0.2032)
							(mid -0.275042 -0.275042)
							(end -0.2032 -0.3048)
						)
						(arc
							(start 0.2032 -0.3048)
							(mid 0.275042 -0.275042)
							(end 0.3048 -0.2032)
						)
					)
					(width 0)
					(fill yes)
				)
			)
		)
	)
	(footprint ""
		(layer "B.Cu")
		(at 93.599 -3.429)
		(property "Reference" "SC1019"
			(at 0 0 0)
			(layer "B.SilkS")
			(hide yes)
			(effects
				(font
					(size 1.27 1.27)
				)
				(justify mirror)
			)
		)
		(property "Value" "SC10U6D3V5KX-4GP"
			(at 0.0762 -6.1214 0)
			(unlocked yes)
			(layer "B.Fab")
			(hide yes)
			(effects
				(font
					(size 1.016 1.016)
					(thickness 0.1524)
				)
				(justify mirror)
			)
		)
		(property "Device Type" "C805H58"
			(at 0.0762 -8.1534 0)
			(unlocked yes)
			(layer "B.Fab")
			(hide yes)
			(effects
				(font
					(size 1.016 1.016)
					(thickness 0.1524)
				)
				(justify mirror)
			)
		)
		(duplicate_pad_numbers_are_jumpers no)
		(fp_line
			(start -0.635 0)
			(end 0.635 0)
			(stroke
				(width 0.508)
				(type default)
			)
			(layer "B.SilkS")
		)
		(fp_rect
			(start 0.9652 1.778)
			(end -0.9652 -1.778)
			(stroke
				(width 0)
				(type default)
			)
			(fill no)
			(layer "B.CrtYd")
		)
		(fp_poly
			(pts
				(xy 0.9652 -1.778) (xy -0.9652 -1.778) (xy -0.9652 1.778) (xy 0.9652 1.778)
			)
			(stroke
				(width 0)
				(type default)
			)
			(fill no)
			(layer "B.Fab")
		)
		(pad "1" smd rect
			(at 0 -0.9652 180)
			(size 1.397 1.143)
			(layers "B.Cu" "B.Mask" "B.Paste")
			(net "P0V955_C")
		)
		(pad "2" smd rect
			(at 0 0.9652 180)
			(size 1.397 1.143)
			(layers "B.Cu" "B.Mask" "B.Paste")
			(net "GND")
		)
	)
	(footprint ""
		(layer "B.Cu")
		(at 116.34597 -82.931 -90)
		(property "Reference" "SC1212"
			(at 0 0 90)
			(layer "B.SilkS")
			(hide yes)
			(effects
				(font
					(size 1.27 1.27)
				)
				(justify mirror)
			)
		)
		(property "Value" "SC1KP50V2KX-1GP"
			(at -1.1811 -2.7051 270)
			(unlocked yes)
			(layer "B.Fab")
			(hide yes)
			(effects
				(font
					(size 1.016 1.016)
					(thickness 0.1524)
				)
				(justify mirror)
			)
		)
		(property "Device Type" "C402H22"
			(at -1.1811 -4.2291 270)
			(unlocked yes)
			(layer "B.Fab")
			(hide yes)
			(effects
				(font
					(size 1.016 1.016)
					(thickness 0.1524)
				)
				(justify mirror)
			)
		)
		(duplicate_pad_numbers_are_jumpers no)
		(fp_rect
			(start 0.4318 0.9525)
			(end -0.4318 -0.9525)
			(stroke
				(width 0)
				(type default)
			)
			(fill no)
			(layer "B.CrtYd")
		)
		(fp_rect
			(start 0.4318 0.9525)
			(end -0.4318 -0.9525)
			(stroke
				(width 0)
				(type default)
			)
			(fill no)
			(layer "B.Fab")
		)
		(pad "1" smd custom
			(at 0 -0.4445 90)
			(size 0.1524 0.1524)
			(layers "B.Cu" "B.Mask" "B.Paste")
			(net "P1V8_E")
			(options
				(clearance outline)
				(anchor circle)
			)
			(primitives
				(gr_poly
					(pts
						(arc
							(start 0.3048 0.2032)
							(mid 0.275042 0.275042)
							(end 0.2032 0.3048)
						)
						(arc
							(start -0.2032 0.3048)
							(mid -0.275042 0.275042)
							(end -0.3048 0.2032)
						)
						(arc
							(start -0.3048 -0.2032)
							(mid -0.275042 -0.275042)
							(end -0.2032 -0.3048)
						)
						(arc
							(start 0.2032 -0.3048)
							(mid 0.275042 -0.275042)
							(end 0.3048 -0.2032)
						)
					)
					(width 0)
					(fill yes)
				)
			)
		)
		(pad "2" smd custom
			(at 0 0.4445 90)
			(size 0.1524 0.1524)
			(layers "B.Cu" "B.Mask" "B.Paste")
			(net "GND")
			(options
				(clearance outline)
				(anchor circle)
			)
			(primitives
				(gr_poly
					(pts
						(arc
							(start 0.3048 0.2032)
							(mid 0.275042 0.275042)
							(end 0.2032 0.3048)
						)
						(arc
							(start -0.2032 0.3048)
							(mid -0.275042 0.275042)
							(end -0.3048 0.2032)
						)
						(arc
							(start -0.3048 -0.2032)
							(mid -0.275042 -0.275042)
							(end -0.2032 -0.3048)
						)
						(arc
							(start 0.2032 -0.3048)
							(mid 0.275042 -0.275042)
							(end 0.3048 -0.2032)
						)
					)
					(width 0)
					(fill yes)
				)
			)
		)
	)
	(footprint ""
		(layer "B.Cu")
		(at 50.87493 -76.761086)
		(property "Reference" "SC1278"
			(at 0 0 0)
			(layer "B.SilkS")
			(hide yes)
			(effects
				(font
					(size 1.27 1.27)
				)
				(justify mirror)
			)
		)
		(property "Value" "SCD01U50V2KX-1GP"
			(at -1.1811 -2.7051 0)
			(unlocked yes)
			(layer "B.Fab")
			(hide yes)
			(effects
				(font
					(size 1.016 1.016)
					(thickness 0.1524)
				)
				(justify mirror)
			)
		)
		(property "Device Type" "C402H22"
			(at -1.1811 -4.2291 0)
			(unlocked yes)
			(layer "B.Fab")
			(hide yes)
			(effects
				(font
					(size 1.016 1.016)
					(thickness 0.1524)
				)
				(justify mirror)
			)
		)
		(duplicate_pad_numbers_are_jumpers no)
		(fp_rect
			(start 0.4318 0.9525)
			(end -0.4318 -0.9525)
			(stroke
				(width 0)
				(type default)
			)
			(fill no)
			(layer "B.CrtYd")
		)
		(fp_rect
			(start 0.4318 0.9525)
			(end -0.4318 -0.9525)
			(stroke
				(width 0)
				(type default)
			)
			(fill no)
			(layer "B.Fab")
		)
		(pad "1" smd custom
			(at 0 -0.4445 180)
			(size 0.1524 0.1524)
			(layers "B.Cu" "B.Mask" "B.Paste")
			(net "SAS_EXP2CONN_RX_P_22")
			(options
				(clearance outline)
				(anchor circle)
			)
			(primitives
				(gr_poly
					(pts
						(arc
							(start 0.3048 0.2032)
							(mid 0.275042 0.275042)
							(end 0.2032 0.3048)
						)
						(arc
							(start -0.2032 0.3048)
							(mid -0.275042 0.275042)
							(end -0.3048 0.2032)
						)
						(arc
							(start -0.3048 -0.2032)
							(mid -0.275042 -0.275042)
							(end -0.2032 -0.3048)
						)
						(arc
							(start 0.2032 -0.3048)
							(mid 0.275042 -0.275042)
							(end 0.3048 -0.2032)
						)
					)
					(width 0)
					(fill yes)
				)
			)
		)
		(pad "2" smd custom
			(at 0 0.4445 180)
			(size 0.1524 0.1524)
			(layers "B.Cu" "B.Mask" "B.Paste")
			(net "MINI_RX_P_22")
			(options
				(clearance outline)
				(anchor circle)
			)
			(primitives
				(gr_poly
					(pts
						(arc
							(start 0.3048 0.2032)
							(mid 0.275042 0.275042)
							(end 0.2032 0.3048)
						)
						(arc
							(start -0.2032 0.3048)
							(mid -0.275042 0.275042)
							(end -0.3048 0.2032)
						)
						(arc
							(start -0.3048 -0.2032)
							(mid -0.275042 -0.275042)
							(end -0.2032 -0.3048)
						)
						(arc
							(start 0.2032 -0.3048)
							(mid 0.275042 -0.275042)
							(end 0.3048 -0.2032)
						)
					)
					(width 0)
					(fill yes)
				)
			)
		)
	)
	(footprint ""
		(layer "B.Cu")
		(at 124.09297 -98.298)
		(property "Reference" "SC1184"
			(at 0 0 0)
			(layer "B.SilkS")
			(hide yes)
			(effects
				(font
					(size 1.27 1.27)
				)
				(justify mirror)
			)
		)
		(property "Value" "SC1U6D3V1MX-GP"
			(at -1.9177 2.0193 0)
			(unlocked yes)
			(layer "B.Fab")
			(hide yes)
			(effects
				(font
					(size 1.016 1.016)
					(thickness 0.1524)
				)
				(justify mirror)
			)
		)
		(property "Device Type" "C0201H14"
			(at -1.9177 0.4953 0)
			(unlocked yes)
			(layer "B.Fab")
			(hide yes)
			(effects
				(font
					(size 1.016 1.016)
					(thickness 0.1524)
				)
				(justify mirror)
			)
		)
		(duplicate_pad_numbers_are_jumpers no)
		(fp_rect
			(start 0.1524 0.3048)
			(end -0.1524 -0.3048)
			(stroke
				(width 0)
				(type default)
			)
			(fill no)
			(layer "B.CrtYd")
		)
		(fp_poly
			(pts
				(xy 0.2794 0.6477) (xy 0.2794 -0.6477) (xy -0.2794 -0.6477) (xy -0.2794 -0.1905) (xy -0.1524 -0.1905)
				(xy -0.1524 -0.3048) (xy 0.1524 -0.3048) (xy 0.1524 0.3048) (xy -0.1524 0.3048) (xy -0.1524 -0.1778)
				(xy -0.2794 -0.1778) (xy -0.2794 0.6477)
			)
			(stroke
				(width 0)
				(type default)
			)
			(fill no)
			(layer "B.CrtYd")
		)
		(fp_rect
			(start 0.2794 0.6477)
			(end -0.2794 -0.6477)
			(stroke
				(width 0)
				(type default)
			)
			(fill no)
			(layer "B.Fab")
		)
		(pad "1" smd custom
			(at 0 -0.2794 180)
			(size 0.0762 0.0762)
			(layers "B.Cu" "B.Mask" "B.Paste")
			(net "GB_VDDA")
			(options
				(clearance outline)
				(anchor circle)
			)
			(primitives
				(gr_poly
					(pts
						(arc
							(start 0.1524 0.127)
							(mid 0.137521 0.162921)
							(end 0.1016 0.1778)
						)
						(arc
							(start -0.1016 0.1778)
							(mid -0.137521 0.162921)
							(end -0.1524 0.127)
						)
						(arc
							(start -0.1524 -0.127)
							(mid -0.137521 -0.162921)
							(end -0.1016 -0.1778)
						)
						(arc
							(start 0.1016 -0.1778)
							(mid 0.137521 -0.162921)
							(end 0.1524 -0.127)
						)
					)
					(width 0)
					(fill yes)
				)
			)
		)
		(pad "2" smd custom
			(at 0 0.2794 180)
			(size 0.0762 0.0762)
			(layers "B.Cu" "B.Mask" "B.Paste")
			(net "GND")
			(options
				(clearance outline)
				(anchor circle)
			)
			(primitives
				(gr_poly
					(pts
						(arc
							(start 0.1524 0.127)
							(mid 0.137521 0.162921)
							(end 0.1016 0.1778)
						)
						(arc
							(start -0.1016 0.1778)
							(mid -0.137521 0.162921)
							(end -0.1524 0.127)
						)
						(arc
							(start -0.1524 -0.127)
							(mid -0.137521 -0.162921)
							(end -0.1016 -0.1778)
						)
						(arc
							(start 0.1016 -0.1778)
							(mid 0.137521 -0.162921)
							(end 0.1524 -0.127)
						)
					)
					(width 0)
					(fill yes)
				)
			)
		)
	)
	(footprint ""
		(layer "B.Cu")
		(at 43.12793 -77.650086)
		(property "Reference" "SC1275"
			(at 0 0 0)
			(layer "B.SilkS")
			(hide yes)
			(effects
				(font
					(size 1.27 1.27)
				)
				(justify mirror)
			)
		)
		(property "Value" "SCD01U50V2KX-1GP"
			(at -1.1811 -2.7051 0)
			(unlocked yes)
			(layer "B.Fab")
			(hide yes)
			(effects
				(font
					(size 1.016 1.016)
					(thickness 0.1524)
				)
				(justify mirror)
			)
		)
		(property "Device Type" "C402H22"
			(at -1.1811 -4.2291 0)
			(unlocked yes)
			(layer "B.Fab")
			(hide yes)
			(effects
				(font
					(size 1.016 1.016)
					(thickness 0.1524)
				)
				(justify mirror)
			)
		)
		(duplicate_pad_numbers_are_jumpers no)
		(fp_rect
			(start 0.4318 0.9525)
			(end -0.4318 -0.9525)
			(stroke
				(width 0)
				(type default)
			)
			(fill no)
			(layer "B.CrtYd")
		)
		(fp_rect
			(start 0.4318 0.9525)
			(end -0.4318 -0.9525)
			(stroke
				(width 0)
				(type default)
			)
			(fill no)
			(layer "B.Fab")
		)
		(pad "1" smd custom
			(at 0 -0.4445 180)
			(size 0.1524 0.1524)
			(layers "B.Cu" "B.Mask" "B.Paste")
			(net "SAS_EXP2CONN_RX_N_20")
			(options
				(clearance outline)
				(anchor circle)
			)
			(primitives
				(gr_poly
					(pts
						(arc
							(start 0.3048 0.2032)
							(mid 0.275042 0.275042)
							(end 0.2032 0.3048)
						)
						(arc
							(start -0.2032 0.3048)
							(mid -0.275042 0.275042)
							(end -0.3048 0.2032)
						)
						(arc
							(start -0.3048 -0.2032)
							(mid -0.275042 -0.275042)
							(end -0.2032 -0.3048)
						)
						(arc
							(start 0.2032 -0.3048)
							(mid 0.275042 -0.275042)
							(end 0.3048 -0.2032)
						)
					)
					(width 0)
					(fill yes)
				)
			)
		)
		(pad "2" smd custom
			(at 0 0.4445 180)
			(size 0.1524 0.1524)
			(layers "B.Cu" "B.Mask" "B.Paste")
			(net "MINI_RX_N_20")
			(options
				(clearance outline)
				(anchor circle)
			)
			(primitives
				(gr_poly
					(pts
						(arc
							(start 0.3048 0.2032)
							(mid 0.275042 0.275042)
							(end 0.2032 0.3048)
						)
						(arc
							(start -0.2032 0.3048)
							(mid -0.275042 0.275042)
							(end -0.3048 0.2032)
						)
						(arc
							(start -0.3048 -0.2032)
							(mid -0.275042 -0.275042)
							(end -0.2032 -0.3048)
						)
						(arc
							(start 0.2032 -0.3048)
							(mid 0.275042 -0.275042)
							(end 0.3048 -0.2032)
						)
					)
					(width 0)
					(fill yes)
				)
			)
		)
	)
	(footprint ""
		(layer "B.Cu")
		(at 105.796842 -82.875882 -90)
		(property "Reference" "SR768"
			(at 0 0 90)
			(layer "B.SilkS")
			(hide yes)
			(effects
				(font
					(size 1.27 1.27)
				)
				(justify mirror)
			)
		)
		(property "Value" "4K75R2F-1-GP"
			(at -0.064008 -3.993896 270)
			(unlocked yes)
			(layer "B.Fab")
			(hide yes)
			(effects
				(font
					(size 1.016 1.016)
					(thickness 0.1524)
				)
				(justify mirror)
			)
		)
		(property "Device Type" "R402H16"
			(at -0.064008 -5.517896 270)
			(unlocked yes)
			(layer "B.Fab")
			(hide yes)
			(effects
				(font
					(size 1.016 1.016)
					(thickness 0.1524)
				)
				(justify mirror)
			)
		)
		(duplicate_pad_numbers_are_jumpers no)
		(fp_line
			(start -0.508 -0.9398)
			(end 0.508 -0.9398)
			(stroke
				(width 0.1524)
				(type default)
			)
			(layer "B.SilkS")
		)
		(fp_line
			(start 0.508 -0.9398)
			(end 0.508 0.9398)
			(stroke
				(width 0.1524)
				(type default)
			)
			(layer "B.SilkS")
		)
		(fp_rect
			(start 0.508 0.9398)
			(end -0.508 -0.9398)
			(stroke
				(width 0)
				(type default)
			)
			(fill no)
			(layer "B.CrtYd")
		)
		(fp_rect
			(start 0.508 0.9398)
			(end -0.508 -0.9398)
			(stroke
				(width 0)
				(type default)
			)
			(fill no)
			(layer "B.Fab")
		)
		(pad "1" smd custom
			(at 0 -0.4445 90)
			(size 0.1397 0.1397)
			(layers "B.Cu" "B.Mask" "B.Paste")
			(net "GND")
			(options
				(clearance outline)
				(anchor circle)
			)
			(primitives
				(gr_poly
					(pts
						(arc
							(start -0.1778 0.2794)
							(mid -0.249642 0.249642)
							(end -0.2794 0.1778)
						)
						(arc
							(start -0.2794 -0.1778)
							(mid -0.249642 -0.249642)
							(end -0.1778 -0.2794)
						)
						(arc
							(start 0.1778 -0.2794)
							(mid 0.249642 -0.249642)
							(end 0.2794 -0.1778)
						)
						(arc
							(start 0.2794 0.1778)
							(mid 0.249642 0.249642)
							(end 0.1778 0.2794)
						)
					)
					(width 0)
					(fill yes)
				)
			)
		)
		(pad "2" smd custom
			(at 0 0.4445 90)
			(size 0.1397 0.1397)
			(layers "B.Cu" "B.Mask" "B.Paste")
			(net "EXP_BLINK_IN")
			(options
				(clearance outline)
				(anchor circle)
			)
			(primitives
				(gr_poly
					(pts
						(arc
							(start -0.1778 0.2794)
							(mid -0.249642 0.249642)
							(end -0.2794 0.1778)
						)
						(arc
							(start -0.2794 -0.1778)
							(mid -0.249642 -0.249642)
							(end -0.1778 -0.2794)
						)
						(arc
							(start 0.1778 -0.2794)
							(mid 0.249642 -0.249642)
							(end 0.2794 -0.1778)
						)
						(arc
							(start 0.2794 0.1778)
							(mid 0.249642 0.249642)
							(end 0.1778 0.2794)
						)
					)
					(width 0)
					(fill yes)
				)
			)
		)
	)
	(footprint ""
		(layer "B.Cu")
		(at 99.822 -239.395)
		(property "Reference" "SR843"
			(at 0 0 0)
			(layer "B.SilkS")
			(hide yes)
			(effects
				(font
					(size 1.27 1.27)
				)
				(justify mirror)
			)
		)
		(property "Value" "4K7R2F-GP"
			(at -0.064008 -3.993896 0)
			(unlocked yes)
			(layer "B.Fab")
			(hide yes)
			(effects
				(font
					(size 1.016 1.016)
					(thickness 0.1524)
				)
				(justify mirror)
			)
		)
		(property "Device Type" "R402H16"
			(at -0.064008 -5.517896 0)
			(unlocked yes)
			(layer "B.Fab")
			(hide yes)
			(effects
				(font
					(size 1.016 1.016)
					(thickness 0.1524)
				)
				(justify mirror)
			)
		)
		(duplicate_pad_numbers_are_jumpers no)
		(fp_line
			(start -0.508 -0.9398)
			(end 0.508 -0.9398)
			(stroke
				(width 0.1524)
				(type default)
			)
			(layer "B.SilkS")
		)
		(fp_line
			(start 0.508 -0.9398)
			(end 0.508 0.9398)
			(stroke
				(width 0.1524)
				(type default)
			)
			(layer "B.SilkS")
		)
		(fp_rect
			(start 0.508 0.9398)
			(end -0.508 -0.9398)
			(stroke
				(width 0)
				(type default)
			)
			(fill no)
			(layer "B.CrtYd")
		)
		(fp_rect
			(start 0.508 0.9398)
			(end -0.508 -0.9398)
			(stroke
				(width 0)
				(type default)
			)
			(fill no)
			(layer "B.Fab")
		)
		(pad "1" smd custom
			(at 0 -0.4445 180)
			(size 0.1397 0.1397)
			(layers "B.Cu" "B.Mask" "B.Paste")
			(net "SAS_FAULT_LED0")
			(options
				(clearance outline)
				(anchor circle)
			)
			(primitives
				(gr_poly
					(pts
						(arc
							(start -0.1778 0.2794)
							(mid -0.249642 0.249642)
							(end -0.2794 0.1778)
						)
						(arc
							(start -0.2794 -0.1778)
							(mid -0.249642 -0.249642)
							(end -0.1778 -0.2794)
						)
						(arc
							(start 0.1778 -0.2794)
							(mid 0.249642 -0.249642)
							(end 0.2794 -0.1778)
						)
						(arc
							(start 0.2794 0.1778)
							(mid 0.249642 0.249642)
							(end 0.1778 0.2794)
						)
					)
					(width 0)
					(fill yes)
				)
			)
		)
		(pad "2" smd custom
			(at 0 0.4445 180)
			(size 0.1397 0.1397)
			(layers "B.Cu" "B.Mask" "B.Paste")
			(net "P3V3_STBY")
			(options
				(clearance outline)
				(anchor circle)
			)
			(primitives
				(gr_poly
					(pts
						(arc
							(start -0.1778 0.2794)
							(mid -0.249642 0.249642)
							(end -0.2794 0.1778)
						)
						(arc
							(start -0.2794 -0.1778)
							(mid -0.249642 -0.249642)
							(end -0.1778 -0.2794)
						)
						(arc
							(start 0.1778 -0.2794)
							(mid 0.249642 -0.249642)
							(end 0.2794 -0.1778)
						)
						(arc
							(start 0.2794 0.1778)
							(mid 0.249642 0.249642)
							(end 0.1778 0.2794)
						)
					)
					(width 0)
					(fill yes)
				)
			)
		)
	)
	(footprint ""
		(layer "B.Cu")
		(at 86.233 -74.041 90)
		(property "Reference" "SQ11"
			(at 0 0 90)
			(layer "B.SilkS")
			(hide yes)
			(effects
				(font
					(size 1.27 1.27)
				)
				(justify mirror)
			)
		)
		(property "Value" "2N7002A-7-GP"
			(at -0.127 -8.9662 90)
			(unlocked yes)
			(layer "B.Fab")
			(hide yes)
			(effects
				(font
					(size 1.016 1.016)
					(thickness 0.1524)
				)
				(justify mirror)
			)
		)
		(property "Device Type" "SOT23DGS2D4H48"
			(at -0.127 -10.4902 90)
			(unlocked yes)
			(layer "B.Fab")
			(hide yes)
			(effects
				(font
					(size 1.016 1.016)
					(thickness 0.1524)
				)
				(justify mirror)
			)
		)
		(duplicate_pad_numbers_are_jumpers no)
		(fp_line
			(start 1.651 -1.778)
			(end 1.651 1.778)
			(stroke
				(width 0.1524)
				(type default)
			)
			(layer "B.SilkS")
		)
		(fp_line
			(start -1.651 -1.778)
			(end 1.651 -1.778)
			(stroke
				(width 0.1524)
				(type default)
			)
			(layer "B.SilkS")
		)
		(fp_line
			(start 1.651 1.778)
			(end -1.651 1.778)
			(stroke
				(width 0.1524)
				(type default)
			)
			(layer "B.SilkS")
		)
		(fp_line
			(start -1.651 1.778)
			(end -1.651 -1.778)
			(stroke
				(width 0.1524)
				(type default)
			)
			(layer "B.SilkS")
		)
		(fp_poly
			(pts
				(xy 1.778 1.8796) (xy 1.778 -1.8796) (xy -1.778 -1.8796) (xy -1.778 1.8796)
			)
			(stroke
				(width 0)
				(type default)
			)
			(fill no)
			(layer "B.CrtYd")
		)
		(fp_poly
			(pts
				(xy 1.778 1.8796) (xy 1.778 -1.8796) (xy -1.778 -1.8796) (xy -1.778 1.8796)
			)
			(stroke
				(width 0)
				(type default)
			)
			(fill no)
			(layer "B.Fab")
		)
		(pad "D" smd custom
			(at 0 -0.9525 270)
			(size 0.1905 0.1905)
			(layers "B.Cu" "B.Mask" "B.Paste")
			(net "P0V955_C_PG_R")
			(options
				(clearance outline)
				(anchor circle)
			)
			(primitives
				(gr_poly
					(pts
						(arc
							(start -0.1778 -0.5715)
							(mid -0.321484 -0.511984)
							(end -0.381 -0.3683)
						)
						(arc
							(start -0.381 0.3683)
							(mid -0.321484 0.511984)
							(end -0.1778 0.5715)
						)
						(arc
							(start 0.1778 0.5715)
							(mid 0.321484 0.511984)
							(end 0.381 0.3683)
						)
						(arc
							(start 0.381 -0.3683)
							(mid 0.321484 -0.511984)
							(end 0.1778 -0.5715)
						)
					)
					(width 0)
					(fill yes)
				)
			)
		)
		(pad "G" smd custom
			(at 0.98425 0.9525 270)
			(size 0.1905 0.1905)
			(layers "B.Cu" "B.Mask" "B.Paste")
			(net "P3V3_STBY_G9")
			(options
				(clearance outline)
				(anchor circle)
			)
			(primitives
				(gr_poly
					(pts
						(arc
							(start -0.1778 -0.5715)
							(mid -0.321484 -0.511984)
							(end -0.381 -0.3683)
						)
						(arc
							(start -0.381 0.3683)
							(mid -0.321484 0.511984)
							(end -0.1778 0.5715)
						)
						(arc
							(start 0.1778 0.5715)
							(mid 0.321484 0.511984)
							(end 0.381 0.3683)
						)
						(arc
							(start 0.381 -0.3683)
							(mid 0.321484 -0.511984)
							(end 0.1778 -0.5715)
						)
					)
					(width 0)
					(fill yes)
				)
			)
		)
		(pad "S" smd custom
			(at -0.98425 0.9525 270)
			(size 0.1905 0.1905)
			(layers "B.Cu" "B.Mask" "B.Paste")
			(net "GND")
			(options
				(clearance outline)
				(anchor circle)
			)
			(primitives
				(gr_poly
					(pts
						(arc
							(start -0.1778 -0.5715)
							(mid -0.321484 -0.511984)
							(end -0.381 -0.3683)
						)
						(arc
							(start -0.381 0.3683)
							(mid -0.321484 0.511984)
							(end -0.1778 0.5715)
						)
						(arc
							(start 0.1778 0.5715)
							(mid 0.321484 0.511984)
							(end 0.381 0.3683)
						)
						(arc
							(start 0.381 -0.3683)
							(mid 0.321484 -0.511984)
							(end 0.1778 -0.5715)
						)
					)
					(width 0)
					(fill yes)
				)
			)
		)
	)
	(footprint ""
		(layer "B.Cu")
		(at 290.9316 -170.9674)
		(property "Reference" "TP85"
			(at 0 0 0)
			(layer "B.SilkS")
			(hide yes)
			(effects
				(font
					(size 1.27 1.27)
				)
				(justify mirror)
			)
		)
		(property "Value" "TPAD28"
			(at 0.0127 -1.6637 0)
			(unlocked yes)
			(layer "B.Fab")
			(hide yes)
			(effects
				(font
					(size 1.016 1.016)
					(thickness 0.1524)
				)
				(justify mirror)
			)
		)
		(property "Device Type" "TPAD28"
			(at 0.0127 -3.1877 0)
			(unlocked yes)
			(layer "B.Fab")
			(hide yes)
			(effects
				(font
					(size 1.016 1.016)
					(thickness 0.1524)
				)
				(justify mirror)
			)
		)
		(duplicate_pad_numbers_are_jumpers no)
		(fp_poly
			(pts
				(arc
					(start 0.3556 0)
					(mid -0.3556 0)
					(end 0.3556 0)
				)
			)
			(stroke
				(width 0)
				(type default)
			)
			(fill no)
			(layer "B.CrtYd")
		)
		(fp_poly
			(pts
				(arc
					(start 0.6096 0)
					(mid -0.6096 0)
					(end 0.6096 0)
				)
			)
			(stroke
				(width 0)
				(type default)
			)
			(fill no)
			(layer "B.Fab")
		)
		(pad "1" smd circle
			(at 0 0 180)
			(size 0.7112 0.7112)
			(layers "B.Cu" "B.Mask" "B.Paste")
			(net "BMC0_TP15")
		)
	)
	(footprint ""
		(layer "B.Cu")
		(at 108.336842 -82.621882 180)
		(property "Reference" "SR770"
			(at 0 0 0)
			(layer "B.SilkS")
			(hide yes)
			(effects
				(font
					(size 1.27 1.27)
				)
				(justify mirror)
			)
		)
		(property "Value" "4K75R2F-1-GP"
			(at -0.064008 -3.993896 180)
			(unlocked yes)
			(layer "B.Fab")
			(hide yes)
			(effects
				(font
					(size 1.016 1.016)
					(thickness 0.1524)
				)
				(justify mirror)
			)
		)
		(property "Device Type" "R402H16"
			(at -0.064008 -5.517896 180)
			(unlocked yes)
			(layer "B.Fab")
			(hide yes)
			(effects
				(font
					(size 1.016 1.016)
					(thickness 0.1524)
				)
				(justify mirror)
			)
		)
		(duplicate_pad_numbers_are_jumpers no)
		(fp_line
			(start 0.508 -0.9398)
			(end 0.508 0.9398)
			(stroke
				(width 0.1524)
				(type default)
			)
			(layer "B.SilkS")
		)
		(fp_line
			(start -0.508 -0.9398)
			(end 0.508 -0.9398)
			(stroke
				(width 0.1524)
				(type default)
			)
			(layer "B.SilkS")
		)
		(fp_rect
			(start 0.508 0.9398)
			(end -0.508 -0.9398)
			(stroke
				(width 0)
				(type default)
			)
			(fill no)
			(layer "B.CrtYd")
		)
		(fp_rect
			(start 0.508 0.9398)
			(end -0.508 -0.9398)
			(stroke
				(width 0)
				(type default)
			)
			(fill no)
			(layer "B.Fab")
		)
		(pad "1" smd custom
			(at 0 -0.4445)
			(size 0.1397 0.1397)
			(layers "B.Cu" "B.Mask" "B.Paste")
			(net "GND")
			(options
				(clearance outline)
				(anchor circle)
			)
			(primitives
				(gr_poly
					(pts
						(arc
							(start -0.1778 0.2794)
							(mid -0.249642 0.249642)
							(end -0.2794 0.1778)
						)
						(arc
							(start -0.2794 -0.1778)
							(mid -0.249642 -0.249642)
							(end -0.1778 -0.2794)
						)
						(arc
							(start 0.1778 -0.2794)
							(mid 0.249642 -0.249642)
							(end 0.2794 -0.1778)
						)
						(arc
							(start 0.2794 0.1778)
							(mid 0.249642 0.249642)
							(end 0.1778 0.2794)
						)
					)
					(width 0)
					(fill yes)
				)
			)
		)
		(pad "2" smd custom
			(at 0 0.4445)
			(size 0.1397 0.1397)
			(layers "B.Cu" "B.Mask" "B.Paste")
			(net "EXP_ADC_IN1")
			(options
				(clearance outline)
				(anchor circle)
			)
			(primitives
				(gr_poly
					(pts
						(arc
							(start -0.1778 0.2794)
							(mid -0.249642 0.249642)
							(end -0.2794 0.1778)
						)
						(arc
							(start -0.2794 -0.1778)
							(mid -0.249642 -0.249642)
							(end -0.1778 -0.2794)
						)
						(arc
							(start 0.1778 -0.2794)
							(mid 0.249642 -0.249642)
							(end 0.2794 -0.1778)
						)
						(arc
							(start 0.2794 0.1778)
							(mid 0.249642 0.249642)
							(end 0.1778 0.2794)
						)
					)
					(width 0)
					(fill yes)
				)
			)
		)
	)
	(footprint ""
		(layer "B.Cu")
		(at 98.679 -50.9524 -90)
		(property "Reference" "SC1043"
			(at 0 0 90)
			(layer "B.SilkS")
			(hide yes)
			(effects
				(font
					(size 1.27 1.27)
				)
				(justify mirror)
			)
		)
		(property "Value" "SCD1U16V2KX-3GP"
			(at -1.1811 -2.7051 270)
			(unlocked yes)
			(layer "B.Fab")
			(hide yes)
			(effects
				(font
					(size 1.016 1.016)
					(thickness 0.1524)
				)
				(justify mirror)
			)
		)
		(property "Device Type" "C402H22"
			(at -1.1811 -4.2291 270)
			(unlocked yes)
			(layer "B.Fab")
			(hide yes)
			(effects
				(font
					(size 1.016 1.016)
					(thickness 0.1524)
				)
				(justify mirror)
			)
		)
		(duplicate_pad_numbers_are_jumpers no)
		(fp_rect
			(start 0.4318 0.9525)
			(end -0.4318 -0.9525)
			(stroke
				(width 0)
				(type default)
			)
			(fill no)
			(layer "B.CrtYd")
		)
		(fp_rect
			(start 0.4318 0.9525)
			(end -0.4318 -0.9525)
			(stroke
				(width 0)
				(type default)
			)
			(fill no)
			(layer "B.Fab")
		)
		(pad "1" smd custom
			(at 0 -0.4445 90)
			(size 0.1524 0.1524)
			(layers "B.Cu" "B.Mask" "B.Paste")
			(net "P0V955_C")
			(options
				(clearance outline)
				(anchor circle)
			)
			(primitives
				(gr_poly
					(pts
						(arc
							(start 0.3048 0.2032)
							(mid 0.275042 0.275042)
							(end 0.2032 0.3048)
						)
						(arc
							(start -0.2032 0.3048)
							(mid -0.275042 0.275042)
							(end -0.3048 0.2032)
						)
						(arc
							(start -0.3048 -0.2032)
							(mid -0.275042 -0.275042)
							(end -0.2032 -0.3048)
						)
						(arc
							(start 0.2032 -0.3048)
							(mid 0.275042 -0.275042)
							(end 0.3048 -0.2032)
						)
					)
					(width 0)
					(fill yes)
				)
			)
		)
		(pad "2" smd custom
			(at 0 0.4445 90)
			(size 0.1524 0.1524)
			(layers "B.Cu" "B.Mask" "B.Paste")
			(net "GND")
			(options
				(clearance outline)
				(anchor circle)
			)
			(primitives
				(gr_poly
					(pts
						(arc
							(start 0.3048 0.2032)
							(mid 0.275042 0.275042)
							(end 0.2032 0.3048)
						)
						(arc
							(start -0.2032 0.3048)
							(mid -0.275042 0.275042)
							(end -0.3048 0.2032)
						)
						(arc
							(start -0.3048 -0.2032)
							(mid -0.275042 -0.275042)
							(end -0.2032 -0.3048)
						)
						(arc
							(start 0.2032 -0.3048)
							(mid 0.275042 -0.275042)
							(end 0.3048 -0.2032)
						)
					)
					(width 0)
					(fill yes)
				)
			)
		)
	)
	(footprint ""
		(layer "B.Cu")
		(at 102.235 -37.719 90)
		(property "Reference" "SC950"
			(at 0 0 90)
			(layer "B.SilkS")
			(hide yes)
			(effects
				(font
					(size 1.27 1.27)
				)
				(justify mirror)
			)
		)
		(property "Value" "SCD1U6D3V1KX-GP"
			(at 2.8321 -1.7399 90)
			(unlocked yes)
			(layer "B.Fab")
			(hide yes)
			(effects
				(font
					(size 1.016 1.016)
					(thickness 0.1524)
				)
				(justify mirror)
			)
		)
		(property "Device Type" "C0201H13"
			(at 2.8321 -3.2639 90)
			(unlocked yes)
			(layer "B.Fab")
			(hide yes)
			(effects
				(font
					(size 1.016 1.016)
					(thickness 0.1524)
				)
				(justify mirror)
			)
		)
		(duplicate_pad_numbers_are_jumpers no)
		(fp_rect
			(start 0.2794 0.6477)
			(end -0.2794 -0.6477)
			(stroke
				(width 0)
				(type default)
			)
			(fill no)
			(layer "B.CrtYd")
		)
		(fp_rect
			(start 0.2794 0.6477)
			(end -0.2794 -0.6477)
			(stroke
				(width 0)
				(type default)
			)
			(fill no)
			(layer "B.Fab")
		)
		(pad "1" smd custom
			(at 0 -0.2794 270)
			(size 0.0762 0.0762)
			(layers "B.Cu" "B.Mask" "B.Paste")
			(net "PCE_AVDD")
			(options
				(clearance outline)
				(anchor circle)
			)
			(primitives
				(gr_poly
					(pts
						(arc
							(start 0.1524 0.127)
							(mid 0.137521 0.162921)
							(end 0.1016 0.1778)
						)
						(arc
							(start -0.1016 0.1778)
							(mid -0.137521 0.162921)
							(end -0.1524 0.127)
						)
						(arc
							(start -0.1524 -0.127)
							(mid -0.137521 -0.162921)
							(end -0.1016 -0.1778)
						)
						(arc
							(start 0.1016 -0.1778)
							(mid 0.137521 -0.162921)
							(end 0.1524 -0.127)
						)
					)
					(width 0)
					(fill yes)
				)
			)
		)
		(pad "2" smd custom
			(at 0 0.2794 270)
			(size 0.0762 0.0762)
			(layers "B.Cu" "B.Mask" "B.Paste")
			(net "GND")
			(options
				(clearance outline)
				(anchor circle)
			)
			(primitives
				(gr_poly
					(pts
						(arc
							(start 0.1524 0.127)
							(mid 0.137521 0.162921)
							(end 0.1016 0.1778)
						)
						(arc
							(start -0.1016 0.1778)
							(mid -0.137521 0.162921)
							(end -0.1524 0.127)
						)
						(arc
							(start -0.1524 -0.127)
							(mid -0.137521 -0.162921)
							(end -0.1016 -0.1778)
						)
						(arc
							(start 0.1016 -0.1778)
							(mid 0.137521 -0.162921)
							(end 0.1524 -0.127)
						)
					)
					(width 0)
					(fill yes)
				)
			)
		)
	)
	(footprint ""
		(layer "B.Cu")
		(at 97.663 -37.973 90)
		(property "Reference" "SC949"
			(at 0 0 90)
			(layer "B.SilkS")
			(hide yes)
			(effects
				(font
					(size 1.27 1.27)
				)
				(justify mirror)
			)
		)
		(property "Value" "SCD1U6D3V1KX-GP"
			(at 2.8321 -1.7399 90)
			(unlocked yes)
			(layer "B.Fab")
			(hide yes)
			(effects
				(font
					(size 1.016 1.016)
					(thickness 0.1524)
				)
				(justify mirror)
			)
		)
		(property "Device Type" "C0201H13"
			(at 2.8321 -3.2639 90)
			(unlocked yes)
			(layer "B.Fab")
			(hide yes)
			(effects
				(font
					(size 1.016 1.016)
					(thickness 0.1524)
				)
				(justify mirror)
			)
		)
		(duplicate_pad_numbers_are_jumpers no)
		(fp_rect
			(start 0.2794 0.6477)
			(end -0.2794 -0.6477)
			(stroke
				(width 0)
				(type default)
			)
			(fill no)
			(layer "B.CrtYd")
		)
		(fp_rect
			(start 0.2794 0.6477)
			(end -0.2794 -0.6477)
			(stroke
				(width 0)
				(type default)
			)
			(fill no)
			(layer "B.Fab")
		)
		(pad "1" smd custom
			(at 0 -0.2794 270)
			(size 0.0762 0.0762)
			(layers "B.Cu" "B.Mask" "B.Paste")
			(net "PCE_AVDD")
			(options
				(clearance outline)
				(anchor circle)
			)
			(primitives
				(gr_poly
					(pts
						(arc
							(start 0.1524 0.127)
							(mid 0.137521 0.162921)
							(end 0.1016 0.1778)
						)
						(arc
							(start -0.1016 0.1778)
							(mid -0.137521 0.162921)
							(end -0.1524 0.127)
						)
						(arc
							(start -0.1524 -0.127)
							(mid -0.137521 -0.162921)
							(end -0.1016 -0.1778)
						)
						(arc
							(start 0.1016 -0.1778)
							(mid 0.137521 -0.162921)
							(end 0.1524 -0.127)
						)
					)
					(width 0)
					(fill yes)
				)
			)
		)
		(pad "2" smd custom
			(at 0 0.2794 270)
			(size 0.0762 0.0762)
			(layers "B.Cu" "B.Mask" "B.Paste")
			(net "GND")
			(options
				(clearance outline)
				(anchor circle)
			)
			(primitives
				(gr_poly
					(pts
						(arc
							(start 0.1524 0.127)
							(mid 0.137521 0.162921)
							(end 0.1016 0.1778)
						)
						(arc
							(start -0.1016 0.1778)
							(mid -0.137521 0.162921)
							(end -0.1524 0.127)
						)
						(arc
							(start -0.1524 -0.127)
							(mid -0.137521 -0.162921)
							(end -0.1016 -0.1778)
						)
						(arc
							(start 0.1016 -0.1778)
							(mid 0.137521 -0.162921)
							(end 0.1524 -0.127)
						)
					)
					(width 0)
					(fill yes)
				)
			)
		)
	)
	(footprint ""
		(layer "B.Cu")
		(at 106.18216 -33.655)
		(property "Reference" "STP27"
			(at 0 0 0)
			(layer "B.SilkS")
			(hide yes)
			(effects
				(font
					(size 1.27 1.27)
				)
				(justify mirror)
			)
		)
		(property "Value" "TPAD28"
			(at -0.0127 -1.8034 0)
			(unlocked yes)
			(layer "B.Fab")
			(hide yes)
			(effects
				(font
					(size 1.016 1.016)
					(thickness 0.1524)
				)
				(justify mirror)
			)
		)
		(property "Device Type" "TPAD28"
			(at -0.0127 -3.3274 0)
			(unlocked yes)
			(layer "B.Fab")
			(hide yes)
			(effects
				(font
					(size 1.016 1.016)
					(thickness 0.1524)
				)
				(justify mirror)
			)
		)
		(duplicate_pad_numbers_are_jumpers no)
		(fp_poly
			(pts
				(arc
					(start 0.3556 0)
					(mid -0.3556 0)
					(end 0.3556 0)
				)
			)
			(stroke
				(width 0)
				(type default)
			)
			(fill no)
			(layer "B.CrtYd")
		)
		(fp_poly
			(pts
				(arc
					(start 0.6096 0)
					(mid -0.6096 0)
					(end 0.6096 0)
				)
			)
			(stroke
				(width 0)
				(type default)
			)
			(fill no)
			(layer "B.Fab")
		)
		(pad "1" smd circle
			(at 0 0 180)
			(size 0.7112 0.7112)
			(layers "B.Cu" "B.Mask" "B.Paste")
			(net "IOC_UART_1_TX")
		)
	)
	(footprint ""
		(layer "B.Cu")
		(at 112.30737 -91.5416 90)
		(property "Reference" "SC1252"
			(at 0 0 90)
			(layer "B.SilkS")
			(hide yes)
			(effects
				(font
					(size 1.27 1.27)
				)
				(justify mirror)
			)
		)
		(property "Value" "SCD1U6D3V1KX-GP"
			(at 2.8321 -1.7399 90)
			(unlocked yes)
			(layer "B.Fab")
			(hide yes)
			(effects
				(font
					(size 1.016 1.016)
					(thickness 0.1524)
				)
				(justify mirror)
			)
		)
		(property "Device Type" "C0201H13"
			(at 2.8321 -3.2639 90)
			(unlocked yes)
			(layer "B.Fab")
			(hide yes)
			(effects
				(font
					(size 1.016 1.016)
					(thickness 0.1524)
				)
				(justify mirror)
			)
		)
		(duplicate_pad_numbers_are_jumpers no)
		(fp_rect
			(start 0.2794 0.6477)
			(end -0.2794 -0.6477)
			(stroke
				(width 0)
				(type default)
			)
			(fill no)
			(layer "B.CrtYd")
		)
		(fp_rect
			(start 0.2794 0.6477)
			(end -0.2794 -0.6477)
			(stroke
				(width 0)
				(type default)
			)
			(fill no)
			(layer "B.Fab")
		)
		(pad "1" smd custom
			(at 0 -0.2794 270)
			(size 0.0762 0.0762)
			(layers "B.Cu" "B.Mask" "B.Paste")
			(net "P0V9_E")
			(options
				(clearance outline)
				(anchor circle)
			)
			(primitives
				(gr_poly
					(pts
						(arc
							(start 0.1524 0.127)
							(mid 0.137521 0.162921)
							(end 0.1016 0.1778)
						)
						(arc
							(start -0.1016 0.1778)
							(mid -0.137521 0.162921)
							(end -0.1524 0.127)
						)
						(arc
							(start -0.1524 -0.127)
							(mid -0.137521 -0.162921)
							(end -0.1016 -0.1778)
						)
						(arc
							(start 0.1016 -0.1778)
							(mid 0.137521 -0.162921)
							(end 0.1524 -0.127)
						)
					)
					(width 0)
					(fill yes)
				)
			)
		)
		(pad "2" smd custom
			(at 0 0.2794 270)
			(size 0.0762 0.0762)
			(layers "B.Cu" "B.Mask" "B.Paste")
			(net "GND")
			(options
				(clearance outline)
				(anchor circle)
			)
			(primitives
				(gr_poly
					(pts
						(arc
							(start 0.1524 0.127)
							(mid 0.137521 0.162921)
							(end 0.1016 0.1778)
						)
						(arc
							(start -0.1016 0.1778)
							(mid -0.137521 0.162921)
							(end -0.1524 0.127)
						)
						(arc
							(start -0.1524 -0.127)
							(mid -0.137521 -0.162921)
							(end -0.1016 -0.1778)
						)
						(arc
							(start 0.1016 -0.1778)
							(mid 0.137521 -0.162921)
							(end 0.1524 -0.127)
						)
					)
					(width 0)
					(fill yes)
				)
			)
		)
	)
	(footprint ""
		(layer "B.Cu")
		(at 16.884904 -100.400866)
		(property "Reference" "C132"
			(at 0 0 0)
			(layer "B.SilkS")
			(hide yes)
			(effects
				(font
					(size 1.27 1.27)
				)
				(justify mirror)
			)
		)
		(property "Value" "SCD01U50V2KX-1GP"
			(at -1.1811 -2.7051 0)
			(unlocked yes)
			(layer "B.Fab")
			(hide yes)
			(effects
				(font
					(size 1.016 1.016)
					(thickness 0.1524)
				)
				(justify mirror)
			)
		)
		(property "Device Type" "C402H22"
			(at -1.1811 -4.2291 0)
			(unlocked yes)
			(layer "B.Fab")
			(hide yes)
			(effects
				(font
					(size 1.016 1.016)
					(thickness 0.1524)
				)
				(justify mirror)
			)
		)
		(duplicate_pad_numbers_are_jumpers no)
		(fp_rect
			(start 0.4318 0.9525)
			(end -0.4318 -0.9525)
			(stroke
				(width 0)
				(type default)
			)
			(fill no)
			(layer "B.CrtYd")
		)
		(fp_rect
			(start 0.4318 0.9525)
			(end -0.4318 -0.9525)
			(stroke
				(width 0)
				(type default)
			)
			(fill no)
			(layer "B.Fab")
		)
		(pad "1" smd custom
			(at 0 -0.4445 180)
			(size 0.1524 0.1524)
			(layers "B.Cu" "B.Mask" "B.Paste")
			(net "IOC_SAS_RX_N6")
			(options
				(clearance outline)
				(anchor circle)
			)
			(primitives
				(gr_poly
					(pts
						(arc
							(start 0.3048 0.2032)
							(mid 0.275042 0.275042)
							(end 0.2032 0.3048)
						)
						(arc
							(start -0.2032 0.3048)
							(mid -0.275042 0.275042)
							(end -0.3048 0.2032)
						)
						(arc
							(start -0.3048 -0.2032)
							(mid -0.275042 -0.275042)
							(end -0.2032 -0.3048)
						)
						(arc
							(start 0.2032 -0.3048)
							(mid 0.275042 -0.275042)
							(end 0.3048 -0.2032)
						)
					)
					(width 0)
					(fill yes)
				)
			)
		)
		(pad "2" smd custom
			(at 0 0.4445 180)
			(size 0.1524 0.1524)
			(layers "B.Cu" "B.Mask" "B.Paste")
			(net "SAS_EXT_CONN_RX18_N")
			(options
				(clearance outline)
				(anchor circle)
			)
			(primitives
				(gr_poly
					(pts
						(arc
							(start 0.3048 0.2032)
							(mid 0.275042 0.275042)
							(end 0.2032 0.3048)
						)
						(arc
							(start -0.2032 0.3048)
							(mid -0.275042 0.275042)
							(end -0.3048 0.2032)
						)
						(arc
							(start -0.3048 -0.2032)
							(mid -0.275042 -0.275042)
							(end -0.2032 -0.3048)
						)
						(arc
							(start 0.2032 -0.3048)
							(mid 0.275042 -0.275042)
							(end 0.3048 -0.2032)
						)
					)
					(width 0)
					(fill yes)
				)
			)
		)
	)
	(footprint ""
		(layer "B.Cu")
		(at 126.63297 -96.52 90)
		(property "Reference" "SC1161"
			(at 0 0 90)
			(layer "B.SilkS")
			(hide yes)
			(effects
				(font
					(size 1.27 1.27)
				)
				(justify mirror)
			)
		)
		(property "Value" "SCD1U6D3V1KX-GP"
			(at 2.8321 -1.7399 90)
			(unlocked yes)
			(layer "B.Fab")
			(hide yes)
			(effects
				(font
					(size 1.016 1.016)
					(thickness 0.1524)
				)
				(justify mirror)
			)
		)
		(property "Device Type" "C0201H13"
			(at 2.8321 -3.2639 90)
			(unlocked yes)
			(layer "B.Fab")
			(hide yes)
			(effects
				(font
					(size 1.016 1.016)
					(thickness 0.1524)
				)
				(justify mirror)
			)
		)
		(duplicate_pad_numbers_are_jumpers no)
		(fp_rect
			(start 0.2794 0.6477)
			(end -0.2794 -0.6477)
			(stroke
				(width 0)
				(type default)
			)
			(fill no)
			(layer "B.CrtYd")
		)
		(fp_rect
			(start 0.2794 0.6477)
			(end -0.2794 -0.6477)
			(stroke
				(width 0)
				(type default)
			)
			(fill no)
			(layer "B.Fab")
		)
		(pad "1" smd custom
			(at 0 -0.2794 270)
			(size 0.0762 0.0762)
			(layers "B.Cu" "B.Mask" "B.Paste")
			(net "GB_VDDA")
			(options
				(clearance outline)
				(anchor circle)
			)
			(primitives
				(gr_poly
					(pts
						(arc
							(start 0.1524 0.127)
							(mid 0.137521 0.162921)
							(end 0.1016 0.1778)
						)
						(arc
							(start -0.1016 0.1778)
							(mid -0.137521 0.162921)
							(end -0.1524 0.127)
						)
						(arc
							(start -0.1524 -0.127)
							(mid -0.137521 -0.162921)
							(end -0.1016 -0.1778)
						)
						(arc
							(start 0.1016 -0.1778)
							(mid 0.137521 -0.162921)
							(end 0.1524 -0.127)
						)
					)
					(width 0)
					(fill yes)
				)
			)
		)
		(pad "2" smd custom
			(at 0 0.2794 270)
			(size 0.0762 0.0762)
			(layers "B.Cu" "B.Mask" "B.Paste")
			(net "GND")
			(options
				(clearance outline)
				(anchor circle)
			)
			(primitives
				(gr_poly
					(pts
						(arc
							(start 0.1524 0.127)
							(mid 0.137521 0.162921)
							(end 0.1016 0.1778)
						)
						(arc
							(start -0.1016 0.1778)
							(mid -0.137521 0.162921)
							(end -0.1524 0.127)
						)
						(arc
							(start -0.1524 -0.127)
							(mid -0.137521 -0.162921)
							(end -0.1016 -0.1778)
						)
						(arc
							(start 0.1016 -0.1778)
							(mid 0.137521 -0.162921)
							(end 0.1524 -0.127)
						)
					)
					(width 0)
					(fill yes)
				)
			)
		)
	)
	(footprint ""
		(layer "B.Cu")
		(at 94.342966 -52.197)
		(property "Reference" "SR673"
			(at 0 0 0)
			(layer "B.SilkS")
			(hide yes)
			(effects
				(font
					(size 1.27 1.27)
				)
				(justify mirror)
			)
		)
		(property "Value" "4K7R2F-GP"
			(at -0.064008 -3.993896 0)
			(unlocked yes)
			(layer "B.Fab")
			(hide yes)
			(effects
				(font
					(size 1.016 1.016)
					(thickness 0.1524)
				)
				(justify mirror)
			)
		)
		(property "Device Type" "R402H16"
			(at -0.064008 -5.517896 0)
			(unlocked yes)
			(layer "B.Fab")
			(hide yes)
			(effects
				(font
					(size 1.016 1.016)
					(thickness 0.1524)
				)
				(justify mirror)
			)
		)
		(duplicate_pad_numbers_are_jumpers no)
		(fp_line
			(start -0.508 -0.9398)
			(end 0.508 -0.9398)
			(stroke
				(width 0.1524)
				(type default)
			)
			(layer "B.SilkS")
		)
		(fp_line
			(start 0.508 -0.9398)
			(end 0.508 0.9398)
			(stroke
				(width 0.1524)
				(type default)
			)
			(layer "B.SilkS")
		)
		(fp_rect
			(start 0.508 0.9398)
			(end -0.508 -0.9398)
			(stroke
				(width 0)
				(type default)
			)
			(fill no)
			(layer "B.CrtYd")
		)
		(fp_rect
			(start 0.508 0.9398)
			(end -0.508 -0.9398)
			(stroke
				(width 0)
				(type default)
			)
			(fill no)
			(layer "B.Fab")
		)
		(pad "1" smd custom
			(at 0 -0.4445 180)
			(size 0.1397 0.1397)
			(layers "B.Cu" "B.Mask" "B.Paste")
			(net "P1V8_C")
			(options
				(clearance outline)
				(anchor circle)
			)
			(primitives
				(gr_poly
					(pts
						(arc
							(start -0.1778 0.2794)
							(mid -0.249642 0.249642)
							(end -0.2794 0.1778)
						)
						(arc
							(start -0.2794 -0.1778)
							(mid -0.249642 -0.249642)
							(end -0.1778 -0.2794)
						)
						(arc
							(start 0.1778 -0.2794)
							(mid 0.249642 -0.249642)
							(end 0.2794 -0.1778)
						)
						(arc
							(start 0.2794 0.1778)
							(mid 0.249642 0.249642)
							(end 0.1778 0.2794)
						)
					)
					(width 0)
					(fill yes)
				)
			)
		)
		(pad "2" smd custom
			(at 0 0.4445 180)
			(size 0.1397 0.1397)
			(layers "B.Cu" "B.Mask" "B.Paste")
			(net "ICE1_TDI")
			(options
				(clearance outline)
				(anchor circle)
			)
			(primitives
				(gr_poly
					(pts
						(arc
							(start -0.1778 0.2794)
							(mid -0.249642 0.249642)
							(end -0.2794 0.1778)
						)
						(arc
							(start -0.2794 -0.1778)
							(mid -0.249642 -0.249642)
							(end -0.1778 -0.2794)
						)
						(arc
							(start 0.1778 -0.2794)
							(mid 0.249642 -0.249642)
							(end 0.2794 -0.1778)
						)
						(arc
							(start 0.2794 0.1778)
							(mid 0.249642 0.249642)
							(end 0.1778 0.2794)
						)
					)
					(width 0)
					(fill yes)
				)
			)
		)
	)
	(footprint ""
		(layer "B.Cu")
		(at 78.220062 -62.700408 180)
		(property "Reference" "SL4"
			(at 0 0 0)
			(layer "B.SilkS")
			(hide yes)
			(effects
				(font
					(size 1.27 1.27)
				)
				(justify mirror)
			)
		)
		(property "Value" "MPZ2012S601AT-GP"
			(at 0 -4.2418 180)
			(unlocked yes)
			(layer "B.Fab")
			(hide yes)
			(effects
				(font
					(size 1.016 1.016)
					(thickness 0.1524)
				)
				(justify mirror)
			)
		)
		(property "Device Type" "L805H42"
			(at 0 -5.7912 180)
			(unlocked yes)
			(layer "B.Fab")
			(hide yes)
			(effects
				(font
					(size 1.016 1.016)
					(thickness 0.1524)
				)
				(justify mirror)
			)
		)
		(duplicate_pad_numbers_are_jumpers no)
		(fp_line
			(start 0.889 1.7018)
			(end 0.889 -1.7018)
			(stroke
				(width 0.1524)
				(type default)
			)
			(layer "B.SilkS")
		)
		(fp_line
			(start 0.889 -1.7018)
			(end -0.889 -1.7018)
			(stroke
				(width 0.1524)
				(type default)
			)
			(layer "B.SilkS")
		)
		(fp_line
			(start -0.889 1.7018)
			(end 0.889 1.7018)
			(stroke
				(width 0.1524)
				(type default)
			)
			(layer "B.SilkS")
		)
		(fp_line
			(start -0.889 -1.7018)
			(end -0.889 1.7018)
			(stroke
				(width 0.1524)
				(type default)
			)
			(layer "B.SilkS")
		)
		(fp_rect
			(start 0.9652 1.778)
			(end -0.9652 -1.778)
			(stroke
				(width 0)
				(type default)
			)
			(fill no)
			(layer "B.CrtYd")
		)
		(fp_rect
			(start 0.9652 1.778)
			(end -0.9652 -1.778)
			(stroke
				(width 0)
				(type default)
			)
			(fill no)
			(layer "B.Fab")
		)
		(pad "1" smd rect
			(at 0 -0.9652)
			(size 1.397 1.143)
			(layers "B.Cu" "B.Mask" "B.Paste")
			(net "VDDA_SAS_REF_CLK")
		)
		(pad "2" smd rect
			(at 0 0.9652)
			(size 1.397 1.143)
			(layers "B.Cu" "B.Mask" "B.Paste")
			(net "P1V8_C")
		)
	)
	(footprint ""
		(layer "B.Cu")
		(at 94.294706 -48.30318)
		(property "Reference" "SC1013"
			(at 0 0 0)
			(layer "B.SilkS")
			(hide yes)
			(effects
				(font
					(size 1.27 1.27)
				)
				(justify mirror)
			)
		)
		(property "Value" "SC1KP50V2KX-1GP"
			(at -1.1811 -2.7051 0)
			(unlocked yes)
			(layer "B.Fab")
			(hide yes)
			(effects
				(font
					(size 1.016 1.016)
					(thickness 0.1524)
				)
				(justify mirror)
			)
		)
		(property "Device Type" "C402H22"
			(at -1.1811 -4.2291 0)
			(unlocked yes)
			(layer "B.Fab")
			(hide yes)
			(effects
				(font
					(size 1.016 1.016)
					(thickness 0.1524)
				)
				(justify mirror)
			)
		)
		(duplicate_pad_numbers_are_jumpers no)
		(fp_rect
			(start 0.4318 0.9525)
			(end -0.4318 -0.9525)
			(stroke
				(width 0)
				(type default)
			)
			(fill no)
			(layer "B.CrtYd")
		)
		(fp_rect
			(start 0.4318 0.9525)
			(end -0.4318 -0.9525)
			(stroke
				(width 0)
				(type default)
			)
			(fill no)
			(layer "B.Fab")
		)
		(pad "1" smd custom
			(at 0 -0.4445 180)
			(size 0.1524 0.1524)
			(layers "B.Cu" "B.Mask" "B.Paste")
			(net "P1V8_C")
			(options
				(clearance outline)
				(anchor circle)
			)
			(primitives
				(gr_poly
					(pts
						(arc
							(start 0.3048 0.2032)
							(mid 0.275042 0.275042)
							(end 0.2032 0.3048)
						)
						(arc
							(start -0.2032 0.3048)
							(mid -0.275042 0.275042)
							(end -0.3048 0.2032)
						)
						(arc
							(start -0.3048 -0.2032)
							(mid -0.275042 -0.275042)
							(end -0.2032 -0.3048)
						)
						(arc
							(start 0.2032 -0.3048)
							(mid 0.275042 -0.275042)
							(end 0.3048 -0.2032)
						)
					)
					(width 0)
					(fill yes)
				)
			)
		)
		(pad "2" smd custom
			(at 0 0.4445 180)
			(size 0.1524 0.1524)
			(layers "B.Cu" "B.Mask" "B.Paste")
			(net "GND")
			(options
				(clearance outline)
				(anchor circle)
			)
			(primitives
				(gr_poly
					(pts
						(arc
							(start 0.3048 0.2032)
							(mid 0.275042 0.275042)
							(end 0.2032 0.3048)
						)
						(arc
							(start -0.2032 0.3048)
							(mid -0.275042 0.275042)
							(end -0.3048 0.2032)
						)
						(arc
							(start -0.3048 -0.2032)
							(mid -0.275042 -0.275042)
							(end -0.2032 -0.3048)
						)
						(arc
							(start 0.2032 -0.3048)
							(mid 0.275042 -0.275042)
							(end 0.3048 -0.2032)
						)
					)
					(width 0)
					(fill yes)
				)
			)
		)
	)
	(footprint ""
		(layer "B.Cu")
		(at 101.48697 -109.982 180)
		(property "Reference" "SR746"
			(at 0 0 0)
			(layer "B.SilkS")
			(hide yes)
			(effects
				(font
					(size 1.27 1.27)
				)
				(justify mirror)
			)
		)
		(property "Value" "4K7R2F-GP"
			(at -0.064008 -3.993896 180)
			(unlocked yes)
			(layer "B.Fab")
			(hide yes)
			(effects
				(font
					(size 1.016 1.016)
					(thickness 0.1524)
				)
				(justify mirror)
			)
		)
		(property "Device Type" "R402H16"
			(at -0.064008 -5.517896 180)
			(unlocked yes)
			(layer "B.Fab")
			(hide yes)
			(effects
				(font
					(size 1.016 1.016)
					(thickness 0.1524)
				)
				(justify mirror)
			)
		)
		(duplicate_pad_numbers_are_jumpers no)
		(fp_line
			(start 0.508 -0.9398)
			(end 0.508 0.9398)
			(stroke
				(width 0.1524)
				(type default)
			)
			(layer "B.SilkS")
		)
		(fp_line
			(start -0.508 -0.9398)
			(end 0.508 -0.9398)
			(stroke
				(width 0.1524)
				(type default)
			)
			(layer "B.SilkS")
		)
		(fp_rect
			(start 0.508 0.9398)
			(end -0.508 -0.9398)
			(stroke
				(width 0)
				(type default)
			)
			(fill no)
			(layer "B.CrtYd")
		)
		(fp_rect
			(start 0.508 0.9398)
			(end -0.508 -0.9398)
			(stroke
				(width 0)
				(type default)
			)
			(fill no)
			(layer "B.Fab")
		)
		(pad "1" smd custom
			(at 0 -0.4445)
			(size 0.1397 0.1397)
			(layers "B.Cu" "B.Mask" "B.Paste")
			(net "EXP_SIO_CLK_OUT")
			(options
				(clearance outline)
				(anchor circle)
			)
			(primitives
				(gr_poly
					(pts
						(arc
							(start -0.1778 0.2794)
							(mid -0.249642 0.249642)
							(end -0.2794 0.1778)
						)
						(arc
							(start -0.2794 -0.1778)
							(mid -0.249642 -0.249642)
							(end -0.1778 -0.2794)
						)
						(arc
							(start 0.1778 -0.2794)
							(mid 0.249642 -0.249642)
							(end 0.2794 -0.1778)
						)
						(arc
							(start 0.2794 0.1778)
							(mid 0.249642 0.249642)
							(end 0.1778 0.2794)
						)
					)
					(width 0)
					(fill yes)
				)
			)
		)
		(pad "2" smd custom
			(at 0 0.4445)
			(size 0.1397 0.1397)
			(layers "B.Cu" "B.Mask" "B.Paste")
			(net "P1V8_E")
			(options
				(clearance outline)
				(anchor circle)
			)
			(primitives
				(gr_poly
					(pts
						(arc
							(start -0.1778 0.2794)
							(mid -0.249642 0.249642)
							(end -0.2794 0.1778)
						)
						(arc
							(start -0.2794 -0.1778)
							(mid -0.249642 -0.249642)
							(end -0.1778 -0.2794)
						)
						(arc
							(start 0.1778 -0.2794)
							(mid 0.249642 -0.249642)
							(end 0.2794 -0.1778)
						)
						(arc
							(start 0.2794 0.1778)
							(mid 0.249642 0.249642)
							(end 0.1778 0.2794)
						)
					)
					(width 0)
					(fill yes)
				)
			)
		)
	)
	(footprint ""
		(layer "B.Cu")
		(at 120.142 -40.005 -90)
		(property "Reference" "SR619"
			(at 0 0 90)
			(layer "B.SilkS")
			(hide yes)
			(effects
				(font
					(size 1.27 1.27)
				)
				(justify mirror)
			)
		)
		(property "Value" "2K2R2F-GP"
			(at -0.064008 -3.993896 270)
			(unlocked yes)
			(layer "B.Fab")
			(hide yes)
			(effects
				(font
					(size 1.016 1.016)
					(thickness 0.1524)
				)
				(justify mirror)
			)
		)
		(property "Device Type" "R402H16"
			(at -0.064008 -5.517896 270)
			(unlocked yes)
			(layer "B.Fab")
			(hide yes)
			(effects
				(font
					(size 1.016 1.016)
					(thickness 0.1524)
				)
				(justify mirror)
			)
		)
		(duplicate_pad_numbers_are_jumpers no)
		(fp_line
			(start -0.508 -0.9398)
			(end 0.508 -0.9398)
			(stroke
				(width 0.1524)
				(type default)
			)
			(layer "B.SilkS")
		)
		(fp_line
			(start 0.508 -0.9398)
			(end 0.508 0.9398)
			(stroke
				(width 0.1524)
				(type default)
			)
			(layer "B.SilkS")
		)
		(fp_rect
			(start 0.508 0.9398)
			(end -0.508 -0.9398)
			(stroke
				(width 0)
				(type default)
			)
			(fill no)
			(layer "B.CrtYd")
		)
		(fp_rect
			(start 0.508 0.9398)
			(end -0.508 -0.9398)
			(stroke
				(width 0)
				(type default)
			)
			(fill no)
			(layer "B.Fab")
		)
		(pad "1" smd custom
			(at 0 -0.4445 90)
			(size 0.1397 0.1397)
			(layers "B.Cu" "B.Mask" "B.Paste")
			(net "P1V8_C")
			(options
				(clearance outline)
				(anchor circle)
			)
			(primitives
				(gr_poly
					(pts
						(arc
							(start -0.1778 0.2794)
							(mid -0.249642 0.249642)
							(end -0.2794 0.1778)
						)
						(arc
							(start -0.2794 -0.1778)
							(mid -0.249642 -0.249642)
							(end -0.1778 -0.2794)
						)
						(arc
							(start 0.1778 -0.2794)
							(mid 0.249642 -0.249642)
							(end 0.2794 -0.1778)
						)
						(arc
							(start 0.2794 0.1778)
							(mid 0.249642 0.249642)
							(end 0.1778 0.2794)
						)
					)
					(width 0)
					(fill yes)
				)
			)
		)
		(pad "2" smd custom
			(at 0 0.4445 90)
			(size 0.1397 0.1397)
			(layers "B.Cu" "B.Mask" "B.Paste")
			(net "IOC_SDA_1")
			(options
				(clearance outline)
				(anchor circle)
			)
			(primitives
				(gr_poly
					(pts
						(arc
							(start -0.1778 0.2794)
							(mid -0.249642 0.249642)
							(end -0.2794 0.1778)
						)
						(arc
							(start -0.2794 -0.1778)
							(mid -0.249642 -0.249642)
							(end -0.1778 -0.2794)
						)
						(arc
							(start 0.1778 -0.2794)
							(mid 0.249642 -0.249642)
							(end 0.2794 -0.1778)
						)
						(arc
							(start 0.2794 0.1778)
							(mid 0.249642 0.249642)
							(end 0.1778 0.2794)
						)
					)
					(width 0)
					(fill yes)
				)
			)
		)
	)
	(footprint ""
		(layer "B.Cu")
		(at 284.92704 -169.07256)
		(property "Reference" "TP163"
			(at 0 0 0)
			(layer "B.SilkS")
			(hide yes)
			(effects
				(font
					(size 1.27 1.27)
				)
				(justify mirror)
			)
		)
		(property "Value" "TPAD28"
			(at -0.0127 -1.8034 0)
			(unlocked yes)
			(layer "B.Fab")
			(hide yes)
			(effects
				(font
					(size 1.016 1.016)
					(thickness 0.1524)
				)
				(justify mirror)
			)
		)
		(property "Device Type" "TPAD28"
			(at -0.0127 -3.3274 0)
			(unlocked yes)
			(layer "B.Fab")
			(hide yes)
			(effects
				(font
					(size 1.016 1.016)
					(thickness 0.1524)
				)
				(justify mirror)
			)
		)
		(duplicate_pad_numbers_are_jumpers no)
		(fp_poly
			(pts
				(arc
					(start 0.3556 0)
					(mid -0.3556 0)
					(end 0.3556 0)
				)
			)
			(stroke
				(width 0)
				(type default)
			)
			(fill no)
			(layer "B.CrtYd")
		)
		(fp_poly
			(pts
				(arc
					(start 0.6096 0)
					(mid -0.6096 0)
					(end 0.6096 0)
				)
			)
			(stroke
				(width 0)
				(type default)
			)
			(fill no)
			(layer "B.Fab")
		)
		(pad "1" smd circle
			(at 0 0 180)
			(size 0.7112 0.7112)
			(layers "B.Cu" "B.Mask" "B.Paste")
			(net "TP_BMC_GPIOB7")
		)
	)
	(footprint ""
		(layer "B.Cu")
		(at 95.53956 -47.4472)
		(property "Reference" "STP29"
			(at 0 0 0)
			(layer "B.SilkS")
			(hide yes)
			(effects
				(font
					(size 1.27 1.27)
				)
				(justify mirror)
			)
		)
		(property "Value" "TPAD28"
			(at -0.0127 -1.8034 0)
			(unlocked yes)
			(layer "B.Fab")
			(hide yes)
			(effects
				(font
					(size 1.016 1.016)
					(thickness 0.1524)
				)
				(justify mirror)
			)
		)
		(property "Device Type" "TPAD28"
			(at -0.0127 -3.3274 0)
			(unlocked yes)
			(layer "B.Fab")
			(hide yes)
			(effects
				(font
					(size 1.016 1.016)
					(thickness 0.1524)
				)
				(justify mirror)
			)
		)
		(duplicate_pad_numbers_are_jumpers no)
		(fp_poly
			(pts
				(arc
					(start 0.3556 0)
					(mid -0.3556 0)
					(end 0.3556 0)
				)
			)
			(stroke
				(width 0)
				(type default)
			)
			(fill no)
			(layer "B.CrtYd")
		)
		(fp_poly
			(pts
				(arc
					(start 0.6096 0)
					(mid -0.6096 0)
					(end 0.6096 0)
				)
			)
			(stroke
				(width 0)
				(type default)
			)
			(fill no)
			(layer "B.Fab")
		)
		(pad "1" smd circle
			(at 0 0 180)
			(size 0.7112 0.7112)
			(layers "B.Cu" "B.Mask" "B.Paste")
			(net "ICE_SEL")
		)
	)
	(footprint ""
		(layer "B.Cu")
		(at 97.9932 -52.559966 -90)
		(property "Reference" "SC1022"
			(at 0 0 90)
			(layer "B.SilkS")
			(hide yes)
			(effects
				(font
					(size 1.27 1.27)
				)
				(justify mirror)
			)
		)
		(property "Value" "SC10U6D3V5KX-4GP"
			(at 0.0762 -6.1214 270)
			(unlocked yes)
			(layer "B.Fab")
			(hide yes)
			(effects
				(font
					(size 1.016 1.016)
					(thickness 0.1524)
				)
				(justify mirror)
			)
		)
		(property "Device Type" "C805H58"
			(at 0.0762 -8.1534 270)
			(unlocked yes)
			(layer "B.Fab")
			(hide yes)
			(effects
				(font
					(size 1.016 1.016)
					(thickness 0.1524)
				)
				(justify mirror)
			)
		)
		(duplicate_pad_numbers_are_jumpers no)
		(fp_line
			(start -0.635 0)
			(end 0.635 0)
			(stroke
				(width 0.508)
				(type default)
			)
			(layer "B.SilkS")
		)
		(fp_rect
			(start 0.9652 1.778)
			(end -0.9652 -1.778)
			(stroke
				(width 0)
				(type default)
			)
			(fill no)
			(layer "B.CrtYd")
		)
		(fp_poly
			(pts
				(xy 0.9652 -1.778) (xy -0.9652 -1.778) (xy -0.9652 1.778) (xy 0.9652 1.778)
			)
			(stroke
				(width 0)
				(type default)
			)
			(fill no)
			(layer "B.Fab")
		)
		(pad "1" smd rect
			(at 0 -0.9652 90)
			(size 1.397 1.143)
			(layers "B.Cu" "B.Mask" "B.Paste")
			(net "P0V955_C")
		)
		(pad "2" smd rect
			(at 0 0.9652 90)
			(size 1.397 1.143)
			(layers "B.Cu" "B.Mask" "B.Paste")
			(net "GND")
		)
	)
	(footprint ""
		(layer "B.Cu")
		(at 115.17757 -101.3968 180)
		(property "Reference" "SC1138"
			(at 0 0 0)
			(layer "B.SilkS")
			(hide yes)
			(effects
				(font
					(size 1.27 1.27)
				)
				(justify mirror)
			)
		)
		(property "Value" "SCD1U6D3V1KX-GP"
			(at 2.8321 -1.7399 180)
			(unlocked yes)
			(layer "B.Fab")
			(hide yes)
			(effects
				(font
					(size 1.016 1.016)
					(thickness 0.1524)
				)
				(justify mirror)
			)
		)
		(property "Device Type" "C0201H13"
			(at 2.8321 -3.2639 180)
			(unlocked yes)
			(layer "B.Fab")
			(hide yes)
			(effects
				(font
					(size 1.016 1.016)
					(thickness 0.1524)
				)
				(justify mirror)
			)
		)
		(duplicate_pad_numbers_are_jumpers no)
		(fp_rect
			(start 0.2794 0.6477)
			(end -0.2794 -0.6477)
			(stroke
				(width 0)
				(type default)
			)
			(fill no)
			(layer "B.CrtYd")
		)
		(fp_rect
			(start 0.2794 0.6477)
			(end -0.2794 -0.6477)
			(stroke
				(width 0)
				(type default)
			)
			(fill no)
			(layer "B.Fab")
		)
		(pad "1" smd custom
			(at 0 -0.2794)
			(size 0.0762 0.0762)
			(layers "B.Cu" "B.Mask" "B.Paste")
			(net "GB_VDDH2")
			(options
				(clearance outline)
				(anchor circle)
			)
			(primitives
				(gr_poly
					(pts
						(arc
							(start 0.1524 0.127)
							(mid 0.137521 0.162921)
							(end 0.1016 0.1778)
						)
						(arc
							(start -0.1016 0.1778)
							(mid -0.137521 0.162921)
							(end -0.1524 0.127)
						)
						(arc
							(start -0.1524 -0.127)
							(mid -0.137521 -0.162921)
							(end -0.1016 -0.1778)
						)
						(arc
							(start 0.1016 -0.1778)
							(mid 0.137521 -0.162921)
							(end 0.1524 -0.127)
						)
					)
					(width 0)
					(fill yes)
				)
			)
		)
		(pad "2" smd custom
			(at 0 0.2794)
			(size 0.0762 0.0762)
			(layers "B.Cu" "B.Mask" "B.Paste")
			(net "GND")
			(options
				(clearance outline)
				(anchor circle)
			)
			(primitives
				(gr_poly
					(pts
						(arc
							(start 0.1524 0.127)
							(mid 0.137521 0.162921)
							(end 0.1016 0.1778)
						)
						(arc
							(start -0.1016 0.1778)
							(mid -0.137521 0.162921)
							(end -0.1524 0.127)
						)
						(arc
							(start -0.1524 -0.127)
							(mid -0.137521 -0.162921)
							(end -0.1016 -0.1778)
						)
						(arc
							(start 0.1016 -0.1778)
							(mid 0.137521 -0.162921)
							(end 0.1524 -0.127)
						)
					)
					(width 0)
					(fill yes)
				)
			)
		)
	)
	(footprint ""
		(layer "B.Cu")
		(at 18.238216 -216.71788 90)
		(property "Reference" "SC428"
			(at 0 0 90)
			(layer "B.SilkS")
			(hide yes)
			(effects
				(font
					(size 1.27 1.27)
				)
				(justify mirror)
			)
		)
		(property "Value" "SCD1U16V2KX-3GP"
			(at -1.1811 -2.7051 90)
			(unlocked yes)
			(layer "B.Fab")
			(hide yes)
			(effects
				(font
					(size 1.016 1.016)
					(thickness 0.1524)
				)
				(justify mirror)
			)
		)
		(property "Device Type" "C402H22"
			(at -1.1811 -4.2291 90)
			(unlocked yes)
			(layer "B.Fab")
			(hide yes)
			(effects
				(font
					(size 1.016 1.016)
					(thickness 0.1524)
				)
				(justify mirror)
			)
		)
		(duplicate_pad_numbers_are_jumpers no)
		(fp_rect
			(start 0.4318 0.9525)
			(end -0.4318 -0.9525)
			(stroke
				(width 0)
				(type default)
			)
			(fill no)
			(layer "B.CrtYd")
		)
		(fp_rect
			(start 0.4318 0.9525)
			(end -0.4318 -0.9525)
			(stroke
				(width 0)
				(type default)
			)
			(fill no)
			(layer "B.Fab")
		)
		(pad "1" smd custom
			(at 0 -0.4445 270)
			(size 0.1524 0.1524)
			(layers "B.Cu" "B.Mask" "B.Paste")
			(net "P1V8_E")
			(options
				(clearance outline)
				(anchor circle)
			)
			(primitives
				(gr_poly
					(pts
						(arc
							(start 0.3048 0.2032)
							(mid 0.275042 0.275042)
							(end 0.2032 0.3048)
						)
						(arc
							(start -0.2032 0.3048)
							(mid -0.275042 0.275042)
							(end -0.3048 0.2032)
						)
						(arc
							(start -0.3048 -0.2032)
							(mid -0.275042 -0.275042)
							(end -0.2032 -0.3048)
						)
						(arc
							(start 0.2032 -0.3048)
							(mid 0.275042 -0.275042)
							(end 0.3048 -0.2032)
						)
					)
					(width 0)
					(fill yes)
				)
			)
		)
		(pad "2" smd custom
			(at 0 0.4445 270)
			(size 0.1524 0.1524)
			(layers "B.Cu" "B.Mask" "B.Paste")
			(net "GND")
			(options
				(clearance outline)
				(anchor circle)
			)
			(primitives
				(gr_poly
					(pts
						(arc
							(start 0.3048 0.2032)
							(mid 0.275042 0.275042)
							(end 0.2032 0.3048)
						)
						(arc
							(start -0.2032 0.3048)
							(mid -0.275042 0.275042)
							(end -0.3048 0.2032)
						)
						(arc
							(start -0.3048 -0.2032)
							(mid -0.275042 -0.275042)
							(end -0.2032 -0.3048)
						)
						(arc
							(start 0.2032 -0.3048)
							(mid 0.275042 -0.275042)
							(end 0.3048 -0.2032)
						)
					)
					(width 0)
					(fill yes)
				)
			)
		)
	)
	(footprint ""
		(layer "B.Cu")
		(at 91.04376 -48.0822)
		(property "Reference" "STP9"
			(at 0 0 0)
			(layer "B.SilkS")
			(hide yes)
			(effects
				(font
					(size 1.27 1.27)
				)
				(justify mirror)
			)
		)
		(property "Value" "TPAD28"
			(at -0.0127 -1.8034 0)
			(unlocked yes)
			(layer "B.Fab")
			(hide yes)
			(effects
				(font
					(size 1.016 1.016)
					(thickness 0.1524)
				)
				(justify mirror)
			)
		)
		(property "Device Type" "TPAD28"
			(at -0.0127 -3.3274 0)
			(unlocked yes)
			(layer "B.Fab")
			(hide yes)
			(effects
				(font
					(size 1.016 1.016)
					(thickness 0.1524)
				)
				(justify mirror)
			)
		)
		(duplicate_pad_numbers_are_jumpers no)
		(fp_poly
			(pts
				(arc
					(start 0.3556 0)
					(mid -0.3556 0)
					(end 0.3556 0)
				)
			)
			(stroke
				(width 0)
				(type default)
			)
			(fill no)
			(layer "B.CrtYd")
		)
		(fp_poly
			(pts
				(arc
					(start 0.6096 0)
					(mid -0.6096 0)
					(end 0.6096 0)
				)
			)
			(stroke
				(width 0)
				(type default)
			)
			(fill no)
			(layer "B.Fab")
		)
		(pad "1" smd circle
			(at 0 0 180)
			(size 0.7112 0.7112)
			(layers "B.Cu" "B.Mask" "B.Paste")
			(net "SIO_LOAD_0")
		)
	)
	(footprint ""
		(layer "B.Cu")
		(at 303.276 -178.562)
		(property "Reference" "TP162"
			(at 0 0 0)
			(layer "B.SilkS")
			(hide yes)
			(effects
				(font
					(size 1.27 1.27)
				)
				(justify mirror)
			)
		)
		(property "Value" "TPAD28"
			(at -0.0127 -1.8034 0)
			(unlocked yes)
			(layer "B.Fab")
			(hide yes)
			(effects
				(font
					(size 1.016 1.016)
					(thickness 0.1524)
				)
				(justify mirror)
			)
		)
		(property "Device Type" "TPAD28"
			(at -0.0127 -3.3274 0)
			(unlocked yes)
			(layer "B.Fab")
			(hide yes)
			(effects
				(font
					(size 1.016 1.016)
					(thickness 0.1524)
				)
				(justify mirror)
			)
		)
		(duplicate_pad_numbers_are_jumpers no)
		(fp_poly
			(pts
				(arc
					(start 0.3556 0)
					(mid -0.3556 0)
					(end 0.3556 0)
				)
			)
			(stroke
				(width 0)
				(type default)
			)
			(fill no)
			(layer "B.CrtYd")
		)
		(fp_poly
			(pts
				(arc
					(start 0.6096 0)
					(mid -0.6096 0)
					(end 0.6096 0)
				)
			)
			(stroke
				(width 0)
				(type default)
			)
			(fill no)
			(layer "B.Fab")
		)
		(pad "1" smd circle
			(at 0 0 180)
			(size 0.7112 0.7112)
			(layers "B.Cu" "B.Mask" "B.Paste")
			(net "TP_BMC_GPIOJ7")
		)
	)
	(footprint ""
		(layer "B.Cu")
		(at 89.67216 -51.435)
		(property "Reference" "STP18"
			(at 0 0 0)
			(layer "B.SilkS")
			(hide yes)
			(effects
				(font
					(size 1.27 1.27)
				)
				(justify mirror)
			)
		)
		(property "Value" "TPAD28"
			(at -0.0127 -1.8034 0)
			(unlocked yes)
			(layer "B.Fab")
			(hide yes)
			(effects
				(font
					(size 1.016 1.016)
					(thickness 0.1524)
				)
				(justify mirror)
			)
		)
		(property "Device Type" "TPAD28"
			(at -0.0127 -3.3274 0)
			(unlocked yes)
			(layer "B.Fab")
			(hide yes)
			(effects
				(font
					(size 1.016 1.016)
					(thickness 0.1524)
				)
				(justify mirror)
			)
		)
		(duplicate_pad_numbers_are_jumpers no)
		(fp_poly
			(pts
				(arc
					(start 0.3556 0)
					(mid -0.3556 0)
					(end 0.3556 0)
				)
			)
			(stroke
				(width 0)
				(type default)
			)
			(fill no)
			(layer "B.CrtYd")
		)
		(fp_poly
			(pts
				(arc
					(start 0.6096 0)
					(mid -0.6096 0)
					(end 0.6096 0)
				)
			)
			(stroke
				(width 0)
				(type default)
			)
			(fill no)
			(layer "B.Fab")
		)
		(pad "1" smd circle
			(at 0 0 180)
			(size 0.7112 0.7112)
			(layers "B.Cu" "B.Mask" "B.Paste")
			(net "SIO_LOAD_1")
		)
	)
	(footprint ""
		(layer "B.Cu")
		(at 124.21997 -100.33)
		(property "Reference" "SC1191"
			(at 0 0 0)
			(layer "B.SilkS")
			(hide yes)
			(effects
				(font
					(size 1.27 1.27)
				)
				(justify mirror)
			)
		)
		(property "Value" "SCD1U6D3V1KX-GP"
			(at 2.8321 -1.7399 0)
			(unlocked yes)
			(layer "B.Fab")
			(hide yes)
			(effects
				(font
					(size 1.016 1.016)
					(thickness 0.1524)
				)
				(justify mirror)
			)
		)
		(property "Device Type" "C0201H13"
			(at 2.8321 -3.2639 0)
			(unlocked yes)
			(layer "B.Fab")
			(hide yes)
			(effects
				(font
					(size 1.016 1.016)
					(thickness 0.1524)
				)
				(justify mirror)
			)
		)
		(duplicate_pad_numbers_are_jumpers no)
		(fp_rect
			(start 0.2794 0.6477)
			(end -0.2794 -0.6477)
			(stroke
				(width 0)
				(type default)
			)
			(fill no)
			(layer "B.CrtYd")
		)
		(fp_rect
			(start 0.2794 0.6477)
			(end -0.2794 -0.6477)
			(stroke
				(width 0)
				(type default)
			)
			(fill no)
			(layer "B.Fab")
		)
		(pad "1" smd custom
			(at 0 -0.2794 180)
			(size 0.0762 0.0762)
			(layers "B.Cu" "B.Mask" "B.Paste")
			(net "GB_VDDA")
			(options
				(clearance outline)
				(anchor circle)
			)
			(primitives
				(gr_poly
					(pts
						(arc
							(start 0.1524 0.127)
							(mid 0.137521 0.162921)
							(end 0.1016 0.1778)
						)
						(arc
							(start -0.1016 0.1778)
							(mid -0.137521 0.162921)
							(end -0.1524 0.127)
						)
						(arc
							(start -0.1524 -0.127)
							(mid -0.137521 -0.162921)
							(end -0.1016 -0.1778)
						)
						(arc
							(start 0.1016 -0.1778)
							(mid 0.137521 -0.162921)
							(end 0.1524 -0.127)
						)
					)
					(width 0)
					(fill yes)
				)
			)
		)
		(pad "2" smd custom
			(at 0 0.2794 180)
			(size 0.0762 0.0762)
			(layers "B.Cu" "B.Mask" "B.Paste")
			(net "GND")
			(options
				(clearance outline)
				(anchor circle)
			)
			(primitives
				(gr_poly
					(pts
						(arc
							(start 0.1524 0.127)
							(mid 0.137521 0.162921)
							(end 0.1016 0.1778)
						)
						(arc
							(start -0.1016 0.1778)
							(mid -0.137521 0.162921)
							(end -0.1524 0.127)
						)
						(arc
							(start -0.1524 -0.127)
							(mid -0.137521 -0.162921)
							(end -0.1016 -0.1778)
						)
						(arc
							(start 0.1016 -0.1778)
							(mid 0.137521 -0.162921)
							(end 0.1524 -0.127)
						)
					)
					(width 0)
					(fill yes)
				)
			)
		)
	)
	(footprint ""
		(layer "B.Cu")
		(at 113.570766 -39.878)
		(property "Reference" "STP22"
			(at 0 0 0)
			(layer "B.SilkS")
			(hide yes)
			(effects
				(font
					(size 1.27 1.27)
				)
				(justify mirror)
			)
		)
		(property "Value" "TPAD28"
			(at -0.0127 -1.8034 0)
			(unlocked yes)
			(layer "B.Fab")
			(hide yes)
			(effects
				(font
					(size 1.016 1.016)
					(thickness 0.1524)
				)
				(justify mirror)
			)
		)
		(property "Device Type" "TPAD28"
			(at -0.0127 -3.3274 0)
			(unlocked yes)
			(layer "B.Fab")
			(hide yes)
			(effects
				(font
					(size 1.016 1.016)
					(thickness 0.1524)
				)
				(justify mirror)
			)
		)
		(duplicate_pad_numbers_are_jumpers no)
		(fp_poly
			(pts
				(arc
					(start 0.3556 0)
					(mid -0.3556 0)
					(end 0.3556 0)
				)
			)
			(stroke
				(width 0)
				(type default)
			)
			(fill no)
			(layer "B.CrtYd")
		)
		(fp_poly
			(pts
				(arc
					(start 0.6096 0)
					(mid -0.6096 0)
					(end 0.6096 0)
				)
			)
			(stroke
				(width 0)
				(type default)
			)
			(fill no)
			(layer "B.Fab")
		)
		(pad "1" smd circle
			(at 0 0 180)
			(size 0.7112 0.7112)
			(layers "B.Cu" "B.Mask" "B.Paste")
			(net "IOC_GPIO_36")
		)
	)
	(footprint ""
		(layer "B.Cu")
		(at 51.76393 -76.761086)
		(property "Reference" "SC1279"
			(at 0 0 0)
			(layer "B.SilkS")
			(hide yes)
			(effects
				(font
					(size 1.27 1.27)
				)
				(justify mirror)
			)
		)
		(property "Value" "SCD01U50V2KX-1GP"
			(at -1.1811 -2.7051 0)
			(unlocked yes)
			(layer "B.Fab")
			(hide yes)
			(effects
				(font
					(size 1.016 1.016)
					(thickness 0.1524)
				)
				(justify mirror)
			)
		)
		(property "Device Type" "C402H22"
			(at -1.1811 -4.2291 0)
			(unlocked yes)
			(layer "B.Fab")
			(hide yes)
			(effects
				(font
					(size 1.016 1.016)
					(thickness 0.1524)
				)
				(justify mirror)
			)
		)
		(duplicate_pad_numbers_are_jumpers no)
		(fp_rect
			(start 0.4318 0.9525)
			(end -0.4318 -0.9525)
			(stroke
				(width 0)
				(type default)
			)
			(fill no)
			(layer "B.CrtYd")
		)
		(fp_rect
			(start 0.4318 0.9525)
			(end -0.4318 -0.9525)
			(stroke
				(width 0)
				(type default)
			)
			(fill no)
			(layer "B.Fab")
		)
		(pad "1" smd custom
			(at 0 -0.4445 180)
			(size 0.1524 0.1524)
			(layers "B.Cu" "B.Mask" "B.Paste")
			(net "SAS_EXP2CONN_RX_N_22")
			(options
				(clearance outline)
				(anchor circle)
			)
			(primitives
				(gr_poly
					(pts
						(arc
							(start 0.3048 0.2032)
							(mid 0.275042 0.275042)
							(end 0.2032 0.3048)
						)
						(arc
							(start -0.2032 0.3048)
							(mid -0.275042 0.275042)
							(end -0.3048 0.2032)
						)
						(arc
							(start -0.3048 -0.2032)
							(mid -0.275042 -0.275042)
							(end -0.2032 -0.3048)
						)
						(arc
							(start 0.2032 -0.3048)
							(mid 0.275042 -0.275042)
							(end 0.3048 -0.2032)
						)
					)
					(width 0)
					(fill yes)
				)
			)
		)
		(pad "2" smd custom
			(at 0 0.4445 180)
			(size 0.1524 0.1524)
			(layers "B.Cu" "B.Mask" "B.Paste")
			(net "MINI_RX_N_22")
			(options
				(clearance outline)
				(anchor circle)
			)
			(primitives
				(gr_poly
					(pts
						(arc
							(start 0.3048 0.2032)
							(mid 0.275042 0.275042)
							(end 0.2032 0.3048)
						)
						(arc
							(start -0.2032 0.3048)
							(mid -0.275042 0.275042)
							(end -0.3048 0.2032)
						)
						(arc
							(start -0.3048 -0.2032)
							(mid -0.275042 -0.275042)
							(end -0.2032 -0.3048)
						)
						(arc
							(start 0.2032 -0.3048)
							(mid 0.275042 -0.275042)
							(end 0.3048 -0.2032)
						)
					)
					(width 0)
					(fill yes)
				)
			)
		)
	)
	(footprint ""
		(layer "B.Cu")
		(at 108.312966 -49.784)
		(property "Reference" "TP260"
			(at 0 0 0)
			(layer "B.SilkS")
			(hide yes)
			(effects
				(font
					(size 1.27 1.27)
				)
				(justify mirror)
			)
		)
		(property "Value" "TPAD28"
			(at -0.0127 -1.8034 0)
			(unlocked yes)
			(layer "B.Fab")
			(hide yes)
			(effects
				(font
					(size 1.016 1.016)
					(thickness 0.1524)
				)
				(justify mirror)
			)
		)
		(property "Device Type" "TPAD28"
			(at -0.0127 -3.3274 0)
			(unlocked yes)
			(layer "B.Fab")
			(hide yes)
			(effects
				(font
					(size 1.016 1.016)
					(thickness 0.1524)
				)
				(justify mirror)
			)
		)
		(duplicate_pad_numbers_are_jumpers no)
		(fp_poly
			(pts
				(arc
					(start 0.3556 0)
					(mid -0.3556 0)
					(end 0.3556 0)
				)
			)
			(stroke
				(width 0)
				(type default)
			)
			(fill no)
			(layer "B.CrtYd")
		)
		(fp_poly
			(pts
				(arc
					(start 0.6096 0)
					(mid -0.6096 0)
					(end 0.6096 0)
				)
			)
			(stroke
				(width 0)
				(type default)
			)
			(fill no)
			(layer "B.Fab")
		)
		(pad "1" smd circle
			(at 0 0 180)
			(size 0.7112 0.7112)
			(layers "B.Cu" "B.Mask" "B.Paste")
			(net "VDDIO_15")
		)
	)
	(footprint ""
		(layer "B.Cu")
		(at 94.7928 -46.11116)
		(property "Reference" "SR667"
			(at 0 0 0)
			(layer "B.SilkS")
			(hide yes)
			(effects
				(font
					(size 1.27 1.27)
				)
				(justify mirror)
			)
		)
		(property "Value" "10KR2F-2-GP"
			(at -0.064008 -3.993896 0)
			(unlocked yes)
			(layer "B.Fab")
			(hide yes)
			(effects
				(font
					(size 1.016 1.016)
					(thickness 0.1524)
				)
				(justify mirror)
			)
		)
		(property "Device Type" "R402H16"
			(at -0.064008 -5.517896 0)
			(unlocked yes)
			(layer "B.Fab")
			(hide yes)
			(effects
				(font
					(size 1.016 1.016)
					(thickness 0.1524)
				)
				(justify mirror)
			)
		)
		(duplicate_pad_numbers_are_jumpers no)
		(fp_line
			(start -0.508 -0.9398)
			(end 0.508 -0.9398)
			(stroke
				(width 0.1524)
				(type default)
			)
			(layer "B.SilkS")
		)
		(fp_line
			(start 0.508 -0.9398)
			(end 0.508 0.9398)
			(stroke
				(width 0.1524)
				(type default)
			)
			(layer "B.SilkS")
		)
		(fp_rect
			(start 0.508 0.9398)
			(end -0.508 -0.9398)
			(stroke
				(width 0)
				(type default)
			)
			(fill no)
			(layer "B.CrtYd")
		)
		(fp_rect
			(start 0.508 0.9398)
			(end -0.508 -0.9398)
			(stroke
				(width 0)
				(type default)
			)
			(fill no)
			(layer "B.Fab")
		)
		(pad "1" smd custom
			(at 0 -0.4445 180)
			(size 0.1397 0.1397)
			(layers "B.Cu" "B.Mask" "B.Paste")
			(net "P1V8_C")
			(options
				(clearance outline)
				(anchor circle)
			)
			(primitives
				(gr_poly
					(pts
						(arc
							(start -0.1778 0.2794)
							(mid -0.249642 0.249642)
							(end -0.2794 0.1778)
						)
						(arc
							(start -0.2794 -0.1778)
							(mid -0.249642 -0.249642)
							(end -0.1778 -0.2794)
						)
						(arc
							(start 0.1778 -0.2794)
							(mid 0.249642 -0.249642)
							(end 0.2794 -0.1778)
						)
						(arc
							(start 0.2794 0.1778)
							(mid 0.249642 0.249642)
							(end 0.1778 0.2794)
						)
					)
					(width 0)
					(fill yes)
				)
			)
		)
		(pad "2" smd custom
			(at 0 0.4445 180)
			(size 0.1397 0.1397)
			(layers "B.Cu" "B.Mask" "B.Paste")
			(net "POWERLOSS#")
			(options
				(clearance outline)
				(anchor circle)
			)
			(primitives
				(gr_poly
					(pts
						(arc
							(start -0.1778 0.2794)
							(mid -0.249642 0.249642)
							(end -0.2794 0.1778)
						)
						(arc
							(start -0.2794 -0.1778)
							(mid -0.249642 -0.249642)
							(end -0.1778 -0.2794)
						)
						(arc
							(start 0.1778 -0.2794)
							(mid 0.249642 -0.249642)
							(end 0.2794 -0.1778)
						)
						(arc
							(start 0.2794 0.1778)
							(mid 0.249642 0.249642)
							(end 0.1778 0.2794)
						)
					)
					(width 0)
					(fill yes)
				)
			)
		)
	)
	(footprint ""
		(layer "B.Cu")
		(at 89.154 -100.203)
		(property "Reference" "SR822"
			(at 0 0 0)
			(layer "B.SilkS")
			(hide yes)
			(effects
				(font
					(size 1.27 1.27)
				)
				(justify mirror)
			)
		)
		(property "Value" "4K75R2F-1-GP"
			(at -0.064008 -3.993896 0)
			(unlocked yes)
			(layer "B.Fab")
			(hide yes)
			(effects
				(font
					(size 1.016 1.016)
					(thickness 0.1524)
				)
				(justify mirror)
			)
		)
		(property "Device Type" "R402H16"
			(at -0.064008 -5.517896 0)
			(unlocked yes)
			(layer "B.Fab")
			(hide yes)
			(effects
				(font
					(size 1.016 1.016)
					(thickness 0.1524)
				)
				(justify mirror)
			)
		)
		(duplicate_pad_numbers_are_jumpers no)
		(fp_line
			(start -0.508 -0.9398)
			(end 0.508 -0.9398)
			(stroke
				(width 0.1524)
				(type default)
			)
			(layer "B.SilkS")
		)
		(fp_line
			(start 0.508 -0.9398)
			(end 0.508 0.9398)
			(stroke
				(width 0.1524)
				(type default)
			)
			(layer "B.SilkS")
		)
		(fp_rect
			(start 0.508 0.9398)
			(end -0.508 -0.9398)
			(stroke
				(width 0)
				(type default)
			)
			(fill no)
			(layer "B.CrtYd")
		)
		(fp_rect
			(start 0.508 0.9398)
			(end -0.508 -0.9398)
			(stroke
				(width 0)
				(type default)
			)
			(fill no)
			(layer "B.Fab")
		)
		(pad "1" smd custom
			(at 0 -0.4445 180)
			(size 0.1397 0.1397)
			(layers "B.Cu" "B.Mask" "B.Paste")
			(net "EXP_FW_DET_BOARD_VER_1")
			(options
				(clearance outline)
				(anchor circle)
			)
			(primitives
				(gr_poly
					(pts
						(arc
							(start -0.1778 0.2794)
							(mid -0.249642 0.249642)
							(end -0.2794 0.1778)
						)
						(arc
							(start -0.2794 -0.1778)
							(mid -0.249642 -0.249642)
							(end -0.1778 -0.2794)
						)
						(arc
							(start 0.1778 -0.2794)
							(mid 0.249642 -0.249642)
							(end 0.2794 -0.1778)
						)
						(arc
							(start 0.2794 0.1778)
							(mid 0.249642 0.249642)
							(end 0.1778 0.2794)
						)
					)
					(width 0)
					(fill yes)
				)
			)
		)
		(pad "2" smd custom
			(at 0 0.4445 180)
			(size 0.1397 0.1397)
			(layers "B.Cu" "B.Mask" "B.Paste")
			(net "GND")
			(options
				(clearance outline)
				(anchor circle)
			)
			(primitives
				(gr_poly
					(pts
						(arc
							(start -0.1778 0.2794)
							(mid -0.249642 0.249642)
							(end -0.2794 0.1778)
						)
						(arc
							(start -0.2794 -0.1778)
							(mid -0.249642 -0.249642)
							(end -0.1778 -0.2794)
						)
						(arc
							(start 0.1778 -0.2794)
							(mid 0.249642 -0.249642)
							(end 0.2794 -0.1778)
						)
						(arc
							(start 0.2794 0.1778)
							(mid 0.249642 0.249642)
							(end 0.1778 0.2794)
						)
					)
					(width 0)
					(fill yes)
				)
			)
		)
	)
	(footprint ""
		(layer "B.Cu")
		(at 100.711 -82.677)
		(property "Reference" "SC1203"
			(at 0 0 0)
			(layer "B.SilkS")
			(hide yes)
			(effects
				(font
					(size 1.27 1.27)
				)
				(justify mirror)
			)
		)
		(property "Value" "SC10U6D3V5KX-4GP"
			(at 0.0762 -6.1214 0)
			(unlocked yes)
			(layer "B.Fab")
			(hide yes)
			(effects
				(font
					(size 1.016 1.016)
					(thickness 0.1524)
				)
				(justify mirror)
			)
		)
		(property "Device Type" "C805H58"
			(at 0.0762 -8.1534 0)
			(unlocked yes)
			(layer "B.Fab")
			(hide yes)
			(effects
				(font
					(size 1.016 1.016)
					(thickness 0.1524)
				)
				(justify mirror)
			)
		)
		(duplicate_pad_numbers_are_jumpers no)
		(fp_line
			(start -0.635 0)
			(end 0.635 0)
			(stroke
				(width 0.508)
				(type default)
			)
			(layer "B.SilkS")
		)
		(fp_rect
			(start 0.9652 1.778)
			(end -0.9652 -1.778)
			(stroke
				(width 0)
				(type default)
			)
			(fill no)
			(layer "B.CrtYd")
		)
		(fp_poly
			(pts
				(xy 0.9652 -1.778) (xy -0.9652 -1.778) (xy -0.9652 1.778) (xy 0.9652 1.778)
			)
			(stroke
				(width 0)
				(type default)
			)
			(fill no)
			(layer "B.Fab")
		)
		(pad "1" smd rect
			(at 0 -0.9652 180)
			(size 1.397 1.143)
			(layers "B.Cu" "B.Mask" "B.Paste")
			(net "P1V8_E")
		)
		(pad "2" smd rect
			(at 0 0.9652 180)
			(size 1.397 1.143)
			(layers "B.Cu" "B.Mask" "B.Paste")
			(net "GND")
		)
	)
	(footprint ""
		(layer "B.Cu")
		(at 117.856 -72.771 -90)
		(property "Reference" "SR957"
			(at 0 0 90)
			(layer "B.SilkS")
			(hide yes)
			(effects
				(font
					(size 1.27 1.27)
				)
				(justify mirror)
			)
		)
		(property "Value" "0R2J-2-GP"
			(at -0.064008 -3.993896 270)
			(unlocked yes)
			(layer "B.Fab")
			(hide yes)
			(effects
				(font
					(size 1.016 1.016)
					(thickness 0.1524)
				)
				(justify mirror)
			)
		)
		(property "Device Type" "R402H16"
			(at -0.064008 -5.517896 270)
			(unlocked yes)
			(layer "B.Fab")
			(hide yes)
			(effects
				(font
					(size 1.016 1.016)
					(thickness 0.1524)
				)
				(justify mirror)
			)
		)
		(duplicate_pad_numbers_are_jumpers no)
		(fp_line
			(start -0.508 -0.9398)
			(end 0.508 -0.9398)
			(stroke
				(width 0.1524)
				(type default)
			)
			(layer "B.SilkS")
		)
		(fp_line
			(start 0.508 -0.9398)
			(end 0.508 0.9398)
			(stroke
				(width 0.1524)
				(type default)
			)
			(layer "B.SilkS")
		)
		(fp_rect
			(start 0.508 0.9398)
			(end -0.508 -0.9398)
			(stroke
				(width 0)
				(type default)
			)
			(fill no)
			(layer "B.CrtYd")
		)
		(fp_rect
			(start 0.508 0.9398)
			(end -0.508 -0.9398)
			(stroke
				(width 0)
				(type default)
			)
			(fill no)
			(layer "B.Fab")
		)
		(pad "1" smd custom
			(at 0 -0.4445 90)
			(size 0.1397 0.1397)
			(layers "B.Cu" "B.Mask" "B.Paste")
			(net "SYS_RST_N_0")
			(options
				(clearance outline)
				(anchor circle)
			)
			(primitives
				(gr_poly
					(pts
						(arc
							(start -0.1778 0.2794)
							(mid -0.249642 0.249642)
							(end -0.2794 0.1778)
						)
						(arc
							(start -0.2794 -0.1778)
							(mid -0.249642 -0.249642)
							(end -0.1778 -0.2794)
						)
						(arc
							(start 0.1778 -0.2794)
							(mid 0.249642 -0.249642)
							(end 0.2794 -0.1778)
						)
						(arc
							(start 0.2794 0.1778)
							(mid 0.249642 0.249642)
							(end 0.1778 0.2794)
						)
					)
					(width 0)
					(fill yes)
				)
			)
		)
		(pad "2" smd custom
			(at 0 0.4445 90)
			(size 0.1397 0.1397)
			(layers "B.Cu" "B.Mask" "B.Paste")
			(net "EXP_LED_12")
			(options
				(clearance outline)
				(anchor circle)
			)
			(primitives
				(gr_poly
					(pts
						(arc
							(start -0.1778 0.2794)
							(mid -0.249642 0.249642)
							(end -0.2794 0.1778)
						)
						(arc
							(start -0.2794 -0.1778)
							(mid -0.249642 -0.249642)
							(end -0.1778 -0.2794)
						)
						(arc
							(start 0.1778 -0.2794)
							(mid 0.249642 -0.249642)
							(end 0.2794 -0.1778)
						)
						(arc
							(start 0.2794 0.1778)
							(mid 0.249642 0.249642)
							(end 0.1778 0.2794)
						)
					)
					(width 0)
					(fill yes)
				)
			)
		)
	)
	(footprint ""
		(layer "B.Cu")
		(at 113.04016 -29.972 -90)
		(property "Reference" "SR645"
			(at 0 0 90)
			(layer "B.SilkS")
			(hide yes)
			(effects
				(font
					(size 1.27 1.27)
				)
				(justify mirror)
			)
		)
		(property "Value" "4K7R2F-GP"
			(at -0.064008 -3.993896 270)
			(unlocked yes)
			(layer "B.Fab")
			(hide yes)
			(effects
				(font
					(size 1.016 1.016)
					(thickness 0.1524)
				)
				(justify mirror)
			)
		)
		(property "Device Type" "R402H16"
			(at -0.064008 -5.517896 270)
			(unlocked yes)
			(layer "B.Fab")
			(hide yes)
			(effects
				(font
					(size 1.016 1.016)
					(thickness 0.1524)
				)
				(justify mirror)
			)
		)
		(duplicate_pad_numbers_are_jumpers no)
		(fp_line
			(start -0.508 -0.9398)
			(end 0.508 -0.9398)
			(stroke
				(width 0.1524)
				(type default)
			)
			(layer "B.SilkS")
		)
		(fp_line
			(start 0.508 -0.9398)
			(end 0.508 0.9398)
			(stroke
				(width 0.1524)
				(type default)
			)
			(layer "B.SilkS")
		)
		(fp_rect
			(start 0.508 0.9398)
			(end -0.508 -0.9398)
			(stroke
				(width 0)
				(type default)
			)
			(fill no)
			(layer "B.CrtYd")
		)
		(fp_rect
			(start 0.508 0.9398)
			(end -0.508 -0.9398)
			(stroke
				(width 0)
				(type default)
			)
			(fill no)
			(layer "B.Fab")
		)
		(pad "1" smd custom
			(at 0 -0.4445 90)
			(size 0.1397 0.1397)
			(layers "B.Cu" "B.Mask" "B.Paste")
			(net "P1V8_C")
			(options
				(clearance outline)
				(anchor circle)
			)
			(primitives
				(gr_poly
					(pts
						(arc
							(start -0.1778 0.2794)
							(mid -0.249642 0.249642)
							(end -0.2794 0.1778)
						)
						(arc
							(start -0.2794 -0.1778)
							(mid -0.249642 -0.249642)
							(end -0.1778 -0.2794)
						)
						(arc
							(start 0.1778 -0.2794)
							(mid 0.249642 -0.249642)
							(end 0.2794 -0.1778)
						)
						(arc
							(start 0.2794 0.1778)
							(mid 0.249642 0.249642)
							(end 0.1778 0.2794)
						)
					)
					(width 0)
					(fill yes)
				)
			)
		)
		(pad "2" smd custom
			(at 0 0.4445 90)
			(size 0.1397 0.1397)
			(layers "B.Cu" "B.Mask" "B.Paste")
			(net "IOC_UART_1_RX")
			(options
				(clearance outline)
				(anchor circle)
			)
			(primitives
				(gr_poly
					(pts
						(arc
							(start -0.1778 0.2794)
							(mid -0.249642 0.249642)
							(end -0.2794 0.1778)
						)
						(arc
							(start -0.2794 -0.1778)
							(mid -0.249642 -0.249642)
							(end -0.1778 -0.2794)
						)
						(arc
							(start 0.1778 -0.2794)
							(mid 0.249642 -0.249642)
							(end 0.2794 -0.1778)
						)
						(arc
							(start 0.2794 0.1778)
							(mid 0.249642 0.249642)
							(end 0.1778 0.2794)
						)
					)
					(width 0)
					(fill yes)
				)
			)
		)
	)
	(footprint ""
		(layer "B.Cu")
		(at 325.374 -184.404)
		(property "Reference" "R5763"
			(at 0 0 0)
			(layer "B.SilkS")
			(hide yes)
			(effects
				(font
					(size 1.27 1.27)
				)
				(justify mirror)
			)
		)
		(property "Value" "1KR2F-3-GP"
			(at -0.064008 -3.993896 0)
			(unlocked yes)
			(layer "B.Fab")
			(hide yes)
			(effects
				(font
					(size 1.016 1.016)
					(thickness 0.1524)
				)
				(justify mirror)
			)
		)
		(property "Device Type" "R402H16"
			(at -0.064008 -5.517896 0)
			(unlocked yes)
			(layer "B.Fab")
			(hide yes)
			(effects
				(font
					(size 1.016 1.016)
					(thickness 0.1524)
				)
				(justify mirror)
			)
		)
		(duplicate_pad_numbers_are_jumpers no)
		(fp_line
			(start -0.508 -0.9398)
			(end 0.508 -0.9398)
			(stroke
				(width 0.1524)
				(type default)
			)
			(layer "B.SilkS")
		)
		(fp_line
			(start 0.508 -0.9398)
			(end 0.508 0.9398)
			(stroke
				(width 0.1524)
				(type default)
			)
			(layer "B.SilkS")
		)
		(fp_rect
			(start 0.508 0.9398)
			(end -0.508 -0.9398)
			(stroke
				(width 0)
				(type default)
			)
			(fill no)
			(layer "B.CrtYd")
		)
		(fp_rect
			(start 0.508 0.9398)
			(end -0.508 -0.9398)
			(stroke
				(width 0)
				(type default)
			)
			(fill no)
			(layer "B.Fab")
		)
		(pad "1" smd custom
			(at 0 -0.4445 180)
			(size 0.1397 0.1397)
			(layers "B.Cu" "B.Mask" "B.Paste")
			(net "P0V9_E")
			(options
				(clearance outline)
				(anchor circle)
			)
			(primitives
				(gr_poly
					(pts
						(arc
							(start -0.1778 0.2794)
							(mid -0.249642 0.249642)
							(end -0.2794 0.1778)
						)
						(arc
							(start -0.2794 -0.1778)
							(mid -0.249642 -0.249642)
							(end -0.1778 -0.2794)
						)
						(arc
							(start 0.1778 -0.2794)
							(mid 0.249642 -0.249642)
							(end 0.2794 -0.1778)
						)
						(arc
							(start 0.2794 0.1778)
							(mid 0.249642 0.249642)
							(end 0.1778 0.2794)
						)
					)
					(width 0)
					(fill yes)
				)
			)
		)
		(pad "2" smd custom
			(at 0 0.4445 180)
			(size 0.1397 0.1397)
			(layers "B.Cu" "B.Mask" "B.Paste")
			(net "ADC_P0V9_E")
			(options
				(clearance outline)
				(anchor circle)
			)
			(primitives
				(gr_poly
					(pts
						(arc
							(start -0.1778 0.2794)
							(mid -0.249642 0.249642)
							(end -0.2794 0.1778)
						)
						(arc
							(start -0.2794 -0.1778)
							(mid -0.249642 -0.249642)
							(end -0.1778 -0.2794)
						)
						(arc
							(start 0.1778 -0.2794)
							(mid 0.249642 -0.249642)
							(end 0.2794 -0.1778)
						)
						(arc
							(start 0.2794 0.1778)
							(mid 0.249642 0.249642)
							(end 0.1778 0.2794)
						)
					)
					(width 0)
					(fill yes)
				)
			)
		)
	)
	(footprint ""
		(layer "B.Cu")
		(at 88.91016 -46.863)
		(property "Reference" "STP5"
			(at 0 0 0)
			(layer "B.SilkS")
			(hide yes)
			(effects
				(font
					(size 1.27 1.27)
				)
				(justify mirror)
			)
		)
		(property "Value" "TPAD28"
			(at -0.0127 -1.8034 0)
			(unlocked yes)
			(layer "B.Fab")
			(hide yes)
			(effects
				(font
					(size 1.016 1.016)
					(thickness 0.1524)
				)
				(justify mirror)
			)
		)
		(property "Device Type" "TPAD28"
			(at -0.0127 -3.3274 0)
			(unlocked yes)
			(layer "B.Fab")
			(hide yes)
			(effects
				(font
					(size 1.016 1.016)
					(thickness 0.1524)
				)
				(justify mirror)
			)
		)
		(duplicate_pad_numbers_are_jumpers no)
		(fp_poly
			(pts
				(arc
					(start 0.3556 0)
					(mid -0.3556 0)
					(end 0.3556 0)
				)
			)
			(stroke
				(width 0)
				(type default)
			)
			(fill no)
			(layer "B.CrtYd")
		)
		(fp_poly
			(pts
				(arc
					(start 0.6096 0)
					(mid -0.6096 0)
					(end 0.6096 0)
				)
			)
			(stroke
				(width 0)
				(type default)
			)
			(fill no)
			(layer "B.Fab")
		)
		(pad "1" smd circle
			(at 0 0 180)
			(size 0.7112 0.7112)
			(layers "B.Cu" "B.Mask" "B.Paste")
			(net "SIO_DIN_0")
		)
	)
	(footprint ""
		(layer "B.Cu")
		(at 98.679 -50.0888 -90)
		(property "Reference" "SC1040"
			(at 0 0 90)
			(layer "B.SilkS")
			(hide yes)
			(effects
				(font
					(size 1.27 1.27)
				)
				(justify mirror)
			)
		)
		(property "Value" "SCD1U16V2KX-3GP"
			(at -1.1811 -2.7051 270)
			(unlocked yes)
			(layer "B.Fab")
			(hide yes)
			(effects
				(font
					(size 1.016 1.016)
					(thickness 0.1524)
				)
				(justify mirror)
			)
		)
		(property "Device Type" "C402H22"
			(at -1.1811 -4.2291 270)
			(unlocked yes)
			(layer "B.Fab")
			(hide yes)
			(effects
				(font
					(size 1.016 1.016)
					(thickness 0.1524)
				)
				(justify mirror)
			)
		)
		(duplicate_pad_numbers_are_jumpers no)
		(fp_rect
			(start 0.4318 0.9525)
			(end -0.4318 -0.9525)
			(stroke
				(width 0)
				(type default)
			)
			(fill no)
			(layer "B.CrtYd")
		)
		(fp_rect
			(start 0.4318 0.9525)
			(end -0.4318 -0.9525)
			(stroke
				(width 0)
				(type default)
			)
			(fill no)
			(layer "B.Fab")
		)
		(pad "1" smd custom
			(at 0 -0.4445 90)
			(size 0.1524 0.1524)
			(layers "B.Cu" "B.Mask" "B.Paste")
			(net "P0V955_C")
			(options
				(clearance outline)
				(anchor circle)
			)
			(primitives
				(gr_poly
					(pts
						(arc
							(start 0.3048 0.2032)
							(mid 0.275042 0.275042)
							(end 0.2032 0.3048)
						)
						(arc
							(start -0.2032 0.3048)
							(mid -0.275042 0.275042)
							(end -0.3048 0.2032)
						)
						(arc
							(start -0.3048 -0.2032)
							(mid -0.275042 -0.275042)
							(end -0.2032 -0.3048)
						)
						(arc
							(start 0.2032 -0.3048)
							(mid 0.275042 -0.275042)
							(end 0.3048 -0.2032)
						)
					)
					(width 0)
					(fill yes)
				)
			)
		)
		(pad "2" smd custom
			(at 0 0.4445 90)
			(size 0.1524 0.1524)
			(layers "B.Cu" "B.Mask" "B.Paste")
			(net "GND")
			(options
				(clearance outline)
				(anchor circle)
			)
			(primitives
				(gr_poly
					(pts
						(arc
							(start 0.3048 0.2032)
							(mid 0.275042 0.275042)
							(end 0.2032 0.3048)
						)
						(arc
							(start -0.2032 0.3048)
							(mid -0.275042 0.275042)
							(end -0.3048 0.2032)
						)
						(arc
							(start -0.3048 -0.2032)
							(mid -0.275042 -0.275042)
							(end -0.2032 -0.3048)
						)
						(arc
							(start 0.2032 -0.3048)
							(mid 0.275042 -0.275042)
							(end 0.3048 -0.2032)
						)
					)
					(width 0)
					(fill yes)
				)
			)
		)
	)
	(footprint ""
		(layer "B.Cu")
		(at 108.008166 -32.6898)
		(property "Reference" "STP44"
			(at 0 0 0)
			(layer "B.SilkS")
			(hide yes)
			(effects
				(font
					(size 1.27 1.27)
				)
				(justify mirror)
			)
		)
		(property "Value" "TPAD28"
			(at -0.0127 -1.8034 0)
			(unlocked yes)
			(layer "B.Fab")
			(hide yes)
			(effects
				(font
					(size 1.016 1.016)
					(thickness 0.1524)
				)
				(justify mirror)
			)
		)
		(property "Device Type" "TPAD28"
			(at -0.0127 -3.3274 0)
			(unlocked yes)
			(layer "B.Fab")
			(hide yes)
			(effects
				(font
					(size 1.016 1.016)
					(thickness 0.1524)
				)
				(justify mirror)
			)
		)
		(duplicate_pad_numbers_are_jumpers no)
		(fp_poly
			(pts
				(arc
					(start 0.3556 0)
					(mid -0.3556 0)
					(end 0.3556 0)
				)
			)
			(stroke
				(width 0)
				(type default)
			)
			(fill no)
			(layer "B.CrtYd")
		)
		(fp_poly
			(pts
				(arc
					(start 0.6096 0)
					(mid -0.6096 0)
					(end 0.6096 0)
				)
			)
			(stroke
				(width 0)
				(type default)
			)
			(fill no)
			(layer "B.Fab")
		)
		(pad "1" smd circle
			(at 0 0 180)
			(size 0.7112 0.7112)
			(layers "B.Cu" "B.Mask" "B.Paste")
			(net "IOC_GPIO_3")
		)
	)
	(footprint ""
		(layer "B.Cu")
		(at 111.41837 -95.1738 -90)
		(property "Reference" "SC1249"
			(at 0 0 90)
			(layer "B.SilkS")
			(hide yes)
			(effects
				(font
					(size 1.27 1.27)
				)
				(justify mirror)
			)
		)
		(property "Value" "SCD1U6D3V1KX-GP"
			(at 2.8321 -1.7399 270)
			(unlocked yes)
			(layer "B.Fab")
			(hide yes)
			(effects
				(font
					(size 1.016 1.016)
					(thickness 0.1524)
				)
				(justify mirror)
			)
		)
		(property "Device Type" "C0201H13"
			(at 2.8321 -3.2639 270)
			(unlocked yes)
			(layer "B.Fab")
			(hide yes)
			(effects
				(font
					(size 1.016 1.016)
					(thickness 0.1524)
				)
				(justify mirror)
			)
		)
		(duplicate_pad_numbers_are_jumpers no)
		(fp_rect
			(start 0.2794 0.6477)
			(end -0.2794 -0.6477)
			(stroke
				(width 0)
				(type default)
			)
			(fill no)
			(layer "B.CrtYd")
		)
		(fp_rect
			(start 0.2794 0.6477)
			(end -0.2794 -0.6477)
			(stroke
				(width 0)
				(type default)
			)
			(fill no)
			(layer "B.Fab")
		)
		(pad "1" smd custom
			(at 0 -0.2794 90)
			(size 0.0762 0.0762)
			(layers "B.Cu" "B.Mask" "B.Paste")
			(net "P0V9_E")
			(options
				(clearance outline)
				(anchor circle)
			)
			(primitives
				(gr_poly
					(pts
						(arc
							(start 0.1524 0.127)
							(mid 0.137521 0.162921)
							(end 0.1016 0.1778)
						)
						(arc
							(start -0.1016 0.1778)
							(mid -0.137521 0.162921)
							(end -0.1524 0.127)
						)
						(arc
							(start -0.1524 -0.127)
							(mid -0.137521 -0.162921)
							(end -0.1016 -0.1778)
						)
						(arc
							(start 0.1016 -0.1778)
							(mid 0.137521 -0.162921)
							(end 0.1524 -0.127)
						)
					)
					(width 0)
					(fill yes)
				)
			)
		)
		(pad "2" smd custom
			(at 0 0.2794 90)
			(size 0.0762 0.0762)
			(layers "B.Cu" "B.Mask" "B.Paste")
			(net "GND")
			(options
				(clearance outline)
				(anchor circle)
			)
			(primitives
				(gr_poly
					(pts
						(arc
							(start 0.1524 0.127)
							(mid 0.137521 0.162921)
							(end 0.1016 0.1778)
						)
						(arc
							(start -0.1016 0.1778)
							(mid -0.137521 0.162921)
							(end -0.1524 0.127)
						)
						(arc
							(start -0.1524 -0.127)
							(mid -0.137521 -0.162921)
							(end -0.1016 -0.1778)
						)
						(arc
							(start 0.1016 -0.1778)
							(mid 0.137521 -0.162921)
							(end 0.1524 -0.127)
						)
					)
					(width 0)
					(fill yes)
				)
			)
		)
	)
	(footprint ""
		(layer "B.Cu")
		(at 114.472212 -205.867)
		(property "Reference" "SC1290"
			(at 0 0 0)
			(layer "B.SilkS")
			(hide yes)
			(effects
				(font
					(size 1.27 1.27)
				)
				(justify mirror)
			)
		)
		(property "Value" "SCD1U16V2KX-3GP"
			(at -1.1811 -2.7051 0)
			(unlocked yes)
			(layer "B.Fab")
			(hide yes)
			(effects
				(font
					(size 1.016 1.016)
					(thickness 0.1524)
				)
				(justify mirror)
			)
		)
		(property "Device Type" "C402H22"
			(at -1.1811 -4.2291 0)
			(unlocked yes)
			(layer "B.Fab")
			(hide yes)
			(effects
				(font
					(size 1.016 1.016)
					(thickness 0.1524)
				)
				(justify mirror)
			)
		)
		(duplicate_pad_numbers_are_jumpers no)
		(fp_rect
			(start 0.4318 0.9525)
			(end -0.4318 -0.9525)
			(stroke
				(width 0)
				(type default)
			)
			(fill no)
			(layer "B.CrtYd")
		)
		(fp_rect
			(start 0.4318 0.9525)
			(end -0.4318 -0.9525)
			(stroke
				(width 0)
				(type default)
			)
			(fill no)
			(layer "B.Fab")
		)
		(pad "1" smd custom
			(at 0 -0.4445 180)
			(size 0.1524 0.1524)
			(layers "B.Cu" "B.Mask" "B.Paste")
			(net "1.2V_REDV")
			(options
				(clearance outline)
				(anchor circle)
			)
			(primitives
				(gr_poly
					(pts
						(arc
							(start 0.3048 0.2032)
							(mid 0.275042 0.275042)
							(end 0.2032 0.3048)
						)
						(arc
							(start -0.2032 0.3048)
							(mid -0.275042 0.275042)
							(end -0.3048 0.2032)
						)
						(arc
							(start -0.3048 -0.2032)
							(mid -0.275042 -0.275042)
							(end -0.2032 -0.3048)
						)
						(arc
							(start 0.2032 -0.3048)
							(mid 0.275042 -0.275042)
							(end 0.3048 -0.2032)
						)
					)
					(width 0)
					(fill yes)
				)
			)
		)
		(pad "2" smd custom
			(at 0 0.4445 180)
			(size 0.1524 0.1524)
			(layers "B.Cu" "B.Mask" "B.Paste")
			(net "GND")
			(options
				(clearance outline)
				(anchor circle)
			)
			(primitives
				(gr_poly
					(pts
						(arc
							(start 0.3048 0.2032)
							(mid 0.275042 0.275042)
							(end 0.2032 0.3048)
						)
						(arc
							(start -0.2032 0.3048)
							(mid -0.275042 0.275042)
							(end -0.3048 0.2032)
						)
						(arc
							(start -0.3048 -0.2032)
							(mid -0.275042 -0.275042)
							(end -0.2032 -0.3048)
						)
						(arc
							(start 0.2032 -0.3048)
							(mid 0.275042 -0.275042)
							(end 0.3048 -0.2032)
						)
					)
					(width 0)
					(fill yes)
				)
			)
		)
	)
	(footprint ""
		(layer "B.Cu")
		(at 12.058904 -100.400866)
		(property "Reference" "C130"
			(at 0 0 0)
			(layer "B.SilkS")
			(hide yes)
			(effects
				(font
					(size 1.27 1.27)
				)
				(justify mirror)
			)
		)
		(property "Value" "SCD01U50V2KX-1GP"
			(at -1.1811 -2.7051 0)
			(unlocked yes)
			(layer "B.Fab")
			(hide yes)
			(effects
				(font
					(size 1.016 1.016)
					(thickness 0.1524)
				)
				(justify mirror)
			)
		)
		(property "Device Type" "C402H22"
			(at -1.1811 -4.2291 0)
			(unlocked yes)
			(layer "B.Fab")
			(hide yes)
			(effects
				(font
					(size 1.016 1.016)
					(thickness 0.1524)
				)
				(justify mirror)
			)
		)
		(duplicate_pad_numbers_are_jumpers no)
		(fp_rect
			(start 0.4318 0.9525)
			(end -0.4318 -0.9525)
			(stroke
				(width 0)
				(type default)
			)
			(fill no)
			(layer "B.CrtYd")
		)
		(fp_rect
			(start 0.4318 0.9525)
			(end -0.4318 -0.9525)
			(stroke
				(width 0)
				(type default)
			)
			(fill no)
			(layer "B.Fab")
		)
		(pad "1" smd custom
			(at 0 -0.4445 180)
			(size 0.1524 0.1524)
			(layers "B.Cu" "B.Mask" "B.Paste")
			(net "IOC_SAS_RX_N4")
			(options
				(clearance outline)
				(anchor circle)
			)
			(primitives
				(gr_poly
					(pts
						(arc
							(start 0.3048 0.2032)
							(mid 0.275042 0.275042)
							(end 0.2032 0.3048)
						)
						(arc
							(start -0.2032 0.3048)
							(mid -0.275042 0.275042)
							(end -0.3048 0.2032)
						)
						(arc
							(start -0.3048 -0.2032)
							(mid -0.275042 -0.275042)
							(end -0.2032 -0.3048)
						)
						(arc
							(start 0.2032 -0.3048)
							(mid 0.275042 -0.275042)
							(end 0.3048 -0.2032)
						)
					)
					(width 0)
					(fill yes)
				)
			)
		)
		(pad "2" smd custom
			(at 0 0.4445 180)
			(size 0.1524 0.1524)
			(layers "B.Cu" "B.Mask" "B.Paste")
			(net "SAS_EXT_CONN_RX16_N")
			(options
				(clearance outline)
				(anchor circle)
			)
			(primitives
				(gr_poly
					(pts
						(arc
							(start 0.3048 0.2032)
							(mid 0.275042 0.275042)
							(end 0.2032 0.3048)
						)
						(arc
							(start -0.2032 0.3048)
							(mid -0.275042 0.275042)
							(end -0.3048 0.2032)
						)
						(arc
							(start -0.3048 -0.2032)
							(mid -0.275042 -0.275042)
							(end -0.2032 -0.3048)
						)
						(arc
							(start 0.2032 -0.3048)
							(mid 0.275042 -0.275042)
							(end 0.3048 -0.2032)
						)
					)
					(width 0)
					(fill yes)
				)
			)
		)
	)
	(footprint ""
		(layer "B.Cu")
		(at 304.89398 -179.3875 180)
		(property "Reference" "C193"
			(at 0 0 0)
			(layer "B.SilkS")
			(hide yes)
			(effects
				(font
					(size 1.27 1.27)
				)
				(justify mirror)
			)
		)
		(property "Value" "SC100P50V2JN-3GP"
			(at -1.1811 -2.7051 180)
			(unlocked yes)
			(layer "B.Fab")
			(hide yes)
			(effects
				(font
					(size 1.016 1.016)
					(thickness 0.1524)
				)
				(justify mirror)
			)
		)
		(property "Device Type" "C402H22"
			(at -1.1811 -4.2291 180)
			(unlocked yes)
			(layer "B.Fab")
			(hide yes)
			(effects
				(font
					(size 1.016 1.016)
					(thickness 0.1524)
				)
				(justify mirror)
			)
		)
		(duplicate_pad_numbers_are_jumpers no)
		(fp_rect
			(start 0.4318 0.9525)
			(end -0.4318 -0.9525)
			(stroke
				(width 0)
				(type default)
			)
			(fill no)
			(layer "B.CrtYd")
		)
		(fp_rect
			(start 0.4318 0.9525)
			(end -0.4318 -0.9525)
			(stroke
				(width 0)
				(type default)
			)
			(fill no)
			(layer "B.Fab")
		)
		(pad "1" smd custom
			(at 0 -0.4445)
			(size 0.1524 0.1524)
			(layers "B.Cu" "B.Mask" "B.Paste")
			(net "ADCAV33")
			(options
				(clearance outline)
				(anchor circle)
			)
			(primitives
				(gr_poly
					(pts
						(arc
							(start 0.3048 0.2032)
							(mid 0.275042 0.275042)
							(end 0.2032 0.3048)
						)
						(arc
							(start -0.2032 0.3048)
							(mid -0.275042 0.275042)
							(end -0.3048 0.2032)
						)
						(arc
							(start -0.3048 -0.2032)
							(mid -0.275042 -0.275042)
							(end -0.2032 -0.3048)
						)
						(arc
							(start 0.2032 -0.3048)
							(mid 0.275042 -0.275042)
							(end 0.3048 -0.2032)
						)
					)
					(width 0)
					(fill yes)
				)
			)
		)
		(pad "2" smd custom
			(at 0 0.4445)
			(size 0.1524 0.1524)
			(layers "B.Cu" "B.Mask" "B.Paste")
			(net "GND")
			(options
				(clearance outline)
				(anchor circle)
			)
			(primitives
				(gr_poly
					(pts
						(arc
							(start 0.3048 0.2032)
							(mid 0.275042 0.275042)
							(end 0.2032 0.3048)
						)
						(arc
							(start -0.2032 0.3048)
							(mid -0.275042 0.275042)
							(end -0.3048 0.2032)
						)
						(arc
							(start -0.3048 -0.2032)
							(mid -0.275042 -0.275042)
							(end -0.2032 -0.3048)
						)
						(arc
							(start 0.2032 -0.3048)
							(mid 0.275042 -0.275042)
							(end 0.3048 -0.2032)
						)
					)
					(width 0)
					(fill yes)
				)
			)
		)
	)
	(footprint ""
		(layer "B.Cu")
		(at 121.67997 -89.916 180)
		(property "Reference" "SC1192"
			(at 0 0 0)
			(layer "B.SilkS")
			(hide yes)
			(effects
				(font
					(size 1.27 1.27)
				)
				(justify mirror)
			)
		)
		(property "Value" "SCD1U6D3V1KX-GP"
			(at 2.8321 -1.7399 180)
			(unlocked yes)
			(layer "B.Fab")
			(hide yes)
			(effects
				(font
					(size 1.016 1.016)
					(thickness 0.1524)
				)
				(justify mirror)
			)
		)
		(property "Device Type" "C0201H13"
			(at 2.8321 -3.2639 180)
			(unlocked yes)
			(layer "B.Fab")
			(hide yes)
			(effects
				(font
					(size 1.016 1.016)
					(thickness 0.1524)
				)
				(justify mirror)
			)
		)
		(duplicate_pad_numbers_are_jumpers no)
		(fp_rect
			(start 0.2794 0.6477)
			(end -0.2794 -0.6477)
			(stroke
				(width 0)
				(type default)
			)
			(fill no)
			(layer "B.CrtYd")
		)
		(fp_rect
			(start 0.2794 0.6477)
			(end -0.2794 -0.6477)
			(stroke
				(width 0)
				(type default)
			)
			(fill no)
			(layer "B.Fab")
		)
		(pad "1" smd custom
			(at 0 -0.2794)
			(size 0.0762 0.0762)
			(layers "B.Cu" "B.Mask" "B.Paste")
			(net "GB_VDDA")
			(options
				(clearance outline)
				(anchor circle)
			)
			(primitives
				(gr_poly
					(pts
						(arc
							(start 0.1524 0.127)
							(mid 0.137521 0.162921)
							(end 0.1016 0.1778)
						)
						(arc
							(start -0.1016 0.1778)
							(mid -0.137521 0.162921)
							(end -0.1524 0.127)
						)
						(arc
							(start -0.1524 -0.127)
							(mid -0.137521 -0.162921)
							(end -0.1016 -0.1778)
						)
						(arc
							(start 0.1016 -0.1778)
							(mid 0.137521 -0.162921)
							(end 0.1524 -0.127)
						)
					)
					(width 0)
					(fill yes)
				)
			)
		)
		(pad "2" smd custom
			(at 0 0.2794)
			(size 0.0762 0.0762)
			(layers "B.Cu" "B.Mask" "B.Paste")
			(net "GND")
			(options
				(clearance outline)
				(anchor circle)
			)
			(primitives
				(gr_poly
					(pts
						(arc
							(start 0.1524 0.127)
							(mid 0.137521 0.162921)
							(end 0.1016 0.1778)
						)
						(arc
							(start -0.1016 0.1778)
							(mid -0.137521 0.162921)
							(end -0.1524 0.127)
						)
						(arc
							(start -0.1524 -0.127)
							(mid -0.137521 -0.162921)
							(end -0.1016 -0.1778)
						)
						(arc
							(start 0.1016 -0.1778)
							(mid 0.137521 -0.162921)
							(end 0.1524 -0.127)
						)
					)
					(width 0)
					(fill yes)
				)
			)
		)
	)
	(footprint ""
		(layer "B.Cu")
		(at 293.878 -172.466 180)
		(property "Reference" "C217"
			(at 0 0 0)
			(layer "B.SilkS")
			(hide yes)
			(effects
				(font
					(size 1.27 1.27)
				)
				(justify mirror)
			)
		)
		(property "Value" "SC1U10V2KX-1GP"
			(at -1.1811 -2.7051 180)
			(unlocked yes)
			(layer "B.Fab")
			(hide yes)
			(effects
				(font
					(size 1.016 1.016)
					(thickness 0.1524)
				)
				(justify mirror)
			)
		)
		(property "Device Type" "C402H22"
			(at -1.1811 -4.2291 180)
			(unlocked yes)
			(layer "B.Fab")
			(hide yes)
			(effects
				(font
					(size 1.016 1.016)
					(thickness 0.1524)
				)
				(justify mirror)
			)
		)
		(duplicate_pad_numbers_are_jumpers no)
		(fp_rect
			(start 0.4318 0.9525)
			(end -0.4318 -0.9525)
			(stroke
				(width 0)
				(type default)
			)
			(fill no)
			(layer "B.CrtYd")
		)
		(fp_rect
			(start 0.4318 0.9525)
			(end -0.4318 -0.9525)
			(stroke
				(width 0)
				(type default)
			)
			(fill no)
			(layer "B.Fab")
		)
		(pad "1" smd custom
			(at 0 -0.4445)
			(size 0.1524 0.1524)
			(layers "B.Cu" "B.Mask" "B.Paste")
			(net "P3V3_STBY")
			(options
				(clearance outline)
				(anchor circle)
			)
			(primitives
				(gr_poly
					(pts
						(arc
							(start 0.3048 0.2032)
							(mid 0.275042 0.275042)
							(end 0.2032 0.3048)
						)
						(arc
							(start -0.2032 0.3048)
							(mid -0.275042 0.275042)
							(end -0.3048 0.2032)
						)
						(arc
							(start -0.3048 -0.2032)
							(mid -0.275042 -0.275042)
							(end -0.2032 -0.3048)
						)
						(arc
							(start 0.2032 -0.3048)
							(mid 0.275042 -0.275042)
							(end 0.3048 -0.2032)
						)
					)
					(width 0)
					(fill yes)
				)
			)
		)
		(pad "2" smd custom
			(at 0 0.4445)
			(size 0.1524 0.1524)
			(layers "B.Cu" "B.Mask" "B.Paste")
			(net "GND")
			(options
				(clearance outline)
				(anchor circle)
			)
			(primitives
				(gr_poly
					(pts
						(arc
							(start 0.3048 0.2032)
							(mid 0.275042 0.275042)
							(end 0.2032 0.3048)
						)
						(arc
							(start -0.2032 0.3048)
							(mid -0.275042 0.275042)
							(end -0.3048 0.2032)
						)
						(arc
							(start -0.3048 -0.2032)
							(mid -0.275042 -0.275042)
							(end -0.2032 -0.3048)
						)
						(arc
							(start 0.2032 -0.3048)
							(mid 0.275042 -0.275042)
							(end 0.3048 -0.2032)
						)
					)
					(width 0)
					(fill yes)
				)
			)
		)
	)
	(footprint ""
		(layer "B.Cu")
		(at 119.996966 -37.846 -90)
		(property "Reference" "SR620"
			(at 0 0 90)
			(layer "B.SilkS")
			(hide yes)
			(effects
				(font
					(size 1.27 1.27)
				)
				(justify mirror)
			)
		)
		(property "Value" "2K2R2F-GP"
			(at -0.064008 -3.993896 270)
			(unlocked yes)
			(layer "B.Fab")
			(hide yes)
			(effects
				(font
					(size 1.016 1.016)
					(thickness 0.1524)
				)
				(justify mirror)
			)
		)
		(property "Device Type" "R402H16"
			(at -0.064008 -5.517896 270)
			(unlocked yes)
			(layer "B.Fab")
			(hide yes)
			(effects
				(font
					(size 1.016 1.016)
					(thickness 0.1524)
				)
				(justify mirror)
			)
		)
		(duplicate_pad_numbers_are_jumpers no)
		(fp_line
			(start -0.508 -0.9398)
			(end 0.508 -0.9398)
			(stroke
				(width 0.1524)
				(type default)
			)
			(layer "B.SilkS")
		)
		(fp_line
			(start 0.508 -0.9398)
			(end 0.508 0.9398)
			(stroke
				(width 0.1524)
				(type default)
			)
			(layer "B.SilkS")
		)
		(fp_rect
			(start 0.508 0.9398)
			(end -0.508 -0.9398)
			(stroke
				(width 0)
				(type default)
			)
			(fill no)
			(layer "B.CrtYd")
		)
		(fp_rect
			(start 0.508 0.9398)
			(end -0.508 -0.9398)
			(stroke
				(width 0)
				(type default)
			)
			(fill no)
			(layer "B.Fab")
		)
		(pad "1" smd custom
			(at 0 -0.4445 90)
			(size 0.1397 0.1397)
			(layers "B.Cu" "B.Mask" "B.Paste")
			(net "P1V8_C")
			(options
				(clearance outline)
				(anchor circle)
			)
			(primitives
				(gr_poly
					(pts
						(arc
							(start -0.1778 0.2794)
							(mid -0.249642 0.249642)
							(end -0.2794 0.1778)
						)
						(arc
							(start -0.2794 -0.1778)
							(mid -0.249642 -0.249642)
							(end -0.1778 -0.2794)
						)
						(arc
							(start 0.1778 -0.2794)
							(mid 0.249642 -0.249642)
							(end 0.2794 -0.1778)
						)
						(arc
							(start 0.2794 0.1778)
							(mid 0.249642 0.249642)
							(end 0.1778 0.2794)
						)
					)
					(width 0)
					(fill yes)
				)
			)
		)
		(pad "2" smd custom
			(at 0 0.4445 90)
			(size 0.1397 0.1397)
			(layers "B.Cu" "B.Mask" "B.Paste")
			(net "IOC_SCL_2")
			(options
				(clearance outline)
				(anchor circle)
			)
			(primitives
				(gr_poly
					(pts
						(arc
							(start -0.1778 0.2794)
							(mid -0.249642 0.249642)
							(end -0.2794 0.1778)
						)
						(arc
							(start -0.2794 -0.1778)
							(mid -0.249642 -0.249642)
							(end -0.1778 -0.2794)
						)
						(arc
							(start 0.1778 -0.2794)
							(mid 0.249642 -0.249642)
							(end 0.2794 -0.1778)
						)
						(arc
							(start 0.2794 0.1778)
							(mid 0.249642 0.249642)
							(end 0.1778 0.2794)
						)
					)
					(width 0)
					(fill yes)
				)
			)
		)
	)
	(footprint ""
		(layer "B.Cu")
		(at 129.42697 -106.299 180)
		(property "Reference" "SR757"
			(at 0 0 0)
			(layer "B.SilkS")
			(hide yes)
			(effects
				(font
					(size 1.27 1.27)
				)
				(justify mirror)
			)
		)
		(property "Value" "3KR2J-2-GP"
			(at -0.064008 -3.993896 180)
			(unlocked yes)
			(layer "B.Fab")
			(hide yes)
			(effects
				(font
					(size 1.016 1.016)
					(thickness 0.1524)
				)
				(justify mirror)
			)
		)
		(property "Device Type" "R402H16"
			(at -0.064008 -5.517896 180)
			(unlocked yes)
			(layer "B.Fab")
			(hide yes)
			(effects
				(font
					(size 1.016 1.016)
					(thickness 0.1524)
				)
				(justify mirror)
			)
		)
		(duplicate_pad_numbers_are_jumpers no)
		(fp_line
			(start 0.508 -0.9398)
			(end 0.508 0.9398)
			(stroke
				(width 0.1524)
				(type default)
			)
			(layer "B.SilkS")
		)
		(fp_line
			(start -0.508 -0.9398)
			(end 0.508 -0.9398)
			(stroke
				(width 0.1524)
				(type default)
			)
			(layer "B.SilkS")
		)
		(fp_rect
			(start 0.508 0.9398)
			(end -0.508 -0.9398)
			(stroke
				(width 0)
				(type default)
			)
			(fill no)
			(layer "B.CrtYd")
		)
		(fp_rect
			(start 0.508 0.9398)
			(end -0.508 -0.9398)
			(stroke
				(width 0)
				(type default)
			)
			(fill no)
			(layer "B.Fab")
		)
		(pad "1" smd custom
			(at 0 -0.4445)
			(size 0.1397 0.1397)
			(layers "B.Cu" "B.Mask" "B.Paste")
			(net "EXP_RTRIM_A")
			(options
				(clearance outline)
				(anchor circle)
			)
			(primitives
				(gr_poly
					(pts
						(arc
							(start -0.1778 0.2794)
							(mid -0.249642 0.249642)
							(end -0.2794 0.1778)
						)
						(arc
							(start -0.2794 -0.1778)
							(mid -0.249642 -0.249642)
							(end -0.1778 -0.2794)
						)
						(arc
							(start 0.1778 -0.2794)
							(mid 0.249642 -0.249642)
							(end 0.2794 -0.1778)
						)
						(arc
							(start 0.2794 0.1778)
							(mid 0.249642 0.249642)
							(end 0.1778 0.2794)
						)
					)
					(width 0)
					(fill yes)
				)
			)
		)
		(pad "2" smd custom
			(at 0 0.4445)
			(size 0.1397 0.1397)
			(layers "B.Cu" "B.Mask" "B.Paste")
			(net "EXP_RTRIM_A_N")
			(options
				(clearance outline)
				(anchor circle)
			)
			(primitives
				(gr_poly
					(pts
						(arc
							(start -0.1778 0.2794)
							(mid -0.249642 0.249642)
							(end -0.2794 0.1778)
						)
						(arc
							(start -0.2794 -0.1778)
							(mid -0.249642 -0.249642)
							(end -0.1778 -0.2794)
						)
						(arc
							(start 0.1778 -0.2794)
							(mid 0.249642 -0.249642)
							(end 0.2794 -0.1778)
						)
						(arc
							(start 0.2794 0.1778)
							(mid 0.249642 0.249642)
							(end 0.1778 0.2794)
						)
					)
					(width 0)
					(fill yes)
				)
			)
		)
	)
	(footprint ""
		(layer "B.Cu")
		(at 100.97516 -31.640018)
		(property "Reference" "SC871"
			(at 0 0 0)
			(layer "B.SilkS")
			(hide yes)
			(effects
				(font
					(size 1.27 1.27)
				)
				(justify mirror)
			)
		)
		(property "Value" "SCD22U6D3V1MX-1-GP"
			(at 2.8321 -1.7399 0)
			(unlocked yes)
			(layer "B.Fab")
			(hide yes)
			(effects
				(font
					(size 1.016 1.016)
					(thickness 0.1524)
				)
				(justify mirror)
			)
		)
		(property "Device Type" "C0201H13"
			(at 2.8321 -3.2639 0)
			(unlocked yes)
			(layer "B.Fab")
			(hide yes)
			(effects
				(font
					(size 1.016 1.016)
					(thickness 0.1524)
				)
				(justify mirror)
			)
		)
		(duplicate_pad_numbers_are_jumpers no)
		(fp_rect
			(start 0.2794 0.6477)
			(end -0.2794 -0.6477)
			(stroke
				(width 0)
				(type default)
			)
			(fill no)
			(layer "B.CrtYd")
		)
		(fp_rect
			(start 0.2794 0.6477)
			(end -0.2794 -0.6477)
			(stroke
				(width 0)
				(type default)
			)
			(fill no)
			(layer "B.Fab")
		)
		(pad "1" smd custom
			(at 0 -0.2794 180)
			(size 0.0762 0.0762)
			(layers "B.Cu" "B.Mask" "B.Paste")
			(net "PCIE_SAS_C_CPU_RX_P5")
			(options
				(clearance outline)
				(anchor circle)
			)
			(primitives
				(gr_poly
					(pts
						(arc
							(start 0.1524 0.127)
							(mid 0.137521 0.162921)
							(end 0.1016 0.1778)
						)
						(arc
							(start -0.1016 0.1778)
							(mid -0.137521 0.162921)
							(end -0.1524 0.127)
						)
						(arc
							(start -0.1524 -0.127)
							(mid -0.137521 -0.162921)
							(end -0.1016 -0.1778)
						)
						(arc
							(start 0.1016 -0.1778)
							(mid 0.137521 -0.162921)
							(end 0.1524 -0.127)
						)
					)
					(width 0)
					(fill yes)
				)
			)
		)
		(pad "2" smd custom
			(at 0 0.2794 180)
			(size 0.0762 0.0762)
			(layers "B.Cu" "B.Mask" "B.Paste")
			(net "PCIE_SAS_CPU_RX_P5")
			(options
				(clearance outline)
				(anchor circle)
			)
			(primitives
				(gr_poly
					(pts
						(arc
							(start 0.1524 0.127)
							(mid 0.137521 0.162921)
							(end 0.1016 0.1778)
						)
						(arc
							(start -0.1016 0.1778)
							(mid -0.137521 0.162921)
							(end -0.1524 0.127)
						)
						(arc
							(start -0.1524 -0.127)
							(mid -0.137521 -0.162921)
							(end -0.1016 -0.1778)
						)
						(arc
							(start 0.1016 -0.1778)
							(mid 0.137521 -0.162921)
							(end 0.1524 -0.127)
						)
					)
					(width 0)
					(fill yes)
				)
			)
		)
	)
	(footprint ""
		(layer "B.Cu")
		(at 87.357966 -55.1815 180)
		(property "Reference" "SC1014"
			(at 0 0 0)
			(layer "B.SilkS")
			(hide yes)
			(effects
				(font
					(size 1.27 1.27)
				)
				(justify mirror)
			)
		)
		(property "Value" "SC1KP50V2KX-1GP"
			(at -1.1811 -2.7051 180)
			(unlocked yes)
			(layer "B.Fab")
			(hide yes)
			(effects
				(font
					(size 1.016 1.016)
					(thickness 0.1524)
				)
				(justify mirror)
			)
		)
		(property "Device Type" "C402H22"
			(at -1.1811 -4.2291 180)
			(unlocked yes)
			(layer "B.Fab")
			(hide yes)
			(effects
				(font
					(size 1.016 1.016)
					(thickness 0.1524)
				)
				(justify mirror)
			)
		)
		(duplicate_pad_numbers_are_jumpers no)
		(fp_rect
			(start 0.4318 0.9525)
			(end -0.4318 -0.9525)
			(stroke
				(width 0)
				(type default)
			)
			(fill no)
			(layer "B.CrtYd")
		)
		(fp_rect
			(start 0.4318 0.9525)
			(end -0.4318 -0.9525)
			(stroke
				(width 0)
				(type default)
			)
			(fill no)
			(layer "B.Fab")
		)
		(pad "1" smd custom
			(at 0 -0.4445)
			(size 0.1524 0.1524)
			(layers "B.Cu" "B.Mask" "B.Paste")
			(net "P1V8_C")
			(options
				(clearance outline)
				(anchor circle)
			)
			(primitives
				(gr_poly
					(pts
						(arc
							(start 0.3048 0.2032)
							(mid 0.275042 0.275042)
							(end 0.2032 0.3048)
						)
						(arc
							(start -0.2032 0.3048)
							(mid -0.275042 0.275042)
							(end -0.3048 0.2032)
						)
						(arc
							(start -0.3048 -0.2032)
							(mid -0.275042 -0.275042)
							(end -0.2032 -0.3048)
						)
						(arc
							(start 0.2032 -0.3048)
							(mid 0.275042 -0.275042)
							(end 0.3048 -0.2032)
						)
					)
					(width 0)
					(fill yes)
				)
			)
		)
		(pad "2" smd custom
			(at 0 0.4445)
			(size 0.1524 0.1524)
			(layers "B.Cu" "B.Mask" "B.Paste")
			(net "GND")
			(options
				(clearance outline)
				(anchor circle)
			)
			(primitives
				(gr_poly
					(pts
						(arc
							(start 0.3048 0.2032)
							(mid 0.275042 0.275042)
							(end 0.2032 0.3048)
						)
						(arc
							(start -0.2032 0.3048)
							(mid -0.275042 0.275042)
							(end -0.3048 0.2032)
						)
						(arc
							(start -0.3048 -0.2032)
							(mid -0.275042 -0.275042)
							(end -0.2032 -0.3048)
						)
						(arc
							(start 0.2032 -0.3048)
							(mid 0.275042 -0.275042)
							(end 0.3048 -0.2032)
						)
					)
					(width 0)
					(fill yes)
				)
			)
		)
	)
	(footprint ""
		(layer "B.Cu")
		(at 323.342 -184.404 180)
		(property "Reference" "C8081"
			(at 0 0 0)
			(layer "B.SilkS")
			(hide yes)
			(effects
				(font
					(size 1.27 1.27)
				)
				(justify mirror)
			)
		)
		(property "Value" "SCD1U25V2KX-2-GP"
			(at -1.1811 -2.7051 180)
			(unlocked yes)
			(layer "B.Fab")
			(hide yes)
			(effects
				(font
					(size 1.016 1.016)
					(thickness 0.1524)
				)
				(justify mirror)
			)
		)
		(property "Device Type" "C402H22"
			(at -1.1811 -4.2291 180)
			(unlocked yes)
			(layer "B.Fab")
			(hide yes)
			(effects
				(font
					(size 1.016 1.016)
					(thickness 0.1524)
				)
				(justify mirror)
			)
		)
		(duplicate_pad_numbers_are_jumpers no)
		(fp_rect
			(start 0.4318 0.9525)
			(end -0.4318 -0.9525)
			(stroke
				(width 0)
				(type default)
			)
			(fill no)
			(layer "B.CrtYd")
		)
		(fp_rect
			(start 0.4318 0.9525)
			(end -0.4318 -0.9525)
			(stroke
				(width 0)
				(type default)
			)
			(fill no)
			(layer "B.Fab")
		)
		(pad "1" smd custom
			(at 0 -0.4445)
			(size 0.1524 0.1524)
			(layers "B.Cu" "B.Mask" "B.Paste")
			(net "ADC_P0V9_E")
			(options
				(clearance outline)
				(anchor circle)
			)
			(primitives
				(gr_poly
					(pts
						(arc
							(start 0.3048 0.2032)
							(mid 0.275042 0.275042)
							(end 0.2032 0.3048)
						)
						(arc
							(start -0.2032 0.3048)
							(mid -0.275042 0.275042)
							(end -0.3048 0.2032)
						)
						(arc
							(start -0.3048 -0.2032)
							(mid -0.275042 -0.275042)
							(end -0.2032 -0.3048)
						)
						(arc
							(start 0.2032 -0.3048)
							(mid 0.275042 -0.275042)
							(end 0.3048 -0.2032)
						)
					)
					(width 0)
					(fill yes)
				)
			)
		)
		(pad "2" smd custom
			(at 0 0.4445)
			(size 0.1524 0.1524)
			(layers "B.Cu" "B.Mask" "B.Paste")
			(net "GND")
			(options
				(clearance outline)
				(anchor circle)
			)
			(primitives
				(gr_poly
					(pts
						(arc
							(start 0.3048 0.2032)
							(mid 0.275042 0.275042)
							(end 0.2032 0.3048)
						)
						(arc
							(start -0.2032 0.3048)
							(mid -0.275042 0.275042)
							(end -0.3048 0.2032)
						)
						(arc
							(start -0.3048 -0.2032)
							(mid -0.275042 -0.275042)
							(end -0.2032 -0.3048)
						)
						(arc
							(start 0.2032 -0.3048)
							(mid 0.275042 -0.275042)
							(end 0.3048 -0.2032)
						)
					)
					(width 0)
					(fill yes)
				)
			)
		)
	)
	(footprint ""
		(layer "B.Cu")
		(at 87.884 -29.09316)
		(property "Reference" "SC877"
			(at 0 0 0)
			(layer "B.SilkS")
			(hide yes)
			(effects
				(font
					(size 1.27 1.27)
				)
				(justify mirror)
			)
		)
		(property "Value" "SCD01U16V2KX-3GP"
			(at -1.1811 -2.7051 0)
			(unlocked yes)
			(layer "B.Fab")
			(hide yes)
			(effects
				(font
					(size 1.016 1.016)
					(thickness 0.1524)
				)
				(justify mirror)
			)
		)
		(property "Device Type" "C402H22"
			(at -1.1811 -4.2291 0)
			(unlocked yes)
			(layer "B.Fab")
			(hide yes)
			(effects
				(font
					(size 1.016 1.016)
					(thickness 0.1524)
				)
				(justify mirror)
			)
		)
		(duplicate_pad_numbers_are_jumpers no)
		(fp_rect
			(start 0.4318 0.9525)
			(end -0.4318 -0.9525)
			(stroke
				(width 0)
				(type default)
			)
			(fill no)
			(layer "B.CrtYd")
		)
		(fp_rect
			(start 0.4318 0.9525)
			(end -0.4318 -0.9525)
			(stroke
				(width 0)
				(type default)
			)
			(fill no)
			(layer "B.Fab")
		)
		(pad "1" smd custom
			(at 0 -0.4445 180)
			(size 0.1524 0.1524)
			(layers "B.Cu" "B.Mask" "B.Paste")
			(net "CK_100M_EXP_SAS")
			(options
				(clearance outline)
				(anchor circle)
			)
			(primitives
				(gr_poly
					(pts
						(arc
							(start 0.3048 0.2032)
							(mid 0.275042 0.275042)
							(end 0.2032 0.3048)
						)
						(arc
							(start -0.2032 0.3048)
							(mid -0.275042 0.275042)
							(end -0.3048 0.2032)
						)
						(arc
							(start -0.3048 -0.2032)
							(mid -0.275042 -0.275042)
							(end -0.2032 -0.3048)
						)
						(arc
							(start 0.2032 -0.3048)
							(mid 0.275042 -0.275042)
							(end 0.3048 -0.2032)
						)
					)
					(width 0)
					(fill yes)
				)
			)
		)
		(pad "2" smd custom
			(at 0 0.4445 180)
			(size 0.1524 0.1524)
			(layers "B.Cu" "B.Mask" "B.Paste")
			(net "GND")
			(options
				(clearance outline)
				(anchor circle)
			)
			(primitives
				(gr_poly
					(pts
						(arc
							(start 0.3048 0.2032)
							(mid 0.275042 0.275042)
							(end 0.2032 0.3048)
						)
						(arc
							(start -0.2032 0.3048)
							(mid -0.275042 0.275042)
							(end -0.3048 0.2032)
						)
						(arc
							(start -0.3048 -0.2032)
							(mid -0.275042 -0.275042)
							(end -0.2032 -0.3048)
						)
						(arc
							(start 0.2032 -0.3048)
							(mid 0.275042 -0.275042)
							(end 0.3048 -0.2032)
						)
					)
					(width 0)
					(fill yes)
				)
			)
		)
	)
	(footprint ""
		(layer "B.Cu")
		(at 133.077966 -35.814 90)
		(property "Reference" "SC976"
			(at 0 0 90)
			(layer "B.SilkS")
			(hide yes)
			(effects
				(font
					(size 1.27 1.27)
				)
				(justify mirror)
			)
		)
		(property "Value" "SCD1U16V2KX-3GP"
			(at -1.1811 -2.7051 90)
			(unlocked yes)
			(layer "B.Fab")
			(hide yes)
			(effects
				(font
					(size 1.016 1.016)
					(thickness 0.1524)
				)
				(justify mirror)
			)
		)
		(property "Device Type" "C402H22"
			(at -1.1811 -4.2291 90)
			(unlocked yes)
			(layer "B.Fab")
			(hide yes)
			(effects
				(font
					(size 1.016 1.016)
					(thickness 0.1524)
				)
				(justify mirror)
			)
		)
		(duplicate_pad_numbers_are_jumpers no)
		(fp_rect
			(start 0.4318 0.9525)
			(end -0.4318 -0.9525)
			(stroke
				(width 0)
				(type default)
			)
			(fill no)
			(layer "B.CrtYd")
		)
		(fp_rect
			(start 0.4318 0.9525)
			(end -0.4318 -0.9525)
			(stroke
				(width 0)
				(type default)
			)
			(fill no)
			(layer "B.Fab")
		)
		(pad "1" smd custom
			(at 0 -0.4445 270)
			(size 0.1524 0.1524)
			(layers "B.Cu" "B.Mask" "B.Paste")
			(net "P1V8_C")
			(options
				(clearance outline)
				(anchor circle)
			)
			(primitives
				(gr_poly
					(pts
						(arc
							(start 0.3048 0.2032)
							(mid 0.275042 0.275042)
							(end 0.2032 0.3048)
						)
						(arc
							(start -0.2032 0.3048)
							(mid -0.275042 0.275042)
							(end -0.3048 0.2032)
						)
						(arc
							(start -0.3048 -0.2032)
							(mid -0.275042 -0.275042)
							(end -0.2032 -0.3048)
						)
						(arc
							(start 0.2032 -0.3048)
							(mid 0.275042 -0.275042)
							(end 0.3048 -0.2032)
						)
					)
					(width 0)
					(fill yes)
				)
			)
		)
		(pad "2" smd custom
			(at 0 0.4445 270)
			(size 0.1524 0.1524)
			(layers "B.Cu" "B.Mask" "B.Paste")
			(net "GND")
			(options
				(clearance outline)
				(anchor circle)
			)
			(primitives
				(gr_poly
					(pts
						(arc
							(start 0.3048 0.2032)
							(mid 0.275042 0.275042)
							(end 0.2032 0.3048)
						)
						(arc
							(start -0.2032 0.3048)
							(mid -0.275042 0.275042)
							(end -0.3048 0.2032)
						)
						(arc
							(start -0.3048 -0.2032)
							(mid -0.275042 -0.275042)
							(end -0.2032 -0.3048)
						)
						(arc
							(start 0.2032 -0.3048)
							(mid 0.275042 -0.275042)
							(end 0.3048 -0.2032)
						)
					)
					(width 0)
					(fill yes)
				)
			)
		)
	)
	(footprint ""
		(layer "B.Cu")
		(at 112.84077 -99.949)
		(property "Reference" "SC1136"
			(at 0 0 0)
			(layer "B.SilkS")
			(hide yes)
			(effects
				(font
					(size 1.27 1.27)
				)
				(justify mirror)
			)
		)
		(property "Value" "SCD1U6D3V1KX-GP"
			(at 2.8321 -1.7399 0)
			(unlocked yes)
			(layer "B.Fab")
			(hide yes)
			(effects
				(font
					(size 1.016 1.016)
					(thickness 0.1524)
				)
				(justify mirror)
			)
		)
		(property "Device Type" "C0201H13"
			(at 2.8321 -3.2639 0)
			(unlocked yes)
			(layer "B.Fab")
			(hide yes)
			(effects
				(font
					(size 1.016 1.016)
					(thickness 0.1524)
				)
				(justify mirror)
			)
		)
		(duplicate_pad_numbers_are_jumpers no)
		(fp_rect
			(start 0.2794 0.6477)
			(end -0.2794 -0.6477)
			(stroke
				(width 0)
				(type default)
			)
			(fill no)
			(layer "B.CrtYd")
		)
		(fp_rect
			(start 0.2794 0.6477)
			(end -0.2794 -0.6477)
			(stroke
				(width 0)
				(type default)
			)
			(fill no)
			(layer "B.Fab")
		)
		(pad "1" smd custom
			(at 0 -0.2794 180)
			(size 0.0762 0.0762)
			(layers "B.Cu" "B.Mask" "B.Paste")
			(net "GB_VDDH2")
			(options
				(clearance outline)
				(anchor circle)
			)
			(primitives
				(gr_poly
					(pts
						(arc
							(start 0.1524 0.127)
							(mid 0.137521 0.162921)
							(end 0.1016 0.1778)
						)
						(arc
							(start -0.1016 0.1778)
							(mid -0.137521 0.162921)
							(end -0.1524 0.127)
						)
						(arc
							(start -0.1524 -0.127)
							(mid -0.137521 -0.162921)
							(end -0.1016 -0.1778)
						)
						(arc
							(start 0.1016 -0.1778)
							(mid 0.137521 -0.162921)
							(end 0.1524 -0.127)
						)
					)
					(width 0)
					(fill yes)
				)
			)
		)
		(pad "2" smd custom
			(at 0 0.2794 180)
			(size 0.0762 0.0762)
			(layers "B.Cu" "B.Mask" "B.Paste")
			(net "GND")
			(options
				(clearance outline)
				(anchor circle)
			)
			(primitives
				(gr_poly
					(pts
						(arc
							(start 0.1524 0.127)
							(mid 0.137521 0.162921)
							(end 0.1016 0.1778)
						)
						(arc
							(start -0.1016 0.1778)
							(mid -0.137521 0.162921)
							(end -0.1524 0.127)
						)
						(arc
							(start -0.1524 -0.127)
							(mid -0.137521 -0.162921)
							(end -0.1016 -0.1778)
						)
						(arc
							(start 0.1016 -0.1778)
							(mid 0.137521 -0.162921)
							(end 0.1524 -0.127)
						)
					)
					(width 0)
					(fill yes)
				)
			)
		)
	)
	(footprint ""
		(layer "B.Cu")
		(at 163.957 -120.396 180)
		(property "Reference" "SR856"
			(at 0 0 0)
			(layer "B.SilkS")
			(hide yes)
			(effects
				(font
					(size 1.27 1.27)
				)
				(justify mirror)
			)
		)
		(property "Value" "1KR2J-1-GP"
			(at -0.064008 -3.993896 180)
			(unlocked yes)
			(layer "B.Fab")
			(hide yes)
			(effects
				(font
					(size 1.016 1.016)
					(thickness 0.1524)
				)
				(justify mirror)
			)
		)
		(property "Device Type" "R402H16"
			(at -0.064008 -5.517896 180)
			(unlocked yes)
			(layer "B.Fab")
			(hide yes)
			(effects
				(font
					(size 1.016 1.016)
					(thickness 0.1524)
				)
				(justify mirror)
			)
		)
		(duplicate_pad_numbers_are_jumpers no)
		(fp_line
			(start 0.508 -0.9398)
			(end 0.508 0.9398)
			(stroke
				(width 0.1524)
				(type default)
			)
			(layer "B.SilkS")
		)
		(fp_line
			(start -0.508 -0.9398)
			(end 0.508 -0.9398)
			(stroke
				(width 0.1524)
				(type default)
			)
			(layer "B.SilkS")
		)
		(fp_rect
			(start 0.508 0.9398)
			(end -0.508 -0.9398)
			(stroke
				(width 0)
				(type default)
			)
			(fill no)
			(layer "B.CrtYd")
		)
		(fp_rect
			(start 0.508 0.9398)
			(end -0.508 -0.9398)
			(stroke
				(width 0)
				(type default)
			)
			(fill no)
			(layer "B.Fab")
		)
		(pad "1" smd custom
			(at 0 -0.4445)
			(size 0.1397 0.1397)
			(layers "B.Cu" "B.Mask" "B.Paste")
			(net "EXP_RST")
			(options
				(clearance outline)
				(anchor circle)
			)
			(primitives
				(gr_poly
					(pts
						(arc
							(start -0.1778 0.2794)
							(mid -0.249642 0.249642)
							(end -0.2794 0.1778)
						)
						(arc
							(start -0.2794 -0.1778)
							(mid -0.249642 -0.249642)
							(end -0.1778 -0.2794)
						)
						(arc
							(start 0.1778 -0.2794)
							(mid 0.249642 -0.249642)
							(end 0.2794 -0.1778)
						)
						(arc
							(start 0.2794 0.1778)
							(mid 0.249642 0.249642)
							(end 0.1778 0.2794)
						)
					)
					(width 0)
					(fill yes)
				)
			)
		)
		(pad "2" smd custom
			(at 0 0.4445)
			(size 0.1397 0.1397)
			(layers "B.Cu" "B.Mask" "B.Paste")
			(net "P1V8_E")
			(options
				(clearance outline)
				(anchor circle)
			)
			(primitives
				(gr_poly
					(pts
						(arc
							(start -0.1778 0.2794)
							(mid -0.249642 0.249642)
							(end -0.2794 0.1778)
						)
						(arc
							(start -0.2794 -0.1778)
							(mid -0.249642 -0.249642)
							(end -0.1778 -0.2794)
						)
						(arc
							(start 0.1778 -0.2794)
							(mid 0.249642 -0.249642)
							(end 0.2794 -0.1778)
						)
						(arc
							(start 0.2794 0.1778)
							(mid 0.249642 0.249642)
							(end 0.1778 0.2794)
						)
					)
					(width 0)
					(fill yes)
				)
			)
		)
	)
	(footprint ""
		(layer "B.Cu")
		(at 107.995212 -219.456 -90)
		(property "Reference" "SC1293"
			(at 0 0 90)
			(layer "B.SilkS")
			(hide yes)
			(effects
				(font
					(size 1.27 1.27)
				)
				(justify mirror)
			)
		)
		(property "Value" "SCD1U16V2KX-3GP"
			(at -1.1811 -2.7051 270)
			(unlocked yes)
			(layer "B.Fab")
			(hide yes)
			(effects
				(font
					(size 1.016 1.016)
					(thickness 0.1524)
				)
				(justify mirror)
			)
		)
		(property "Device Type" "C402H22"
			(at -1.1811 -4.2291 270)
			(unlocked yes)
			(layer "B.Fab")
			(hide yes)
			(effects
				(font
					(size 1.016 1.016)
					(thickness 0.1524)
				)
				(justify mirror)
			)
		)
		(duplicate_pad_numbers_are_jumpers no)
		(fp_rect
			(start 0.4318 0.9525)
			(end -0.4318 -0.9525)
			(stroke
				(width 0)
				(type default)
			)
			(fill no)
			(layer "B.CrtYd")
		)
		(fp_rect
			(start 0.4318 0.9525)
			(end -0.4318 -0.9525)
			(stroke
				(width 0)
				(type default)
			)
			(fill no)
			(layer "B.Fab")
		)
		(pad "1" smd custom
			(at 0 -0.4445 90)
			(size 0.1524 0.1524)
			(layers "B.Cu" "B.Mask" "B.Paste")
			(net "1.2V_REDV")
			(options
				(clearance outline)
				(anchor circle)
			)
			(primitives
				(gr_poly
					(pts
						(arc
							(start 0.3048 0.2032)
							(mid 0.275042 0.275042)
							(end 0.2032 0.3048)
						)
						(arc
							(start -0.2032 0.3048)
							(mid -0.275042 0.275042)
							(end -0.3048 0.2032)
						)
						(arc
							(start -0.3048 -0.2032)
							(mid -0.275042 -0.275042)
							(end -0.2032 -0.3048)
						)
						(arc
							(start 0.2032 -0.3048)
							(mid 0.275042 -0.275042)
							(end 0.3048 -0.2032)
						)
					)
					(width 0)
					(fill yes)
				)
			)
		)
		(pad "2" smd custom
			(at 0 0.4445 90)
			(size 0.1524 0.1524)
			(layers "B.Cu" "B.Mask" "B.Paste")
			(net "GND")
			(options
				(clearance outline)
				(anchor circle)
			)
			(primitives
				(gr_poly
					(pts
						(arc
							(start 0.3048 0.2032)
							(mid 0.275042 0.275042)
							(end 0.2032 0.3048)
						)
						(arc
							(start -0.2032 0.3048)
							(mid -0.275042 0.275042)
							(end -0.3048 0.2032)
						)
						(arc
							(start -0.3048 -0.2032)
							(mid -0.275042 -0.275042)
							(end -0.2032 -0.3048)
						)
						(arc
							(start 0.2032 -0.3048)
							(mid 0.275042 -0.275042)
							(end 0.3048 -0.2032)
						)
					)
					(width 0)
					(fill yes)
				)
			)
		)
	)
	(footprint ""
		(layer "B.Cu")
		(at 180.013864 -32.076136 90)
		(property "Reference" "C222"
			(at 0 0 90)
			(layer "B.SilkS")
			(hide yes)
			(effects
				(font
					(size 1.27 1.27)
				)
				(justify mirror)
			)
		)
		(property "Value" "SCD01U16V2KX-3GP"
			(at -1.1811 -2.7051 90)
			(unlocked yes)
			(layer "B.Fab")
			(hide yes)
			(effects
				(font
					(size 1.016 1.016)
					(thickness 0.1524)
				)
				(justify mirror)
			)
		)
		(property "Device Type" "C402H22"
			(at -1.1811 -4.2291 90)
			(unlocked yes)
			(layer "B.Fab")
			(hide yes)
			(effects
				(font
					(size 1.016 1.016)
					(thickness 0.1524)
				)
				(justify mirror)
			)
		)
		(duplicate_pad_numbers_are_jumpers no)
		(fp_rect
			(start 0.4318 0.9525)
			(end -0.4318 -0.9525)
			(stroke
				(width 0)
				(type default)
			)
			(fill no)
			(layer "B.CrtYd")
		)
		(fp_rect
			(start 0.4318 0.9525)
			(end -0.4318 -0.9525)
			(stroke
				(width 0)
				(type default)
			)
			(fill no)
			(layer "B.Fab")
		)
		(pad "1" smd custom
			(at 0 -0.4445 270)
			(size 0.1524 0.1524)
			(layers "B.Cu" "B.Mask" "B.Paste")
			(net "PHY_AVDD")
			(options
				(clearance outline)
				(anchor circle)
			)
			(primitives
				(gr_poly
					(pts
						(arc
							(start 0.3048 0.2032)
							(mid 0.275042 0.275042)
							(end 0.2032 0.3048)
						)
						(arc
							(start -0.2032 0.3048)
							(mid -0.275042 0.275042)
							(end -0.3048 0.2032)
						)
						(arc
							(start -0.3048 -0.2032)
							(mid -0.275042 -0.275042)
							(end -0.2032 -0.3048)
						)
						(arc
							(start 0.2032 -0.3048)
							(mid 0.275042 -0.275042)
							(end 0.3048 -0.2032)
						)
					)
					(width 0)
					(fill yes)
				)
			)
		)
		(pad "2" smd custom
			(at 0 0.4445 270)
			(size 0.1524 0.1524)
			(layers "B.Cu" "B.Mask" "B.Paste")
			(net "GND")
			(options
				(clearance outline)
				(anchor circle)
			)
			(primitives
				(gr_poly
					(pts
						(arc
							(start 0.3048 0.2032)
							(mid 0.275042 0.275042)
							(end 0.2032 0.3048)
						)
						(arc
							(start -0.2032 0.3048)
							(mid -0.275042 0.275042)
							(end -0.3048 0.2032)
						)
						(arc
							(start -0.3048 -0.2032)
							(mid -0.275042 -0.275042)
							(end -0.2032 -0.3048)
						)
						(arc
							(start 0.2032 -0.3048)
							(mid 0.275042 -0.275042)
							(end 0.3048 -0.2032)
						)
					)
					(width 0)
					(fill yes)
				)
			)
		)
	)
	(footprint ""
		(layer "B.Cu")
		(at 115.043966 -34.163)
		(property "Reference" "STP94"
			(at 0 0 0)
			(layer "B.SilkS")
			(hide yes)
			(effects
				(font
					(size 1.27 1.27)
				)
				(justify mirror)
			)
		)
		(property "Value" "TPAD28"
			(at -0.0127 -1.8034 0)
			(unlocked yes)
			(layer "B.Fab")
			(hide yes)
			(effects
				(font
					(size 1.016 1.016)
					(thickness 0.1524)
				)
				(justify mirror)
			)
		)
		(property "Device Type" "TPAD28"
			(at -0.0127 -3.3274 0)
			(unlocked yes)
			(layer "B.Fab")
			(hide yes)
			(effects
				(font
					(size 1.016 1.016)
					(thickness 0.1524)
				)
				(justify mirror)
			)
		)
		(duplicate_pad_numbers_are_jumpers no)
		(fp_poly
			(pts
				(arc
					(start 0.3556 0)
					(mid -0.3556 0)
					(end 0.3556 0)
				)
			)
			(stroke
				(width 0)
				(type default)
			)
			(fill no)
			(layer "B.CrtYd")
		)
		(fp_poly
			(pts
				(arc
					(start 0.6096 0)
					(mid -0.6096 0)
					(end 0.6096 0)
				)
			)
			(stroke
				(width 0)
				(type default)
			)
			(fill no)
			(layer "B.Fab")
		)
		(pad "1" smd circle
			(at 0 0 180)
			(size 0.7112 0.7112)
			(layers "B.Cu" "B.Mask" "B.Paste")
			(net "IOC_GPIO_0")
		)
	)
	(footprint ""
		(layer "B.Cu")
		(at 49.60493 -76.634086)
		(property "Reference" "TP186"
			(at 0 0 0)
			(layer "B.SilkS")
			(hide yes)
			(effects
				(font
					(size 1.27 1.27)
				)
				(justify mirror)
			)
		)
		(property "Value" "TPAD32-GP"
			(at 0 -3.166364 0)
			(unlocked yes)
			(layer "B.Fab")
			(hide yes)
			(effects
				(font
					(size 1.016 1.016)
					(thickness 0.1524)
				)
				(justify mirror)
			)
		)
		(property "Device Type" "TPAD32"
			(at 0 -4.690618 0)
			(unlocked yes)
			(layer "B.Fab")
			(hide yes)
			(effects
				(font
					(size 1.016 1.016)
					(thickness 0.1524)
				)
				(justify mirror)
			)
		)
		(duplicate_pad_numbers_are_jumpers no)
		(fp_poly
			(pts
				(arc
					(start 0.4064 0)
					(mid -0.4064 0)
					(end 0.4064 0)
				)
			)
			(stroke
				(width 0)
				(type default)
			)
			(fill no)
			(layer "B.CrtYd")
		)
		(fp_poly
			(pts
				(arc
					(start 0.7112 0)
					(mid -0.7112 0)
					(end 0.7112 0)
				)
			)
			(stroke
				(width 0)
				(type default)
			)
			(fill no)
			(layer "B.Fab")
		)
		(pad "1" smd circle
			(at 0 0 180)
			(size 0.8128 0.8128)
			(layers "B.Cu" "B.Mask" "B.Paste")
			(net "INT_CONN_A_SB5")
		)
	)
	(footprint ""
		(layer "B.Cu")
		(at 105.16616 -35.306 -90)
		(property "Reference" "SC998"
			(at 0 0 90)
			(layer "B.SilkS")
			(hide yes)
			(effects
				(font
					(size 1.27 1.27)
				)
				(justify mirror)
			)
		)
		(property "Value" "SCD1U16V2KX-3GP"
			(at -1.1811 -2.7051 270)
			(unlocked yes)
			(layer "B.Fab")
			(hide yes)
			(effects
				(font
					(size 1.016 1.016)
					(thickness 0.1524)
				)
				(justify mirror)
			)
		)
		(property "Device Type" "C402H22"
			(at -1.1811 -4.2291 270)
			(unlocked yes)
			(layer "B.Fab")
			(hide yes)
			(effects
				(font
					(size 1.016 1.016)
					(thickness 0.1524)
				)
				(justify mirror)
			)
		)
		(duplicate_pad_numbers_are_jumpers no)
		(fp_rect
			(start 0.4318 0.9525)
			(end -0.4318 -0.9525)
			(stroke
				(width 0)
				(type default)
			)
			(fill no)
			(layer "B.CrtYd")
		)
		(fp_rect
			(start 0.4318 0.9525)
			(end -0.4318 -0.9525)
			(stroke
				(width 0)
				(type default)
			)
			(fill no)
			(layer "B.Fab")
		)
		(pad "1" smd custom
			(at 0 -0.4445 90)
			(size 0.1524 0.1524)
			(layers "B.Cu" "B.Mask" "B.Paste")
			(net "P1V8_C")
			(options
				(clearance outline)
				(anchor circle)
			)
			(primitives
				(gr_poly
					(pts
						(arc
							(start 0.3048 0.2032)
							(mid 0.275042 0.275042)
							(end 0.2032 0.3048)
						)
						(arc
							(start -0.2032 0.3048)
							(mid -0.275042 0.275042)
							(end -0.3048 0.2032)
						)
						(arc
							(start -0.3048 -0.2032)
							(mid -0.275042 -0.275042)
							(end -0.2032 -0.3048)
						)
						(arc
							(start 0.2032 -0.3048)
							(mid 0.275042 -0.275042)
							(end 0.3048 -0.2032)
						)
					)
					(width 0)
					(fill yes)
				)
			)
		)
		(pad "2" smd custom
			(at 0 0.4445 90)
			(size 0.1524 0.1524)
			(layers "B.Cu" "B.Mask" "B.Paste")
			(net "GND")
			(options
				(clearance outline)
				(anchor circle)
			)
			(primitives
				(gr_poly
					(pts
						(arc
							(start 0.3048 0.2032)
							(mid 0.275042 0.275042)
							(end 0.2032 0.3048)
						)
						(arc
							(start -0.2032 0.3048)
							(mid -0.275042 0.275042)
							(end -0.3048 0.2032)
						)
						(arc
							(start -0.3048 -0.2032)
							(mid -0.275042 -0.275042)
							(end -0.2032 -0.3048)
						)
						(arc
							(start 0.2032 -0.3048)
							(mid 0.275042 -0.275042)
							(end 0.3048 -0.2032)
						)
					)
					(width 0)
					(fill yes)
				)
			)
		)
	)
	(footprint ""
		(layer "B.Cu")
		(at 122.44197 -94.996)
		(property "Reference" "SC1190"
			(at 0 0 0)
			(layer "B.SilkS")
			(hide yes)
			(effects
				(font
					(size 1.27 1.27)
				)
				(justify mirror)
			)
		)
		(property "Value" "SC1U6D3V1MX-GP"
			(at -1.9177 2.0193 0)
			(unlocked yes)
			(layer "B.Fab")
			(hide yes)
			(effects
				(font
					(size 1.016 1.016)
					(thickness 0.1524)
				)
				(justify mirror)
			)
		)
		(property "Device Type" "C0201H14"
			(at -1.9177 0.4953 0)
			(unlocked yes)
			(layer "B.Fab")
			(hide yes)
			(effects
				(font
					(size 1.016 1.016)
					(thickness 0.1524)
				)
				(justify mirror)
			)
		)
		(duplicate_pad_numbers_are_jumpers no)
		(fp_rect
			(start 0.1524 0.3048)
			(end -0.1524 -0.3048)
			(stroke
				(width 0)
				(type default)
			)
			(fill no)
			(layer "B.CrtYd")
		)
		(fp_poly
			(pts
				(xy 0.2794 0.6477) (xy 0.2794 -0.6477) (xy -0.2794 -0.6477) (xy -0.2794 -0.1905) (xy -0.1524 -0.1905)
				(xy -0.1524 -0.3048) (xy 0.1524 -0.3048) (xy 0.1524 0.3048) (xy -0.1524 0.3048) (xy -0.1524 -0.1778)
				(xy -0.2794 -0.1778) (xy -0.2794 0.6477)
			)
			(stroke
				(width 0)
				(type default)
			)
			(fill no)
			(layer "B.CrtYd")
		)
		(fp_rect
			(start 0.2794 0.6477)
			(end -0.2794 -0.6477)
			(stroke
				(width 0)
				(type default)
			)
			(fill no)
			(layer "B.Fab")
		)
		(pad "1" smd custom
			(at 0 -0.2794 180)
			(size 0.0762 0.0762)
			(layers "B.Cu" "B.Mask" "B.Paste")
			(net "GB_VDDA")
			(options
				(clearance outline)
				(anchor circle)
			)
			(primitives
				(gr_poly
					(pts
						(arc
							(start 0.1524 0.127)
							(mid 0.137521 0.162921)
							(end 0.1016 0.1778)
						)
						(arc
							(start -0.1016 0.1778)
							(mid -0.137521 0.162921)
							(end -0.1524 0.127)
						)
						(arc
							(start -0.1524 -0.127)
							(mid -0.137521 -0.162921)
							(end -0.1016 -0.1778)
						)
						(arc
							(start 0.1016 -0.1778)
							(mid 0.137521 -0.162921)
							(end 0.1524 -0.127)
						)
					)
					(width 0)
					(fill yes)
				)
			)
		)
		(pad "2" smd custom
			(at 0 0.2794 180)
			(size 0.0762 0.0762)
			(layers "B.Cu" "B.Mask" "B.Paste")
			(net "GND")
			(options
				(clearance outline)
				(anchor circle)
			)
			(primitives
				(gr_poly
					(pts
						(arc
							(start 0.1524 0.127)
							(mid 0.137521 0.162921)
							(end 0.1016 0.1778)
						)
						(arc
							(start -0.1016 0.1778)
							(mid -0.137521 0.162921)
							(end -0.1524 0.127)
						)
						(arc
							(start -0.1524 -0.127)
							(mid -0.137521 -0.162921)
							(end -0.1016 -0.1778)
						)
						(arc
							(start 0.1016 -0.1778)
							(mid 0.137521 -0.162921)
							(end 0.1524 -0.127)
						)
					)
					(width 0)
					(fill yes)
				)
			)
		)
	)
	(footprint ""
		(layer "B.Cu")
		(at 88.91397 -136.779 90)
		(property "Reference" "SC1118"
			(at 0 0 90)
			(layer "B.SilkS")
			(hide yes)
			(effects
				(font
					(size 1.27 1.27)
				)
				(justify mirror)
			)
		)
		(property "Value" "SCD1U16V2KX-3GP"
			(at -1.1811 -2.7051 90)
			(unlocked yes)
			(layer "B.Fab")
			(hide yes)
			(effects
				(font
					(size 1.016 1.016)
					(thickness 0.1524)
				)
				(justify mirror)
			)
		)
		(property "Device Type" "C402H22"
			(at -1.1811 -4.2291 90)
			(unlocked yes)
			(layer "B.Fab")
			(hide yes)
			(effects
				(font
					(size 1.016 1.016)
					(thickness 0.1524)
				)
				(justify mirror)
			)
		)
		(duplicate_pad_numbers_are_jumpers no)
		(fp_rect
			(start 0.4318 0.9525)
			(end -0.4318 -0.9525)
			(stroke
				(width 0)
				(type default)
			)
			(fill no)
			(layer "B.CrtYd")
		)
		(fp_rect
			(start 0.4318 0.9525)
			(end -0.4318 -0.9525)
			(stroke
				(width 0)
				(type default)
			)
			(fill no)
			(layer "B.Fab")
		)
		(pad "1" smd custom
			(at 0 -0.4445 270)
			(size 0.1524 0.1524)
			(layers "B.Cu" "B.Mask" "B.Paste")
			(net "P3V3_STBY")
			(options
				(clearance outline)
				(anchor circle)
			)
			(primitives
				(gr_poly
					(pts
						(arc
							(start 0.3048 0.2032)
							(mid 0.275042 0.275042)
							(end 0.2032 0.3048)
						)
						(arc
							(start -0.2032 0.3048)
							(mid -0.275042 0.275042)
							(end -0.3048 0.2032)
						)
						(arc
							(start -0.3048 -0.2032)
							(mid -0.275042 -0.275042)
							(end -0.2032 -0.3048)
						)
						(arc
							(start 0.2032 -0.3048)
							(mid 0.275042 -0.275042)
							(end 0.3048 -0.2032)
						)
					)
					(width 0)
					(fill yes)
				)
			)
		)
		(pad "2" smd custom
			(at 0 0.4445 270)
			(size 0.1524 0.1524)
			(layers "B.Cu" "B.Mask" "B.Paste")
			(net "GND")
			(options
				(clearance outline)
				(anchor circle)
			)
			(primitives
				(gr_poly
					(pts
						(arc
							(start 0.3048 0.2032)
							(mid 0.275042 0.275042)
							(end 0.2032 0.3048)
						)
						(arc
							(start -0.2032 0.3048)
							(mid -0.275042 0.275042)
							(end -0.3048 0.2032)
						)
						(arc
							(start -0.3048 -0.2032)
							(mid -0.275042 -0.275042)
							(end -0.2032 -0.3048)
						)
						(arc
							(start 0.2032 -0.3048)
							(mid 0.275042 -0.275042)
							(end 0.3048 -0.2032)
						)
					)
					(width 0)
					(fill yes)
				)
			)
		)
	)
	(footprint ""
		(layer "B.Cu")
		(at 185.474864 -33.981136)
		(property "Reference" "C221"
			(at 0 0 0)
			(layer "B.SilkS")
			(hide yes)
			(effects
				(font
					(size 1.27 1.27)
				)
				(justify mirror)
			)
		)
		(property "Value" "SC1KP50V2KX-1GP"
			(at -1.1811 -2.7051 0)
			(unlocked yes)
			(layer "B.Fab")
			(hide yes)
			(effects
				(font
					(size 1.016 1.016)
					(thickness 0.1524)
				)
				(justify mirror)
			)
		)
		(property "Device Type" "C402H22"
			(at -1.1811 -4.2291 0)
			(unlocked yes)
			(layer "B.Fab")
			(hide yes)
			(effects
				(font
					(size 1.016 1.016)
					(thickness 0.1524)
				)
				(justify mirror)
			)
		)
		(duplicate_pad_numbers_are_jumpers no)
		(fp_rect
			(start 0.4318 0.9525)
			(end -0.4318 -0.9525)
			(stroke
				(width 0)
				(type default)
			)
			(fill no)
			(layer "B.CrtYd")
		)
		(fp_rect
			(start 0.4318 0.9525)
			(end -0.4318 -0.9525)
			(stroke
				(width 0)
				(type default)
			)
			(fill no)
			(layer "B.Fab")
		)
		(pad "1" smd custom
			(at 0 -0.4445 180)
			(size 0.1524 0.1524)
			(layers "B.Cu" "B.Mask" "B.Paste")
			(net "P3V3_STBY")
			(options
				(clearance outline)
				(anchor circle)
			)
			(primitives
				(gr_poly
					(pts
						(arc
							(start 0.3048 0.2032)
							(mid 0.275042 0.275042)
							(end 0.2032 0.3048)
						)
						(arc
							(start -0.2032 0.3048)
							(mid -0.275042 0.275042)
							(end -0.3048 0.2032)
						)
						(arc
							(start -0.3048 -0.2032)
							(mid -0.275042 -0.275042)
							(end -0.2032 -0.3048)
						)
						(arc
							(start 0.2032 -0.3048)
							(mid 0.275042 -0.275042)
							(end 0.3048 -0.2032)
						)
					)
					(width 0)
					(fill yes)
				)
			)
		)
		(pad "2" smd custom
			(at 0 0.4445 180)
			(size 0.1524 0.1524)
			(layers "B.Cu" "B.Mask" "B.Paste")
			(net "GND")
			(options
				(clearance outline)
				(anchor circle)
			)
			(primitives
				(gr_poly
					(pts
						(arc
							(start 0.3048 0.2032)
							(mid 0.275042 0.275042)
							(end 0.2032 0.3048)
						)
						(arc
							(start -0.2032 0.3048)
							(mid -0.275042 0.275042)
							(end -0.3048 0.2032)
						)
						(arc
							(start -0.3048 -0.2032)
							(mid -0.275042 -0.275042)
							(end -0.2032 -0.3048)
						)
						(arc
							(start 0.2032 -0.3048)
							(mid 0.275042 -0.275042)
							(end 0.3048 -0.2032)
						)
					)
					(width 0)
					(fill yes)
				)
			)
		)
	)
	(footprint ""
		(layer "B.Cu")
		(at 264.541 -16.891 180)
		(property "Reference" "C336"
			(at 0 0 0)
			(layer "B.SilkS")
			(hide yes)
			(effects
				(font
					(size 1.27 1.27)
				)
				(justify mirror)
			)
		)
		(property "Value" "SC1U10V3KX-4GP-U"
			(at 0 -2.8194 180)
			(unlocked yes)
			(layer "B.Fab")
			(hide yes)
			(effects
				(font
					(size 1.016 1.016)
					(thickness 0.1524)
				)
				(justify mirror)
			)
		)
		(property "Device Type" "C603H36"
			(at 0 -4.3434 180)
			(unlocked yes)
			(layer "B.Fab")
			(hide yes)
			(effects
				(font
					(size 1.016 1.016)
					(thickness 0.1524)
				)
				(justify mirror)
			)
		)
		(duplicate_pad_numbers_are_jumpers no)
		(fp_line
			(start -0.508 0)
			(end 0.508 0)
			(stroke
				(width 0.2032)
				(type default)
			)
			(layer "B.SilkS")
		)
		(fp_rect
			(start 0.5842 1.3335)
			(end -0.5842 -1.3335)
			(stroke
				(width 0)
				(type default)
			)
			(fill no)
			(layer "B.CrtYd")
		)
		(fp_rect
			(start 0.5842 1.3335)
			(end -0.5842 -1.3335)
			(stroke
				(width 0)
				(type default)
			)
			(fill no)
			(layer "B.Fab")
		)
		(pad "1" smd custom
			(at 0 -0.762)
			(size 0.2159 0.2159)
			(layers "B.Cu" "B.Mask" "B.Paste")
			(net "P5V_USB")
			(options
				(clearance outline)
				(anchor circle)
			)
			(primitives
				(gr_poly
					(pts
						(arc
							(start -0.3302 0.4318)
							(mid -0.402042 0.402042)
							(end -0.4318 0.3302)
						)
						(arc
							(start -0.4318 -0.3302)
							(mid -0.402042 -0.402042)
							(end -0.3302 -0.4318)
						)
						(arc
							(start 0.3302 -0.4318)
							(mid 0.402042 -0.402042)
							(end 0.4318 -0.3302)
						)
						(arc
							(start 0.4318 0.3302)
							(mid 0.402042 0.402042)
							(end 0.3302 0.4318)
						)
					)
					(width 0)
					(fill yes)
				)
			)
		)
		(pad "2" smd custom
			(at 0 0.762)
			(size 0.2159 0.2159)
			(layers "B.Cu" "B.Mask" "B.Paste")
			(net "GND")
			(options
				(clearance outline)
				(anchor circle)
			)
			(primitives
				(gr_poly
					(pts
						(arc
							(start -0.3302 0.4318)
							(mid -0.402042 0.402042)
							(end -0.4318 0.3302)
						)
						(arc
							(start -0.4318 -0.3302)
							(mid -0.402042 -0.402042)
							(end -0.3302 -0.4318)
						)
						(arc
							(start 0.3302 -0.4318)
							(mid 0.402042 -0.402042)
							(end 0.4318 -0.3302)
						)
						(arc
							(start 0.4318 0.3302)
							(mid 0.402042 0.402042)
							(end 0.3302 0.4318)
						)
					)
					(width 0)
					(fill yes)
				)
			)
		)
	)
	(footprint ""
		(layer "B.Cu")
		(at 158.42996 -110.591854 90)
		(property "Reference" "SC1246"
			(at 0 0 90)
			(layer "B.SilkS")
			(hide yes)
			(effects
				(font
					(size 1.27 1.27)
				)
				(justify mirror)
			)
		)
		(property "Value" "SCD1U6D3V1KX-GP"
			(at 2.8321 -1.7399 90)
			(unlocked yes)
			(layer "B.Fab")
			(hide yes)
			(effects
				(font
					(size 1.016 1.016)
					(thickness 0.1524)
				)
				(justify mirror)
			)
		)
		(property "Device Type" "C0201H13"
			(at 2.8321 -3.2639 90)
			(unlocked yes)
			(layer "B.Fab")
			(hide yes)
			(effects
				(font
					(size 1.016 1.016)
					(thickness 0.1524)
				)
				(justify mirror)
			)
		)
		(duplicate_pad_numbers_are_jumpers no)
		(fp_rect
			(start 0.2794 0.6477)
			(end -0.2794 -0.6477)
			(stroke
				(width 0)
				(type default)
			)
			(fill no)
			(layer "B.CrtYd")
		)
		(fp_rect
			(start 0.2794 0.6477)
			(end -0.2794 -0.6477)
			(stroke
				(width 0)
				(type default)
			)
			(fill no)
			(layer "B.Fab")
		)
		(pad "1" smd custom
			(at 0 -0.2794 270)
			(size 0.0762 0.0762)
			(layers "B.Cu" "B.Mask" "B.Paste")
			(net "P0V9_E")
			(options
				(clearance outline)
				(anchor circle)
			)
			(primitives
				(gr_poly
					(pts
						(arc
							(start 0.1524 0.127)
							(mid 0.137521 0.162921)
							(end 0.1016 0.1778)
						)
						(arc
							(start -0.1016 0.1778)
							(mid -0.137521 0.162921)
							(end -0.1524 0.127)
						)
						(arc
							(start -0.1524 -0.127)
							(mid -0.137521 -0.162921)
							(end -0.1016 -0.1778)
						)
						(arc
							(start 0.1016 -0.1778)
							(mid 0.137521 -0.162921)
							(end 0.1524 -0.127)
						)
					)
					(width 0)
					(fill yes)
				)
			)
		)
		(pad "2" smd custom
			(at 0 0.2794 270)
			(size 0.0762 0.0762)
			(layers "B.Cu" "B.Mask" "B.Paste")
			(net "GND")
			(options
				(clearance outline)
				(anchor circle)
			)
			(primitives
				(gr_poly
					(pts
						(arc
							(start 0.1524 0.127)
							(mid 0.137521 0.162921)
							(end 0.1016 0.1778)
						)
						(arc
							(start -0.1016 0.1778)
							(mid -0.137521 0.162921)
							(end -0.1524 0.127)
						)
						(arc
							(start -0.1524 -0.127)
							(mid -0.137521 -0.162921)
							(end -0.1016 -0.1778)
						)
						(arc
							(start 0.1016 -0.1778)
							(mid 0.137521 -0.162921)
							(end 0.1524 -0.127)
						)
					)
					(width 0)
					(fill yes)
				)
			)
		)
	)
	(footprint ""
		(layer "B.Cu")
		(at 292.354 -179.07)
		(property "Reference" "C204"
			(at 0 0 0)
			(layer "B.SilkS")
			(hide yes)
			(effects
				(font
					(size 1.27 1.27)
				)
				(justify mirror)
			)
		)
		(property "Value" "SC1U10V3KX-4GP-U"
			(at 0 -2.8194 0)
			(unlocked yes)
			(layer "B.Fab")
			(hide yes)
			(effects
				(font
					(size 1.016 1.016)
					(thickness 0.1524)
				)
				(justify mirror)
			)
		)
		(property "Device Type" "C603H36"
			(at 0 -4.3434 0)
			(unlocked yes)
			(layer "B.Fab")
			(hide yes)
			(effects
				(font
					(size 1.016 1.016)
					(thickness 0.1524)
				)
				(justify mirror)
			)
		)
		(duplicate_pad_numbers_are_jumpers no)
		(fp_line
			(start -0.508 0)
			(end 0.508 0)
			(stroke
				(width 0.2032)
				(type default)
			)
			(layer "B.SilkS")
		)
		(fp_rect
			(start 0.5842 1.3335)
			(end -0.5842 -1.3335)
			(stroke
				(width 0)
				(type default)
			)
			(fill no)
			(layer "B.CrtYd")
		)
		(fp_rect
			(start 0.5842 1.3335)
			(end -0.5842 -1.3335)
			(stroke
				(width 0)
				(type default)
			)
			(fill no)
			(layer "B.Fab")
		)
		(pad "1" smd custom
			(at 0 -0.762 180)
			(size 0.2159 0.2159)
			(layers "B.Cu" "B.Mask" "B.Paste")
			(net "P1V26_STBY")
			(options
				(clearance outline)
				(anchor circle)
			)
			(primitives
				(gr_poly
					(pts
						(arc
							(start -0.3302 0.4318)
							(mid -0.402042 0.402042)
							(end -0.4318 0.3302)
						)
						(arc
							(start -0.4318 -0.3302)
							(mid -0.402042 -0.402042)
							(end -0.3302 -0.4318)
						)
						(arc
							(start 0.3302 -0.4318)
							(mid 0.402042 -0.402042)
							(end 0.4318 -0.3302)
						)
						(arc
							(start 0.4318 0.3302)
							(mid 0.402042 0.402042)
							(end 0.3302 0.4318)
						)
					)
					(width 0)
					(fill yes)
				)
			)
		)
		(pad "2" smd custom
			(at 0 0.762 180)
			(size 0.2159 0.2159)
			(layers "B.Cu" "B.Mask" "B.Paste")
			(net "GND")
			(options
				(clearance outline)
				(anchor circle)
			)
			(primitives
				(gr_poly
					(pts
						(arc
							(start -0.3302 0.4318)
							(mid -0.402042 0.402042)
							(end -0.4318 0.3302)
						)
						(arc
							(start -0.4318 -0.3302)
							(mid -0.402042 -0.402042)
							(end -0.3302 -0.4318)
						)
						(arc
							(start 0.3302 -0.4318)
							(mid 0.402042 -0.402042)
							(end 0.4318 -0.3302)
						)
						(arc
							(start 0.4318 0.3302)
							(mid 0.402042 0.402042)
							(end 0.3302 0.4318)
						)
					)
					(width 0)
					(fill yes)
				)
			)
		)
	)
	(footprint ""
		(layer "B.Cu")
		(at 109.544612 -222.885 180)
		(property "Reference" "SR898"
			(at 0 0 0)
			(layer "B.SilkS")
			(hide yes)
			(effects
				(font
					(size 1.27 1.27)
				)
				(justify mirror)
			)
		)
		(property "Value" "0R2J-2-GP"
			(at -0.064008 -3.993896 180)
			(unlocked yes)
			(layer "B.Fab")
			(hide yes)
			(effects
				(font
					(size 1.016 1.016)
					(thickness 0.1524)
				)
				(justify mirror)
			)
		)
		(property "Device Type" "R402H16"
			(at -0.064008 -5.517896 180)
			(unlocked yes)
			(layer "B.Fab")
			(hide yes)
			(effects
				(font
					(size 1.016 1.016)
					(thickness 0.1524)
				)
				(justify mirror)
			)
		)
		(duplicate_pad_numbers_are_jumpers no)
		(fp_line
			(start 0.508 -0.9398)
			(end 0.508 0.9398)
			(stroke
				(width 0.1524)
				(type default)
			)
			(layer "B.SilkS")
		)
		(fp_line
			(start -0.508 -0.9398)
			(end 0.508 -0.9398)
			(stroke
				(width 0.1524)
				(type default)
			)
			(layer "B.SilkS")
		)
		(fp_rect
			(start 0.508 0.9398)
			(end -0.508 -0.9398)
			(stroke
				(width 0)
				(type default)
			)
			(fill no)
			(layer "B.CrtYd")
		)
		(fp_rect
			(start 0.508 0.9398)
			(end -0.508 -0.9398)
			(stroke
				(width 0)
				(type default)
			)
			(fill no)
			(layer "B.Fab")
		)
		(pad "1" smd custom
			(at 0 -0.4445)
			(size 0.1397 0.1397)
			(layers "B.Cu" "B.Mask" "B.Paste")
			(net "SAS_GF_EXP_RX_DN8")
			(options
				(clearance outline)
				(anchor circle)
			)
			(primitives
				(gr_poly
					(pts
						(arc
							(start -0.1778 0.2794)
							(mid -0.249642 0.249642)
							(end -0.2794 0.1778)
						)
						(arc
							(start -0.2794 -0.1778)
							(mid -0.249642 -0.249642)
							(end -0.1778 -0.2794)
						)
						(arc
							(start 0.1778 -0.2794)
							(mid 0.249642 -0.249642)
							(end 0.2794 -0.1778)
						)
						(arc
							(start 0.2794 0.1778)
							(mid 0.249642 0.249642)
							(end 0.1778 0.2794)
						)
					)
					(width 0)
					(fill yes)
				)
			)
		)
		(pad "2" smd custom
			(at 0 0.4445)
			(size 0.1397 0.1397)
			(layers "B.Cu" "B.Mask" "B.Paste")
			(net "REDV_RX8_N")
			(options
				(clearance outline)
				(anchor circle)
			)
			(primitives
				(gr_poly
					(pts
						(arc
							(start -0.1778 0.2794)
							(mid -0.249642 0.249642)
							(end -0.2794 0.1778)
						)
						(arc
							(start -0.2794 -0.1778)
							(mid -0.249642 -0.249642)
							(end -0.1778 -0.2794)
						)
						(arc
							(start 0.1778 -0.2794)
							(mid 0.249642 -0.249642)
							(end 0.2794 -0.1778)
						)
						(arc
							(start 0.2794 0.1778)
							(mid 0.249642 0.249642)
							(end 0.1778 0.2794)
						)
					)
					(width 0)
					(fill yes)
				)
			)
		)
	)
	(footprint ""
		(layer "B.Cu")
		(at 112.293146 -47.6504)
		(property "Reference" "STP15"
			(at 0 0 0)
			(layer "B.SilkS")
			(hide yes)
			(effects
				(font
					(size 1.27 1.27)
				)
				(justify mirror)
			)
		)
		(property "Value" "TPAD28"
			(at -0.0127 -1.8034 0)
			(unlocked yes)
			(layer "B.Fab")
			(hide yes)
			(effects
				(font
					(size 1.016 1.016)
					(thickness 0.1524)
				)
				(justify mirror)
			)
		)
		(property "Device Type" "TPAD28"
			(at -0.0127 -3.3274 0)
			(unlocked yes)
			(layer "B.Fab")
			(hide yes)
			(effects
				(font
					(size 1.016 1.016)
					(thickness 0.1524)
				)
				(justify mirror)
			)
		)
		(duplicate_pad_numbers_are_jumpers no)
		(fp_poly
			(pts
				(arc
					(start 0.3556 0)
					(mid -0.3556 0)
					(end 0.3556 0)
				)
			)
			(stroke
				(width 0)
				(type default)
			)
			(fill no)
			(layer "B.CrtYd")
		)
		(fp_poly
			(pts
				(arc
					(start 0.6096 0)
					(mid -0.6096 0)
					(end 0.6096 0)
				)
			)
			(stroke
				(width 0)
				(type default)
			)
			(fill no)
			(layer "B.Fab")
		)
		(pad "1" smd circle
			(at 0 0 180)
			(size 0.7112 0.7112)
			(layers "B.Cu" "B.Mask" "B.Paste")
			(net "IOC_GPIO_32")
		)
	)
	(footprint ""
		(layer "B.Cu")
		(at 109.982 -94.488 -90)
		(property "Reference" "SC1251"
			(at 0 0 90)
			(layer "B.SilkS")
			(hide yes)
			(effects
				(font
					(size 1.27 1.27)
				)
				(justify mirror)
			)
		)
		(property "Value" "SCD1U6D3V1KX-GP"
			(at 2.8321 -1.7399 270)
			(unlocked yes)
			(layer "B.Fab")
			(hide yes)
			(effects
				(font
					(size 1.016 1.016)
					(thickness 0.1524)
				)
				(justify mirror)
			)
		)
		(property "Device Type" "C0201H13"
			(at 2.8321 -3.2639 270)
			(unlocked yes)
			(layer "B.Fab")
			(hide yes)
			(effects
				(font
					(size 1.016 1.016)
					(thickness 0.1524)
				)
				(justify mirror)
			)
		)
		(duplicate_pad_numbers_are_jumpers no)
		(fp_rect
			(start 0.2794 0.6477)
			(end -0.2794 -0.6477)
			(stroke
				(width 0)
				(type default)
			)
			(fill no)
			(layer "B.CrtYd")
		)
		(fp_rect
			(start 0.2794 0.6477)
			(end -0.2794 -0.6477)
			(stroke
				(width 0)
				(type default)
			)
			(fill no)
			(layer "B.Fab")
		)
		(pad "1" smd custom
			(at 0 -0.2794 90)
			(size 0.0762 0.0762)
			(layers "B.Cu" "B.Mask" "B.Paste")
			(net "P0V9_E")
			(options
				(clearance outline)
				(anchor circle)
			)
			(primitives
				(gr_poly
					(pts
						(arc
							(start 0.1524 0.127)
							(mid 0.137521 0.162921)
							(end 0.1016 0.1778)
						)
						(arc
							(start -0.1016 0.1778)
							(mid -0.137521 0.162921)
							(end -0.1524 0.127)
						)
						(arc
							(start -0.1524 -0.127)
							(mid -0.137521 -0.162921)
							(end -0.1016 -0.1778)
						)
						(arc
							(start 0.1016 -0.1778)
							(mid 0.137521 -0.162921)
							(end 0.1524 -0.127)
						)
					)
					(width 0)
					(fill yes)
				)
			)
		)
		(pad "2" smd custom
			(at 0 0.2794 90)
			(size 0.0762 0.0762)
			(layers "B.Cu" "B.Mask" "B.Paste")
			(net "GND")
			(options
				(clearance outline)
				(anchor circle)
			)
			(primitives
				(gr_poly
					(pts
						(arc
							(start 0.1524 0.127)
							(mid 0.137521 0.162921)
							(end 0.1016 0.1778)
						)
						(arc
							(start -0.1016 0.1778)
							(mid -0.137521 0.162921)
							(end -0.1524 0.127)
						)
						(arc
							(start -0.1524 -0.127)
							(mid -0.137521 -0.162921)
							(end -0.1016 -0.1778)
						)
						(arc
							(start 0.1016 -0.1778)
							(mid 0.137521 -0.162921)
							(end 0.1524 -0.127)
						)
					)
					(width 0)
					(fill yes)
				)
			)
		)
	)
	(footprint ""
		(layer "B.Cu")
		(at 107.169966 -44.958 90)
		(property "Reference" "SC1055"
			(at 0 0 90)
			(layer "B.SilkS")
			(hide yes)
			(effects
				(font
					(size 1.27 1.27)
				)
				(justify mirror)
			)
		)
		(property "Value" "SCD1U16V2KX-3GP"
			(at -1.1811 -2.7051 90)
			(unlocked yes)
			(layer "B.Fab")
			(hide yes)
			(effects
				(font
					(size 1.016 1.016)
					(thickness 0.1524)
				)
				(justify mirror)
			)
		)
		(property "Device Type" "C402H22"
			(at -1.1811 -4.2291 90)
			(unlocked yes)
			(layer "B.Fab")
			(hide yes)
			(effects
				(font
					(size 1.016 1.016)
					(thickness 0.1524)
				)
				(justify mirror)
			)
		)
		(duplicate_pad_numbers_are_jumpers no)
		(fp_rect
			(start 0.4318 0.9525)
			(end -0.4318 -0.9525)
			(stroke
				(width 0)
				(type default)
			)
			(fill no)
			(layer "B.CrtYd")
		)
		(fp_rect
			(start 0.4318 0.9525)
			(end -0.4318 -0.9525)
			(stroke
				(width 0)
				(type default)
			)
			(fill no)
			(layer "B.Fab")
		)
		(pad "1" smd custom
			(at 0 -0.4445 270)
			(size 0.1524 0.1524)
			(layers "B.Cu" "B.Mask" "B.Paste")
			(net "P0V955_C")
			(options
				(clearance outline)
				(anchor circle)
			)
			(primitives
				(gr_poly
					(pts
						(arc
							(start 0.3048 0.2032)
							(mid 0.275042 0.275042)
							(end 0.2032 0.3048)
						)
						(arc
							(start -0.2032 0.3048)
							(mid -0.275042 0.275042)
							(end -0.3048 0.2032)
						)
						(arc
							(start -0.3048 -0.2032)
							(mid -0.275042 -0.275042)
							(end -0.2032 -0.3048)
						)
						(arc
							(start 0.2032 -0.3048)
							(mid 0.275042 -0.275042)
							(end 0.3048 -0.2032)
						)
					)
					(width 0)
					(fill yes)
				)
			)
		)
		(pad "2" smd custom
			(at 0 0.4445 270)
			(size 0.1524 0.1524)
			(layers "B.Cu" "B.Mask" "B.Paste")
			(net "GND")
			(options
				(clearance outline)
				(anchor circle)
			)
			(primitives
				(gr_poly
					(pts
						(arc
							(start 0.3048 0.2032)
							(mid 0.275042 0.275042)
							(end 0.2032 0.3048)
						)
						(arc
							(start -0.2032 0.3048)
							(mid -0.275042 0.275042)
							(end -0.3048 0.2032)
						)
						(arc
							(start -0.3048 -0.2032)
							(mid -0.275042 -0.275042)
							(end -0.2032 -0.3048)
						)
						(arc
							(start 0.2032 -0.3048)
							(mid 0.275042 -0.275042)
							(end 0.3048 -0.2032)
						)
					)
					(width 0)
					(fill yes)
				)
			)
		)
	)
	(footprint ""
		(layer "B.Cu")
		(at 109.728 -92.964)
		(property "Reference" "STP162"
			(at 0 0 0)
			(layer "B.SilkS")
			(hide yes)
			(effects
				(font
					(size 1.27 1.27)
				)
				(justify mirror)
			)
		)
		(property "Value" "TPAD28"
			(at -0.0127 -1.8034 0)
			(unlocked yes)
			(layer "B.Fab")
			(hide yes)
			(effects
				(font
					(size 1.016 1.016)
					(thickness 0.1524)
				)
				(justify mirror)
			)
		)
		(property "Device Type" "TPAD28"
			(at -0.0127 -3.3274 0)
			(unlocked yes)
			(layer "B.Fab")
			(hide yes)
			(effects
				(font
					(size 1.016 1.016)
					(thickness 0.1524)
				)
				(justify mirror)
			)
		)
		(duplicate_pad_numbers_are_jumpers no)
		(fp_poly
			(pts
				(arc
					(start 0.3556 0)
					(mid -0.3556 0)
					(end 0.3556 0)
				)
			)
			(stroke
				(width 0)
				(type default)
			)
			(fill no)
			(layer "B.CrtYd")
		)
		(fp_poly
			(pts
				(arc
					(start 0.6096 0)
					(mid -0.6096 0)
					(end 0.6096 0)
				)
			)
			(stroke
				(width 0)
				(type default)
			)
			(fill no)
			(layer "B.Fab")
		)
		(pad "1" smd circle
			(at 0 0 180)
			(size 0.7112 0.7112)
			(layers "B.Cu" "B.Mask" "B.Paste")
			(net "EXP_XM_ADDR_24")
		)
	)
	(footprint ""
		(layer "B.Cu")
		(at 89.67216 -53.086)
		(property "Reference" "SR633"
			(at 0 0 0)
			(layer "B.SilkS")
			(hide yes)
			(effects
				(font
					(size 1.27 1.27)
				)
				(justify mirror)
			)
		)
		(property "Value" "2K2R2F-GP"
			(at -0.064008 -3.993896 0)
			(unlocked yes)
			(layer "B.Fab")
			(hide yes)
			(effects
				(font
					(size 1.016 1.016)
					(thickness 0.1524)
				)
				(justify mirror)
			)
		)
		(property "Device Type" "R402H16"
			(at -0.064008 -5.517896 0)
			(unlocked yes)
			(layer "B.Fab")
			(hide yes)
			(effects
				(font
					(size 1.016 1.016)
					(thickness 0.1524)
				)
				(justify mirror)
			)
		)
		(duplicate_pad_numbers_are_jumpers no)
		(fp_line
			(start -0.508 -0.9398)
			(end 0.508 -0.9398)
			(stroke
				(width 0.1524)
				(type default)
			)
			(layer "B.SilkS")
		)
		(fp_line
			(start 0.508 -0.9398)
			(end 0.508 0.9398)
			(stroke
				(width 0.1524)
				(type default)
			)
			(layer "B.SilkS")
		)
		(fp_rect
			(start 0.508 0.9398)
			(end -0.508 -0.9398)
			(stroke
				(width 0)
				(type default)
			)
			(fill no)
			(layer "B.CrtYd")
		)
		(fp_rect
			(start 0.508 0.9398)
			(end -0.508 -0.9398)
			(stroke
				(width 0)
				(type default)
			)
			(fill no)
			(layer "B.Fab")
		)
		(pad "1" smd custom
			(at 0 -0.4445 180)
			(size 0.1397 0.1397)
			(layers "B.Cu" "B.Mask" "B.Paste")
			(net "P1V8_C")
			(options
				(clearance outline)
				(anchor circle)
			)
			(primitives
				(gr_poly
					(pts
						(arc
							(start -0.1778 0.2794)
							(mid -0.249642 0.249642)
							(end -0.2794 0.1778)
						)
						(arc
							(start -0.2794 -0.1778)
							(mid -0.249642 -0.249642)
							(end -0.1778 -0.2794)
						)
						(arc
							(start 0.1778 -0.2794)
							(mid 0.249642 -0.249642)
							(end 0.2794 -0.1778)
						)
						(arc
							(start 0.2794 0.1778)
							(mid 0.249642 0.249642)
							(end 0.1778 0.2794)
						)
					)
					(width 0)
					(fill yes)
				)
			)
		)
		(pad "2" smd custom
			(at 0 0.4445 180)
			(size 0.1397 0.1397)
			(layers "B.Cu" "B.Mask" "B.Paste")
			(net "SIO_LOAD_1")
			(options
				(clearance outline)
				(anchor circle)
			)
			(primitives
				(gr_poly
					(pts
						(arc
							(start -0.1778 0.2794)
							(mid -0.249642 0.249642)
							(end -0.2794 0.1778)
						)
						(arc
							(start -0.2794 -0.1778)
							(mid -0.249642 -0.249642)
							(end -0.1778 -0.2794)
						)
						(arc
							(start 0.1778 -0.2794)
							(mid 0.249642 -0.249642)
							(end 0.2794 -0.1778)
						)
						(arc
							(start 0.2794 0.1778)
							(mid 0.249642 0.249642)
							(end 0.1778 0.2794)
						)
					)
					(width 0)
					(fill yes)
				)
			)
		)
	)
	(footprint ""
		(layer "B.Cu")
		(at 105.290366 -41.91 90)
		(property "Reference" "SC1032"
			(at 0 0 90)
			(layer "B.SilkS")
			(hide yes)
			(effects
				(font
					(size 1.27 1.27)
				)
				(justify mirror)
			)
		)
		(property "Value" "SC1KP50V2KX-1GP"
			(at -1.1811 -2.7051 90)
			(unlocked yes)
			(layer "B.Fab")
			(hide yes)
			(effects
				(font
					(size 1.016 1.016)
					(thickness 0.1524)
				)
				(justify mirror)
			)
		)
		(property "Device Type" "C402H22"
			(at -1.1811 -4.2291 90)
			(unlocked yes)
			(layer "B.Fab")
			(hide yes)
			(effects
				(font
					(size 1.016 1.016)
					(thickness 0.1524)
				)
				(justify mirror)
			)
		)
		(duplicate_pad_numbers_are_jumpers no)
		(fp_rect
			(start 0.4318 0.9525)
			(end -0.4318 -0.9525)
			(stroke
				(width 0)
				(type default)
			)
			(fill no)
			(layer "B.CrtYd")
		)
		(fp_rect
			(start 0.4318 0.9525)
			(end -0.4318 -0.9525)
			(stroke
				(width 0)
				(type default)
			)
			(fill no)
			(layer "B.Fab")
		)
		(pad "1" smd custom
			(at 0 -0.4445 270)
			(size 0.1524 0.1524)
			(layers "B.Cu" "B.Mask" "B.Paste")
			(net "P0V955_C")
			(options
				(clearance outline)
				(anchor circle)
			)
			(primitives
				(gr_poly
					(pts
						(arc
							(start 0.3048 0.2032)
							(mid 0.275042 0.275042)
							(end 0.2032 0.3048)
						)
						(arc
							(start -0.2032 0.3048)
							(mid -0.275042 0.275042)
							(end -0.3048 0.2032)
						)
						(arc
							(start -0.3048 -0.2032)
							(mid -0.275042 -0.275042)
							(end -0.2032 -0.3048)
						)
						(arc
							(start 0.2032 -0.3048)
							(mid 0.275042 -0.275042)
							(end 0.3048 -0.2032)
						)
					)
					(width 0)
					(fill yes)
				)
			)
		)
		(pad "2" smd custom
			(at 0 0.4445 270)
			(size 0.1524 0.1524)
			(layers "B.Cu" "B.Mask" "B.Paste")
			(net "GND")
			(options
				(clearance outline)
				(anchor circle)
			)
			(primitives
				(gr_poly
					(pts
						(arc
							(start 0.3048 0.2032)
							(mid 0.275042 0.275042)
							(end 0.2032 0.3048)
						)
						(arc
							(start -0.2032 0.3048)
							(mid -0.275042 0.275042)
							(end -0.3048 0.2032)
						)
						(arc
							(start -0.3048 -0.2032)
							(mid -0.275042 -0.275042)
							(end -0.2032 -0.3048)
						)
						(arc
							(start 0.2032 -0.3048)
							(mid 0.275042 -0.275042)
							(end 0.3048 -0.2032)
						)
					)
					(width 0)
					(fill yes)
				)
			)
		)
	)
	(footprint ""
		(layer "B.Cu")
		(at 285.6992 -204.978 180)
		(property "Reference" "C199"
			(at 0 0 0)
			(layer "B.SilkS")
			(hide yes)
			(effects
				(font
					(size 1.27 1.27)
				)
				(justify mirror)
			)
		)
		(property "Value" "SC1U10V3KX-4GP-U"
			(at 0 -2.8194 180)
			(unlocked yes)
			(layer "B.Fab")
			(hide yes)
			(effects
				(font
					(size 1.016 1.016)
					(thickness 0.1524)
				)
				(justify mirror)
			)
		)
		(property "Device Type" "C603H36"
			(at 0 -4.3434 180)
			(unlocked yes)
			(layer "B.Fab")
			(hide yes)
			(effects
				(font
					(size 1.016 1.016)
					(thickness 0.1524)
				)
				(justify mirror)
			)
		)
		(duplicate_pad_numbers_are_jumpers no)
		(fp_line
			(start -0.508 0)
			(end 0.508 0)
			(stroke
				(width 0.2032)
				(type default)
			)
			(layer "B.SilkS")
		)
		(fp_rect
			(start 0.5842 1.3335)
			(end -0.5842 -1.3335)
			(stroke
				(width 0)
				(type default)
			)
			(fill no)
			(layer "B.CrtYd")
		)
		(fp_rect
			(start 0.5842 1.3335)
			(end -0.5842 -1.3335)
			(stroke
				(width 0)
				(type default)
			)
			(fill no)
			(layer "B.Fab")
		)
		(pad "1" smd custom
			(at 0 -0.762)
			(size 0.2159 0.2159)
			(layers "B.Cu" "B.Mask" "B.Paste")
			(net "P1V53_STBY")
			(options
				(clearance outline)
				(anchor circle)
			)
			(primitives
				(gr_poly
					(pts
						(arc
							(start -0.3302 0.4318)
							(mid -0.402042 0.402042)
							(end -0.4318 0.3302)
						)
						(arc
							(start -0.4318 -0.3302)
							(mid -0.402042 -0.402042)
							(end -0.3302 -0.4318)
						)
						(arc
							(start 0.3302 -0.4318)
							(mid 0.402042 -0.402042)
							(end 0.4318 -0.3302)
						)
						(arc
							(start 0.4318 0.3302)
							(mid 0.402042 0.402042)
							(end 0.3302 0.4318)
						)
					)
					(width 0)
					(fill yes)
				)
			)
		)
		(pad "2" smd custom
			(at 0 0.762)
			(size 0.2159 0.2159)
			(layers "B.Cu" "B.Mask" "B.Paste")
			(net "GND")
			(options
				(clearance outline)
				(anchor circle)
			)
			(primitives
				(gr_poly
					(pts
						(arc
							(start -0.3302 0.4318)
							(mid -0.402042 0.402042)
							(end -0.4318 0.3302)
						)
						(arc
							(start -0.4318 -0.3302)
							(mid -0.402042 -0.402042)
							(end -0.3302 -0.4318)
						)
						(arc
							(start 0.3302 -0.4318)
							(mid 0.402042 -0.402042)
							(end 0.4318 -0.3302)
						)
						(arc
							(start 0.4318 0.3302)
							(mid 0.402042 0.402042)
							(end 0.3302 0.4318)
						)
					)
					(width 0)
					(fill yes)
				)
			)
		)
	)
	(footprint ""
		(layer "B.Cu")
		(at 124.403612 -211.328 90)
		(property "Reference" "SC1291"
			(at 0 0 90)
			(layer "B.SilkS")
			(hide yes)
			(effects
				(font
					(size 1.27 1.27)
				)
				(justify mirror)
			)
		)
		(property "Value" "SCD1U16V2KX-3GP"
			(at -1.1811 -2.7051 90)
			(unlocked yes)
			(layer "B.Fab")
			(hide yes)
			(effects
				(font
					(size 1.016 1.016)
					(thickness 0.1524)
				)
				(justify mirror)
			)
		)
		(property "Device Type" "C402H22"
			(at -1.1811 -4.2291 90)
			(unlocked yes)
			(layer "B.Fab")
			(hide yes)
			(effects
				(font
					(size 1.016 1.016)
					(thickness 0.1524)
				)
				(justify mirror)
			)
		)
		(duplicate_pad_numbers_are_jumpers no)
		(fp_rect
			(start 0.4318 0.9525)
			(end -0.4318 -0.9525)
			(stroke
				(width 0)
				(type default)
			)
			(fill no)
			(layer "B.CrtYd")
		)
		(fp_rect
			(start 0.4318 0.9525)
			(end -0.4318 -0.9525)
			(stroke
				(width 0)
				(type default)
			)
			(fill no)
			(layer "B.Fab")
		)
		(pad "1" smd custom
			(at 0 -0.4445 270)
			(size 0.1524 0.1524)
			(layers "B.Cu" "B.Mask" "B.Paste")
			(net "1.2V_REDV")
			(options
				(clearance outline)
				(anchor circle)
			)
			(primitives
				(gr_poly
					(pts
						(arc
							(start 0.3048 0.2032)
							(mid 0.275042 0.275042)
							(end 0.2032 0.3048)
						)
						(arc
							(start -0.2032 0.3048)
							(mid -0.275042 0.275042)
							(end -0.3048 0.2032)
						)
						(arc
							(start -0.3048 -0.2032)
							(mid -0.275042 -0.275042)
							(end -0.2032 -0.3048)
						)
						(arc
							(start 0.2032 -0.3048)
							(mid 0.275042 -0.275042)
							(end 0.3048 -0.2032)
						)
					)
					(width 0)
					(fill yes)
				)
			)
		)
		(pad "2" smd custom
			(at 0 0.4445 270)
			(size 0.1524 0.1524)
			(layers "B.Cu" "B.Mask" "B.Paste")
			(net "GND")
			(options
				(clearance outline)
				(anchor circle)
			)
			(primitives
				(gr_poly
					(pts
						(arc
							(start 0.3048 0.2032)
							(mid 0.275042 0.275042)
							(end 0.2032 0.3048)
						)
						(arc
							(start -0.2032 0.3048)
							(mid -0.275042 0.275042)
							(end -0.3048 0.2032)
						)
						(arc
							(start -0.3048 -0.2032)
							(mid -0.275042 -0.275042)
							(end -0.2032 -0.3048)
						)
						(arc
							(start 0.2032 -0.3048)
							(mid 0.275042 -0.275042)
							(end 0.3048 -0.2032)
						)
					)
					(width 0)
					(fill yes)
				)
			)
		)
	)
	(footprint ""
		(layer "B.Cu")
		(at 102.997 -225.933 -90)
		(property "Reference" "R666"
			(at 0 0 90)
			(layer "B.SilkS")
			(hide yes)
			(effects
				(font
					(size 1.27 1.27)
				)
				(justify mirror)
			)
		)
		(property "Value" "0R2J-2-GP"
			(at -0.064008 -3.993896 270)
			(unlocked yes)
			(layer "B.Fab")
			(hide yes)
			(effects
				(font
					(size 1.016 1.016)
					(thickness 0.1524)
				)
				(justify mirror)
			)
		)
		(property "Device Type" "R402H16"
			(at -0.064008 -5.517896 270)
			(unlocked yes)
			(layer "B.Fab")
			(hide yes)
			(effects
				(font
					(size 1.016 1.016)
					(thickness 0.1524)
				)
				(justify mirror)
			)
		)
		(duplicate_pad_numbers_are_jumpers no)
		(fp_line
			(start -0.508 -0.9398)
			(end 0.508 -0.9398)
			(stroke
				(width 0.1524)
				(type default)
			)
			(layer "B.SilkS")
		)
		(fp_line
			(start 0.508 -0.9398)
			(end 0.508 0.9398)
			(stroke
				(width 0.1524)
				(type default)
			)
			(layer "B.SilkS")
		)
		(fp_rect
			(start 0.508 0.9398)
			(end -0.508 -0.9398)
			(stroke
				(width 0)
				(type default)
			)
			(fill no)
			(layer "B.CrtYd")
		)
		(fp_rect
			(start 0.508 0.9398)
			(end -0.508 -0.9398)
			(stroke
				(width 0)
				(type default)
			)
			(fill no)
			(layer "B.Fab")
		)
		(pad "1" smd custom
			(at 0 -0.4445 90)
			(size 0.1397 0.1397)
			(layers "B.Cu" "B.Mask" "B.Paste")
			(net "SAS_FAULT_LED1")
			(options
				(clearance outline)
				(anchor circle)
			)
			(primitives
				(gr_poly
					(pts
						(arc
							(start -0.1778 0.2794)
							(mid -0.249642 0.249642)
							(end -0.2794 0.1778)
						)
						(arc
							(start -0.2794 -0.1778)
							(mid -0.249642 -0.249642)
							(end -0.1778 -0.2794)
						)
						(arc
							(start 0.1778 -0.2794)
							(mid 0.249642 -0.249642)
							(end 0.2794 -0.1778)
						)
						(arc
							(start 0.2794 0.1778)
							(mid 0.249642 0.249642)
							(end 0.1778 0.2794)
						)
					)
					(width 0)
					(fill yes)
				)
			)
		)
		(pad "2" smd custom
			(at 0 0.4445 90)
			(size 0.1397 0.1397)
			(layers "B.Cu" "B.Mask" "B.Paste")
			(net "SAS_HDD_LED_1")
			(options
				(clearance outline)
				(anchor circle)
			)
			(primitives
				(gr_poly
					(pts
						(arc
							(start -0.1778 0.2794)
							(mid -0.249642 0.249642)
							(end -0.2794 0.1778)
						)
						(arc
							(start -0.2794 -0.1778)
							(mid -0.249642 -0.249642)
							(end -0.1778 -0.2794)
						)
						(arc
							(start 0.1778 -0.2794)
							(mid 0.249642 -0.249642)
							(end 0.2794 -0.1778)
						)
						(arc
							(start 0.2794 0.1778)
							(mid 0.249642 0.249642)
							(end 0.1778 0.2794)
						)
					)
					(width 0)
					(fill yes)
				)
			)
		)
	)
	(footprint ""
		(layer "B.Cu")
		(at 110.75797 -86.868)
		(property "Reference" "STP157"
			(at 0 0 0)
			(layer "B.SilkS")
			(hide yes)
			(effects
				(font
					(size 1.27 1.27)
				)
				(justify mirror)
			)
		)
		(property "Value" "TPAD28"
			(at -0.0127 -1.8034 0)
			(unlocked yes)
			(layer "B.Fab")
			(hide yes)
			(effects
				(font
					(size 1.016 1.016)
					(thickness 0.1524)
				)
				(justify mirror)
			)
		)
		(property "Device Type" "TPAD28"
			(at -0.0127 -3.3274 0)
			(unlocked yes)
			(layer "B.Fab")
			(hide yes)
			(effects
				(font
					(size 1.016 1.016)
					(thickness 0.1524)
				)
				(justify mirror)
			)
		)
		(duplicate_pad_numbers_are_jumpers no)
		(fp_poly
			(pts
				(arc
					(start 0.3556 0)
					(mid -0.3556 0)
					(end 0.3556 0)
				)
			)
			(stroke
				(width 0)
				(type default)
			)
			(fill no)
			(layer "B.CrtYd")
		)
		(fp_poly
			(pts
				(arc
					(start 0.6096 0)
					(mid -0.6096 0)
					(end 0.6096 0)
				)
			)
			(stroke
				(width 0)
				(type default)
			)
			(fill no)
			(layer "B.Fab")
		)
		(pad "1" smd circle
			(at 0 0 180)
			(size 0.7112 0.7112)
			(layers "B.Cu" "B.Mask" "B.Paste")
			(net "EXP_LED_14")
		)
	)
	(footprint ""
		(layer "B.Cu")
		(at 16.76908 -231.822752)
		(property "Reference" "R517"
			(at 0 0 0)
			(layer "B.SilkS")
			(hide yes)
			(effects
				(font
					(size 1.27 1.27)
				)
				(justify mirror)
			)
		)
		(property "Value" "0R2J-2-GP"
			(at -0.064008 -3.993896 0)
			(unlocked yes)
			(layer "B.Fab")
			(hide yes)
			(effects
				(font
					(size 1.016 1.016)
					(thickness 0.1524)
				)
				(justify mirror)
			)
		)
		(property "Device Type" "R402H16"
			(at -0.064008 -5.517896 0)
			(unlocked yes)
			(layer "B.Fab")
			(hide yes)
			(effects
				(font
					(size 1.016 1.016)
					(thickness 0.1524)
				)
				(justify mirror)
			)
		)
		(duplicate_pad_numbers_are_jumpers no)
		(fp_line
			(start -0.508 -0.9398)
			(end 0.508 -0.9398)
			(stroke
				(width 0.1524)
				(type default)
			)
			(layer "B.SilkS")
		)
		(fp_line
			(start 0.508 -0.9398)
			(end 0.508 0.9398)
			(stroke
				(width 0.1524)
				(type default)
			)
			(layer "B.SilkS")
		)
		(fp_rect
			(start 0.508 0.9398)
			(end -0.508 -0.9398)
			(stroke
				(width 0)
				(type default)
			)
			(fill no)
			(layer "B.CrtYd")
		)
		(fp_rect
			(start 0.508 0.9398)
			(end -0.508 -0.9398)
			(stroke
				(width 0)
				(type default)
			)
			(fill no)
			(layer "B.Fab")
		)
		(pad "1" smd custom
			(at 0 -0.4445 180)
			(size 0.1397 0.1397)
			(layers "B.Cu" "B.Mask" "B.Paste")
			(net "SAS_HDD_PWR15_PCIE")
			(options
				(clearance outline)
				(anchor circle)
			)
			(primitives
				(gr_poly
					(pts
						(arc
							(start -0.1778 0.2794)
							(mid -0.249642 0.249642)
							(end -0.2794 0.1778)
						)
						(arc
							(start -0.2794 -0.1778)
							(mid -0.249642 -0.249642)
							(end -0.1778 -0.2794)
						)
						(arc
							(start 0.1778 -0.2794)
							(mid 0.249642 -0.249642)
							(end 0.2794 -0.1778)
						)
						(arc
							(start 0.2794 0.1778)
							(mid 0.249642 0.249642)
							(end 0.1778 0.2794)
						)
					)
					(width 0)
					(fill yes)
				)
			)
		)
		(pad "2" smd custom
			(at 0 0.4445 180)
			(size 0.1397 0.1397)
			(layers "B.Cu" "B.Mask" "B.Paste")
			(net "SAS_HDD_PWR15")
			(options
				(clearance outline)
				(anchor circle)
			)
			(primitives
				(gr_poly
					(pts
						(arc
							(start -0.1778 0.2794)
							(mid -0.249642 0.249642)
							(end -0.2794 0.1778)
						)
						(arc
							(start -0.2794 -0.1778)
							(mid -0.249642 -0.249642)
							(end -0.1778 -0.2794)
						)
						(arc
							(start 0.1778 -0.2794)
							(mid 0.249642 -0.249642)
							(end 0.2794 -0.1778)
						)
						(arc
							(start 0.2794 0.1778)
							(mid 0.249642 0.249642)
							(end 0.1778 0.2794)
						)
					)
					(width 0)
					(fill yes)
				)
			)
		)
	)
	(footprint ""
		(layer "B.Cu")
		(at 103.89616 -36.83 180)
		(property "Reference" "SC943"
			(at 0 0 0)
			(layer "B.SilkS")
			(hide yes)
			(effects
				(font
					(size 1.27 1.27)
				)
				(justify mirror)
			)
		)
		(property "Value" "SCD1U6D3V1KX-GP"
			(at 2.8321 -1.7399 180)
			(unlocked yes)
			(layer "B.Fab")
			(hide yes)
			(effects
				(font
					(size 1.016 1.016)
					(thickness 0.1524)
				)
				(justify mirror)
			)
		)
		(property "Device Type" "C0201H13"
			(at 2.8321 -3.2639 180)
			(unlocked yes)
			(layer "B.Fab")
			(hide yes)
			(effects
				(font
					(size 1.016 1.016)
					(thickness 0.1524)
				)
				(justify mirror)
			)
		)
		(duplicate_pad_numbers_are_jumpers no)
		(fp_rect
			(start 0.2794 0.6477)
			(end -0.2794 -0.6477)
			(stroke
				(width 0)
				(type default)
			)
			(fill no)
			(layer "B.CrtYd")
		)
		(fp_rect
			(start 0.2794 0.6477)
			(end -0.2794 -0.6477)
			(stroke
				(width 0)
				(type default)
			)
			(fill no)
			(layer "B.Fab")
		)
		(pad "1" smd custom
			(at 0 -0.2794)
			(size 0.0762 0.0762)
			(layers "B.Cu" "B.Mask" "B.Paste")
			(net "P1V5_C")
			(options
				(clearance outline)
				(anchor circle)
			)
			(primitives
				(gr_poly
					(pts
						(arc
							(start 0.1524 0.127)
							(mid 0.137521 0.162921)
							(end 0.1016 0.1778)
						)
						(arc
							(start -0.1016 0.1778)
							(mid -0.137521 0.162921)
							(end -0.1524 0.127)
						)
						(arc
							(start -0.1524 -0.127)
							(mid -0.137521 -0.162921)
							(end -0.1016 -0.1778)
						)
						(arc
							(start 0.1016 -0.1778)
							(mid 0.137521 -0.162921)
							(end 0.1524 -0.127)
						)
					)
					(width 0)
					(fill yes)
				)
			)
		)
		(pad "2" smd custom
			(at 0 0.2794)
			(size 0.0762 0.0762)
			(layers "B.Cu" "B.Mask" "B.Paste")
			(net "GND")
			(options
				(clearance outline)
				(anchor circle)
			)
			(primitives
				(gr_poly
					(pts
						(arc
							(start 0.1524 0.127)
							(mid 0.137521 0.162921)
							(end 0.1016 0.1778)
						)
						(arc
							(start -0.1016 0.1778)
							(mid -0.137521 0.162921)
							(end -0.1524 0.127)
						)
						(arc
							(start -0.1524 -0.127)
							(mid -0.137521 -0.162921)
							(end -0.1016 -0.1778)
						)
						(arc
							(start 0.1016 -0.1778)
							(mid 0.137521 -0.162921)
							(end 0.1524 -0.127)
						)
					)
					(width 0)
					(fill yes)
				)
			)
		)
	)
	(footprint ""
		(layer "B.Cu")
		(at 111.44377 -83.1088 -90)
		(property "Reference" "SC1222"
			(at 0 0 90)
			(layer "B.SilkS")
			(hide yes)
			(effects
				(font
					(size 1.27 1.27)
				)
				(justify mirror)
			)
		)
		(property "Value" "SCD1U6D3V1KX-GP"
			(at 2.8321 -1.7399 270)
			(unlocked yes)
			(layer "B.Fab")
			(hide yes)
			(effects
				(font
					(size 1.016 1.016)
					(thickness 0.1524)
				)
				(justify mirror)
			)
		)
		(property "Device Type" "C0201H13"
			(at 2.8321 -3.2639 270)
			(unlocked yes)
			(layer "B.Fab")
			(hide yes)
			(effects
				(font
					(size 1.016 1.016)
					(thickness 0.1524)
				)
				(justify mirror)
			)
		)
		(duplicate_pad_numbers_are_jumpers no)
		(fp_rect
			(start 0.2794 0.6477)
			(end -0.2794 -0.6477)
			(stroke
				(width 0)
				(type default)
			)
			(fill no)
			(layer "B.CrtYd")
		)
		(fp_rect
			(start 0.2794 0.6477)
			(end -0.2794 -0.6477)
			(stroke
				(width 0)
				(type default)
			)
			(fill no)
			(layer "B.Fab")
		)
		(pad "1" smd custom
			(at 0 -0.2794 90)
			(size 0.0762 0.0762)
			(layers "B.Cu" "B.Mask" "B.Paste")
			(net "P1V8_E")
			(options
				(clearance outline)
				(anchor circle)
			)
			(primitives
				(gr_poly
					(pts
						(arc
							(start 0.1524 0.127)
							(mid 0.137521 0.162921)
							(end 0.1016 0.1778)
						)
						(arc
							(start -0.1016 0.1778)
							(mid -0.137521 0.162921)
							(end -0.1524 0.127)
						)
						(arc
							(start -0.1524 -0.127)
							(mid -0.137521 -0.162921)
							(end -0.1016 -0.1778)
						)
						(arc
							(start 0.1016 -0.1778)
							(mid 0.137521 -0.162921)
							(end 0.1524 -0.127)
						)
					)
					(width 0)
					(fill yes)
				)
			)
		)
		(pad "2" smd custom
			(at 0 0.2794 90)
			(size 0.0762 0.0762)
			(layers "B.Cu" "B.Mask" "B.Paste")
			(net "GND")
			(options
				(clearance outline)
				(anchor circle)
			)
			(primitives
				(gr_poly
					(pts
						(arc
							(start 0.1524 0.127)
							(mid 0.137521 0.162921)
							(end 0.1016 0.1778)
						)
						(arc
							(start -0.1016 0.1778)
							(mid -0.137521 0.162921)
							(end -0.1524 0.127)
						)
						(arc
							(start -0.1524 -0.127)
							(mid -0.137521 -0.162921)
							(end -0.1016 -0.1778)
						)
						(arc
							(start 0.1016 -0.1778)
							(mid 0.137521 -0.162921)
							(end 0.1524 -0.127)
						)
					)
					(width 0)
					(fill yes)
				)
			)
		)
	)
	(footprint ""
		(layer "B.Cu")
		(at 127.72517 -85.7758 90)
		(property "Reference" "SC1159"
			(at 0 0 90)
			(layer "B.SilkS")
			(hide yes)
			(effects
				(font
					(size 1.27 1.27)
				)
				(justify mirror)
			)
		)
		(property "Value" "SC22U6D3V5MX-2GP"
			(at 0.0762 -6.1214 90)
			(unlocked yes)
			(layer "B.Fab")
			(hide yes)
			(effects
				(font
					(size 1.016 1.016)
					(thickness 0.1524)
				)
				(justify mirror)
			)
		)
		(property "Device Type" "C805H58"
			(at 0.0762 -8.1534 90)
			(unlocked yes)
			(layer "B.Fab")
			(hide yes)
			(effects
				(font
					(size 1.016 1.016)
					(thickness 0.1524)
				)
				(justify mirror)
			)
		)
		(duplicate_pad_numbers_are_jumpers no)
		(fp_line
			(start -0.635 0)
			(end 0.635 0)
			(stroke
				(width 0.508)
				(type default)
			)
			(layer "B.SilkS")
		)
		(fp_rect
			(start 0.9652 1.778)
			(end -0.9652 -1.778)
			(stroke
				(width 0)
				(type default)
			)
			(fill no)
			(layer "B.CrtYd")
		)
		(fp_poly
			(pts
				(xy 0.9652 -1.778) (xy -0.9652 -1.778) (xy -0.9652 1.778) (xy 0.9652 1.778)
			)
			(stroke
				(width 0)
				(type default)
			)
			(fill no)
			(layer "B.Fab")
		)
		(pad "1" smd rect
			(at 0 -0.9652 270)
			(size 1.397 1.143)
			(layers "B.Cu" "B.Mask" "B.Paste")
			(net "GB_VDDA")
		)
		(pad "2" smd rect
			(at 0 0.9652 270)
			(size 1.397 1.143)
			(layers "B.Cu" "B.Mask" "B.Paste")
			(net "GND")
		)
	)
	(footprint ""
		(layer "B.Cu")
		(at 133.585966 -32.766 -90)
		(property "Reference" "SR657"
			(at 0 0 90)
			(layer "B.SilkS")
			(hide yes)
			(effects
				(font
					(size 1.27 1.27)
				)
				(justify mirror)
			)
		)
		(property "Value" "10KR2F-2-GP"
			(at -0.064008 -3.993896 270)
			(unlocked yes)
			(layer "B.Fab")
			(hide yes)
			(effects
				(font
					(size 1.016 1.016)
					(thickness 0.1524)
				)
				(justify mirror)
			)
		)
		(property "Device Type" "R402H16"
			(at -0.064008 -5.517896 270)
			(unlocked yes)
			(layer "B.Fab")
			(hide yes)
			(effects
				(font
					(size 1.016 1.016)
					(thickness 0.1524)
				)
				(justify mirror)
			)
		)
		(duplicate_pad_numbers_are_jumpers no)
		(fp_line
			(start -0.508 -0.9398)
			(end 0.508 -0.9398)
			(stroke
				(width 0.1524)
				(type default)
			)
			(layer "B.SilkS")
		)
		(fp_line
			(start 0.508 -0.9398)
			(end 0.508 0.9398)
			(stroke
				(width 0.1524)
				(type default)
			)
			(layer "B.SilkS")
		)
		(fp_rect
			(start 0.508 0.9398)
			(end -0.508 -0.9398)
			(stroke
				(width 0)
				(type default)
			)
			(fill no)
			(layer "B.CrtYd")
		)
		(fp_rect
			(start 0.508 0.9398)
			(end -0.508 -0.9398)
			(stroke
				(width 0)
				(type default)
			)
			(fill no)
			(layer "B.Fab")
		)
		(pad "1" smd custom
			(at 0 -0.4445 90)
			(size 0.1397 0.1397)
			(layers "B.Cu" "B.Mask" "B.Paste")
			(net "P3V3_STBY_R")
			(options
				(clearance outline)
				(anchor circle)
			)
			(primitives
				(gr_poly
					(pts
						(arc
							(start -0.1778 0.2794)
							(mid -0.249642 0.249642)
							(end -0.2794 0.1778)
						)
						(arc
							(start -0.2794 -0.1778)
							(mid -0.249642 -0.249642)
							(end -0.1778 -0.2794)
						)
						(arc
							(start 0.1778 -0.2794)
							(mid 0.249642 -0.249642)
							(end 0.2794 -0.1778)
						)
						(arc
							(start 0.2794 0.1778)
							(mid 0.249642 0.249642)
							(end 0.1778 0.2794)
						)
					)
					(width 0)
					(fill yes)
				)
			)
		)
		(pad "2" smd custom
			(at 0 0.4445 90)
			(size 0.1397 0.1397)
			(layers "B.Cu" "B.Mask" "B.Paste")
			(net "P3V3_STBY_B")
			(options
				(clearance outline)
				(anchor circle)
			)
			(primitives
				(gr_poly
					(pts
						(arc
							(start -0.1778 0.2794)
							(mid -0.249642 0.249642)
							(end -0.2794 0.1778)
						)
						(arc
							(start -0.2794 -0.1778)
							(mid -0.249642 -0.249642)
							(end -0.1778 -0.2794)
						)
						(arc
							(start 0.1778 -0.2794)
							(mid 0.249642 -0.249642)
							(end 0.2794 -0.1778)
						)
						(arc
							(start 0.2794 0.1778)
							(mid 0.249642 0.249642)
							(end 0.1778 0.2794)
						)
					)
					(width 0)
					(fill yes)
				)
			)
		)
	)
	(footprint ""
		(layer "B.Cu")
		(at 108.020612 -216.154 -90)
		(property "Reference" "SR901"
			(at 0 0 90)
			(layer "B.SilkS")
			(hide yes)
			(effects
				(font
					(size 1.27 1.27)
				)
				(justify mirror)
			)
		)
		(property "Value" "4K7R2F-GP"
			(at -0.064008 -3.993896 270)
			(unlocked yes)
			(layer "B.Fab")
			(hide yes)
			(effects
				(font
					(size 1.016 1.016)
					(thickness 0.1524)
				)
				(justify mirror)
			)
		)
		(property "Device Type" "R402H16"
			(at -0.064008 -5.517896 270)
			(unlocked yes)
			(layer "B.Fab")
			(hide yes)
			(effects
				(font
					(size 1.016 1.016)
					(thickness 0.1524)
				)
				(justify mirror)
			)
		)
		(duplicate_pad_numbers_are_jumpers no)
		(fp_line
			(start -0.508 -0.9398)
			(end 0.508 -0.9398)
			(stroke
				(width 0.1524)
				(type default)
			)
			(layer "B.SilkS")
		)
		(fp_line
			(start 0.508 -0.9398)
			(end 0.508 0.9398)
			(stroke
				(width 0.1524)
				(type default)
			)
			(layer "B.SilkS")
		)
		(fp_rect
			(start 0.508 0.9398)
			(end -0.508 -0.9398)
			(stroke
				(width 0)
				(type default)
			)
			(fill no)
			(layer "B.CrtYd")
		)
		(fp_rect
			(start 0.508 0.9398)
			(end -0.508 -0.9398)
			(stroke
				(width 0)
				(type default)
			)
			(fill no)
			(layer "B.Fab")
		)
		(pad "1" smd custom
			(at 0 -0.4445 90)
			(size 0.1397 0.1397)
			(layers "B.Cu" "B.Mask" "B.Paste")
			(net "REDV_I2C_A1")
			(options
				(clearance outline)
				(anchor circle)
			)
			(primitives
				(gr_poly
					(pts
						(arc
							(start -0.1778 0.2794)
							(mid -0.249642 0.249642)
							(end -0.2794 0.1778)
						)
						(arc
							(start -0.2794 -0.1778)
							(mid -0.249642 -0.249642)
							(end -0.1778 -0.2794)
						)
						(arc
							(start 0.1778 -0.2794)
							(mid 0.249642 -0.249642)
							(end 0.2794 -0.1778)
						)
						(arc
							(start 0.2794 0.1778)
							(mid 0.249642 0.249642)
							(end 0.1778 0.2794)
						)
					)
					(width 0)
					(fill yes)
				)
			)
		)
		(pad "2" smd custom
			(at 0 0.4445 90)
			(size 0.1397 0.1397)
			(layers "B.Cu" "B.Mask" "B.Paste")
			(net "GND")
			(options
				(clearance outline)
				(anchor circle)
			)
			(primitives
				(gr_poly
					(pts
						(arc
							(start -0.1778 0.2794)
							(mid -0.249642 0.249642)
							(end -0.2794 0.1778)
						)
						(arc
							(start -0.2794 -0.1778)
							(mid -0.249642 -0.249642)
							(end -0.1778 -0.2794)
						)
						(arc
							(start 0.1778 -0.2794)
							(mid 0.249642 -0.249642)
							(end 0.2794 -0.1778)
						)
						(arc
							(start 0.2794 0.1778)
							(mid 0.249642 0.249642)
							(end 0.1778 0.2794)
						)
					)
					(width 0)
					(fill yes)
				)
			)
		)
	)
	(footprint ""
		(layer "B.Cu")
		(at 86.087966 -48.006 90)
		(property "Reference" "SR627"
			(at 0 0 90)
			(layer "B.SilkS")
			(hide yes)
			(effects
				(font
					(size 1.27 1.27)
				)
				(justify mirror)
			)
		)
		(property "Value" "2K2R2F-GP"
			(at -0.064008 -3.993896 90)
			(unlocked yes)
			(layer "B.Fab")
			(hide yes)
			(effects
				(font
					(size 1.016 1.016)
					(thickness 0.1524)
				)
				(justify mirror)
			)
		)
		(property "Device Type" "R402H16"
			(at -0.064008 -5.517896 90)
			(unlocked yes)
			(layer "B.Fab")
			(hide yes)
			(effects
				(font
					(size 1.016 1.016)
					(thickness 0.1524)
				)
				(justify mirror)
			)
		)
		(duplicate_pad_numbers_are_jumpers no)
		(fp_line
			(start 0.508 -0.9398)
			(end 0.508 0.9398)
			(stroke
				(width 0.1524)
				(type default)
			)
			(layer "B.SilkS")
		)
		(fp_line
			(start -0.508 -0.9398)
			(end 0.508 -0.9398)
			(stroke
				(width 0.1524)
				(type default)
			)
			(layer "B.SilkS")
		)
		(fp_rect
			(start 0.508 0.9398)
			(end -0.508 -0.9398)
			(stroke
				(width 0)
				(type default)
			)
			(fill no)
			(layer "B.CrtYd")
		)
		(fp_rect
			(start 0.508 0.9398)
			(end -0.508 -0.9398)
			(stroke
				(width 0)
				(type default)
			)
			(fill no)
			(layer "B.Fab")
		)
		(pad "1" smd custom
			(at 0 -0.4445 270)
			(size 0.1397 0.1397)
			(layers "B.Cu" "B.Mask" "B.Paste")
			(net "P1V8_C")
			(options
				(clearance outline)
				(anchor circle)
			)
			(primitives
				(gr_poly
					(pts
						(arc
							(start -0.1778 0.2794)
							(mid -0.249642 0.249642)
							(end -0.2794 0.1778)
						)
						(arc
							(start -0.2794 -0.1778)
							(mid -0.249642 -0.249642)
							(end -0.1778 -0.2794)
						)
						(arc
							(start 0.1778 -0.2794)
							(mid 0.249642 -0.249642)
							(end 0.2794 -0.1778)
						)
						(arc
							(start 0.2794 0.1778)
							(mid 0.249642 0.249642)
							(end 0.1778 0.2794)
						)
					)
					(width 0)
					(fill yes)
				)
			)
		)
		(pad "2" smd custom
			(at 0 0.4445 270)
			(size 0.1397 0.1397)
			(layers "B.Cu" "B.Mask" "B.Paste")
			(net "SIO_DIN_0")
			(options
				(clearance outline)
				(anchor circle)
			)
			(primitives
				(gr_poly
					(pts
						(arc
							(start -0.1778 0.2794)
							(mid -0.249642 0.249642)
							(end -0.2794 0.1778)
						)
						(arc
							(start -0.2794 -0.1778)
							(mid -0.249642 -0.249642)
							(end -0.1778 -0.2794)
						)
						(arc
							(start 0.1778 -0.2794)
							(mid 0.249642 -0.249642)
							(end 0.2794 -0.1778)
						)
						(arc
							(start 0.2794 0.1778)
							(mid 0.249642 0.249642)
							(end 0.1778 0.2794)
						)
					)
					(width 0)
					(fill yes)
				)
			)
		)
	)
	(footprint ""
		(layer "B.Cu")
		(at 108.085128 -57.946798)
		(property "Reference" "STP159"
			(at 0 0 0)
			(layer "B.SilkS")
			(hide yes)
			(effects
				(font
					(size 1.27 1.27)
				)
				(justify mirror)
			)
		)
		(property "Value" "TPAD28"
			(at -0.0127 -1.8034 0)
			(unlocked yes)
			(layer "B.Fab")
			(hide yes)
			(effects
				(font
					(size 1.016 1.016)
					(thickness 0.1524)
				)
				(justify mirror)
			)
		)
		(property "Device Type" "TPAD28"
			(at -0.0127 -3.3274 0)
			(unlocked yes)
			(layer "B.Fab")
			(hide yes)
			(effects
				(font
					(size 1.016 1.016)
					(thickness 0.1524)
				)
				(justify mirror)
			)
		)
		(duplicate_pad_numbers_are_jumpers no)
		(fp_poly
			(pts
				(arc
					(start 0.3556 0)
					(mid -0.3556 0)
					(end 0.3556 0)
				)
			)
			(stroke
				(width 0)
				(type default)
			)
			(fill no)
			(layer "B.CrtYd")
		)
		(fp_poly
			(pts
				(arc
					(start 0.6096 0)
					(mid -0.6096 0)
					(end 0.6096 0)
				)
			)
			(stroke
				(width 0)
				(type default)
			)
			(fill no)
			(layer "B.Fab")
		)
		(pad "1" smd circle
			(at 0 0 180)
			(size 0.7112 0.7112)
			(layers "B.Cu" "B.Mask" "B.Paste")
			(net "XM_RB")
		)
	)
	(footprint ""
		(layer "B.Cu")
		(at 98.94316 -33.401 180)
		(property "Reference" "SC952"
			(at 0 0 0)
			(layer "B.SilkS")
			(hide yes)
			(effects
				(font
					(size 1.27 1.27)
				)
				(justify mirror)
			)
		)
		(property "Value" "SCD1U6D3V1KX-GP"
			(at 2.8321 -1.7399 180)
			(unlocked yes)
			(layer "B.Fab")
			(hide yes)
			(effects
				(font
					(size 1.016 1.016)
					(thickness 0.1524)
				)
				(justify mirror)
			)
		)
		(property "Device Type" "C0201H13"
			(at 2.8321 -3.2639 180)
			(unlocked yes)
			(layer "B.Fab")
			(hide yes)
			(effects
				(font
					(size 1.016 1.016)
					(thickness 0.1524)
				)
				(justify mirror)
			)
		)
		(duplicate_pad_numbers_are_jumpers no)
		(fp_rect
			(start 0.2794 0.6477)
			(end -0.2794 -0.6477)
			(stroke
				(width 0)
				(type default)
			)
			(fill no)
			(layer "B.CrtYd")
		)
		(fp_rect
			(start 0.2794 0.6477)
			(end -0.2794 -0.6477)
			(stroke
				(width 0)
				(type default)
			)
			(fill no)
			(layer "B.Fab")
		)
		(pad "1" smd custom
			(at 0 -0.2794)
			(size 0.0762 0.0762)
			(layers "B.Cu" "B.Mask" "B.Paste")
			(net "PCE_AVDD")
			(options
				(clearance outline)
				(anchor circle)
			)
			(primitives
				(gr_poly
					(pts
						(arc
							(start 0.1524 0.127)
							(mid 0.137521 0.162921)
							(end 0.1016 0.1778)
						)
						(arc
							(start -0.1016 0.1778)
							(mid -0.137521 0.162921)
							(end -0.1524 0.127)
						)
						(arc
							(start -0.1524 -0.127)
							(mid -0.137521 -0.162921)
							(end -0.1016 -0.1778)
						)
						(arc
							(start 0.1016 -0.1778)
							(mid 0.137521 -0.162921)
							(end 0.1524 -0.127)
						)
					)
					(width 0)
					(fill yes)
				)
			)
		)
		(pad "2" smd custom
			(at 0 0.2794)
			(size 0.0762 0.0762)
			(layers "B.Cu" "B.Mask" "B.Paste")
			(net "GND")
			(options
				(clearance outline)
				(anchor circle)
			)
			(primitives
				(gr_poly
					(pts
						(arc
							(start 0.1524 0.127)
							(mid 0.137521 0.162921)
							(end 0.1016 0.1778)
						)
						(arc
							(start -0.1016 0.1778)
							(mid -0.137521 0.162921)
							(end -0.1524 0.127)
						)
						(arc
							(start -0.1524 -0.127)
							(mid -0.137521 -0.162921)
							(end -0.1016 -0.1778)
						)
						(arc
							(start 0.1016 -0.1778)
							(mid 0.137521 -0.162921)
							(end 0.1524 -0.127)
						)
					)
					(width 0)
					(fill yes)
				)
			)
		)
	)
	(footprint ""
		(layer "B.Cu")
		(at 91.56954 -45.69714 90)
		(property "Reference" "SR650"
			(at 0 0 90)
			(layer "B.SilkS")
			(hide yes)
			(effects
				(font
					(size 1.27 1.27)
				)
				(justify mirror)
			)
		)
		(property "Value" "3KR2J-2-GP"
			(at -0.064008 -3.993896 90)
			(unlocked yes)
			(layer "B.Fab")
			(hide yes)
			(effects
				(font
					(size 1.016 1.016)
					(thickness 0.1524)
				)
				(justify mirror)
			)
		)
		(property "Device Type" "R402H16"
			(at -0.064008 -5.517896 90)
			(unlocked yes)
			(layer "B.Fab")
			(hide yes)
			(effects
				(font
					(size 1.016 1.016)
					(thickness 0.1524)
				)
				(justify mirror)
			)
		)
		(duplicate_pad_numbers_are_jumpers no)
		(fp_line
			(start 0.508 -0.9398)
			(end 0.508 0.9398)
			(stroke
				(width 0.1524)
				(type default)
			)
			(layer "B.SilkS")
		)
		(fp_line
			(start -0.508 -0.9398)
			(end 0.508 -0.9398)
			(stroke
				(width 0.1524)
				(type default)
			)
			(layer "B.SilkS")
		)
		(fp_rect
			(start 0.508 0.9398)
			(end -0.508 -0.9398)
			(stroke
				(width 0)
				(type default)
			)
			(fill no)
			(layer "B.CrtYd")
		)
		(fp_rect
			(start 0.508 0.9398)
			(end -0.508 -0.9398)
			(stroke
				(width 0)
				(type default)
			)
			(fill no)
			(layer "B.Fab")
		)
		(pad "1" smd custom
			(at 0 -0.4445 270)
			(size 0.1397 0.1397)
			(layers "B.Cu" "B.Mask" "B.Paste")
			(net "RTRIM")
			(options
				(clearance outline)
				(anchor circle)
			)
			(primitives
				(gr_poly
					(pts
						(arc
							(start -0.1778 0.2794)
							(mid -0.249642 0.249642)
							(end -0.2794 0.1778)
						)
						(arc
							(start -0.2794 -0.1778)
							(mid -0.249642 -0.249642)
							(end -0.1778 -0.2794)
						)
						(arc
							(start 0.1778 -0.2794)
							(mid 0.249642 -0.249642)
							(end 0.2794 -0.1778)
						)
						(arc
							(start 0.2794 0.1778)
							(mid 0.249642 0.249642)
							(end 0.1778 0.2794)
						)
					)
					(width 0)
					(fill yes)
				)
			)
		)
		(pad "2" smd custom
			(at 0 0.4445 270)
			(size 0.1397 0.1397)
			(layers "B.Cu" "B.Mask" "B.Paste")
			(net "RTRIM#")
			(options
				(clearance outline)
				(anchor circle)
			)
			(primitives
				(gr_poly
					(pts
						(arc
							(start -0.1778 0.2794)
							(mid -0.249642 0.249642)
							(end -0.2794 0.1778)
						)
						(arc
							(start -0.2794 -0.1778)
							(mid -0.249642 -0.249642)
							(end -0.1778 -0.2794)
						)
						(arc
							(start 0.1778 -0.2794)
							(mid 0.249642 -0.249642)
							(end 0.2794 -0.1778)
						)
						(arc
							(start 0.2794 0.1778)
							(mid 0.249642 0.249642)
							(end 0.1778 0.2794)
						)
					)
					(width 0)
					(fill yes)
				)
			)
		)
	)
	(footprint ""
		(layer "B.Cu")
		(at 88.646 -3.429)
		(property "Reference" "SC1039"
			(at 0 0 0)
			(layer "B.SilkS")
			(hide yes)
			(effects
				(font
					(size 1.27 1.27)
				)
				(justify mirror)
			)
		)
		(property "Value" "SCD1U16V2KX-3GP"
			(at -1.1811 -2.7051 0)
			(unlocked yes)
			(layer "B.Fab")
			(hide yes)
			(effects
				(font
					(size 1.016 1.016)
					(thickness 0.1524)
				)
				(justify mirror)
			)
		)
		(property "Device Type" "C402H22"
			(at -1.1811 -4.2291 0)
			(unlocked yes)
			(layer "B.Fab")
			(hide yes)
			(effects
				(font
					(size 1.016 1.016)
					(thickness 0.1524)
				)
				(justify mirror)
			)
		)
		(duplicate_pad_numbers_are_jumpers no)
		(fp_rect
			(start 0.4318 0.9525)
			(end -0.4318 -0.9525)
			(stroke
				(width 0)
				(type default)
			)
			(fill no)
			(layer "B.CrtYd")
		)
		(fp_rect
			(start 0.4318 0.9525)
			(end -0.4318 -0.9525)
			(stroke
				(width 0)
				(type default)
			)
			(fill no)
			(layer "B.Fab")
		)
		(pad "1" smd custom
			(at 0 -0.4445 180)
			(size 0.1524 0.1524)
			(layers "B.Cu" "B.Mask" "B.Paste")
			(net "P0V955_C")
			(options
				(clearance outline)
				(anchor circle)
			)
			(primitives
				(gr_poly
					(pts
						(arc
							(start 0.3048 0.2032)
							(mid 0.275042 0.275042)
							(end 0.2032 0.3048)
						)
						(arc
							(start -0.2032 0.3048)
							(mid -0.275042 0.275042)
							(end -0.3048 0.2032)
						)
						(arc
							(start -0.3048 -0.2032)
							(mid -0.275042 -0.275042)
							(end -0.2032 -0.3048)
						)
						(arc
							(start 0.2032 -0.3048)
							(mid 0.275042 -0.275042)
							(end 0.3048 -0.2032)
						)
					)
					(width 0)
					(fill yes)
				)
			)
		)
		(pad "2" smd custom
			(at 0 0.4445 180)
			(size 0.1524 0.1524)
			(layers "B.Cu" "B.Mask" "B.Paste")
			(net "GND")
			(options
				(clearance outline)
				(anchor circle)
			)
			(primitives
				(gr_poly
					(pts
						(arc
							(start 0.3048 0.2032)
							(mid 0.275042 0.275042)
							(end 0.2032 0.3048)
						)
						(arc
							(start -0.2032 0.3048)
							(mid -0.275042 0.275042)
							(end -0.3048 0.2032)
						)
						(arc
							(start -0.3048 -0.2032)
							(mid -0.275042 -0.275042)
							(end -0.2032 -0.3048)
						)
						(arc
							(start 0.2032 -0.3048)
							(mid 0.275042 -0.275042)
							(end 0.3048 -0.2032)
						)
					)
					(width 0)
					(fill yes)
				)
			)
		)
	)
	(footprint ""
		(layer "B.Cu")
		(at 318.008 -166.878 -90)
		(property "Reference" "R242"
			(at 0 0 90)
			(layer "B.SilkS")
			(hide yes)
			(effects
				(font
					(size 1.27 1.27)
				)
				(justify mirror)
			)
		)
		(property "Value" "0R2J-2-GP"
			(at -0.064008 -3.993896 270)
			(unlocked yes)
			(layer "B.Fab")
			(hide yes)
			(effects
				(font
					(size 1.016 1.016)
					(thickness 0.1524)
				)
				(justify mirror)
			)
		)
		(property "Device Type" "R402H16"
			(at -0.064008 -5.517896 270)
			(unlocked yes)
			(layer "B.Fab")
			(hide yes)
			(effects
				(font
					(size 1.016 1.016)
					(thickness 0.1524)
				)
				(justify mirror)
			)
		)
		(duplicate_pad_numbers_are_jumpers no)
		(fp_line
			(start -0.508 -0.9398)
			(end 0.508 -0.9398)
			(stroke
				(width 0.1524)
				(type default)
			)
			(layer "B.SilkS")
		)
		(fp_line
			(start 0.508 -0.9398)
			(end 0.508 0.9398)
			(stroke
				(width 0.1524)
				(type default)
			)
			(layer "B.SilkS")
		)
		(fp_rect
			(start 0.508 0.9398)
			(end -0.508 -0.9398)
			(stroke
				(width 0)
				(type default)
			)
			(fill no)
			(layer "B.CrtYd")
		)
		(fp_rect
			(start 0.508 0.9398)
			(end -0.508 -0.9398)
			(stroke
				(width 0)
				(type default)
			)
			(fill no)
			(layer "B.Fab")
		)
		(pad "1" smd custom
			(at 0 -0.4445 90)
			(size 0.1397 0.1397)
			(layers "B.Cu" "B.Mask" "B.Paste")
			(net "BMC_I2C_D_SCL")
			(options
				(clearance outline)
				(anchor circle)
			)
			(primitives
				(gr_poly
					(pts
						(arc
							(start -0.1778 0.2794)
							(mid -0.249642 0.249642)
							(end -0.2794 0.1778)
						)
						(arc
							(start -0.2794 -0.1778)
							(mid -0.249642 -0.249642)
							(end -0.1778 -0.2794)
						)
						(arc
							(start 0.1778 -0.2794)
							(mid 0.249642 -0.249642)
							(end 0.2794 -0.1778)
						)
						(arc
							(start 0.2794 0.1778)
							(mid 0.249642 0.249642)
							(end 0.1778 0.2794)
						)
					)
					(width 0)
					(fill yes)
				)
			)
		)
		(pad "2" smd custom
			(at 0 0.4445 90)
			(size 0.1397 0.1397)
			(layers "B.Cu" "B.Mask" "B.Paste")
			(net "BMC0_SMB3_CLK")
			(options
				(clearance outline)
				(anchor circle)
			)
			(primitives
				(gr_poly
					(pts
						(arc
							(start -0.1778 0.2794)
							(mid -0.249642 0.249642)
							(end -0.2794 0.1778)
						)
						(arc
							(start -0.2794 -0.1778)
							(mid -0.249642 -0.249642)
							(end -0.1778 -0.2794)
						)
						(arc
							(start 0.1778 -0.2794)
							(mid 0.249642 -0.249642)
							(end 0.2794 -0.1778)
						)
						(arc
							(start 0.2794 0.1778)
							(mid 0.249642 0.249642)
							(end 0.1778 0.2794)
						)
					)
					(width 0)
					(fill yes)
				)
			)
		)
	)
	(footprint ""
		(layer "B.Cu")
		(at 79.871062 -62.700408)
		(property "Reference" "SR711"
			(at 0 0 0)
			(layer "B.SilkS")
			(hide yes)
			(effects
				(font
					(size 1.27 1.27)
				)
				(justify mirror)
			)
		)
		(property "Value" "10R2F-L-GP"
			(at -0.064008 -3.993896 0)
			(unlocked yes)
			(layer "B.Fab")
			(hide yes)
			(effects
				(font
					(size 1.016 1.016)
					(thickness 0.1524)
				)
				(justify mirror)
			)
		)
		(property "Device Type" "R402H14"
			(at -0.064008 -5.517896 0)
			(unlocked yes)
			(layer "B.Fab")
			(hide yes)
			(effects
				(font
					(size 1.016 1.016)
					(thickness 0.1524)
				)
				(justify mirror)
			)
		)
		(duplicate_pad_numbers_are_jumpers no)
		(fp_line
			(start -0.508 -0.9398)
			(end 0.508 -0.9398)
			(stroke
				(width 0.1524)
				(type default)
			)
			(layer "B.SilkS")
		)
		(fp_line
			(start 0.508 -0.9398)
			(end 0.508 0.9398)
			(stroke
				(width 0.1524)
				(type default)
			)
			(layer "B.SilkS")
		)
		(fp_rect
			(start 0.508 0.9398)
			(end -0.508 -0.9398)
			(stroke
				(width 0)
				(type default)
			)
			(fill no)
			(layer "B.CrtYd")
		)
		(fp_rect
			(start 0.508 0.9398)
			(end -0.508 -0.9398)
			(stroke
				(width 0)
				(type default)
			)
			(fill no)
			(layer "B.Fab")
		)
		(pad "1" smd custom
			(at 0 -0.4445 180)
			(size 0.1397 0.1397)
			(layers "B.Cu" "B.Mask" "B.Paste")
			(net "P1V8_C")
			(options
				(clearance outline)
				(anchor circle)
			)
			(primitives
				(gr_poly
					(pts
						(arc
							(start -0.1778 0.2794)
							(mid -0.249642 0.249642)
							(end -0.2794 0.1778)
						)
						(arc
							(start -0.2794 -0.1778)
							(mid -0.249642 -0.249642)
							(end -0.1778 -0.2794)
						)
						(arc
							(start 0.1778 -0.2794)
							(mid 0.249642 -0.249642)
							(end 0.2794 -0.1778)
						)
						(arc
							(start 0.2794 0.1778)
							(mid 0.249642 0.249642)
							(end 0.1778 0.2794)
						)
					)
					(width 0)
					(fill yes)
				)
			)
		)
		(pad "2" smd custom
			(at 0 0.4445 180)
			(size 0.1397 0.1397)
			(layers "B.Cu" "B.Mask" "B.Paste")
			(net "VDDA_SAS_REF_CLK")
			(options
				(clearance outline)
				(anchor circle)
			)
			(primitives
				(gr_poly
					(pts
						(arc
							(start -0.1778 0.2794)
							(mid -0.249642 0.249642)
							(end -0.2794 0.1778)
						)
						(arc
							(start -0.2794 -0.1778)
							(mid -0.249642 -0.249642)
							(end -0.1778 -0.2794)
						)
						(arc
							(start 0.1778 -0.2794)
							(mid 0.249642 -0.249642)
							(end 0.2794 -0.1778)
						)
						(arc
							(start 0.2794 0.1778)
							(mid 0.249642 0.249642)
							(end 0.1778 0.2794)
						)
					)
					(width 0)
					(fill yes)
				)
			)
		)
	)
	(footprint ""
		(layer "B.Cu")
		(at 110.776766 -46.6852 -90)
		(property "Reference" "SC993"
			(at 0 0 90)
			(layer "B.SilkS")
			(hide yes)
			(effects
				(font
					(size 1.27 1.27)
				)
				(justify mirror)
			)
		)
		(property "Value" "SCD1U16V2KX-3GP"
			(at -1.1811 -2.7051 270)
			(unlocked yes)
			(layer "B.Fab")
			(hide yes)
			(effects
				(font
					(size 1.016 1.016)
					(thickness 0.1524)
				)
				(justify mirror)
			)
		)
		(property "Device Type" "C402H22"
			(at -1.1811 -4.2291 270)
			(unlocked yes)
			(layer "B.Fab")
			(hide yes)
			(effects
				(font
					(size 1.016 1.016)
					(thickness 0.1524)
				)
				(justify mirror)
			)
		)
		(duplicate_pad_numbers_are_jumpers no)
		(fp_rect
			(start 0.4318 0.9525)
			(end -0.4318 -0.9525)
			(stroke
				(width 0)
				(type default)
			)
			(fill no)
			(layer "B.CrtYd")
		)
		(fp_rect
			(start 0.4318 0.9525)
			(end -0.4318 -0.9525)
			(stroke
				(width 0)
				(type default)
			)
			(fill no)
			(layer "B.Fab")
		)
		(pad "1" smd custom
			(at 0 -0.4445 90)
			(size 0.1524 0.1524)
			(layers "B.Cu" "B.Mask" "B.Paste")
			(net "P1V8_C")
			(options
				(clearance outline)
				(anchor circle)
			)
			(primitives
				(gr_poly
					(pts
						(arc
							(start 0.3048 0.2032)
							(mid 0.275042 0.275042)
							(end 0.2032 0.3048)
						)
						(arc
							(start -0.2032 0.3048)
							(mid -0.275042 0.275042)
							(end -0.3048 0.2032)
						)
						(arc
							(start -0.3048 -0.2032)
							(mid -0.275042 -0.275042)
							(end -0.2032 -0.3048)
						)
						(arc
							(start 0.2032 -0.3048)
							(mid 0.275042 -0.275042)
							(end 0.3048 -0.2032)
						)
					)
					(width 0)
					(fill yes)
				)
			)
		)
		(pad "2" smd custom
			(at 0 0.4445 90)
			(size 0.1524 0.1524)
			(layers "B.Cu" "B.Mask" "B.Paste")
			(net "GND")
			(options
				(clearance outline)
				(anchor circle)
			)
			(primitives
				(gr_poly
					(pts
						(arc
							(start 0.3048 0.2032)
							(mid 0.275042 0.275042)
							(end 0.2032 0.3048)
						)
						(arc
							(start -0.2032 0.3048)
							(mid -0.275042 0.275042)
							(end -0.3048 0.2032)
						)
						(arc
							(start -0.3048 -0.2032)
							(mid -0.275042 -0.275042)
							(end -0.2032 -0.3048)
						)
						(arc
							(start 0.2032 -0.3048)
							(mid 0.275042 -0.275042)
							(end 0.3048 -0.2032)
						)
					)
					(width 0)
					(fill yes)
				)
			)
		)
	)
	(footprint ""
		(layer "B.Cu")
		(at 103.359966 -44.958 90)
		(property "Reference" "SC1024"
			(at 0 0 90)
			(layer "B.SilkS")
			(hide yes)
			(effects
				(font
					(size 1.27 1.27)
				)
				(justify mirror)
			)
		)
		(property "Value" "SC1U10V2KX-4-GP"
			(at -1.1811 -2.7051 90)
			(unlocked yes)
			(layer "B.Fab")
			(hide yes)
			(effects
				(font
					(size 1.016 1.016)
					(thickness 0.1524)
				)
				(justify mirror)
			)
		)
		(property "Device Type" "C402H22"
			(at -1.1811 -4.2291 90)
			(unlocked yes)
			(layer "B.Fab")
			(hide yes)
			(effects
				(font
					(size 1.016 1.016)
					(thickness 0.1524)
				)
				(justify mirror)
			)
		)
		(duplicate_pad_numbers_are_jumpers no)
		(fp_rect
			(start 0.4318 0.9525)
			(end -0.4318 -0.9525)
			(stroke
				(width 0)
				(type default)
			)
			(fill no)
			(layer "B.CrtYd")
		)
		(fp_rect
			(start 0.4318 0.9525)
			(end -0.4318 -0.9525)
			(stroke
				(width 0)
				(type default)
			)
			(fill no)
			(layer "B.Fab")
		)
		(pad "1" smd custom
			(at 0 -0.4445 270)
			(size 0.1524 0.1524)
			(layers "B.Cu" "B.Mask" "B.Paste")
			(net "P0V955_C")
			(options
				(clearance outline)
				(anchor circle)
			)
			(primitives
				(gr_poly
					(pts
						(arc
							(start 0.3048 0.2032)
							(mid 0.275042 0.275042)
							(end 0.2032 0.3048)
						)
						(arc
							(start -0.2032 0.3048)
							(mid -0.275042 0.275042)
							(end -0.3048 0.2032)
						)
						(arc
							(start -0.3048 -0.2032)
							(mid -0.275042 -0.275042)
							(end -0.2032 -0.3048)
						)
						(arc
							(start 0.2032 -0.3048)
							(mid 0.275042 -0.275042)
							(end 0.3048 -0.2032)
						)
					)
					(width 0)
					(fill yes)
				)
			)
		)
		(pad "2" smd custom
			(at 0 0.4445 270)
			(size 0.1524 0.1524)
			(layers "B.Cu" "B.Mask" "B.Paste")
			(net "GND")
			(options
				(clearance outline)
				(anchor circle)
			)
			(primitives
				(gr_poly
					(pts
						(arc
							(start 0.3048 0.2032)
							(mid 0.275042 0.275042)
							(end 0.2032 0.3048)
						)
						(arc
							(start -0.2032 0.3048)
							(mid -0.275042 0.275042)
							(end -0.3048 0.2032)
						)
						(arc
							(start -0.3048 -0.2032)
							(mid -0.275042 -0.275042)
							(end -0.2032 -0.3048)
						)
						(arc
							(start 0.2032 -0.3048)
							(mid 0.275042 -0.275042)
							(end 0.3048 -0.2032)
						)
					)
					(width 0)
					(fill yes)
				)
			)
		)
	)
	(footprint ""
		(layer "B.Cu")
		(at 123.298966 -43.815 90)
		(property "Reference" "SC975"
			(at 0 0 90)
			(layer "B.SilkS")
			(hide yes)
			(effects
				(font
					(size 1.27 1.27)
				)
				(justify mirror)
			)
		)
		(property "Value" "SCD1U16V2KX-3GP"
			(at -1.1811 -2.7051 90)
			(unlocked yes)
			(layer "B.Fab")
			(hide yes)
			(effects
				(font
					(size 1.016 1.016)
					(thickness 0.1524)
				)
				(justify mirror)
			)
		)
		(property "Device Type" "C402H22"
			(at -1.1811 -4.2291 90)
			(unlocked yes)
			(layer "B.Fab")
			(hide yes)
			(effects
				(font
					(size 1.016 1.016)
					(thickness 0.1524)
				)
				(justify mirror)
			)
		)
		(duplicate_pad_numbers_are_jumpers no)
		(fp_rect
			(start 0.4318 0.9525)
			(end -0.4318 -0.9525)
			(stroke
				(width 0)
				(type default)
			)
			(fill no)
			(layer "B.CrtYd")
		)
		(fp_rect
			(start 0.4318 0.9525)
			(end -0.4318 -0.9525)
			(stroke
				(width 0)
				(type default)
			)
			(fill no)
			(layer "B.Fab")
		)
		(pad "1" smd custom
			(at 0 -0.4445 270)
			(size 0.1524 0.1524)
			(layers "B.Cu" "B.Mask" "B.Paste")
			(net "P1V8_C")
			(options
				(clearance outline)
				(anchor circle)
			)
			(primitives
				(gr_poly
					(pts
						(arc
							(start 0.3048 0.2032)
							(mid 0.275042 0.275042)
							(end 0.2032 0.3048)
						)
						(arc
							(start -0.2032 0.3048)
							(mid -0.275042 0.275042)
							(end -0.3048 0.2032)
						)
						(arc
							(start -0.3048 -0.2032)
							(mid -0.275042 -0.275042)
							(end -0.2032 -0.3048)
						)
						(arc
							(start 0.2032 -0.3048)
							(mid 0.275042 -0.275042)
							(end 0.3048 -0.2032)
						)
					)
					(width 0)
					(fill yes)
				)
			)
		)
		(pad "2" smd custom
			(at 0 0.4445 270)
			(size 0.1524 0.1524)
			(layers "B.Cu" "B.Mask" "B.Paste")
			(net "GND")
			(options
				(clearance outline)
				(anchor circle)
			)
			(primitives
				(gr_poly
					(pts
						(arc
							(start 0.3048 0.2032)
							(mid 0.275042 0.275042)
							(end 0.2032 0.3048)
						)
						(arc
							(start -0.2032 0.3048)
							(mid -0.275042 0.275042)
							(end -0.3048 0.2032)
						)
						(arc
							(start -0.3048 -0.2032)
							(mid -0.275042 -0.275042)
							(end -0.2032 -0.3048)
						)
						(arc
							(start 0.2032 -0.3048)
							(mid 0.275042 -0.275042)
							(end 0.3048 -0.2032)
						)
					)
					(width 0)
					(fill yes)
				)
			)
		)
	)
	(footprint ""
		(layer "B.Cu")
		(at 82.804 -18.161 180)
		(property "Reference" "PC216"
			(at 0 0 0)
			(layer "B.SilkS")
			(hide yes)
			(effects
				(font
					(size 1.27 1.27)
				)
				(justify mirror)
			)
		)
		(property "Value" "SC22U25V5MX-GP"
			(at 0.0762 -6.1214 180)
			(unlocked yes)
			(layer "B.Fab")
			(hide yes)
			(effects
				(font
					(size 1.016 1.016)
					(thickness 0.1524)
				)
				(justify mirror)
			)
		)
		(property "Device Type" "C805H58"
			(at 0.0762 -8.1534 180)
			(unlocked yes)
			(layer "B.Fab")
			(hide yes)
			(effects
				(font
					(size 1.016 1.016)
					(thickness 0.1524)
				)
				(justify mirror)
			)
		)
		(duplicate_pad_numbers_are_jumpers no)
		(fp_line
			(start -0.635 0)
			(end 0.635 0)
			(stroke
				(width 0.508)
				(type default)
			)
			(layer "B.SilkS")
		)
		(fp_rect
			(start 0.9652 1.778)
			(end -0.9652 -1.778)
			(stroke
				(width 0)
				(type default)
			)
			(fill no)
			(layer "B.CrtYd")
		)
		(fp_poly
			(pts
				(xy 0.9652 -1.778) (xy -0.9652 -1.778) (xy -0.9652 1.778) (xy 0.9652 1.778)
			)
			(stroke
				(width 0)
				(type default)
			)
			(fill no)
			(layer "B.Fab")
		)
		(pad "1" smd rect
			(at 0 -0.9652)
			(size 1.397 1.143)
			(layers "B.Cu" "B.Mask" "B.Paste")
			(net "VT235_VDDL")
		)
		(pad "2" smd rect
			(at 0 0.9652)
			(size 1.397 1.143)
			(layers "B.Cu" "B.Mask" "B.Paste")
			(net "AGND_P0V9_C")
		)
	)
	(footprint ""
		(layer "B.Cu")
		(at 14.48308 -231.822752)
		(property "Reference" "R515"
			(at 0 0 0)
			(layer "B.SilkS")
			(hide yes)
			(effects
				(font
					(size 1.27 1.27)
				)
				(justify mirror)
			)
		)
		(property "Value" "0R2J-2-GP"
			(at -0.064008 -3.993896 0)
			(unlocked yes)
			(layer "B.Fab")
			(hide yes)
			(effects
				(font
					(size 1.016 1.016)
					(thickness 0.1524)
				)
				(justify mirror)
			)
		)
		(property "Device Type" "R402H16"
			(at -0.064008 -5.517896 0)
			(unlocked yes)
			(layer "B.Fab")
			(hide yes)
			(effects
				(font
					(size 1.016 1.016)
					(thickness 0.1524)
				)
				(justify mirror)
			)
		)
		(duplicate_pad_numbers_are_jumpers no)
		(fp_line
			(start -0.508 -0.9398)
			(end 0.508 -0.9398)
			(stroke
				(width 0.1524)
				(type default)
			)
			(layer "B.SilkS")
		)
		(fp_line
			(start 0.508 -0.9398)
			(end 0.508 0.9398)
			(stroke
				(width 0.1524)
				(type default)
			)
			(layer "B.SilkS")
		)
		(fp_rect
			(start 0.508 0.9398)
			(end -0.508 -0.9398)
			(stroke
				(width 0)
				(type default)
			)
			(fill no)
			(layer "B.CrtYd")
		)
		(fp_rect
			(start 0.508 0.9398)
			(end -0.508 -0.9398)
			(stroke
				(width 0)
				(type default)
			)
			(fill no)
			(layer "B.Fab")
		)
		(pad "1" smd custom
			(at 0 -0.4445 180)
			(size 0.1397 0.1397)
			(layers "B.Cu" "B.Mask" "B.Paste")
			(net "SAS_HDD_PWR13_PCIE")
			(options
				(clearance outline)
				(anchor circle)
			)
			(primitives
				(gr_poly
					(pts
						(arc
							(start -0.1778 0.2794)
							(mid -0.249642 0.249642)
							(end -0.2794 0.1778)
						)
						(arc
							(start -0.2794 -0.1778)
							(mid -0.249642 -0.249642)
							(end -0.1778 -0.2794)
						)
						(arc
							(start 0.1778 -0.2794)
							(mid 0.249642 -0.249642)
							(end 0.2794 -0.1778)
						)
						(arc
							(start 0.2794 0.1778)
							(mid 0.249642 0.249642)
							(end 0.1778 0.2794)
						)
					)
					(width 0)
					(fill yes)
				)
			)
		)
		(pad "2" smd custom
			(at 0 0.4445 180)
			(size 0.1397 0.1397)
			(layers "B.Cu" "B.Mask" "B.Paste")
			(net "SAS_HDD_PWR13")
			(options
				(clearance outline)
				(anchor circle)
			)
			(primitives
				(gr_poly
					(pts
						(arc
							(start -0.1778 0.2794)
							(mid -0.249642 0.249642)
							(end -0.2794 0.1778)
						)
						(arc
							(start -0.2794 -0.1778)
							(mid -0.249642 -0.249642)
							(end -0.1778 -0.2794)
						)
						(arc
							(start 0.1778 -0.2794)
							(mid 0.249642 -0.249642)
							(end 0.2794 -0.1778)
						)
						(arc
							(start 0.2794 0.1778)
							(mid 0.249642 0.249642)
							(end 0.1778 0.2794)
						)
					)
					(width 0)
					(fill yes)
				)
			)
		)
	)
	(footprint ""
		(layer "B.Cu")
		(at 298.0944 -178.943)
		(property "Reference" "TP89"
			(at 0 0 0)
			(layer "B.SilkS")
			(hide yes)
			(effects
				(font
					(size 1.27 1.27)
				)
				(justify mirror)
			)
		)
		(property "Value" "TPAD28"
			(at -0.0127 -1.8034 0)
			(unlocked yes)
			(layer "B.Fab")
			(hide yes)
			(effects
				(font
					(size 1.016 1.016)
					(thickness 0.1524)
				)
				(justify mirror)
			)
		)
		(property "Device Type" "TPAD28"
			(at -0.0127 -3.3274 0)
			(unlocked yes)
			(layer "B.Fab")
			(hide yes)
			(effects
				(font
					(size 1.016 1.016)
					(thickness 0.1524)
				)
				(justify mirror)
			)
		)
		(duplicate_pad_numbers_are_jumpers no)
		(fp_poly
			(pts
				(arc
					(start 0.3556 0)
					(mid -0.3556 0)
					(end 0.3556 0)
				)
			)
			(stroke
				(width 0)
				(type default)
			)
			(fill no)
			(layer "B.CrtYd")
		)
		(fp_poly
			(pts
				(arc
					(start 0.6096 0)
					(mid -0.6096 0)
					(end 0.6096 0)
				)
			)
			(stroke
				(width 0)
				(type default)
			)
			(fill no)
			(layer "B.Fab")
		)
		(pad "1" smd circle
			(at 0 0 180)
			(size 0.7112 0.7112)
			(layers "B.Cu" "B.Mask" "B.Paste")
			(net "TP_BMC_GPIOL1")
		)
	)
	(footprint ""
		(layer "B.Cu")
		(at 99.189286 -37.69868 -90)
		(property "Reference" "SC941"
			(at 0 0 90)
			(layer "B.SilkS")
			(hide yes)
			(effects
				(font
					(size 1.27 1.27)
				)
				(justify mirror)
			)
		)
		(property "Value" "SC1U6D3V1MX-GP"
			(at -1.9177 2.0193 270)
			(unlocked yes)
			(layer "B.Fab")
			(hide yes)
			(effects
				(font
					(size 1.016 1.016)
					(thickness 0.1524)
				)
				(justify mirror)
			)
		)
		(property "Device Type" "C0201H14"
			(at -1.9177 0.4953 270)
			(unlocked yes)
			(layer "B.Fab")
			(hide yes)
			(effects
				(font
					(size 1.016 1.016)
					(thickness 0.1524)
				)
				(justify mirror)
			)
		)
		(duplicate_pad_numbers_are_jumpers no)
		(fp_rect
			(start 0.1524 0.3048)
			(end -0.1524 -0.3048)
			(stroke
				(width 0)
				(type default)
			)
			(fill no)
			(layer "B.CrtYd")
		)
		(fp_poly
			(pts
				(xy 0.2794 0.6477) (xy 0.2794 -0.6477) (xy -0.2794 -0.6477) (xy -0.2794 -0.1905) (xy -0.1524 -0.1905)
				(xy -0.1524 -0.3048) (xy 0.1524 -0.3048) (xy 0.1524 0.3048) (xy -0.1524 0.3048) (xy -0.1524 -0.1778)
				(xy -0.2794 -0.1778) (xy -0.2794 0.6477)
			)
			(stroke
				(width 0)
				(type default)
			)
			(fill no)
			(layer "B.CrtYd")
		)
		(fp_rect
			(start 0.2794 0.6477)
			(end -0.2794 -0.6477)
			(stroke
				(width 0)
				(type default)
			)
			(fill no)
			(layer "B.Fab")
		)
		(pad "1" smd custom
			(at 0 -0.2794 90)
			(size 0.0762 0.0762)
			(layers "B.Cu" "B.Mask" "B.Paste")
			(net "P1V5_C")
			(options
				(clearance outline)
				(anchor circle)
			)
			(primitives
				(gr_poly
					(pts
						(arc
							(start 0.1524 0.127)
							(mid 0.137521 0.162921)
							(end 0.1016 0.1778)
						)
						(arc
							(start -0.1016 0.1778)
							(mid -0.137521 0.162921)
							(end -0.1524 0.127)
						)
						(arc
							(start -0.1524 -0.127)
							(mid -0.137521 -0.162921)
							(end -0.1016 -0.1778)
						)
						(arc
							(start 0.1016 -0.1778)
							(mid 0.137521 -0.162921)
							(end 0.1524 -0.127)
						)
					)
					(width 0)
					(fill yes)
				)
			)
		)
		(pad "2" smd custom
			(at 0 0.2794 90)
			(size 0.0762 0.0762)
			(layers "B.Cu" "B.Mask" "B.Paste")
			(net "GND")
			(options
				(clearance outline)
				(anchor circle)
			)
			(primitives
				(gr_poly
					(pts
						(arc
							(start 0.1524 0.127)
							(mid 0.137521 0.162921)
							(end 0.1016 0.1778)
						)
						(arc
							(start -0.1016 0.1778)
							(mid -0.137521 0.162921)
							(end -0.1524 0.127)
						)
						(arc
							(start -0.1524 -0.127)
							(mid -0.137521 -0.162921)
							(end -0.1016 -0.1778)
						)
						(arc
							(start 0.1016 -0.1778)
							(mid 0.137521 -0.162921)
							(end 0.1524 -0.127)
						)
					)
					(width 0)
					(fill yes)
				)
			)
		)
	)
	(footprint ""
		(layer "B.Cu")
		(at 124.403612 -214.376 90)
		(property "Reference" "SR904"
			(at 0 0 90)
			(layer "B.SilkS")
			(hide yes)
			(effects
				(font
					(size 1.27 1.27)
				)
				(justify mirror)
			)
		)
		(property "Value" "4K7R2F-GP"
			(at -0.064008 -3.993896 90)
			(unlocked yes)
			(layer "B.Fab")
			(hide yes)
			(effects
				(font
					(size 1.016 1.016)
					(thickness 0.1524)
				)
				(justify mirror)
			)
		)
		(property "Device Type" "R402H16"
			(at -0.064008 -5.517896 90)
			(unlocked yes)
			(layer "B.Fab")
			(hide yes)
			(effects
				(font
					(size 1.016 1.016)
					(thickness 0.1524)
				)
				(justify mirror)
			)
		)
		(duplicate_pad_numbers_are_jumpers no)
		(fp_line
			(start 0.508 -0.9398)
			(end 0.508 0.9398)
			(stroke
				(width 0.1524)
				(type default)
			)
			(layer "B.SilkS")
		)
		(fp_line
			(start -0.508 -0.9398)
			(end 0.508 -0.9398)
			(stroke
				(width 0.1524)
				(type default)
			)
			(layer "B.SilkS")
		)
		(fp_rect
			(start 0.508 0.9398)
			(end -0.508 -0.9398)
			(stroke
				(width 0)
				(type default)
			)
			(fill no)
			(layer "B.CrtYd")
		)
		(fp_rect
			(start 0.508 0.9398)
			(end -0.508 -0.9398)
			(stroke
				(width 0)
				(type default)
			)
			(fill no)
			(layer "B.Fab")
		)
		(pad "1" smd custom
			(at 0 -0.4445 270)
			(size 0.1397 0.1397)
			(layers "B.Cu" "B.Mask" "B.Paste")
			(net "REDV_D1_A")
			(options
				(clearance outline)
				(anchor circle)
			)
			(primitives
				(gr_poly
					(pts
						(arc
							(start -0.1778 0.2794)
							(mid -0.249642 0.249642)
							(end -0.2794 0.1778)
						)
						(arc
							(start -0.2794 -0.1778)
							(mid -0.249642 -0.249642)
							(end -0.1778 -0.2794)
						)
						(arc
							(start 0.1778 -0.2794)
							(mid 0.249642 -0.249642)
							(end 0.2794 -0.1778)
						)
						(arc
							(start 0.2794 0.1778)
							(mid 0.249642 0.249642)
							(end 0.1778 0.2794)
						)
					)
					(width 0)
					(fill yes)
				)
			)
		)
		(pad "2" smd custom
			(at 0 0.4445 270)
			(size 0.1397 0.1397)
			(layers "B.Cu" "B.Mask" "B.Paste")
			(net "GND")
			(options
				(clearance outline)
				(anchor circle)
			)
			(primitives
				(gr_poly
					(pts
						(arc
							(start -0.1778 0.2794)
							(mid -0.249642 0.249642)
							(end -0.2794 0.1778)
						)
						(arc
							(start -0.2794 -0.1778)
							(mid -0.249642 -0.249642)
							(end -0.1778 -0.2794)
						)
						(arc
							(start 0.1778 -0.2794)
							(mid 0.249642 -0.249642)
							(end 0.2794 -0.1778)
						)
						(arc
							(start 0.2794 0.1778)
							(mid 0.249642 0.249642)
							(end 0.1778 0.2794)
						)
					)
					(width 0)
					(fill yes)
				)
			)
		)
	)
	(footprint ""
		(layer "B.Cu")
		(at 341.507318 -135.385048 -90)
		(property "Reference" "R556"
			(at 0 0 90)
			(layer "B.SilkS")
			(hide yes)
			(effects
				(font
					(size 1.27 1.27)
				)
				(justify mirror)
			)
		)
		(property "Value" "0R3J-0-U-GP"
			(at 0.0254 -2.5146 270)
			(unlocked yes)
			(layer "B.Fab")
			(hide yes)
			(effects
				(font
					(size 1.016 1.016)
					(thickness 0.1524)
				)
				(justify mirror)
			)
		)
		(property "Device Type" "R603H22"
			(at 0.0254 -4.0386 270)
			(unlocked yes)
			(layer "B.Fab")
			(hide yes)
			(effects
				(font
					(size 1.016 1.016)
					(thickness 0.1524)
				)
				(justify mirror)
			)
		)
		(duplicate_pad_numbers_are_jumpers no)
		(fp_line
			(start -0.2032 0)
			(end -0.4826 0)
			(stroke
				(width 0.2032)
				(type default)
			)
			(layer "B.SilkS")
		)
		(fp_line
			(start 0.4826 0)
			(end 0.2032 0)
			(stroke
				(width 0.2032)
				(type default)
			)
			(layer "B.SilkS")
		)
		(fp_rect
			(start 0.5842 1.3335)
			(end -0.5842 -1.3335)
			(stroke
				(width 0)
				(type default)
			)
			(fill no)
			(layer "B.CrtYd")
		)
		(fp_rect
			(start 0.5842 1.3335)
			(end -0.5842 -1.3335)
			(stroke
				(width 0)
				(type default)
			)
			(fill no)
			(layer "B.Fab")
		)
		(pad "1" smd custom
			(at 0 -0.762 90)
			(size 0.2159 0.2159)
			(layers "B.Cu" "B.Mask" "B.Paste")
			(net "USB_P1_DN")
			(options
				(clearance outline)
				(anchor circle)
			)
			(primitives
				(gr_poly
					(pts
						(arc
							(start -0.3302 0.4318)
							(mid -0.402042 0.402042)
							(end -0.4318 0.3302)
						)
						(arc
							(start -0.4318 -0.3302)
							(mid -0.402042 -0.402042)
							(end -0.3302 -0.4318)
						)
						(arc
							(start 0.3302 -0.4318)
							(mid 0.402042 -0.402042)
							(end 0.4318 -0.3302)
						)
						(arc
							(start 0.4318 0.3302)
							(mid 0.402042 0.402042)
							(end 0.3302 0.4318)
						)
					)
					(width 0)
					(fill yes)
				)
			)
		)
		(pad "2" smd custom
			(at 0 0.762 90)
			(size 0.2159 0.2159)
			(layers "B.Cu" "B.Mask" "B.Paste")
			(net "USB_DN_R")
			(options
				(clearance outline)
				(anchor circle)
			)
			(primitives
				(gr_poly
					(pts
						(arc
							(start -0.3302 0.4318)
							(mid -0.402042 0.402042)
							(end -0.4318 0.3302)
						)
						(arc
							(start -0.4318 -0.3302)
							(mid -0.402042 -0.402042)
							(end -0.3302 -0.4318)
						)
						(arc
							(start 0.3302 -0.4318)
							(mid 0.402042 -0.402042)
							(end 0.4318 -0.3302)
						)
						(arc
							(start 0.4318 0.3302)
							(mid 0.402042 0.402042)
							(end 0.3302 0.4318)
						)
					)
					(width 0)
					(fill yes)
				)
			)
		)
	)
	(footprint ""
		(layer "B.Cu")
		(at 46.81093 -77.650086)
		(property "Reference" "TP188"
			(at 0 0 0)
			(layer "B.SilkS")
			(hide yes)
			(effects
				(font
					(size 1.27 1.27)
				)
				(justify mirror)
			)
		)
		(property "Value" "TPAD32-GP"
			(at 0 -3.166364 0)
			(unlocked yes)
			(layer "B.Fab")
			(hide yes)
			(effects
				(font
					(size 1.016 1.016)
					(thickness 0.1524)
				)
				(justify mirror)
			)
		)
		(property "Device Type" "TPAD32"
			(at 0 -4.690618 0)
			(unlocked yes)
			(layer "B.Fab")
			(hide yes)
			(effects
				(font
					(size 1.016 1.016)
					(thickness 0.1524)
				)
				(justify mirror)
			)
		)
		(duplicate_pad_numbers_are_jumpers no)
		(fp_poly
			(pts
				(arc
					(start 0.4064 0)
					(mid -0.4064 0)
					(end 0.4064 0)
				)
			)
			(stroke
				(width 0)
				(type default)
			)
			(fill no)
			(layer "B.CrtYd")
		)
		(fp_poly
			(pts
				(arc
					(start 0.7112 0)
					(mid -0.7112 0)
					(end 0.7112 0)
				)
			)
			(stroke
				(width 0)
				(type default)
			)
			(fill no)
			(layer "B.Fab")
		)
		(pad "1" smd circle
			(at 0 0 180)
			(size 0.8128 0.8128)
			(layers "B.Cu" "B.Mask" "B.Paste")
			(net "INT_CONN_A_SB7")
		)
	)
	(footprint ""
		(layer "B.Cu")
		(at 114.94897 -89.6366)
		(property "Reference" "STP69"
			(at 0 0 0)
			(layer "B.SilkS")
			(hide yes)
			(effects
				(font
					(size 1.27 1.27)
				)
				(justify mirror)
			)
		)
		(property "Value" "TPAD28"
			(at -0.0127 -1.8034 0)
			(unlocked yes)
			(layer "B.Fab")
			(hide yes)
			(effects
				(font
					(size 1.016 1.016)
					(thickness 0.1524)
				)
				(justify mirror)
			)
		)
		(property "Device Type" "TPAD28"
			(at -0.0127 -3.3274 0)
			(unlocked yes)
			(layer "B.Fab")
			(hide yes)
			(effects
				(font
					(size 1.016 1.016)
					(thickness 0.1524)
				)
				(justify mirror)
			)
		)
		(duplicate_pad_numbers_are_jumpers no)
		(fp_poly
			(pts
				(arc
					(start 0.3556 0)
					(mid -0.3556 0)
					(end 0.3556 0)
				)
			)
			(stroke
				(width 0)
				(type default)
			)
			(fill no)
			(layer "B.CrtYd")
		)
		(fp_poly
			(pts
				(arc
					(start 0.6096 0)
					(mid -0.6096 0)
					(end 0.6096 0)
				)
			)
			(stroke
				(width 0)
				(type default)
			)
			(fill no)
			(layer "B.Fab")
		)
		(pad "1" smd circle
			(at 0 0 180)
			(size 0.7112 0.7112)
			(layers "B.Cu" "B.Mask" "B.Paste")
			(net "EXP_TEST_MUX31")
		)
	)
	(footprint ""
		(layer "B.Cu")
		(at 143.9926 -49.7586)
		(property "Reference" "STP120"
			(at 0 0 0)
			(layer "B.SilkS")
			(hide yes)
			(effects
				(font
					(size 1.27 1.27)
				)
				(justify mirror)
			)
		)
		(property "Value" "TPAD28"
			(at -0.0127 -1.8034 0)
			(unlocked yes)
			(layer "B.Fab")
			(hide yes)
			(effects
				(font
					(size 1.016 1.016)
					(thickness 0.1524)
				)
				(justify mirror)
			)
		)
		(property "Device Type" "TPAD28"
			(at -0.0127 -3.3274 0)
			(unlocked yes)
			(layer "B.Fab")
			(hide yes)
			(effects
				(font
					(size 1.016 1.016)
					(thickness 0.1524)
				)
				(justify mirror)
			)
		)
		(duplicate_pad_numbers_are_jumpers no)
		(fp_poly
			(pts
				(arc
					(start 0.3556 0)
					(mid -0.3556 0)
					(end 0.3556 0)
				)
			)
			(stroke
				(width 0)
				(type default)
			)
			(fill no)
			(layer "B.CrtYd")
		)
		(fp_poly
			(pts
				(arc
					(start 0.6096 0)
					(mid -0.6096 0)
					(end 0.6096 0)
				)
			)
			(stroke
				(width 0)
				(type default)
			)
			(fill no)
			(layer "B.Fab")
		)
		(pad "1" smd circle
			(at 0 0 180)
			(size 0.7112 0.7112)
			(layers "B.Cu" "B.Mask" "B.Paste")
			(net "XM_ADDR_20")
		)
	)
	(footprint ""
		(layer "B.Cu")
		(at 318.008 -165.354 -90)
		(property "Reference" "R243"
			(at 0 0 90)
			(layer "B.SilkS")
			(hide yes)
			(effects
				(font
					(size 1.27 1.27)
				)
				(justify mirror)
			)
		)
		(property "Value" "0R2J-2-GP"
			(at -0.064008 -3.993896 270)
			(unlocked yes)
			(layer "B.Fab")
			(hide yes)
			(effects
				(font
					(size 1.016 1.016)
					(thickness 0.1524)
				)
				(justify mirror)
			)
		)
		(property "Device Type" "R402H16"
			(at -0.064008 -5.517896 270)
			(unlocked yes)
			(layer "B.Fab")
			(hide yes)
			(effects
				(font
					(size 1.016 1.016)
					(thickness 0.1524)
				)
				(justify mirror)
			)
		)
		(duplicate_pad_numbers_are_jumpers no)
		(fp_line
			(start -0.508 -0.9398)
			(end 0.508 -0.9398)
			(stroke
				(width 0.1524)
				(type default)
			)
			(layer "B.SilkS")
		)
		(fp_line
			(start 0.508 -0.9398)
			(end 0.508 0.9398)
			(stroke
				(width 0.1524)
				(type default)
			)
			(layer "B.SilkS")
		)
		(fp_rect
			(start 0.508 0.9398)
			(end -0.508 -0.9398)
			(stroke
				(width 0)
				(type default)
			)
			(fill no)
			(layer "B.CrtYd")
		)
		(fp_rect
			(start 0.508 0.9398)
			(end -0.508 -0.9398)
			(stroke
				(width 0)
				(type default)
			)
			(fill no)
			(layer "B.Fab")
		)
		(pad "1" smd custom
			(at 0 -0.4445 90)
			(size 0.1397 0.1397)
			(layers "B.Cu" "B.Mask" "B.Paste")
			(net "BMC_I2C_D_SDA")
			(options
				(clearance outline)
				(anchor circle)
			)
			(primitives
				(gr_poly
					(pts
						(arc
							(start -0.1778 0.2794)
							(mid -0.249642 0.249642)
							(end -0.2794 0.1778)
						)
						(arc
							(start -0.2794 -0.1778)
							(mid -0.249642 -0.249642)
							(end -0.1778 -0.2794)
						)
						(arc
							(start 0.1778 -0.2794)
							(mid 0.249642 -0.249642)
							(end 0.2794 -0.1778)
						)
						(arc
							(start 0.2794 0.1778)
							(mid 0.249642 0.249642)
							(end 0.1778 0.2794)
						)
					)
					(width 0)
					(fill yes)
				)
			)
		)
		(pad "2" smd custom
			(at 0 0.4445 90)
			(size 0.1397 0.1397)
			(layers "B.Cu" "B.Mask" "B.Paste")
			(net "BMC0_SMB3_DAT")
			(options
				(clearance outline)
				(anchor circle)
			)
			(primitives
				(gr_poly
					(pts
						(arc
							(start -0.1778 0.2794)
							(mid -0.249642 0.249642)
							(end -0.2794 0.1778)
						)
						(arc
							(start -0.2794 -0.1778)
							(mid -0.249642 -0.249642)
							(end -0.1778 -0.2794)
						)
						(arc
							(start 0.1778 -0.2794)
							(mid 0.249642 -0.249642)
							(end 0.2794 -0.1778)
						)
						(arc
							(start 0.2794 0.1778)
							(mid 0.249642 0.249642)
							(end 0.1778 0.2794)
						)
					)
					(width 0)
					(fill yes)
				)
			)
		)
	)
	(footprint ""
		(layer "B.Cu")
		(at 110.50016 -32.512)
		(property "Reference" "STP92"
			(at 0 0 0)
			(layer "B.SilkS")
			(hide yes)
			(effects
				(font
					(size 1.27 1.27)
				)
				(justify mirror)
			)
		)
		(property "Value" "TPAD28"
			(at -0.0127 -1.8034 0)
			(unlocked yes)
			(layer "B.Fab")
			(hide yes)
			(effects
				(font
					(size 1.016 1.016)
					(thickness 0.1524)
				)
				(justify mirror)
			)
		)
		(property "Device Type" "TPAD28"
			(at -0.0127 -3.3274 0)
			(unlocked yes)
			(layer "B.Fab")
			(hide yes)
			(effects
				(font
					(size 1.016 1.016)
					(thickness 0.1524)
				)
				(justify mirror)
			)
		)
		(duplicate_pad_numbers_are_jumpers no)
		(fp_poly
			(pts
				(arc
					(start 0.3556 0)
					(mid -0.3556 0)
					(end 0.3556 0)
				)
			)
			(stroke
				(width 0)
				(type default)
			)
			(fill no)
			(layer "B.CrtYd")
		)
		(fp_poly
			(pts
				(arc
					(start 0.6096 0)
					(mid -0.6096 0)
					(end 0.6096 0)
				)
			)
			(stroke
				(width 0)
				(type default)
			)
			(fill no)
			(layer "B.Fab")
		)
		(pad "1" smd circle
			(at 0 0 180)
			(size 0.7112 0.7112)
			(layers "B.Cu" "B.Mask" "B.Paste")
			(net "IOC_GPIO_14")
		)
	)
	(footprint ""
		(layer "B.Cu")
		(at 318.008 -172.593 -90)
		(property "Reference" "R467"
			(at 0 0 90)
			(layer "B.SilkS")
			(hide yes)
			(effects
				(font
					(size 1.27 1.27)
				)
				(justify mirror)
			)
		)
		(property "Value" "0R2J-2-GP"
			(at -0.064008 -3.993896 270)
			(unlocked yes)
			(layer "B.Fab")
			(hide yes)
			(effects
				(font
					(size 1.016 1.016)
					(thickness 0.1524)
				)
				(justify mirror)
			)
		)
		(property "Device Type" "R402H16"
			(at -0.064008 -5.517896 270)
			(unlocked yes)
			(layer "B.Fab")
			(hide yes)
			(effects
				(font
					(size 1.016 1.016)
					(thickness 0.1524)
				)
				(justify mirror)
			)
		)
		(duplicate_pad_numbers_are_jumpers no)
		(fp_line
			(start -0.508 -0.9398)
			(end 0.508 -0.9398)
			(stroke
				(width 0.1524)
				(type default)
			)
			(layer "B.SilkS")
		)
		(fp_line
			(start 0.508 -0.9398)
			(end 0.508 0.9398)
			(stroke
				(width 0.1524)
				(type default)
			)
			(layer "B.SilkS")
		)
		(fp_rect
			(start 0.508 0.9398)
			(end -0.508 -0.9398)
			(stroke
				(width 0)
				(type default)
			)
			(fill no)
			(layer "B.CrtYd")
		)
		(fp_rect
			(start 0.508 0.9398)
			(end -0.508 -0.9398)
			(stroke
				(width 0)
				(type default)
			)
			(fill no)
			(layer "B.Fab")
		)
		(pad "1" smd custom
			(at 0 -0.4445 90)
			(size 0.1397 0.1397)
			(layers "B.Cu" "B.Mask" "B.Paste")
			(net "BMC_I2C_F_SDA")
			(options
				(clearance outline)
				(anchor circle)
			)
			(primitives
				(gr_poly
					(pts
						(arc
							(start -0.1778 0.2794)
							(mid -0.249642 0.249642)
							(end -0.2794 0.1778)
						)
						(arc
							(start -0.2794 -0.1778)
							(mid -0.249642 -0.249642)
							(end -0.1778 -0.2794)
						)
						(arc
							(start 0.1778 -0.2794)
							(mid 0.249642 -0.249642)
							(end 0.2794 -0.1778)
						)
						(arc
							(start 0.2794 0.1778)
							(mid 0.249642 0.249642)
							(end 0.1778 0.2794)
						)
					)
					(width 0)
					(fill yes)
				)
			)
		)
		(pad "2" smd custom
			(at 0 0.4445 90)
			(size 0.1397 0.1397)
			(layers "B.Cu" "B.Mask" "B.Paste")
			(net "BMC0_SMB8_DAT")
			(options
				(clearance outline)
				(anchor circle)
			)
			(primitives
				(gr_poly
					(pts
						(arc
							(start -0.1778 0.2794)
							(mid -0.249642 0.249642)
							(end -0.2794 0.1778)
						)
						(arc
							(start -0.2794 -0.1778)
							(mid -0.249642 -0.249642)
							(end -0.1778 -0.2794)
						)
						(arc
							(start 0.1778 -0.2794)
							(mid 0.249642 -0.249642)
							(end 0.2794 -0.1778)
						)
						(arc
							(start 0.2794 0.1778)
							(mid 0.249642 0.249642)
							(end 0.1778 0.2794)
						)
					)
					(width 0)
					(fill yes)
				)
			)
		)
	)
	(footprint ""
		(layer "B.Cu")
		(at 116.420646 -34.991548)
		(property "Reference" "STP136"
			(at 0 0 0)
			(layer "B.SilkS")
			(hide yes)
			(effects
				(font
					(size 1.27 1.27)
				)
				(justify mirror)
			)
		)
		(property "Value" "TPAD28"
			(at -0.0127 -1.8034 0)
			(unlocked yes)
			(layer "B.Fab")
			(hide yes)
			(effects
				(font
					(size 1.016 1.016)
					(thickness 0.1524)
				)
				(justify mirror)
			)
		)
		(property "Device Type" "TPAD28"
			(at -0.0127 -3.3274 0)
			(unlocked yes)
			(layer "B.Fab")
			(hide yes)
			(effects
				(font
					(size 1.016 1.016)
					(thickness 0.1524)
				)
				(justify mirror)
			)
		)
		(duplicate_pad_numbers_are_jumpers no)
		(fp_poly
			(pts
				(arc
					(start 0.3556 0)
					(mid -0.3556 0)
					(end 0.3556 0)
				)
			)
			(stroke
				(width 0)
				(type default)
			)
			(fill no)
			(layer "B.CrtYd")
		)
		(fp_poly
			(pts
				(arc
					(start 0.6096 0)
					(mid -0.6096 0)
					(end 0.6096 0)
				)
			)
			(stroke
				(width 0)
				(type default)
			)
			(fill no)
			(layer "B.Fab")
		)
		(pad "1" smd circle
			(at 0 0 180)
			(size 0.7112 0.7112)
			(layers "B.Cu" "B.Mask" "B.Paste")
			(net "IOC_GPIO_16")
		)
	)
	(footprint ""
		(layer "B.Cu")
		(at 301.58182 -181.79288)
		(property "Reference" "TP160"
			(at 0 0 0)
			(layer "B.SilkS")
			(hide yes)
			(effects
				(font
					(size 1.27 1.27)
				)
				(justify mirror)
			)
		)
		(property "Value" "TPAD28"
			(at -0.0127 -1.8034 0)
			(unlocked yes)
			(layer "B.Fab")
			(hide yes)
			(effects
				(font
					(size 1.016 1.016)
					(thickness 0.1524)
				)
				(justify mirror)
			)
		)
		(property "Device Type" "TPAD28"
			(at -0.0127 -3.3274 0)
			(unlocked yes)
			(layer "B.Fab")
			(hide yes)
			(effects
				(font
					(size 1.016 1.016)
					(thickness 0.1524)
				)
				(justify mirror)
			)
		)
		(duplicate_pad_numbers_are_jumpers no)
		(fp_poly
			(pts
				(arc
					(start 0.3556 0)
					(mid -0.3556 0)
					(end 0.3556 0)
				)
			)
			(stroke
				(width 0)
				(type default)
			)
			(fill no)
			(layer "B.CrtYd")
		)
		(fp_poly
			(pts
				(arc
					(start 0.6096 0)
					(mid -0.6096 0)
					(end 0.6096 0)
				)
			)
			(stroke
				(width 0)
				(type default)
			)
			(fill no)
			(layer "B.Fab")
		)
		(pad "1" smd circle
			(at 0 0 180)
			(size 0.7112 0.7112)
			(layers "B.Cu" "B.Mask" "B.Paste")
			(net "TP_BMC_GPIOJ5")
		)
	)
	(footprint ""
		(layer "B.Cu")
		(at 88.14816 -49.022)
		(property "Reference" "STP16"
			(at 0 0 0)
			(layer "B.SilkS")
			(hide yes)
			(effects
				(font
					(size 1.27 1.27)
				)
				(justify mirror)
			)
		)
		(property "Value" "TPAD28"
			(at -0.0127 -1.8034 0)
			(unlocked yes)
			(layer "B.Fab")
			(hide yes)
			(effects
				(font
					(size 1.016 1.016)
					(thickness 0.1524)
				)
				(justify mirror)
			)
		)
		(property "Device Type" "TPAD28"
			(at -0.0127 -3.3274 0)
			(unlocked yes)
			(layer "B.Fab")
			(hide yes)
			(effects
				(font
					(size 1.016 1.016)
					(thickness 0.1524)
				)
				(justify mirror)
			)
		)
		(duplicate_pad_numbers_are_jumpers no)
		(fp_poly
			(pts
				(arc
					(start 0.3556 0)
					(mid -0.3556 0)
					(end 0.3556 0)
				)
			)
			(stroke
				(width 0)
				(type default)
			)
			(fill no)
			(layer "B.CrtYd")
		)
		(fp_poly
			(pts
				(arc
					(start 0.6096 0)
					(mid -0.6096 0)
					(end 0.6096 0)
				)
			)
			(stroke
				(width 0)
				(type default)
			)
			(fill no)
			(layer "B.Fab")
		)
		(pad "1" smd circle
			(at 0 0 180)
			(size 0.7112 0.7112)
			(layers "B.Cu" "B.Mask" "B.Paste")
			(net "SIO_DOUT_1")
		)
	)
	(footprint ""
		(layer "B.Cu")
		(at 310.896 -186.817 90)
		(property "Reference" "R302"
			(at 0 0 90)
			(layer "B.SilkS")
			(hide yes)
			(effects
				(font
					(size 1.27 1.27)
				)
				(justify mirror)
			)
		)
		(property "Value" "0R2J-2-GP"
			(at -0.064008 -3.993896 90)
			(unlocked yes)
			(layer "B.Fab")
			(hide yes)
			(effects
				(font
					(size 1.016 1.016)
					(thickness 0.1524)
				)
				(justify mirror)
			)
		)
		(property "Device Type" "R402H16"
			(at -0.064008 -5.517896 90)
			(unlocked yes)
			(layer "B.Fab")
			(hide yes)
			(effects
				(font
					(size 1.016 1.016)
					(thickness 0.1524)
				)
				(justify mirror)
			)
		)
		(duplicate_pad_numbers_are_jumpers no)
		(fp_line
			(start 0.508 -0.9398)
			(end 0.508 0.9398)
			(stroke
				(width 0.1524)
				(type default)
			)
			(layer "B.SilkS")
		)
		(fp_line
			(start -0.508 -0.9398)
			(end 0.508 -0.9398)
			(stroke
				(width 0.1524)
				(type default)
			)
			(layer "B.SilkS")
		)
		(fp_rect
			(start 0.508 0.9398)
			(end -0.508 -0.9398)
			(stroke
				(width 0)
				(type default)
			)
			(fill no)
			(layer "B.CrtYd")
		)
		(fp_rect
			(start 0.508 0.9398)
			(end -0.508 -0.9398)
			(stroke
				(width 0)
				(type default)
			)
			(fill no)
			(layer "B.Fab")
		)
		(pad "1" smd custom
			(at 0 -0.4445 270)
			(size 0.1397 0.1397)
			(layers "B.Cu" "B.Mask" "B.Paste")
			(net "HB0_R_IN0")
			(options
				(clearance outline)
				(anchor circle)
			)
			(primitives
				(gr_poly
					(pts
						(arc
							(start -0.1778 0.2794)
							(mid -0.249642 0.249642)
							(end -0.2794 0.1778)
						)
						(arc
							(start -0.2794 -0.1778)
							(mid -0.249642 -0.249642)
							(end -0.1778 -0.2794)
						)
						(arc
							(start 0.1778 -0.2794)
							(mid 0.249642 -0.249642)
							(end 0.2794 -0.1778)
						)
						(arc
							(start 0.2794 0.1778)
							(mid 0.249642 0.249642)
							(end 0.1778 0.2794)
						)
					)
					(width 0)
					(fill yes)
				)
			)
		)
		(pad "2" smd custom
			(at 0 0.4445 270)
			(size 0.1397 0.1397)
			(layers "B.Cu" "B.Mask" "B.Paste")
			(net "PEER_1B_2B_HB")
			(options
				(clearance outline)
				(anchor circle)
			)
			(primitives
				(gr_poly
					(pts
						(arc
							(start -0.1778 0.2794)
							(mid -0.249642 0.249642)
							(end -0.2794 0.1778)
						)
						(arc
							(start -0.2794 -0.1778)
							(mid -0.249642 -0.249642)
							(end -0.1778 -0.2794)
						)
						(arc
							(start 0.1778 -0.2794)
							(mid 0.249642 -0.249642)
							(end 0.2794 -0.1778)
						)
						(arc
							(start 0.2794 0.1778)
							(mid 0.249642 0.249642)
							(end 0.1778 0.2794)
						)
					)
					(width 0)
					(fill yes)
				)
			)
		)
	)
	(footprint ""
		(layer "B.Cu")
		(at 108.389166 -52.1208 -90)
		(property "Reference" "SC1008"
			(at 0 0 90)
			(layer "B.SilkS")
			(hide yes)
			(effects
				(font
					(size 1.27 1.27)
				)
				(justify mirror)
			)
		)
		(property "Value" "SCD1U16V2KX-3GP"
			(at -1.1811 -2.7051 270)
			(unlocked yes)
			(layer "B.Fab")
			(hide yes)
			(effects
				(font
					(size 1.016 1.016)
					(thickness 0.1524)
				)
				(justify mirror)
			)
		)
		(property "Device Type" "C402H22"
			(at -1.1811 -4.2291 270)
			(unlocked yes)
			(layer "B.Fab")
			(hide yes)
			(effects
				(font
					(size 1.016 1.016)
					(thickness 0.1524)
				)
				(justify mirror)
			)
		)
		(duplicate_pad_numbers_are_jumpers no)
		(fp_rect
			(start 0.4318 0.9525)
			(end -0.4318 -0.9525)
			(stroke
				(width 0)
				(type default)
			)
			(fill no)
			(layer "B.CrtYd")
		)
		(fp_rect
			(start 0.4318 0.9525)
			(end -0.4318 -0.9525)
			(stroke
				(width 0)
				(type default)
			)
			(fill no)
			(layer "B.Fab")
		)
		(pad "1" smd custom
			(at 0 -0.4445 90)
			(size 0.1524 0.1524)
			(layers "B.Cu" "B.Mask" "B.Paste")
			(net "P1V8_C")
			(options
				(clearance outline)
				(anchor circle)
			)
			(primitives
				(gr_poly
					(pts
						(arc
							(start 0.3048 0.2032)
							(mid 0.275042 0.275042)
							(end 0.2032 0.3048)
						)
						(arc
							(start -0.2032 0.3048)
							(mid -0.275042 0.275042)
							(end -0.3048 0.2032)
						)
						(arc
							(start -0.3048 -0.2032)
							(mid -0.275042 -0.275042)
							(end -0.2032 -0.3048)
						)
						(arc
							(start 0.2032 -0.3048)
							(mid 0.275042 -0.275042)
							(end 0.3048 -0.2032)
						)
					)
					(width 0)
					(fill yes)
				)
			)
		)
		(pad "2" smd custom
			(at 0 0.4445 90)
			(size 0.1524 0.1524)
			(layers "B.Cu" "B.Mask" "B.Paste")
			(net "GND")
			(options
				(clearance outline)
				(anchor circle)
			)
			(primitives
				(gr_poly
					(pts
						(arc
							(start 0.3048 0.2032)
							(mid 0.275042 0.275042)
							(end 0.2032 0.3048)
						)
						(arc
							(start -0.2032 0.3048)
							(mid -0.275042 0.275042)
							(end -0.3048 0.2032)
						)
						(arc
							(start -0.3048 -0.2032)
							(mid -0.275042 -0.275042)
							(end -0.2032 -0.3048)
						)
						(arc
							(start 0.2032 -0.3048)
							(mid 0.275042 -0.275042)
							(end 0.3048 -0.2032)
						)
					)
					(width 0)
					(fill yes)
				)
			)
		)
	)
	(footprint ""
		(layer "B.Cu")
		(at 47.82693 -76.507086)
		(property "Reference" "TP184"
			(at 0 0 0)
			(layer "B.SilkS")
			(hide yes)
			(effects
				(font
					(size 1.27 1.27)
				)
				(justify mirror)
			)
		)
		(property "Value" "TPAD32-GP"
			(at 0 -3.166364 0)
			(unlocked yes)
			(layer "B.Fab")
			(hide yes)
			(effects
				(font
					(size 1.016 1.016)
					(thickness 0.1524)
				)
				(justify mirror)
			)
		)
		(property "Device Type" "TPAD32"
			(at 0 -4.690618 0)
			(unlocked yes)
			(layer "B.Fab")
			(hide yes)
			(effects
				(font
					(size 1.016 1.016)
					(thickness 0.1524)
				)
				(justify mirror)
			)
		)
		(duplicate_pad_numbers_are_jumpers no)
		(fp_poly
			(pts
				(arc
					(start 0.4064 0)
					(mid -0.4064 0)
					(end 0.4064 0)
				)
			)
			(stroke
				(width 0)
				(type default)
			)
			(fill no)
			(layer "B.CrtYd")
		)
		(fp_poly
			(pts
				(arc
					(start 0.7112 0)
					(mid -0.7112 0)
					(end 0.7112 0)
				)
			)
			(stroke
				(width 0)
				(type default)
			)
			(fill no)
			(layer "B.Fab")
		)
		(pad "1" smd circle
			(at 0 0 180)
			(size 0.8128 0.8128)
			(layers "B.Cu" "B.Mask" "B.Paste")
			(net "INT_CONN_A_SB3")
		)
	)
	(footprint ""
		(layer "B.Cu")
		(at 103.537766 -38.5064 90)
		(property "Reference" "SC948"
			(at 0 0 90)
			(layer "B.SilkS")
			(hide yes)
			(effects
				(font
					(size 1.27 1.27)
				)
				(justify mirror)
			)
		)
		(property "Value" "SCD1U6D3V1KX-GP"
			(at 2.8321 -1.7399 90)
			(unlocked yes)
			(layer "B.Fab")
			(hide yes)
			(effects
				(font
					(size 1.016 1.016)
					(thickness 0.1524)
				)
				(justify mirror)
			)
		)
		(property "Device Type" "C0201H13"
			(at 2.8321 -3.2639 90)
			(unlocked yes)
			(layer "B.Fab")
			(hide yes)
			(effects
				(font
					(size 1.016 1.016)
					(thickness 0.1524)
				)
				(justify mirror)
			)
		)
		(duplicate_pad_numbers_are_jumpers no)
		(fp_rect
			(start 0.2794 0.6477)
			(end -0.2794 -0.6477)
			(stroke
				(width 0)
				(type default)
			)
			(fill no)
			(layer "B.CrtYd")
		)
		(fp_rect
			(start 0.2794 0.6477)
			(end -0.2794 -0.6477)
			(stroke
				(width 0)
				(type default)
			)
			(fill no)
			(layer "B.Fab")
		)
		(pad "1" smd custom
			(at 0 -0.2794 270)
			(size 0.0762 0.0762)
			(layers "B.Cu" "B.Mask" "B.Paste")
			(net "PCE_AVDD")
			(options
				(clearance outline)
				(anchor circle)
			)
			(primitives
				(gr_poly
					(pts
						(arc
							(start 0.1524 0.127)
							(mid 0.137521 0.162921)
							(end 0.1016 0.1778)
						)
						(arc
							(start -0.1016 0.1778)
							(mid -0.137521 0.162921)
							(end -0.1524 0.127)
						)
						(arc
							(start -0.1524 -0.127)
							(mid -0.137521 -0.162921)
							(end -0.1016 -0.1778)
						)
						(arc
							(start 0.1016 -0.1778)
							(mid 0.137521 -0.162921)
							(end 0.1524 -0.127)
						)
					)
					(width 0)
					(fill yes)
				)
			)
		)
		(pad "2" smd custom
			(at 0 0.2794 270)
			(size 0.0762 0.0762)
			(layers "B.Cu" "B.Mask" "B.Paste")
			(net "GND")
			(options
				(clearance outline)
				(anchor circle)
			)
			(primitives
				(gr_poly
					(pts
						(arc
							(start 0.1524 0.127)
							(mid 0.137521 0.162921)
							(end 0.1016 0.1778)
						)
						(arc
							(start -0.1016 0.1778)
							(mid -0.137521 0.162921)
							(end -0.1524 0.127)
						)
						(arc
							(start -0.1524 -0.127)
							(mid -0.137521 -0.162921)
							(end -0.1016 -0.1778)
						)
						(arc
							(start 0.1016 -0.1778)
							(mid 0.137521 -0.162921)
							(end 0.1524 -0.127)
						)
					)
					(width 0)
					(fill yes)
				)
			)
		)
	)
	(footprint ""
		(layer "B.Cu")
		(at 307.975 -50.927 180)
		(property "Reference" "C278"
			(at 0 0 0)
			(layer "B.SilkS")
			(hide yes)
			(effects
				(font
					(size 1.27 1.27)
				)
				(justify mirror)
			)
		)
		(property "Value" "SC1U25V3KX-GP"
			(at 0 -2.8194 180)
			(unlocked yes)
			(layer "B.Fab")
			(hide yes)
			(effects
				(font
					(size 1.016 1.016)
					(thickness 0.1524)
				)
				(justify mirror)
			)
		)
		(property "Device Type" "C603H36"
			(at 0 -4.3434 180)
			(unlocked yes)
			(layer "B.Fab")
			(hide yes)
			(effects
				(font
					(size 1.016 1.016)
					(thickness 0.1524)
				)
				(justify mirror)
			)
		)
		(duplicate_pad_numbers_are_jumpers no)
		(fp_line
			(start -0.508 0)
			(end 0.508 0)
			(stroke
				(width 0.2032)
				(type default)
			)
			(layer "B.SilkS")
		)
		(fp_rect
			(start 0.5842 1.3335)
			(end -0.5842 -1.3335)
			(stroke
				(width 0)
				(type default)
			)
			(fill no)
			(layer "B.CrtYd")
		)
		(fp_rect
			(start 0.5842 1.3335)
			(end -0.5842 -1.3335)
			(stroke
				(width 0)
				(type default)
			)
			(fill no)
			(layer "B.Fab")
		)
		(pad "1" smd custom
			(at 0 -0.762)
			(size 0.2159 0.2159)
			(layers "B.Cu" "B.Mask" "B.Paste")
			(net "P12V")
			(options
				(clearance outline)
				(anchor circle)
			)
			(primitives
				(gr_poly
					(pts
						(arc
							(start -0.3302 0.4318)
							(mid -0.402042 0.402042)
							(end -0.4318 0.3302)
						)
						(arc
							(start -0.4318 -0.3302)
							(mid -0.402042 -0.402042)
							(end -0.3302 -0.4318)
						)
						(arc
							(start 0.3302 -0.4318)
							(mid 0.402042 -0.402042)
							(end 0.4318 -0.3302)
						)
						(arc
							(start 0.4318 0.3302)
							(mid 0.402042 0.402042)
							(end 0.3302 0.4318)
						)
					)
					(width 0)
					(fill yes)
				)
			)
		)
		(pad "2" smd custom
			(at 0 0.762)
			(size 0.2159 0.2159)
			(layers "B.Cu" "B.Mask" "B.Paste")
			(net "GND")
			(options
				(clearance outline)
				(anchor circle)
			)
			(primitives
				(gr_poly
					(pts
						(arc
							(start -0.3302 0.4318)
							(mid -0.402042 0.402042)
							(end -0.4318 0.3302)
						)
						(arc
							(start -0.4318 -0.3302)
							(mid -0.402042 -0.402042)
							(end -0.3302 -0.4318)
						)
						(arc
							(start 0.3302 -0.4318)
							(mid 0.402042 -0.402042)
							(end 0.4318 -0.3302)
						)
						(arc
							(start 0.4318 0.3302)
							(mid 0.402042 0.402042)
							(end 0.3302 0.4318)
						)
					)
					(width 0)
					(fill yes)
				)
			)
		)
	)
	(footprint ""
		(layer "B.Cu")
		(at 115.20297 -92.3798 180)
		(property "Reference" "SC1257"
			(at 0 0 0)
			(layer "B.SilkS")
			(hide yes)
			(effects
				(font
					(size 1.27 1.27)
				)
				(justify mirror)
			)
		)
		(property "Value" "SCD1U6D3V1KX-GP"
			(at 2.8321 -1.7399 180)
			(unlocked yes)
			(layer "B.Fab")
			(hide yes)
			(effects
				(font
					(size 1.016 1.016)
					(thickness 0.1524)
				)
				(justify mirror)
			)
		)
		(property "Device Type" "C0201H13"
			(at 2.8321 -3.2639 180)
			(unlocked yes)
			(layer "B.Fab")
			(hide yes)
			(effects
				(font
					(size 1.016 1.016)
					(thickness 0.1524)
				)
				(justify mirror)
			)
		)
		(duplicate_pad_numbers_are_jumpers no)
		(fp_rect
			(start 0.2794 0.6477)
			(end -0.2794 -0.6477)
			(stroke
				(width 0)
				(type default)
			)
			(fill no)
			(layer "B.CrtYd")
		)
		(fp_rect
			(start 0.2794 0.6477)
			(end -0.2794 -0.6477)
			(stroke
				(width 0)
				(type default)
			)
			(fill no)
			(layer "B.Fab")
		)
		(pad "1" smd custom
			(at 0 -0.2794)
			(size 0.0762 0.0762)
			(layers "B.Cu" "B.Mask" "B.Paste")
			(net "P0V9_E")
			(options
				(clearance outline)
				(anchor circle)
			)
			(primitives
				(gr_poly
					(pts
						(arc
							(start 0.1524 0.127)
							(mid 0.137521 0.162921)
							(end 0.1016 0.1778)
						)
						(arc
							(start -0.1016 0.1778)
							(mid -0.137521 0.162921)
							(end -0.1524 0.127)
						)
						(arc
							(start -0.1524 -0.127)
							(mid -0.137521 -0.162921)
							(end -0.1016 -0.1778)
						)
						(arc
							(start 0.1016 -0.1778)
							(mid 0.137521 -0.162921)
							(end 0.1524 -0.127)
						)
					)
					(width 0)
					(fill yes)
				)
			)
		)
		(pad "2" smd custom
			(at 0 0.2794)
			(size 0.0762 0.0762)
			(layers "B.Cu" "B.Mask" "B.Paste")
			(net "GND")
			(options
				(clearance outline)
				(anchor circle)
			)
			(primitives
				(gr_poly
					(pts
						(arc
							(start 0.1524 0.127)
							(mid 0.137521 0.162921)
							(end 0.1016 0.1778)
						)
						(arc
							(start -0.1016 0.1778)
							(mid -0.137521 0.162921)
							(end -0.1524 0.127)
						)
						(arc
							(start -0.1524 -0.127)
							(mid -0.137521 -0.162921)
							(end -0.1016 -0.1778)
						)
						(arc
							(start 0.1016 -0.1778)
							(mid 0.137521 -0.162921)
							(end 0.1524 -0.127)
						)
					)
					(width 0)
					(fill yes)
				)
			)
		)
	)
	(footprint ""
		(layer "B.Cu")
		(at 110.88497 -85.598)
		(property "Reference" "STP56"
			(at 0 0 0)
			(layer "B.SilkS")
			(hide yes)
			(effects
				(font
					(size 1.27 1.27)
				)
				(justify mirror)
			)
		)
		(property "Value" "TPAD28"
			(at -0.0127 -1.8034 0)
			(unlocked yes)
			(layer "B.Fab")
			(hide yes)
			(effects
				(font
					(size 1.016 1.016)
					(thickness 0.1524)
				)
				(justify mirror)
			)
		)
		(property "Device Type" "TPAD28"
			(at -0.0127 -3.3274 0)
			(unlocked yes)
			(layer "B.Fab")
			(hide yes)
			(effects
				(font
					(size 1.016 1.016)
					(thickness 0.1524)
				)
				(justify mirror)
			)
		)
		(duplicate_pad_numbers_are_jumpers no)
		(fp_poly
			(pts
				(arc
					(start 0.3556 0)
					(mid -0.3556 0)
					(end 0.3556 0)
				)
			)
			(stroke
				(width 0)
				(type default)
			)
			(fill no)
			(layer "B.CrtYd")
		)
		(fp_poly
			(pts
				(arc
					(start 0.6096 0)
					(mid -0.6096 0)
					(end 0.6096 0)
				)
			)
			(stroke
				(width 0)
				(type default)
			)
			(fill no)
			(layer "B.Fab")
		)
		(pad "1" smd circle
			(at 0 0 180)
			(size 0.7112 0.7112)
			(layers "B.Cu" "B.Mask" "B.Paste")
			(net "EXP_LED18")
		)
	)
	(footprint ""
		(layer "B.Cu")
		(at 115.83797 -81.661)
		(property "Reference" "STP105"
			(at 0 0 0)
			(layer "B.SilkS")
			(hide yes)
			(effects
				(font
					(size 1.27 1.27)
				)
				(justify mirror)
			)
		)
		(property "Value" "TPAD28"
			(at -0.0127 -1.8034 0)
			(unlocked yes)
			(layer "B.Fab")
			(hide yes)
			(effects
				(font
					(size 1.016 1.016)
					(thickness 0.1524)
				)
				(justify mirror)
			)
		)
		(property "Device Type" "TPAD28"
			(at -0.0127 -3.3274 0)
			(unlocked yes)
			(layer "B.Fab")
			(hide yes)
			(effects
				(font
					(size 1.016 1.016)
					(thickness 0.1524)
				)
				(justify mirror)
			)
		)
		(duplicate_pad_numbers_are_jumpers no)
		(fp_poly
			(pts
				(arc
					(start 0.3556 0)
					(mid -0.3556 0)
					(end 0.3556 0)
				)
			)
			(stroke
				(width 0)
				(type default)
			)
			(fill no)
			(layer "B.CrtYd")
		)
		(fp_poly
			(pts
				(arc
					(start 0.6096 0)
					(mid -0.6096 0)
					(end 0.6096 0)
				)
			)
			(stroke
				(width 0)
				(type default)
			)
			(fill no)
			(layer "B.Fab")
		)
		(pad "1" smd circle
			(at 0 0 180)
			(size 0.7112 0.7112)
			(layers "B.Cu" "B.Mask" "B.Paste")
			(net "TEST_MUX_38")
		)
	)
	(footprint ""
		(layer "B.Cu")
		(at 106.407966 -51.054 180)
		(property "Reference" "SC1017"
			(at 0 0 0)
			(layer "B.SilkS")
			(hide yes)
			(effects
				(font
					(size 1.27 1.27)
				)
				(justify mirror)
			)
		)
		(property "Value" "SC10U6D3V5KX-4GP"
			(at 0.0762 -6.1214 180)
			(unlocked yes)
			(layer "B.Fab")
			(hide yes)
			(effects
				(font
					(size 1.016 1.016)
					(thickness 0.1524)
				)
				(justify mirror)
			)
		)
		(property "Device Type" "C805H58"
			(at 0.0762 -8.1534 180)
			(unlocked yes)
			(layer "B.Fab")
			(hide yes)
			(effects
				(font
					(size 1.016 1.016)
					(thickness 0.1524)
				)
				(justify mirror)
			)
		)
		(duplicate_pad_numbers_are_jumpers no)
		(fp_line
			(start -0.635 0)
			(end 0.635 0)
			(stroke
				(width 0.508)
				(type default)
			)
			(layer "B.SilkS")
		)
		(fp_rect
			(start 0.9652 1.778)
			(end -0.9652 -1.778)
			(stroke
				(width 0)
				(type default)
			)
			(fill no)
			(layer "B.CrtYd")
		)
		(fp_poly
			(pts
				(xy 0.9652 -1.778) (xy -0.9652 -1.778) (xy -0.9652 1.778) (xy 0.9652 1.778)
			)
			(stroke
				(width 0)
				(type default)
			)
			(fill no)
			(layer "B.Fab")
		)
		(pad "1" smd rect
			(at 0 -0.9652)
			(size 1.397 1.143)
			(layers "B.Cu" "B.Mask" "B.Paste")
			(net "P0V955_C")
		)
		(pad "2" smd rect
			(at 0 0.9652)
			(size 1.397 1.143)
			(layers "B.Cu" "B.Mask" "B.Paste")
			(net "GND")
		)
	)
	(footprint ""
		(layer "B.Cu")
		(at 269.748 -31.623 -90)
		(property "Reference" "PR46"
			(at 0 0 90)
			(layer "B.SilkS")
			(hide yes)
			(effects
				(font
					(size 1.27 1.27)
				)
				(justify mirror)
			)
		)
		(property "Value" "3K9R2F-GP"
			(at -0.064008 -3.993896 270)
			(unlocked yes)
			(layer "B.Fab")
			(hide yes)
			(effects
				(font
					(size 1.016 1.016)
					(thickness 0.1524)
				)
				(justify mirror)
			)
		)
		(property "Device Type" "R402H16"
			(at -0.064008 -5.517896 270)
			(unlocked yes)
			(layer "B.Fab")
			(hide yes)
			(effects
				(font
					(size 1.016 1.016)
					(thickness 0.1524)
				)
				(justify mirror)
			)
		)
		(duplicate_pad_numbers_are_jumpers no)
		(fp_line
			(start -0.508 -0.9398)
			(end 0.508 -0.9398)
			(stroke
				(width 0.1524)
				(type default)
			)
			(layer "B.SilkS")
		)
		(fp_line
			(start 0.508 -0.9398)
			(end 0.508 0.9398)
			(stroke
				(width 0.1524)
				(type default)
			)
			(layer "B.SilkS")
		)
		(fp_rect
			(start 0.508 0.9398)
			(end -0.508 -0.9398)
			(stroke
				(width 0)
				(type default)
			)
			(fill no)
			(layer "B.CrtYd")
		)
		(fp_rect
			(start 0.508 0.9398)
			(end -0.508 -0.9398)
			(stroke
				(width 0)
				(type default)
			)
			(fill no)
			(layer "B.Fab")
		)
		(pad "1" smd custom
			(at 0 -0.4445 90)
			(size 0.1397 0.1397)
			(layers "B.Cu" "B.Mask" "B.Paste")
			(net "P1V8_STBY_LL")
			(options
				(clearance outline)
				(anchor circle)
			)
			(primitives
				(gr_poly
					(pts
						(arc
							(start -0.1778 0.2794)
							(mid -0.249642 0.249642)
							(end -0.2794 0.1778)
						)
						(arc
							(start -0.2794 -0.1778)
							(mid -0.249642 -0.249642)
							(end -0.1778 -0.2794)
						)
						(arc
							(start 0.1778 -0.2794)
							(mid 0.249642 -0.249642)
							(end 0.2794 -0.1778)
						)
						(arc
							(start 0.2794 0.1778)
							(mid 0.249642 0.249642)
							(end 0.1778 0.2794)
						)
					)
					(width 0)
					(fill yes)
				)
			)
		)
		(pad "2" smd custom
			(at 0 0.4445 90)
			(size 0.1397 0.1397)
			(layers "B.Cu" "B.Mask" "B.Paste")
			(net "P1V8_STBY_LL_R")
			(options
				(clearance outline)
				(anchor circle)
			)
			(primitives
				(gr_poly
					(pts
						(arc
							(start -0.1778 0.2794)
							(mid -0.249642 0.249642)
							(end -0.2794 0.1778)
						)
						(arc
							(start -0.2794 -0.1778)
							(mid -0.249642 -0.249642)
							(end -0.1778 -0.2794)
						)
						(arc
							(start 0.1778 -0.2794)
							(mid 0.249642 -0.249642)
							(end 0.2794 -0.1778)
						)
						(arc
							(start 0.2794 0.1778)
							(mid 0.249642 0.249642)
							(end 0.1778 0.2794)
						)
					)
					(width 0)
					(fill yes)
				)
			)
		)
	)
	(footprint ""
		(layer "B.Cu")
		(at 276.352 -160.02 90)
		(property "Reference" "R331"
			(at 0 0 90)
			(layer "B.SilkS")
			(hide yes)
			(effects
				(font
					(size 1.27 1.27)
				)
				(justify mirror)
			)
		)
		(property "Value" "0R2J-2-GP"
			(at -0.064008 -3.993896 90)
			(unlocked yes)
			(layer "B.Fab")
			(hide yes)
			(effects
				(font
					(size 1.016 1.016)
					(thickness 0.1524)
				)
				(justify mirror)
			)
		)
		(property "Device Type" "R402H16"
			(at -0.064008 -5.517896 90)
			(unlocked yes)
			(layer "B.Fab")
			(hide yes)
			(effects
				(font
					(size 1.016 1.016)
					(thickness 0.1524)
				)
				(justify mirror)
			)
		)
		(duplicate_pad_numbers_are_jumpers no)
		(fp_line
			(start 0.508 -0.9398)
			(end 0.508 0.9398)
			(stroke
				(width 0.1524)
				(type default)
			)
			(layer "B.SilkS")
		)
		(fp_line
			(start -0.508 -0.9398)
			(end 0.508 -0.9398)
			(stroke
				(width 0.1524)
				(type default)
			)
			(layer "B.SilkS")
		)
		(fp_rect
			(start 0.508 0.9398)
			(end -0.508 -0.9398)
			(stroke
				(width 0)
				(type default)
			)
			(fill no)
			(layer "B.CrtYd")
		)
		(fp_rect
			(start 0.508 0.9398)
			(end -0.508 -0.9398)
			(stroke
				(width 0)
				(type default)
			)
			(fill no)
			(layer "B.Fab")
		)
		(pad "1" smd custom
			(at 0 -0.4445 270)
			(size 0.1397 0.1397)
			(layers "B.Cu" "B.Mask" "B.Paste")
			(net "BMC_EN_0V955_C")
			(options
				(clearance outline)
				(anchor circle)
			)
			(primitives
				(gr_poly
					(pts
						(arc
							(start -0.1778 0.2794)
							(mid -0.249642 0.249642)
							(end -0.2794 0.1778)
						)
						(arc
							(start -0.2794 -0.1778)
							(mid -0.249642 -0.249642)
							(end -0.1778 -0.2794)
						)
						(arc
							(start 0.1778 -0.2794)
							(mid 0.249642 -0.249642)
							(end 0.2794 -0.1778)
						)
						(arc
							(start 0.2794 0.1778)
							(mid 0.249642 0.249642)
							(end 0.1778 0.2794)
						)
					)
					(width 0)
					(fill yes)
				)
			)
		)
		(pad "2" smd custom
			(at 0 0.4445 270)
			(size 0.1397 0.1397)
			(layers "B.Cu" "B.Mask" "B.Paste")
			(net "BMC_EN_0V955_R")
			(options
				(clearance outline)
				(anchor circle)
			)
			(primitives
				(gr_poly
					(pts
						(arc
							(start -0.1778 0.2794)
							(mid -0.249642 0.249642)
							(end -0.2794 0.1778)
						)
						(arc
							(start -0.2794 -0.1778)
							(mid -0.249642 -0.249642)
							(end -0.1778 -0.2794)
						)
						(arc
							(start 0.1778 -0.2794)
							(mid 0.249642 -0.249642)
							(end 0.2794 -0.1778)
						)
						(arc
							(start 0.2794 0.1778)
							(mid 0.249642 0.249642)
							(end 0.1778 0.2794)
						)
					)
					(width 0)
					(fill yes)
				)
			)
		)
	)
	(footprint ""
		(layer "B.Cu")
		(at 78.982062 -59.906408 -90)
		(property "Reference" "SC923"
			(at 0 0 90)
			(layer "B.SilkS")
			(hide yes)
			(effects
				(font
					(size 1.27 1.27)
				)
				(justify mirror)
			)
		)
		(property "Value" "SC22U6D3V5MX-2GP"
			(at 0.0762 -6.1214 270)
			(unlocked yes)
			(layer "B.Fab")
			(hide yes)
			(effects
				(font
					(size 1.016 1.016)
					(thickness 0.1524)
				)
				(justify mirror)
			)
		)
		(property "Device Type" "C805H58"
			(at 0.0762 -8.1534 270)
			(unlocked yes)
			(layer "B.Fab")
			(hide yes)
			(effects
				(font
					(size 1.016 1.016)
					(thickness 0.1524)
				)
				(justify mirror)
			)
		)
		(duplicate_pad_numbers_are_jumpers no)
		(fp_line
			(start -0.635 0)
			(end 0.635 0)
			(stroke
				(width 0.508)
				(type default)
			)
			(layer "B.SilkS")
		)
		(fp_rect
			(start 0.9652 1.778)
			(end -0.9652 -1.778)
			(stroke
				(width 0)
				(type default)
			)
			(fill no)
			(layer "B.CrtYd")
		)
		(fp_poly
			(pts
				(xy 0.9652 -1.778) (xy -0.9652 -1.778) (xy -0.9652 1.778) (xy 0.9652 1.778)
			)
			(stroke
				(width 0)
				(type default)
			)
			(fill no)
			(layer "B.Fab")
		)
		(pad "1" smd rect
			(at 0 -0.9652 90)
			(size 1.397 1.143)
			(layers "B.Cu" "B.Mask" "B.Paste")
			(net "VDDA_SAS_REF_CLK")
		)
		(pad "2" smd rect
			(at 0 0.9652 90)
			(size 1.397 1.143)
			(layers "B.Cu" "B.Mask" "B.Paste")
			(net "GND")
		)
	)
	(footprint ""
		(layer "B.Cu")
		(at 295.656 -167.64)
		(property "Reference" "TP156"
			(at 0 0 0)
			(layer "B.SilkS")
			(hide yes)
			(effects
				(font
					(size 1.27 1.27)
				)
				(justify mirror)
			)
		)
		(property "Value" "TPAD28"
			(at -0.0127 -1.8034 0)
			(unlocked yes)
			(layer "B.Fab")
			(hide yes)
			(effects
				(font
					(size 1.016 1.016)
					(thickness 0.1524)
				)
				(justify mirror)
			)
		)
		(property "Device Type" "TPAD28"
			(at -0.0127 -3.3274 0)
			(unlocked yes)
			(layer "B.Fab")
			(hide yes)
			(effects
				(font
					(size 1.016 1.016)
					(thickness 0.1524)
				)
				(justify mirror)
			)
		)
		(duplicate_pad_numbers_are_jumpers no)
		(fp_poly
			(pts
				(arc
					(start 0.3556 0)
					(mid -0.3556 0)
					(end 0.3556 0)
				)
			)
			(stroke
				(width 0)
				(type default)
			)
			(fill no)
			(layer "B.CrtYd")
		)
		(fp_poly
			(pts
				(arc
					(start 0.6096 0)
					(mid -0.6096 0)
					(end 0.6096 0)
				)
			)
			(stroke
				(width 0)
				(type default)
			)
			(fill no)
			(layer "B.Fab")
		)
		(pad "1" smd circle
			(at 0 0 180)
			(size 0.7112 0.7112)
			(layers "B.Cu" "B.Mask" "B.Paste")
			(net "TP_BMC_GPIOT7")
		)
	)
	(footprint ""
		(layer "B.Cu")
		(at 297.45432 -171.58462)
		(property "Reference" "TP97"
			(at 0 0 0)
			(layer "B.SilkS")
			(hide yes)
			(effects
				(font
					(size 1.27 1.27)
				)
				(justify mirror)
			)
		)
		(property "Value" "TPAD28"
			(at -0.0127 -1.8034 0)
			(unlocked yes)
			(layer "B.Fab")
			(hide yes)
			(effects
				(font
					(size 1.016 1.016)
					(thickness 0.1524)
				)
				(justify mirror)
			)
		)
		(property "Device Type" "TPAD28"
			(at -0.0127 -3.3274 0)
			(unlocked yes)
			(layer "B.Fab")
			(hide yes)
			(effects
				(font
					(size 1.016 1.016)
					(thickness 0.1524)
				)
				(justify mirror)
			)
		)
		(duplicate_pad_numbers_are_jumpers no)
		(fp_poly
			(pts
				(arc
					(start 0.3556 0)
					(mid -0.3556 0)
					(end 0.3556 0)
				)
			)
			(stroke
				(width 0)
				(type default)
			)
			(fill no)
			(layer "B.CrtYd")
		)
		(fp_poly
			(pts
				(arc
					(start 0.6096 0)
					(mid -0.6096 0)
					(end 0.6096 0)
				)
			)
			(stroke
				(width 0)
				(type default)
			)
			(fill no)
			(layer "B.Fab")
		)
		(pad "1" smd circle
			(at 0 0 180)
			(size 0.7112 0.7112)
			(layers "B.Cu" "B.Mask" "B.Paste")
			(net "TP_GPIOH7")
		)
	)
	(footprint ""
		(layer "B.Cu")
		(at 91.858084 -251.659136)
		(property "Reference" "TP79"
			(at 0 0 0)
			(layer "B.SilkS")
			(hide yes)
			(effects
				(font
					(size 1.27 1.27)
				)
				(justify mirror)
			)
		)
		(property "Value" "TPAD28"
			(at -0.0127 -1.8034 0)
			(unlocked yes)
			(layer "B.Fab")
			(hide yes)
			(effects
				(font
					(size 1.016 1.016)
					(thickness 0.1524)
				)
				(justify mirror)
			)
		)
		(property "Device Type" "TPAD28"
			(at -0.0127 -3.3274 0)
			(unlocked yes)
			(layer "B.Fab")
			(hide yes)
			(effects
				(font
					(size 1.016 1.016)
					(thickness 0.1524)
				)
				(justify mirror)
			)
		)
		(duplicate_pad_numbers_are_jumpers no)
		(fp_poly
			(pts
				(arc
					(start 0.3556 0)
					(mid -0.3556 0)
					(end 0.3556 0)
				)
			)
			(stroke
				(width 0)
				(type default)
			)
			(fill no)
			(layer "B.CrtYd")
		)
		(fp_poly
			(pts
				(arc
					(start 0.6096 0)
					(mid -0.6096 0)
					(end 0.6096 0)
				)
			)
			(stroke
				(width 0)
				(type default)
			)
			(fill no)
			(layer "B.Fab")
		)
		(pad "1" smd circle
			(at 0 0 180)
			(size 0.7112 0.7112)
			(layers "B.Cu" "B.Mask" "B.Paste")
			(net "SAS_I2C_D_BUF_SDA_R")
		)
	)
	(footprint ""
		(layer "B.Cu")
		(at 347.472 -115.951)
		(property "Reference" "PG2"
			(at 0 0 0)
			(layer "B.SilkS")
			(hide yes)
			(effects
				(font
					(size 1.27 1.27)
				)
				(justify mirror)
			)
		)
		(property "Value" "COPPER-CLOSE-GP-U"
			(at -0.0762 -2.8702 0)
			(unlocked yes)
			(layer "B.Fab")
			(hide yes)
			(effects
				(font
					(size 1.016 1.016)
					(thickness 0.1524)
				)
				(justify mirror)
			)
		)
		(property "Device Type" "CON2C-U"
			(at -0.0762 -4.3942 0)
			(unlocked yes)
			(layer "B.Fab")
			(hide yes)
			(effects
				(font
					(size 1.016 1.016)
					(thickness 0.1524)
				)
				(justify mirror)
			)
		)
		(duplicate_pad_numbers_are_jumpers no)
		(fp_rect
			(start 0.9398 0.9652)
			(end -0.9398 -0.9652)
			(stroke
				(width 0)
				(type default)
			)
			(fill no)
			(layer "B.CrtYd")
		)
		(fp_rect
			(start 0.9398 0.9652)
			(end -0.9398 -0.9652)
			(stroke
				(width 0)
				(type default)
			)
			(fill no)
			(layer "B.Fab")
		)
		(pad "1" smd custom
			(at 0 -0.5334 180)
			(size 0.17145 0.17145)
			(layers "B.Cu" "B.Mask" "B.Paste")
			(net "AGND_P5V_STBY")
			(options
				(clearance outline)
				(anchor circle)
			)
			(primitives
				(gr_poly
					(pts
						(xy -0.127 -0.3429) (xy -0.127 -0.1651) (xy -0.635 0.3429) (xy 0.635 0.3429) (xy 0.127 -0.1651)
						(xy 0.127 -0.3429)
					)
					(width 0)
					(fill yes)
				)
			)
		)
		(pad "2" smd custom
			(at 0 0.5334 180)
			(size 0.17145 0.17145)
			(layers "B.Cu" "B.Mask" "B.Paste")
			(net "GND")
			(options
				(clearance outline)
				(anchor circle)
			)
			(primitives
				(gr_poly
					(pts
						(xy -0.635 -0.3429) (xy -0.127 0.1651) (xy -0.127 0.3429) (xy 0.127 0.3429) (xy 0.127 0.1651)
						(xy 0.635 -0.3429)
					)
					(width 0)
					(fill yes)
				)
			)
		)
	)
	(footprint ""
		(layer "B.Cu")
		(at 101.454966 -48.26 -90)
		(property "Reference" "SC1054"
			(at 0 0 90)
			(layer "B.SilkS")
			(hide yes)
			(effects
				(font
					(size 1.27 1.27)
				)
				(justify mirror)
			)
		)
		(property "Value" "SCD1U16V2KX-3GP"
			(at -1.1811 -2.7051 270)
			(unlocked yes)
			(layer "B.Fab")
			(hide yes)
			(effects
				(font
					(size 1.016 1.016)
					(thickness 0.1524)
				)
				(justify mirror)
			)
		)
		(property "Device Type" "C402H22"
			(at -1.1811 -4.2291 270)
			(unlocked yes)
			(layer "B.Fab")
			(hide yes)
			(effects
				(font
					(size 1.016 1.016)
					(thickness 0.1524)
				)
				(justify mirror)
			)
		)
		(duplicate_pad_numbers_are_jumpers no)
		(fp_rect
			(start 0.4318 0.9525)
			(end -0.4318 -0.9525)
			(stroke
				(width 0)
				(type default)
			)
			(fill no)
			(layer "B.CrtYd")
		)
		(fp_rect
			(start 0.4318 0.9525)
			(end -0.4318 -0.9525)
			(stroke
				(width 0)
				(type default)
			)
			(fill no)
			(layer "B.Fab")
		)
		(pad "1" smd custom
			(at 0 -0.4445 90)
			(size 0.1524 0.1524)
			(layers "B.Cu" "B.Mask" "B.Paste")
			(net "P0V955_C")
			(options
				(clearance outline)
				(anchor circle)
			)
			(primitives
				(gr_poly
					(pts
						(arc
							(start 0.3048 0.2032)
							(mid 0.275042 0.275042)
							(end 0.2032 0.3048)
						)
						(arc
							(start -0.2032 0.3048)
							(mid -0.275042 0.275042)
							(end -0.3048 0.2032)
						)
						(arc
							(start -0.3048 -0.2032)
							(mid -0.275042 -0.275042)
							(end -0.2032 -0.3048)
						)
						(arc
							(start 0.2032 -0.3048)
							(mid 0.275042 -0.275042)
							(end 0.3048 -0.2032)
						)
					)
					(width 0)
					(fill yes)
				)
			)
		)
		(pad "2" smd custom
			(at 0 0.4445 90)
			(size 0.1524 0.1524)
			(layers "B.Cu" "B.Mask" "B.Paste")
			(net "GND")
			(options
				(clearance outline)
				(anchor circle)
			)
			(primitives
				(gr_poly
					(pts
						(arc
							(start 0.3048 0.2032)
							(mid 0.275042 0.275042)
							(end 0.2032 0.3048)
						)
						(arc
							(start -0.2032 0.3048)
							(mid -0.275042 0.275042)
							(end -0.3048 0.2032)
						)
						(arc
							(start -0.3048 -0.2032)
							(mid -0.275042 -0.275042)
							(end -0.2032 -0.3048)
						)
						(arc
							(start 0.2032 -0.3048)
							(mid 0.275042 -0.275042)
							(end 0.3048 -0.2032)
						)
					)
					(width 0)
					(fill yes)
				)
			)
		)
	)
	(footprint ""
		(layer "B.Cu")
		(at 103.385366 -41.91 90)
		(property "Reference" "SC1058"
			(at 0 0 90)
			(layer "B.SilkS")
			(hide yes)
			(effects
				(font
					(size 1.27 1.27)
				)
				(justify mirror)
			)
		)
		(property "Value" "SCD1U16V2KX-3GP"
			(at -1.1811 -2.7051 90)
			(unlocked yes)
			(layer "B.Fab")
			(hide yes)
			(effects
				(font
					(size 1.016 1.016)
					(thickness 0.1524)
				)
				(justify mirror)
			)
		)
		(property "Device Type" "C402H22"
			(at -1.1811 -4.2291 90)
			(unlocked yes)
			(layer "B.Fab")
			(hide yes)
			(effects
				(font
					(size 1.016 1.016)
					(thickness 0.1524)
				)
				(justify mirror)
			)
		)
		(duplicate_pad_numbers_are_jumpers no)
		(fp_rect
			(start 0.4318 0.9525)
			(end -0.4318 -0.9525)
			(stroke
				(width 0)
				(type default)
			)
			(fill no)
			(layer "B.CrtYd")
		)
		(fp_rect
			(start 0.4318 0.9525)
			(end -0.4318 -0.9525)
			(stroke
				(width 0)
				(type default)
			)
			(fill no)
			(layer "B.Fab")
		)
		(pad "1" smd custom
			(at 0 -0.4445 270)
			(size 0.1524 0.1524)
			(layers "B.Cu" "B.Mask" "B.Paste")
			(net "P0V955_C")
			(options
				(clearance outline)
				(anchor circle)
			)
			(primitives
				(gr_poly
					(pts
						(arc
							(start 0.3048 0.2032)
							(mid 0.275042 0.275042)
							(end 0.2032 0.3048)
						)
						(arc
							(start -0.2032 0.3048)
							(mid -0.275042 0.275042)
							(end -0.3048 0.2032)
						)
						(arc
							(start -0.3048 -0.2032)
							(mid -0.275042 -0.275042)
							(end -0.2032 -0.3048)
						)
						(arc
							(start 0.2032 -0.3048)
							(mid 0.275042 -0.275042)
							(end 0.3048 -0.2032)
						)
					)
					(width 0)
					(fill yes)
				)
			)
		)
		(pad "2" smd custom
			(at 0 0.4445 270)
			(size 0.1524 0.1524)
			(layers "B.Cu" "B.Mask" "B.Paste")
			(net "GND")
			(options
				(clearance outline)
				(anchor circle)
			)
			(primitives
				(gr_poly
					(pts
						(arc
							(start 0.3048 0.2032)
							(mid 0.275042 0.275042)
							(end 0.2032 0.3048)
						)
						(arc
							(start -0.2032 0.3048)
							(mid -0.275042 0.275042)
							(end -0.3048 0.2032)
						)
						(arc
							(start -0.3048 -0.2032)
							(mid -0.275042 -0.275042)
							(end -0.2032 -0.3048)
						)
						(arc
							(start 0.2032 -0.3048)
							(mid 0.275042 -0.275042)
							(end 0.3048 -0.2032)
						)
					)
					(width 0)
					(fill yes)
				)
			)
		)
	)
	(footprint ""
		(layer "B.Cu")
		(at 92.686886 -48.747426 180)
		(property "Reference" "SC1066"
			(at 0 0 0)
			(layer "B.SilkS")
			(hide yes)
			(effects
				(font
					(size 1.27 1.27)
				)
				(justify mirror)
			)
		)
		(property "Value" "SCD1U16V2KX-3GP"
			(at -1.1811 -2.7051 180)
			(unlocked yes)
			(layer "B.Fab")
			(hide yes)
			(effects
				(font
					(size 1.016 1.016)
					(thickness 0.1524)
				)
				(justify mirror)
			)
		)
		(property "Device Type" "C402H22"
			(at -1.1811 -4.2291 180)
			(unlocked yes)
			(layer "B.Fab")
			(hide yes)
			(effects
				(font
					(size 1.016 1.016)
					(thickness 0.1524)
				)
				(justify mirror)
			)
		)
		(duplicate_pad_numbers_are_jumpers no)
		(fp_rect
			(start 0.4318 0.9525)
			(end -0.4318 -0.9525)
			(stroke
				(width 0)
				(type default)
			)
			(fill no)
			(layer "B.CrtYd")
		)
		(fp_rect
			(start 0.4318 0.9525)
			(end -0.4318 -0.9525)
			(stroke
				(width 0)
				(type default)
			)
			(fill no)
			(layer "B.Fab")
		)
		(pad "1" smd custom
			(at 0 -0.4445)
			(size 0.1524 0.1524)
			(layers "B.Cu" "B.Mask" "B.Paste")
			(net "P1V8_C")
			(options
				(clearance outline)
				(anchor circle)
			)
			(primitives
				(gr_poly
					(pts
						(arc
							(start 0.3048 0.2032)
							(mid 0.275042 0.275042)
							(end 0.2032 0.3048)
						)
						(arc
							(start -0.2032 0.3048)
							(mid -0.275042 0.275042)
							(end -0.3048 0.2032)
						)
						(arc
							(start -0.3048 -0.2032)
							(mid -0.275042 -0.275042)
							(end -0.2032 -0.3048)
						)
						(arc
							(start 0.2032 -0.3048)
							(mid 0.275042 -0.275042)
							(end 0.3048 -0.2032)
						)
					)
					(width 0)
					(fill yes)
				)
			)
		)
		(pad "2" smd custom
			(at 0 0.4445)
			(size 0.1524 0.1524)
			(layers "B.Cu" "B.Mask" "B.Paste")
			(net "GND")
			(options
				(clearance outline)
				(anchor circle)
			)
			(primitives
				(gr_poly
					(pts
						(arc
							(start 0.3048 0.2032)
							(mid 0.275042 0.275042)
							(end 0.2032 0.3048)
						)
						(arc
							(start -0.2032 0.3048)
							(mid -0.275042 0.275042)
							(end -0.3048 0.2032)
						)
						(arc
							(start -0.3048 -0.2032)
							(mid -0.275042 -0.275042)
							(end -0.2032 -0.3048)
						)
						(arc
							(start 0.2032 -0.3048)
							(mid 0.275042 -0.275042)
							(end 0.3048 -0.2032)
						)
					)
					(width 0)
					(fill yes)
				)
			)
		)
	)
	(footprint ""
		(layer "B.Cu")
		(at 341.507318 -133.353048 -90)
		(property "Reference" "R554"
			(at 0 0 90)
			(layer "B.SilkS")
			(hide yes)
			(effects
				(font
					(size 1.27 1.27)
				)
				(justify mirror)
			)
		)
		(property "Value" "0R3J-0-U-GP"
			(at 0.0254 -2.5146 270)
			(unlocked yes)
			(layer "B.Fab")
			(hide yes)
			(effects
				(font
					(size 1.016 1.016)
					(thickness 0.1524)
				)
				(justify mirror)
			)
		)
		(property "Device Type" "R603H22"
			(at 0.0254 -4.0386 270)
			(unlocked yes)
			(layer "B.Fab")
			(hide yes)
			(effects
				(font
					(size 1.016 1.016)
					(thickness 0.1524)
				)
				(justify mirror)
			)
		)
		(duplicate_pad_numbers_are_jumpers no)
		(fp_line
			(start -0.2032 0)
			(end -0.4826 0)
			(stroke
				(width 0.2032)
				(type default)
			)
			(layer "B.SilkS")
		)
		(fp_line
			(start 0.4826 0)
			(end 0.2032 0)
			(stroke
				(width 0.2032)
				(type default)
			)
			(layer "B.SilkS")
		)
		(fp_rect
			(start 0.5842 1.3335)
			(end -0.5842 -1.3335)
			(stroke
				(width 0)
				(type default)
			)
			(fill no)
			(layer "B.CrtYd")
		)
		(fp_rect
			(start 0.5842 1.3335)
			(end -0.5842 -1.3335)
			(stroke
				(width 0)
				(type default)
			)
			(fill no)
			(layer "B.Fab")
		)
		(pad "1" smd custom
			(at 0 -0.762 90)
			(size 0.2159 0.2159)
			(layers "B.Cu" "B.Mask" "B.Paste")
			(net "USB_P1_DP")
			(options
				(clearance outline)
				(anchor circle)
			)
			(primitives
				(gr_poly
					(pts
						(arc
							(start -0.3302 0.4318)
							(mid -0.402042 0.402042)
							(end -0.4318 0.3302)
						)
						(arc
							(start -0.4318 -0.3302)
							(mid -0.402042 -0.402042)
							(end -0.3302 -0.4318)
						)
						(arc
							(start 0.3302 -0.4318)
							(mid 0.402042 -0.402042)
							(end 0.4318 -0.3302)
						)
						(arc
							(start 0.4318 0.3302)
							(mid 0.402042 0.402042)
							(end 0.3302 0.4318)
						)
					)
					(width 0)
					(fill yes)
				)
			)
		)
		(pad "2" smd custom
			(at 0 0.762 90)
			(size 0.2159 0.2159)
			(layers "B.Cu" "B.Mask" "B.Paste")
			(net "USB_DP_R")
			(options
				(clearance outline)
				(anchor circle)
			)
			(primitives
				(gr_poly
					(pts
						(arc
							(start -0.3302 0.4318)
							(mid -0.402042 0.402042)
							(end -0.4318 0.3302)
						)
						(arc
							(start -0.4318 -0.3302)
							(mid -0.402042 -0.402042)
							(end -0.3302 -0.4318)
						)
						(arc
							(start 0.3302 -0.4318)
							(mid 0.402042 -0.402042)
							(end 0.4318 -0.3302)
						)
						(arc
							(start 0.4318 0.3302)
							(mid 0.402042 0.402042)
							(end 0.3302 0.4318)
						)
					)
					(width 0)
					(fill yes)
				)
			)
		)
	)
	(footprint ""
		(layer "B.Cu")
		(at 271.238472 -173.114716 90)
		(property "Reference" "R257"
			(at 0 0 90)
			(layer "B.SilkS")
			(hide yes)
			(effects
				(font
					(size 1.27 1.27)
				)
				(justify mirror)
			)
		)
		(property "Value" "10KR2F-2-GP"
			(at -0.064008 -3.993896 90)
			(unlocked yes)
			(layer "B.Fab")
			(hide yes)
			(effects
				(font
					(size 1.016 1.016)
					(thickness 0.1524)
				)
				(justify mirror)
			)
		)
		(property "Device Type" "R402H16"
			(at -0.064008 -5.517896 90)
			(unlocked yes)
			(layer "B.Fab")
			(hide yes)
			(effects
				(font
					(size 1.016 1.016)
					(thickness 0.1524)
				)
				(justify mirror)
			)
		)
		(duplicate_pad_numbers_are_jumpers no)
		(fp_line
			(start 0.508 -0.9398)
			(end 0.508 0.9398)
			(stroke
				(width 0.1524)
				(type default)
			)
			(layer "B.SilkS")
		)
		(fp_line
			(start -0.508 -0.9398)
			(end 0.508 -0.9398)
			(stroke
				(width 0.1524)
				(type default)
			)
			(layer "B.SilkS")
		)
		(fp_rect
			(start 0.508 0.9398)
			(end -0.508 -0.9398)
			(stroke
				(width 0)
				(type default)
			)
			(fill no)
			(layer "B.CrtYd")
		)
		(fp_rect
			(start 0.508 0.9398)
			(end -0.508 -0.9398)
			(stroke
				(width 0)
				(type default)
			)
			(fill no)
			(layer "B.Fab")
		)
		(pad "1" smd custom
			(at 0 -0.4445 270)
			(size 0.1397 0.1397)
			(layers "B.Cu" "B.Mask" "B.Paste")
			(net "P3V3_STBY")
			(options
				(clearance outline)
				(anchor circle)
			)
			(primitives
				(gr_poly
					(pts
						(arc
							(start -0.1778 0.2794)
							(mid -0.249642 0.249642)
							(end -0.2794 0.1778)
						)
						(arc
							(start -0.2794 -0.1778)
							(mid -0.249642 -0.249642)
							(end -0.1778 -0.2794)
						)
						(arc
							(start 0.1778 -0.2794)
							(mid 0.249642 -0.249642)
							(end 0.2794 -0.1778)
						)
						(arc
							(start 0.2794 0.1778)
							(mid 0.249642 0.249642)
							(end 0.1778 0.2794)
						)
					)
					(width 0)
					(fill yes)
				)
			)
		)
		(pad "2" smd custom
			(at 0 0.4445 270)
			(size 0.1397 0.1397)
			(layers "B.Cu" "B.Mask" "B.Paste")
			(net "SAS_SEB_PEER_PRSNT_BMC")
			(options
				(clearance outline)
				(anchor circle)
			)
			(primitives
				(gr_poly
					(pts
						(arc
							(start -0.1778 0.2794)
							(mid -0.249642 0.249642)
							(end -0.2794 0.1778)
						)
						(arc
							(start -0.2794 -0.1778)
							(mid -0.249642 -0.249642)
							(end -0.1778 -0.2794)
						)
						(arc
							(start 0.1778 -0.2794)
							(mid 0.249642 -0.249642)
							(end 0.2794 -0.1778)
						)
						(arc
							(start 0.2794 0.1778)
							(mid 0.249642 0.249642)
							(end 0.1778 0.2794)
						)
					)
					(width 0)
					(fill yes)
				)
			)
		)
	)
	(footprint ""
		(layer "B.Cu")
		(at 318.008 -178.689 -90)
		(property "Reference" "R318"
			(at 0 0 90)
			(layer "B.SilkS")
			(hide yes)
			(effects
				(font
					(size 1.27 1.27)
				)
				(justify mirror)
			)
		)
		(property "Value" "0R2J-2-GP"
			(at -0.064008 -3.993896 270)
			(unlocked yes)
			(layer "B.Fab")
			(hide yes)
			(effects
				(font
					(size 1.016 1.016)
					(thickness 0.1524)
				)
				(justify mirror)
			)
		)
		(property "Device Type" "R402H16"
			(at -0.064008 -5.517896 270)
			(unlocked yes)
			(layer "B.Fab")
			(hide yes)
			(effects
				(font
					(size 1.016 1.016)
					(thickness 0.1524)
				)
				(justify mirror)
			)
		)
		(duplicate_pad_numbers_are_jumpers no)
		(fp_line
			(start -0.508 -0.9398)
			(end 0.508 -0.9398)
			(stroke
				(width 0.1524)
				(type default)
			)
			(layer "B.SilkS")
		)
		(fp_line
			(start 0.508 -0.9398)
			(end 0.508 0.9398)
			(stroke
				(width 0.1524)
				(type default)
			)
			(layer "B.SilkS")
		)
		(fp_rect
			(start 0.508 0.9398)
			(end -0.508 -0.9398)
			(stroke
				(width 0)
				(type default)
			)
			(fill no)
			(layer "B.CrtYd")
		)
		(fp_rect
			(start 0.508 0.9398)
			(end -0.508 -0.9398)
			(stroke
				(width 0)
				(type default)
			)
			(fill no)
			(layer "B.Fab")
		)
		(pad "1" smd custom
			(at 0 -0.4445 90)
			(size 0.1397 0.1397)
			(layers "B.Cu" "B.Mask" "B.Paste")
			(net "ADC_P3V3_STBY")
			(options
				(clearance outline)
				(anchor circle)
			)
			(primitives
				(gr_poly
					(pts
						(arc
							(start -0.1778 0.2794)
							(mid -0.249642 0.249642)
							(end -0.2794 0.1778)
						)
						(arc
							(start -0.2794 -0.1778)
							(mid -0.249642 -0.249642)
							(end -0.1778 -0.2794)
						)
						(arc
							(start 0.1778 -0.2794)
							(mid 0.249642 -0.249642)
							(end 0.2794 -0.1778)
						)
						(arc
							(start 0.2794 0.1778)
							(mid 0.249642 0.249642)
							(end 0.1778 0.2794)
						)
					)
					(width 0)
					(fill yes)
				)
			)
		)
		(pad "2" smd custom
			(at 0 0.4445 90)
			(size 0.1397 0.1397)
			(layers "B.Cu" "B.Mask" "B.Paste")
			(net "ADC_P3V3_STBY_BMC")
			(options
				(clearance outline)
				(anchor circle)
			)
			(primitives
				(gr_poly
					(pts
						(arc
							(start -0.1778 0.2794)
							(mid -0.249642 0.249642)
							(end -0.2794 0.1778)
						)
						(arc
							(start -0.2794 -0.1778)
							(mid -0.249642 -0.249642)
							(end -0.1778 -0.2794)
						)
						(arc
							(start 0.1778 -0.2794)
							(mid 0.249642 -0.249642)
							(end 0.2794 -0.1778)
						)
						(arc
							(start 0.2794 0.1778)
							(mid 0.249642 0.249642)
							(end 0.1778 0.2794)
						)
					)
					(width 0)
					(fill yes)
				)
			)
		)
	)
	(footprint ""
		(layer "B.Cu")
		(at 117.545612 -205.867)
		(property "Reference" "SR886"
			(at 0 0 0)
			(layer "B.SilkS")
			(hide yes)
			(effects
				(font
					(size 1.27 1.27)
				)
				(justify mirror)
			)
		)
		(property "Value" "0R2J-2-GP"
			(at -0.064008 -3.993896 0)
			(unlocked yes)
			(layer "B.Fab")
			(hide yes)
			(effects
				(font
					(size 1.016 1.016)
					(thickness 0.1524)
				)
				(justify mirror)
			)
		)
		(property "Device Type" "R402H16"
			(at -0.064008 -5.517896 0)
			(unlocked yes)
			(layer "B.Fab")
			(hide yes)
			(effects
				(font
					(size 1.016 1.016)
					(thickness 0.1524)
				)
				(justify mirror)
			)
		)
		(duplicate_pad_numbers_are_jumpers no)
		(fp_line
			(start -0.508 -0.9398)
			(end 0.508 -0.9398)
			(stroke
				(width 0.1524)
				(type default)
			)
			(layer "B.SilkS")
		)
		(fp_line
			(start 0.508 -0.9398)
			(end 0.508 0.9398)
			(stroke
				(width 0.1524)
				(type default)
			)
			(layer "B.SilkS")
		)
		(fp_rect
			(start 0.508 0.9398)
			(end -0.508 -0.9398)
			(stroke
				(width 0)
				(type default)
			)
			(fill no)
			(layer "B.CrtYd")
		)
		(fp_rect
			(start 0.508 0.9398)
			(end -0.508 -0.9398)
			(stroke
				(width 0)
				(type default)
			)
			(fill no)
			(layer "B.Fab")
		)
		(pad "1" smd custom
			(at 0 -0.4445 180)
			(size 0.1397 0.1397)
			(layers "B.Cu" "B.Mask" "B.Paste")
			(net "SAS_HDD_REDV_SER_RX7_P")
			(options
				(clearance outline)
				(anchor circle)
			)
			(primitives
				(gr_poly
					(pts
						(arc
							(start -0.1778 0.2794)
							(mid -0.249642 0.249642)
							(end -0.2794 0.1778)
						)
						(arc
							(start -0.2794 -0.1778)
							(mid -0.249642 -0.249642)
							(end -0.1778 -0.2794)
						)
						(arc
							(start 0.1778 -0.2794)
							(mid 0.249642 -0.249642)
							(end 0.2794 -0.1778)
						)
						(arc
							(start 0.2794 0.1778)
							(mid 0.249642 0.249642)
							(end 0.1778 0.2794)
						)
					)
					(width 0)
					(fill yes)
				)
			)
		)
		(pad "2" smd custom
			(at 0 0.4445 180)
			(size 0.1397 0.1397)
			(layers "B.Cu" "B.Mask" "B.Paste")
			(net "SAS_HDD_CONN_RX7_P")
			(options
				(clearance outline)
				(anchor circle)
			)
			(primitives
				(gr_poly
					(pts
						(arc
							(start -0.1778 0.2794)
							(mid -0.249642 0.249642)
							(end -0.2794 0.1778)
						)
						(arc
							(start -0.2794 -0.1778)
							(mid -0.249642 -0.249642)
							(end -0.1778 -0.2794)
						)
						(arc
							(start 0.1778 -0.2794)
							(mid 0.249642 -0.249642)
							(end 0.2794 -0.1778)
						)
						(arc
							(start 0.2794 0.1778)
							(mid 0.249642 0.249642)
							(end 0.1778 0.2794)
						)
					)
					(width 0)
					(fill yes)
				)
			)
		)
	)
	(footprint ""
		(layer "B.Cu")
		(at 108.97616 -35.306 90)
		(property "Reference" "SC996"
			(at 0 0 90)
			(layer "B.SilkS")
			(hide yes)
			(effects
				(font
					(size 1.27 1.27)
				)
				(justify mirror)
			)
		)
		(property "Value" "SCD1U16V2KX-3GP"
			(at -1.1811 -2.7051 90)
			(unlocked yes)
			(layer "B.Fab")
			(hide yes)
			(effects
				(font
					(size 1.016 1.016)
					(thickness 0.1524)
				)
				(justify mirror)
			)
		)
		(property "Device Type" "C402H22"
			(at -1.1811 -4.2291 90)
			(unlocked yes)
			(layer "B.Fab")
			(hide yes)
			(effects
				(font
					(size 1.016 1.016)
					(thickness 0.1524)
				)
				(justify mirror)
			)
		)
		(duplicate_pad_numbers_are_jumpers no)
		(fp_rect
			(start 0.4318 0.9525)
			(end -0.4318 -0.9525)
			(stroke
				(width 0)
				(type default)
			)
			(fill no)
			(layer "B.CrtYd")
		)
		(fp_rect
			(start 0.4318 0.9525)
			(end -0.4318 -0.9525)
			(stroke
				(width 0)
				(type default)
			)
			(fill no)
			(layer "B.Fab")
		)
		(pad "1" smd custom
			(at 0 -0.4445 270)
			(size 0.1524 0.1524)
			(layers "B.Cu" "B.Mask" "B.Paste")
			(net "P1V8_C")
			(options
				(clearance outline)
				(anchor circle)
			)
			(primitives
				(gr_poly
					(pts
						(arc
							(start 0.3048 0.2032)
							(mid 0.275042 0.275042)
							(end 0.2032 0.3048)
						)
						(arc
							(start -0.2032 0.3048)
							(mid -0.275042 0.275042)
							(end -0.3048 0.2032)
						)
						(arc
							(start -0.3048 -0.2032)
							(mid -0.275042 -0.275042)
							(end -0.2032 -0.3048)
						)
						(arc
							(start 0.2032 -0.3048)
							(mid 0.275042 -0.275042)
							(end 0.3048 -0.2032)
						)
					)
					(width 0)
					(fill yes)
				)
			)
		)
		(pad "2" smd custom
			(at 0 0.4445 270)
			(size 0.1524 0.1524)
			(layers "B.Cu" "B.Mask" "B.Paste")
			(net "GND")
			(options
				(clearance outline)
				(anchor circle)
			)
			(primitives
				(gr_poly
					(pts
						(arc
							(start 0.3048 0.2032)
							(mid 0.275042 0.275042)
							(end 0.2032 0.3048)
						)
						(arc
							(start -0.2032 0.3048)
							(mid -0.275042 0.275042)
							(end -0.3048 0.2032)
						)
						(arc
							(start -0.3048 -0.2032)
							(mid -0.275042 -0.275042)
							(end -0.2032 -0.3048)
						)
						(arc
							(start 0.2032 -0.3048)
							(mid 0.275042 -0.275042)
							(end 0.3048 -0.2032)
						)
					)
					(width 0)
					(fill yes)
				)
			)
		)
	)
	(footprint ""
		(layer "B.Cu")
		(at 117.475 -39.116)
		(property "Reference" "STP132"
			(at 0 0 0)
			(layer "B.SilkS")
			(hide yes)
			(effects
				(font
					(size 1.27 1.27)
				)
				(justify mirror)
			)
		)
		(property "Value" "TPAD28"
			(at -0.0127 -1.8034 0)
			(unlocked yes)
			(layer "B.Fab")
			(hide yes)
			(effects
				(font
					(size 1.016 1.016)
					(thickness 0.1524)
				)
				(justify mirror)
			)
		)
		(property "Device Type" "TPAD28"
			(at -0.0127 -3.3274 0)
			(unlocked yes)
			(layer "B.Fab")
			(hide yes)
			(effects
				(font
					(size 1.016 1.016)
					(thickness 0.1524)
				)
				(justify mirror)
			)
		)
		(duplicate_pad_numbers_are_jumpers no)
		(fp_poly
			(pts
				(arc
					(start 0.3556 0)
					(mid -0.3556 0)
					(end 0.3556 0)
				)
			)
			(stroke
				(width 0)
				(type default)
			)
			(fill no)
			(layer "B.CrtYd")
		)
		(fp_poly
			(pts
				(arc
					(start 0.6096 0)
					(mid -0.6096 0)
					(end 0.6096 0)
				)
			)
			(stroke
				(width 0)
				(type default)
			)
			(fill no)
			(layer "B.Fab")
		)
		(pad "1" smd circle
			(at 0 0 180)
			(size 0.7112 0.7112)
			(layers "B.Cu" "B.Mask" "B.Paste")
			(net "IOC_GPIO_15")
		)
	)
	(footprint ""
		(layer "B.Cu")
		(at 103.359966 -43.307 90)
		(property "Reference" "SC1028"
			(at 0 0 90)
			(layer "B.SilkS")
			(hide yes)
			(effects
				(font
					(size 1.27 1.27)
				)
				(justify mirror)
			)
		)
		(property "Value" "SC1U10V2KX-4-GP"
			(at -1.1811 -2.7051 90)
			(unlocked yes)
			(layer "B.Fab")
			(hide yes)
			(effects
				(font
					(size 1.016 1.016)
					(thickness 0.1524)
				)
				(justify mirror)
			)
		)
		(property "Device Type" "C402H22"
			(at -1.1811 -4.2291 90)
			(unlocked yes)
			(layer "B.Fab")
			(hide yes)
			(effects
				(font
					(size 1.016 1.016)
					(thickness 0.1524)
				)
				(justify mirror)
			)
		)
		(duplicate_pad_numbers_are_jumpers no)
		(fp_rect
			(start 0.4318 0.9525)
			(end -0.4318 -0.9525)
			(stroke
				(width 0)
				(type default)
			)
			(fill no)
			(layer "B.CrtYd")
		)
		(fp_rect
			(start 0.4318 0.9525)
			(end -0.4318 -0.9525)
			(stroke
				(width 0)
				(type default)
			)
			(fill no)
			(layer "B.Fab")
		)
		(pad "1" smd custom
			(at 0 -0.4445 270)
			(size 0.1524 0.1524)
			(layers "B.Cu" "B.Mask" "B.Paste")
			(net "P0V955_C")
			(options
				(clearance outline)
				(anchor circle)
			)
			(primitives
				(gr_poly
					(pts
						(arc
							(start 0.3048 0.2032)
							(mid 0.275042 0.275042)
							(end 0.2032 0.3048)
						)
						(arc
							(start -0.2032 0.3048)
							(mid -0.275042 0.275042)
							(end -0.3048 0.2032)
						)
						(arc
							(start -0.3048 -0.2032)
							(mid -0.275042 -0.275042)
							(end -0.2032 -0.3048)
						)
						(arc
							(start 0.2032 -0.3048)
							(mid 0.275042 -0.275042)
							(end 0.3048 -0.2032)
						)
					)
					(width 0)
					(fill yes)
				)
			)
		)
		(pad "2" smd custom
			(at 0 0.4445 270)
			(size 0.1524 0.1524)
			(layers "B.Cu" "B.Mask" "B.Paste")
			(net "GND")
			(options
				(clearance outline)
				(anchor circle)
			)
			(primitives
				(gr_poly
					(pts
						(arc
							(start 0.3048 0.2032)
							(mid 0.275042 0.275042)
							(end 0.2032 0.3048)
						)
						(arc
							(start -0.2032 0.3048)
							(mid -0.275042 0.275042)
							(end -0.3048 0.2032)
						)
						(arc
							(start -0.3048 -0.2032)
							(mid -0.275042 -0.275042)
							(end -0.2032 -0.3048)
						)
						(arc
							(start 0.2032 -0.3048)
							(mid 0.275042 -0.275042)
							(end 0.3048 -0.2032)
						)
					)
					(width 0)
					(fill yes)
				)
			)
		)
	)
	(footprint ""
		(layer "B.Cu")
		(at 107.07116 -35.306 90)
		(property "Reference" "SC997"
			(at 0 0 90)
			(layer "B.SilkS")
			(hide yes)
			(effects
				(font
					(size 1.27 1.27)
				)
				(justify mirror)
			)
		)
		(property "Value" "SCD1U16V2KX-3GP"
			(at -1.1811 -2.7051 90)
			(unlocked yes)
			(layer "B.Fab")
			(hide yes)
			(effects
				(font
					(size 1.016 1.016)
					(thickness 0.1524)
				)
				(justify mirror)
			)
		)
		(property "Device Type" "C402H22"
			(at -1.1811 -4.2291 90)
			(unlocked yes)
			(layer "B.Fab")
			(hide yes)
			(effects
				(font
					(size 1.016 1.016)
					(thickness 0.1524)
				)
				(justify mirror)
			)
		)
		(duplicate_pad_numbers_are_jumpers no)
		(fp_rect
			(start 0.4318 0.9525)
			(end -0.4318 -0.9525)
			(stroke
				(width 0)
				(type default)
			)
			(fill no)
			(layer "B.CrtYd")
		)
		(fp_rect
			(start 0.4318 0.9525)
			(end -0.4318 -0.9525)
			(stroke
				(width 0)
				(type default)
			)
			(fill no)
			(layer "B.Fab")
		)
		(pad "1" smd custom
			(at 0 -0.4445 270)
			(size 0.1524 0.1524)
			(layers "B.Cu" "B.Mask" "B.Paste")
			(net "P1V8_C")
			(options
				(clearance outline)
				(anchor circle)
			)
			(primitives
				(gr_poly
					(pts
						(arc
							(start 0.3048 0.2032)
							(mid 0.275042 0.275042)
							(end 0.2032 0.3048)
						)
						(arc
							(start -0.2032 0.3048)
							(mid -0.275042 0.275042)
							(end -0.3048 0.2032)
						)
						(arc
							(start -0.3048 -0.2032)
							(mid -0.275042 -0.275042)
							(end -0.2032 -0.3048)
						)
						(arc
							(start 0.2032 -0.3048)
							(mid 0.275042 -0.275042)
							(end 0.3048 -0.2032)
						)
					)
					(width 0)
					(fill yes)
				)
			)
		)
		(pad "2" smd custom
			(at 0 0.4445 270)
			(size 0.1524 0.1524)
			(layers "B.Cu" "B.Mask" "B.Paste")
			(net "GND")
			(options
				(clearance outline)
				(anchor circle)
			)
			(primitives
				(gr_poly
					(pts
						(arc
							(start 0.3048 0.2032)
							(mid 0.275042 0.275042)
							(end 0.2032 0.3048)
						)
						(arc
							(start -0.2032 0.3048)
							(mid -0.275042 0.275042)
							(end -0.3048 0.2032)
						)
						(arc
							(start -0.3048 -0.2032)
							(mid -0.275042 -0.275042)
							(end -0.2032 -0.3048)
						)
						(arc
							(start 0.2032 -0.3048)
							(mid 0.275042 -0.275042)
							(end 0.3048 -0.2032)
						)
					)
					(width 0)
					(fill yes)
				)
			)
		)
	)
	(footprint ""
		(layer "B.Cu")
		(at 164.338 -89.281)
		(property "Reference" "PC182"
			(at 0 0 0)
			(layer "B.SilkS")
			(hide yes)
			(effects
				(font
					(size 1.27 1.27)
				)
				(justify mirror)
			)
		)
		(property "Value" "SC47U6D3V5MX-1-GP"
			(at 0.0762 -6.1214 0)
			(unlocked yes)
			(layer "B.Fab")
			(hide yes)
			(effects
				(font
					(size 1.016 1.016)
					(thickness 0.1524)
				)
				(justify mirror)
			)
		)
		(property "Device Type" "C805H54"
			(at 0.0762 -8.1534 0)
			(unlocked yes)
			(layer "B.Fab")
			(hide yes)
			(effects
				(font
					(size 1.016 1.016)
					(thickness 0.1524)
				)
				(justify mirror)
			)
		)
		(duplicate_pad_numbers_are_jumpers no)
		(fp_line
			(start -0.635 0)
			(end 0.635 0)
			(stroke
				(width 0.508)
				(type default)
			)
			(layer "B.SilkS")
		)
		(fp_rect
			(start 0.9652 1.778)
			(end -0.9652 -1.778)
			(stroke
				(width 0)
				(type default)
			)
			(fill no)
			(layer "B.CrtYd")
		)
		(fp_poly
			(pts
				(xy 0.9652 -1.778) (xy -0.9652 -1.778) (xy -0.9652 1.778) (xy 0.9652 1.778)
			)
			(stroke
				(width 0)
				(type default)
			)
			(fill no)
			(layer "B.Fab")
		)
		(pad "1" smd rect
			(at 0 -0.9652 180)
			(size 1.397 1.143)
			(layers "B.Cu" "B.Mask" "B.Paste")
			(net "P0V9_E")
		)
		(pad "2" smd rect
			(at 0 0.9652 180)
			(size 1.397 1.143)
			(layers "B.Cu" "B.Mask" "B.Paste")
			(net "GND")
		)
	)
	(footprint ""
		(layer "B.Cu")
		(at 118.37797 -82.931 -90)
		(property "Reference" "SC1223"
			(at 0 0 90)
			(layer "B.SilkS")
			(hide yes)
			(effects
				(font
					(size 1.27 1.27)
				)
				(justify mirror)
			)
		)
		(property "Value" "SCD1U6D3V1KX-GP"
			(at 2.8321 -1.7399 270)
			(unlocked yes)
			(layer "B.Fab")
			(hide yes)
			(effects
				(font
					(size 1.016 1.016)
					(thickness 0.1524)
				)
				(justify mirror)
			)
		)
		(property "Device Type" "C0201H13"
			(at 2.8321 -3.2639 270)
			(unlocked yes)
			(layer "B.Fab")
			(hide yes)
			(effects
				(font
					(size 1.016 1.016)
					(thickness 0.1524)
				)
				(justify mirror)
			)
		)
		(duplicate_pad_numbers_are_jumpers no)
		(fp_rect
			(start 0.2794 0.6477)
			(end -0.2794 -0.6477)
			(stroke
				(width 0)
				(type default)
			)
			(fill no)
			(layer "B.CrtYd")
		)
		(fp_rect
			(start 0.2794 0.6477)
			(end -0.2794 -0.6477)
			(stroke
				(width 0)
				(type default)
			)
			(fill no)
			(layer "B.Fab")
		)
		(pad "1" smd custom
			(at 0 -0.2794 90)
			(size 0.0762 0.0762)
			(layers "B.Cu" "B.Mask" "B.Paste")
			(net "P1V8_E")
			(options
				(clearance outline)
				(anchor circle)
			)
			(primitives
				(gr_poly
					(pts
						(arc
							(start 0.1524 0.127)
							(mid 0.137521 0.162921)
							(end 0.1016 0.1778)
						)
						(arc
							(start -0.1016 0.1778)
							(mid -0.137521 0.162921)
							(end -0.1524 0.127)
						)
						(arc
							(start -0.1524 -0.127)
							(mid -0.137521 -0.162921)
							(end -0.1016 -0.1778)
						)
						(arc
							(start 0.1016 -0.1778)
							(mid 0.137521 -0.162921)
							(end 0.1524 -0.127)
						)
					)
					(width 0)
					(fill yes)
				)
			)
		)
		(pad "2" smd custom
			(at 0 0.2794 90)
			(size 0.0762 0.0762)
			(layers "B.Cu" "B.Mask" "B.Paste")
			(net "GND")
			(options
				(clearance outline)
				(anchor circle)
			)
			(primitives
				(gr_poly
					(pts
						(arc
							(start 0.1524 0.127)
							(mid 0.137521 0.162921)
							(end 0.1016 0.1778)
						)
						(arc
							(start -0.1016 0.1778)
							(mid -0.137521 0.162921)
							(end -0.1524 0.127)
						)
						(arc
							(start -0.1524 -0.127)
							(mid -0.137521 -0.162921)
							(end -0.1016 -0.1778)
						)
						(arc
							(start 0.1016 -0.1778)
							(mid 0.137521 -0.162921)
							(end 0.1524 -0.127)
						)
					)
					(width 0)
					(fill yes)
				)
			)
		)
	)
	(footprint ""
		(layer "B.Cu")
		(at 180.013864 -31.187136 90)
		(property "Reference" "C223"
			(at 0 0 90)
			(layer "B.SilkS")
			(hide yes)
			(effects
				(font
					(size 1.27 1.27)
				)
				(justify mirror)
			)
		)
		(property "Value" "SCD1U16V2KX-3GP"
			(at -1.1811 -2.7051 90)
			(unlocked yes)
			(layer "B.Fab")
			(hide yes)
			(effects
				(font
					(size 1.016 1.016)
					(thickness 0.1524)
				)
				(justify mirror)
			)
		)
		(property "Device Type" "C402H22"
			(at -1.1811 -4.2291 90)
			(unlocked yes)
			(layer "B.Fab")
			(hide yes)
			(effects
				(font
					(size 1.016 1.016)
					(thickness 0.1524)
				)
				(justify mirror)
			)
		)
		(duplicate_pad_numbers_are_jumpers no)
		(fp_rect
			(start 0.4318 0.9525)
			(end -0.4318 -0.9525)
			(stroke
				(width 0)
				(type default)
			)
			(fill no)
			(layer "B.CrtYd")
		)
		(fp_rect
			(start 0.4318 0.9525)
			(end -0.4318 -0.9525)
			(stroke
				(width 0)
				(type default)
			)
			(fill no)
			(layer "B.Fab")
		)
		(pad "1" smd custom
			(at 0 -0.4445 270)
			(size 0.1524 0.1524)
			(layers "B.Cu" "B.Mask" "B.Paste")
			(net "PHY_AVDD")
			(options
				(clearance outline)
				(anchor circle)
			)
			(primitives
				(gr_poly
					(pts
						(arc
							(start 0.3048 0.2032)
							(mid 0.275042 0.275042)
							(end 0.2032 0.3048)
						)
						(arc
							(start -0.2032 0.3048)
							(mid -0.275042 0.275042)
							(end -0.3048 0.2032)
						)
						(arc
							(start -0.3048 -0.2032)
							(mid -0.275042 -0.275042)
							(end -0.2032 -0.3048)
						)
						(arc
							(start 0.2032 -0.3048)
							(mid 0.275042 -0.275042)
							(end 0.3048 -0.2032)
						)
					)
					(width 0)
					(fill yes)
				)
			)
		)
		(pad "2" smd custom
			(at 0 0.4445 270)
			(size 0.1524 0.1524)
			(layers "B.Cu" "B.Mask" "B.Paste")
			(net "GND")
			(options
				(clearance outline)
				(anchor circle)
			)
			(primitives
				(gr_poly
					(pts
						(arc
							(start 0.3048 0.2032)
							(mid 0.275042 0.275042)
							(end 0.2032 0.3048)
						)
						(arc
							(start -0.2032 0.3048)
							(mid -0.275042 0.275042)
							(end -0.3048 0.2032)
						)
						(arc
							(start -0.3048 -0.2032)
							(mid -0.275042 -0.275042)
							(end -0.2032 -0.3048)
						)
						(arc
							(start 0.2032 -0.3048)
							(mid 0.275042 -0.275042)
							(end 0.3048 -0.2032)
						)
					)
					(width 0)
					(fill yes)
				)
			)
		)
	)
	(footprint ""
		(layer "B.Cu")
		(at 108.72216 -33.782)
		(property "Reference" "STP134"
			(at 0 0 0)
			(layer "B.SilkS")
			(hide yes)
			(effects
				(font
					(size 1.27 1.27)
				)
				(justify mirror)
			)
		)
		(property "Value" "TPAD28"
			(at -0.0127 -1.8034 0)
			(unlocked yes)
			(layer "B.Fab")
			(hide yes)
			(effects
				(font
					(size 1.016 1.016)
					(thickness 0.1524)
				)
				(justify mirror)
			)
		)
		(property "Device Type" "TPAD28"
			(at -0.0127 -3.3274 0)
			(unlocked yes)
			(layer "B.Fab")
			(hide yes)
			(effects
				(font
					(size 1.016 1.016)
					(thickness 0.1524)
				)
				(justify mirror)
			)
		)
		(duplicate_pad_numbers_are_jumpers no)
		(fp_poly
			(pts
				(arc
					(start 0.3556 0)
					(mid -0.3556 0)
					(end 0.3556 0)
				)
			)
			(stroke
				(width 0)
				(type default)
			)
			(fill no)
			(layer "B.CrtYd")
		)
		(fp_poly
			(pts
				(arc
					(start 0.6096 0)
					(mid -0.6096 0)
					(end 0.6096 0)
				)
			)
			(stroke
				(width 0)
				(type default)
			)
			(fill no)
			(layer "B.Fab")
		)
		(pad "1" smd circle
			(at 0 0 180)
			(size 0.7112 0.7112)
			(layers "B.Cu" "B.Mask" "B.Paste")
			(net "IOC_GPIO_5")
		)
	)
	(footprint ""
		(layer "B.Cu")
		(at 310.896 -185.674 90)
		(property "Reference" "R303"
			(at 0 0 90)
			(layer "B.SilkS")
			(hide yes)
			(effects
				(font
					(size 1.27 1.27)
				)
				(justify mirror)
			)
		)
		(property "Value" "0R2J-2-GP"
			(at -0.064008 -3.993896 90)
			(unlocked yes)
			(layer "B.Fab")
			(hide yes)
			(effects
				(font
					(size 1.016 1.016)
					(thickness 0.1524)
				)
				(justify mirror)
			)
		)
		(property "Device Type" "R402H16"
			(at -0.064008 -5.517896 90)
			(unlocked yes)
			(layer "B.Fab")
			(hide yes)
			(effects
				(font
					(size 1.016 1.016)
					(thickness 0.1524)
				)
				(justify mirror)
			)
		)
		(duplicate_pad_numbers_are_jumpers no)
		(fp_line
			(start 0.508 -0.9398)
			(end 0.508 0.9398)
			(stroke
				(width 0.1524)
				(type default)
			)
			(layer "B.SilkS")
		)
		(fp_line
			(start -0.508 -0.9398)
			(end 0.508 -0.9398)
			(stroke
				(width 0.1524)
				(type default)
			)
			(layer "B.SilkS")
		)
		(fp_rect
			(start 0.508 0.9398)
			(end -0.508 -0.9398)
			(stroke
				(width 0)
				(type default)
			)
			(fill no)
			(layer "B.CrtYd")
		)
		(fp_rect
			(start 0.508 0.9398)
			(end -0.508 -0.9398)
			(stroke
				(width 0)
				(type default)
			)
			(fill no)
			(layer "B.Fab")
		)
		(pad "1" smd custom
			(at 0 -0.4445 270)
			(size 0.1397 0.1397)
			(layers "B.Cu" "B.Mask" "B.Paste")
			(net "HB0_R_IN1")
			(options
				(clearance outline)
				(anchor circle)
			)
			(primitives
				(gr_poly
					(pts
						(arc
							(start -0.1778 0.2794)
							(mid -0.249642 0.249642)
							(end -0.2794 0.1778)
						)
						(arc
							(start -0.2794 -0.1778)
							(mid -0.249642 -0.249642)
							(end -0.1778 -0.2794)
						)
						(arc
							(start 0.1778 -0.2794)
							(mid 0.249642 -0.249642)
							(end 0.2794 -0.1778)
						)
						(arc
							(start 0.2794 0.1778)
							(mid 0.249642 0.249642)
							(end 0.1778 0.2794)
						)
					)
					(width 0)
					(fill yes)
				)
			)
		)
		(pad "2" smd custom
			(at 0 0.4445 270)
			(size 0.1397 0.1397)
			(layers "B.Cu" "B.Mask" "B.Paste")
			(net "PEER_1A_2A_HB")
			(options
				(clearance outline)
				(anchor circle)
			)
			(primitives
				(gr_poly
					(pts
						(arc
							(start -0.1778 0.2794)
							(mid -0.249642 0.249642)
							(end -0.2794 0.1778)
						)
						(arc
							(start -0.2794 -0.1778)
							(mid -0.249642 -0.249642)
							(end -0.1778 -0.2794)
						)
						(arc
							(start 0.1778 -0.2794)
							(mid 0.249642 -0.249642)
							(end 0.2794 -0.1778)
						)
						(arc
							(start 0.2794 0.1778)
							(mid 0.249642 0.249642)
							(end 0.1778 0.2794)
						)
					)
					(width 0)
					(fill yes)
				)
			)
		)
	)
	(footprint ""
		(layer "B.Cu")
		(at 117.73789 -89.86774)
		(property "Reference" "SC1258"
			(at 0 0 0)
			(layer "B.SilkS")
			(hide yes)
			(effects
				(font
					(size 1.27 1.27)
				)
				(justify mirror)
			)
		)
		(property "Value" "SCD1U6D3V1KX-GP"
			(at 2.8321 -1.7399 0)
			(unlocked yes)
			(layer "B.Fab")
			(hide yes)
			(effects
				(font
					(size 1.016 1.016)
					(thickness 0.1524)
				)
				(justify mirror)
			)
		)
		(property "Device Type" "C0201H13"
			(at 2.8321 -3.2639 0)
			(unlocked yes)
			(layer "B.Fab")
			(hide yes)
			(effects
				(font
					(size 1.016 1.016)
					(thickness 0.1524)
				)
				(justify mirror)
			)
		)
		(duplicate_pad_numbers_are_jumpers no)
		(fp_rect
			(start 0.2794 0.6477)
			(end -0.2794 -0.6477)
			(stroke
				(width 0)
				(type default)
			)
			(fill no)
			(layer "B.CrtYd")
		)
		(fp_rect
			(start 0.2794 0.6477)
			(end -0.2794 -0.6477)
			(stroke
				(width 0)
				(type default)
			)
			(fill no)
			(layer "B.Fab")
		)
		(pad "1" smd custom
			(at 0 -0.2794 180)
			(size 0.0762 0.0762)
			(layers "B.Cu" "B.Mask" "B.Paste")
			(net "P0V9_E")
			(options
				(clearance outline)
				(anchor circle)
			)
			(primitives
				(gr_poly
					(pts
						(arc
							(start 0.1524 0.127)
							(mid 0.137521 0.162921)
							(end 0.1016 0.1778)
						)
						(arc
							(start -0.1016 0.1778)
							(mid -0.137521 0.162921)
							(end -0.1524 0.127)
						)
						(arc
							(start -0.1524 -0.127)
							(mid -0.137521 -0.162921)
							(end -0.1016 -0.1778)
						)
						(arc
							(start 0.1016 -0.1778)
							(mid 0.137521 -0.162921)
							(end 0.1524 -0.127)
						)
					)
					(width 0)
					(fill yes)
				)
			)
		)
		(pad "2" smd custom
			(at 0 0.2794 180)
			(size 0.0762 0.0762)
			(layers "B.Cu" "B.Mask" "B.Paste")
			(net "GND")
			(options
				(clearance outline)
				(anchor circle)
			)
			(primitives
				(gr_poly
					(pts
						(arc
							(start 0.1524 0.127)
							(mid 0.137521 0.162921)
							(end 0.1016 0.1778)
						)
						(arc
							(start -0.1016 0.1778)
							(mid -0.137521 0.162921)
							(end -0.1524 0.127)
						)
						(arc
							(start -0.1524 -0.127)
							(mid -0.137521 -0.162921)
							(end -0.1016 -0.1778)
						)
						(arc
							(start 0.1016 -0.1778)
							(mid 0.137521 -0.162921)
							(end 0.1524 -0.127)
						)
					)
					(width 0)
					(fill yes)
				)
			)
		)
	)
	(footprint ""
		(layer "B.Cu")
		(at 118.218966 -32.258)
		(property "Reference" "STP28"
			(at 0 0 0)
			(layer "B.SilkS")
			(hide yes)
			(effects
				(font
					(size 1.27 1.27)
				)
				(justify mirror)
			)
		)
		(property "Value" "TPAD28"
			(at -0.0127 -1.8034 0)
			(unlocked yes)
			(layer "B.Fab")
			(hide yes)
			(effects
				(font
					(size 1.016 1.016)
					(thickness 0.1524)
				)
				(justify mirror)
			)
		)
		(property "Device Type" "TPAD28"
			(at -0.0127 -3.3274 0)
			(unlocked yes)
			(layer "B.Fab")
			(hide yes)
			(effects
				(font
					(size 1.016 1.016)
					(thickness 0.1524)
				)
				(justify mirror)
			)
		)
		(duplicate_pad_numbers_are_jumpers no)
		(fp_poly
			(pts
				(arc
					(start 0.3556 0)
					(mid -0.3556 0)
					(end 0.3556 0)
				)
			)
			(stroke
				(width 0)
				(type default)
			)
			(fill no)
			(layer "B.CrtYd")
		)
		(fp_poly
			(pts
				(arc
					(start 0.6096 0)
					(mid -0.6096 0)
					(end 0.6096 0)
				)
			)
			(stroke
				(width 0)
				(type default)
			)
			(fill no)
			(layer "B.Fab")
		)
		(pad "1" smd circle
			(at 0 0 180)
			(size 0.7112 0.7112)
			(layers "B.Cu" "B.Mask" "B.Paste")
			(net "UART_SERCLK")
		)
	)
	(footprint ""
		(layer "B.Cu")
		(at 105.264966 -43.307 90)
		(property "Reference" "SC1029"
			(at 0 0 90)
			(layer "B.SilkS")
			(hide yes)
			(effects
				(font
					(size 1.27 1.27)
				)
				(justify mirror)
			)
		)
		(property "Value" "SC1KP50V2KX-1GP"
			(at -1.1811 -2.7051 90)
			(unlocked yes)
			(layer "B.Fab")
			(hide yes)
			(effects
				(font
					(size 1.016 1.016)
					(thickness 0.1524)
				)
				(justify mirror)
			)
		)
		(property "Device Type" "C402H22"
			(at -1.1811 -4.2291 90)
			(unlocked yes)
			(layer "B.Fab")
			(hide yes)
			(effects
				(font
					(size 1.016 1.016)
					(thickness 0.1524)
				)
				(justify mirror)
			)
		)
		(duplicate_pad_numbers_are_jumpers no)
		(fp_rect
			(start 0.4318 0.9525)
			(end -0.4318 -0.9525)
			(stroke
				(width 0)
				(type default)
			)
			(fill no)
			(layer "B.CrtYd")
		)
		(fp_rect
			(start 0.4318 0.9525)
			(end -0.4318 -0.9525)
			(stroke
				(width 0)
				(type default)
			)
			(fill no)
			(layer "B.Fab")
		)
		(pad "1" smd custom
			(at 0 -0.4445 270)
			(size 0.1524 0.1524)
			(layers "B.Cu" "B.Mask" "B.Paste")
			(net "P0V955_C")
			(options
				(clearance outline)
				(anchor circle)
			)
			(primitives
				(gr_poly
					(pts
						(arc
							(start 0.3048 0.2032)
							(mid 0.275042 0.275042)
							(end 0.2032 0.3048)
						)
						(arc
							(start -0.2032 0.3048)
							(mid -0.275042 0.275042)
							(end -0.3048 0.2032)
						)
						(arc
							(start -0.3048 -0.2032)
							(mid -0.275042 -0.275042)
							(end -0.2032 -0.3048)
						)
						(arc
							(start 0.2032 -0.3048)
							(mid 0.275042 -0.275042)
							(end 0.3048 -0.2032)
						)
					)
					(width 0)
					(fill yes)
				)
			)
		)
		(pad "2" smd custom
			(at 0 0.4445 270)
			(size 0.1524 0.1524)
			(layers "B.Cu" "B.Mask" "B.Paste")
			(net "GND")
			(options
				(clearance outline)
				(anchor circle)
			)
			(primitives
				(gr_poly
					(pts
						(arc
							(start 0.3048 0.2032)
							(mid 0.275042 0.275042)
							(end 0.2032 0.3048)
						)
						(arc
							(start -0.2032 0.3048)
							(mid -0.275042 0.275042)
							(end -0.3048 0.2032)
						)
						(arc
							(start -0.3048 -0.2032)
							(mid -0.275042 -0.275042)
							(end -0.2032 -0.3048)
						)
						(arc
							(start 0.2032 -0.3048)
							(mid 0.275042 -0.275042)
							(end 0.3048 -0.2032)
						)
					)
					(width 0)
					(fill yes)
				)
			)
		)
	)
	(footprint ""
		(layer "B.Cu")
		(at 98.305366 -39.0398 180)
		(property "Reference" "SC955"
			(at 0 0 0)
			(layer "B.SilkS")
			(hide yes)
			(effects
				(font
					(size 1.27 1.27)
				)
				(justify mirror)
			)
		)
		(property "Value" "SCD1U6D3V1KX-GP"
			(at 2.8321 -1.7399 180)
			(unlocked yes)
			(layer "B.Fab")
			(hide yes)
			(effects
				(font
					(size 1.016 1.016)
					(thickness 0.1524)
				)
				(justify mirror)
			)
		)
		(property "Device Type" "C0201H13"
			(at 2.8321 -3.2639 180)
			(unlocked yes)
			(layer "B.Fab")
			(hide yes)
			(effects
				(font
					(size 1.016 1.016)
					(thickness 0.1524)
				)
				(justify mirror)
			)
		)
		(duplicate_pad_numbers_are_jumpers no)
		(fp_rect
			(start 0.2794 0.6477)
			(end -0.2794 -0.6477)
			(stroke
				(width 0)
				(type default)
			)
			(fill no)
			(layer "B.CrtYd")
		)
		(fp_rect
			(start 0.2794 0.6477)
			(end -0.2794 -0.6477)
			(stroke
				(width 0)
				(type default)
			)
			(fill no)
			(layer "B.Fab")
		)
		(pad "1" smd custom
			(at 0 -0.2794)
			(size 0.0762 0.0762)
			(layers "B.Cu" "B.Mask" "B.Paste")
			(net "PCE_AVDD")
			(options
				(clearance outline)
				(anchor circle)
			)
			(primitives
				(gr_poly
					(pts
						(arc
							(start 0.1524 0.127)
							(mid 0.137521 0.162921)
							(end 0.1016 0.1778)
						)
						(arc
							(start -0.1016 0.1778)
							(mid -0.137521 0.162921)
							(end -0.1524 0.127)
						)
						(arc
							(start -0.1524 -0.127)
							(mid -0.137521 -0.162921)
							(end -0.1016 -0.1778)
						)
						(arc
							(start 0.1016 -0.1778)
							(mid 0.137521 -0.162921)
							(end 0.1524 -0.127)
						)
					)
					(width 0)
					(fill yes)
				)
			)
		)
		(pad "2" smd custom
			(at 0 0.2794)
			(size 0.0762 0.0762)
			(layers "B.Cu" "B.Mask" "B.Paste")
			(net "GND")
			(options
				(clearance outline)
				(anchor circle)
			)
			(primitives
				(gr_poly
					(pts
						(arc
							(start 0.1524 0.127)
							(mid 0.137521 0.162921)
							(end 0.1016 0.1778)
						)
						(arc
							(start -0.1016 0.1778)
							(mid -0.137521 0.162921)
							(end -0.1524 0.127)
						)
						(arc
							(start -0.1524 -0.127)
							(mid -0.137521 -0.162921)
							(end -0.1016 -0.1778)
						)
						(arc
							(start 0.1016 -0.1778)
							(mid 0.137521 -0.162921)
							(end 0.1524 -0.127)
						)
					)
					(width 0)
					(fill yes)
				)
			)
		)
	)
	(footprint ""
		(layer "B.Cu")
		(at 83.693 -74.295 180)
		(property "Reference" "SR929"
			(at 0 0 0)
			(layer "B.SilkS")
			(hide yes)
			(effects
				(font
					(size 1.27 1.27)
				)
				(justify mirror)
			)
		)
		(property "Value" "0R2J-2-GP"
			(at -0.064008 -3.993896 180)
			(unlocked yes)
			(layer "B.Fab")
			(hide yes)
			(effects
				(font
					(size 1.016 1.016)
					(thickness 0.1524)
				)
				(justify mirror)
			)
		)
		(property "Device Type" "R402H16"
			(at -0.064008 -5.517896 180)
			(unlocked yes)
			(layer "B.Fab")
			(hide yes)
			(effects
				(font
					(size 1.016 1.016)
					(thickness 0.1524)
				)
				(justify mirror)
			)
		)
		(duplicate_pad_numbers_are_jumpers no)
		(fp_line
			(start 0.508 -0.9398)
			(end 0.508 0.9398)
			(stroke
				(width 0.1524)
				(type default)
			)
			(layer "B.SilkS")
		)
		(fp_line
			(start -0.508 -0.9398)
			(end 0.508 -0.9398)
			(stroke
				(width 0.1524)
				(type default)
			)
			(layer "B.SilkS")
		)
		(fp_rect
			(start 0.508 0.9398)
			(end -0.508 -0.9398)
			(stroke
				(width 0)
				(type default)
			)
			(fill no)
			(layer "B.CrtYd")
		)
		(fp_rect
			(start 0.508 0.9398)
			(end -0.508 -0.9398)
			(stroke
				(width 0)
				(type default)
			)
			(fill no)
			(layer "B.Fab")
		)
		(pad "1" smd custom
			(at 0 -0.4445)
			(size 0.1397 0.1397)
			(layers "B.Cu" "B.Mask" "B.Paste")
			(net "PG_STAT")
			(options
				(clearance outline)
				(anchor circle)
			)
			(primitives
				(gr_poly
					(pts
						(arc
							(start -0.1778 0.2794)
							(mid -0.249642 0.249642)
							(end -0.2794 0.1778)
						)
						(arc
							(start -0.2794 -0.1778)
							(mid -0.249642 -0.249642)
							(end -0.1778 -0.2794)
						)
						(arc
							(start 0.1778 -0.2794)
							(mid 0.249642 -0.249642)
							(end 0.2794 -0.1778)
						)
						(arc
							(start 0.2794 0.1778)
							(mid 0.249642 0.249642)
							(end 0.1778 0.2794)
						)
					)
					(width 0)
					(fill yes)
				)
			)
		)
		(pad "2" smd custom
			(at 0 0.4445)
			(size 0.1397 0.1397)
			(layers "B.Cu" "B.Mask" "B.Paste")
			(net "P0V955_C_PG_R")
			(options
				(clearance outline)
				(anchor circle)
			)
			(primitives
				(gr_poly
					(pts
						(arc
							(start -0.1778 0.2794)
							(mid -0.249642 0.249642)
							(end -0.2794 0.1778)
						)
						(arc
							(start -0.2794 -0.1778)
							(mid -0.249642 -0.249642)
							(end -0.1778 -0.2794)
						)
						(arc
							(start 0.1778 -0.2794)
							(mid 0.249642 -0.249642)
							(end 0.2794 -0.1778)
						)
						(arc
							(start 0.2794 0.1778)
							(mid 0.249642 0.249642)
							(end 0.1778 0.2794)
						)
					)
					(width 0)
					(fill yes)
				)
			)
		)
	)
	(footprint ""
		(layer "B.Cu")
		(at 112.78997 -75.438)
		(property "Reference" "SR704"
			(at 0 0 0)
			(layer "B.SilkS")
			(hide yes)
			(effects
				(font
					(size 1.27 1.27)
				)
				(justify mirror)
			)
		)
		(property "Value" "10KR2F-2-GP"
			(at -0.064008 -3.993896 0)
			(unlocked yes)
			(layer "B.Fab")
			(hide yes)
			(effects
				(font
					(size 1.016 1.016)
					(thickness 0.1524)
				)
				(justify mirror)
			)
		)
		(property "Device Type" "R402H16"
			(at -0.064008 -5.517896 0)
			(unlocked yes)
			(layer "B.Fab")
			(hide yes)
			(effects
				(font
					(size 1.016 1.016)
					(thickness 0.1524)
				)
				(justify mirror)
			)
		)
		(duplicate_pad_numbers_are_jumpers no)
		(fp_line
			(start -0.508 -0.9398)
			(end 0.508 -0.9398)
			(stroke
				(width 0.1524)
				(type default)
			)
			(layer "B.SilkS")
		)
		(fp_line
			(start 0.508 -0.9398)
			(end 0.508 0.9398)
			(stroke
				(width 0.1524)
				(type default)
			)
			(layer "B.SilkS")
		)
		(fp_rect
			(start 0.508 0.9398)
			(end -0.508 -0.9398)
			(stroke
				(width 0)
				(type default)
			)
			(fill no)
			(layer "B.CrtYd")
		)
		(fp_rect
			(start 0.508 0.9398)
			(end -0.508 -0.9398)
			(stroke
				(width 0)
				(type default)
			)
			(fill no)
			(layer "B.Fab")
		)
		(pad "1" smd custom
			(at 0 -0.4445 180)
			(size 0.1397 0.1397)
			(layers "B.Cu" "B.Mask" "B.Paste")
			(net "P1V8_E")
			(options
				(clearance outline)
				(anchor circle)
			)
			(primitives
				(gr_poly
					(pts
						(arc
							(start -0.1778 0.2794)
							(mid -0.249642 0.249642)
							(end -0.2794 0.1778)
						)
						(arc
							(start -0.2794 -0.1778)
							(mid -0.249642 -0.249642)
							(end -0.1778 -0.2794)
						)
						(arc
							(start 0.1778 -0.2794)
							(mid 0.249642 -0.249642)
							(end 0.2794 -0.1778)
						)
						(arc
							(start 0.2794 0.1778)
							(mid 0.249642 0.249642)
							(end 0.1778 0.2794)
						)
					)
					(width 0)
					(fill yes)
				)
			)
		)
		(pad "2" smd custom
			(at 0 0.4445 180)
			(size 0.1397 0.1397)
			(layers "B.Cu" "B.Mask" "B.Paste")
			(net "EXP_BLINK_OUT")
			(options
				(clearance outline)
				(anchor circle)
			)
			(primitives
				(gr_poly
					(pts
						(arc
							(start -0.1778 0.2794)
							(mid -0.249642 0.249642)
							(end -0.2794 0.1778)
						)
						(arc
							(start -0.2794 -0.1778)
							(mid -0.249642 -0.249642)
							(end -0.1778 -0.2794)
						)
						(arc
							(start 0.1778 -0.2794)
							(mid 0.249642 -0.249642)
							(end 0.2794 -0.1778)
						)
						(arc
							(start 0.2794 0.1778)
							(mid 0.249642 0.249642)
							(end 0.1778 0.2794)
						)
					)
					(width 0)
					(fill yes)
				)
			)
		)
	)
	(footprint ""
		(layer "B.Cu")
		(at 135.89 -35.179 180)
		(property "Reference" "SQ4"
			(at 0 0 0)
			(layer "B.SilkS")
			(hide yes)
			(effects
				(font
					(size 1.27 1.27)
				)
				(justify mirror)
			)
		)
		(property "Value" "2N7002A-7-GP"
			(at -0.127 -8.9662 180)
			(unlocked yes)
			(layer "B.Fab")
			(hide yes)
			(effects
				(font
					(size 1.016 1.016)
					(thickness 0.1524)
				)
				(justify mirror)
			)
		)
		(property "Device Type" "SOT23DGS2D4H48"
			(at -0.127 -10.4902 180)
			(unlocked yes)
			(layer "B.Fab")
			(hide yes)
			(effects
				(font
					(size 1.016 1.016)
					(thickness 0.1524)
				)
				(justify mirror)
			)
		)
		(duplicate_pad_numbers_are_jumpers no)
		(fp_line
			(start 1.651 1.778)
			(end -1.651 1.778)
			(stroke
				(width 0.1524)
				(type default)
			)
			(layer "B.SilkS")
		)
		(fp_line
			(start 1.651 -1.778)
			(end 1.651 1.778)
			(stroke
				(width 0.1524)
				(type default)
			)
			(layer "B.SilkS")
		)
		(fp_line
			(start -1.651 1.778)
			(end -1.651 -1.778)
			(stroke
				(width 0.1524)
				(type default)
			)
			(layer "B.SilkS")
		)
		(fp_line
			(start -1.651 -1.778)
			(end 1.651 -1.778)
			(stroke
				(width 0.1524)
				(type default)
			)
			(layer "B.SilkS")
		)
		(fp_poly
			(pts
				(xy 1.778 1.8796) (xy 1.778 -1.8796) (xy -1.778 -1.8796) (xy -1.778 1.8796)
			)
			(stroke
				(width 0)
				(type default)
			)
			(fill no)
			(layer "B.CrtYd")
		)
		(fp_poly
			(pts
				(xy 1.778 1.8796) (xy 1.778 -1.8796) (xy -1.778 -1.8796) (xy -1.778 1.8796)
			)
			(stroke
				(width 0)
				(type default)
			)
			(fill no)
			(layer "B.Fab")
		)
		(pad "D" smd custom
			(at 0 -0.9525)
			(size 0.1905 0.1905)
			(layers "B.Cu" "B.Mask" "B.Paste")
			(net "P3V3_STBY_R")
			(options
				(clearance outline)
				(anchor circle)
			)
			(primitives
				(gr_poly
					(pts
						(arc
							(start -0.1778 -0.5715)
							(mid -0.321484 -0.511984)
							(end -0.381 -0.3683)
						)
						(arc
							(start -0.381 0.3683)
							(mid -0.321484 0.511984)
							(end -0.1778 0.5715)
						)
						(arc
							(start 0.1778 0.5715)
							(mid 0.321484 0.511984)
							(end 0.381 0.3683)
						)
						(arc
							(start 0.381 -0.3683)
							(mid 0.321484 -0.511984)
							(end 0.1778 -0.5715)
						)
					)
					(width 0)
					(fill yes)
				)
			)
		)
		(pad "G" smd custom
			(at 0.98425 0.9525)
			(size 0.1905 0.1905)
			(layers "B.Cu" "B.Mask" "B.Paste")
			(net "PMU_PLTRST_R_N")
			(options
				(clearance outline)
				(anchor circle)
			)
			(primitives
				(gr_poly
					(pts
						(arc
							(start -0.1778 -0.5715)
							(mid -0.321484 -0.511984)
							(end -0.381 -0.3683)
						)
						(arc
							(start -0.381 0.3683)
							(mid -0.321484 0.511984)
							(end -0.1778 0.5715)
						)
						(arc
							(start 0.1778 0.5715)
							(mid 0.321484 0.511984)
							(end 0.381 0.3683)
						)
						(arc
							(start 0.381 -0.3683)
							(mid 0.321484 -0.511984)
							(end 0.1778 -0.5715)
						)
					)
					(width 0)
					(fill yes)
				)
			)
		)
		(pad "S" smd custom
			(at -0.98425 0.9525)
			(size 0.1905 0.1905)
			(layers "B.Cu" "B.Mask" "B.Paste")
			(net "GND")
			(options
				(clearance outline)
				(anchor circle)
			)
			(primitives
				(gr_poly
					(pts
						(arc
							(start -0.1778 -0.5715)
							(mid -0.321484 -0.511984)
							(end -0.381 -0.3683)
						)
						(arc
							(start -0.381 0.3683)
							(mid -0.321484 0.511984)
							(end -0.1778 0.5715)
						)
						(arc
							(start 0.1778 0.5715)
							(mid 0.321484 0.511984)
							(end 0.381 0.3683)
						)
						(arc
							(start 0.381 -0.3683)
							(mid 0.321484 -0.511984)
							(end 0.1778 -0.5715)
						)
					)
					(width 0)
					(fill yes)
				)
			)
		)
	)
	(footprint ""
		(layer "B.Cu")
		(at 173.863 -113.284 90)
		(property "Reference" "PR153"
			(at 0 0 90)
			(layer "B.SilkS")
			(hide yes)
			(effects
				(font
					(size 1.27 1.27)
				)
				(justify mirror)
			)
		)
		(property "Value" "0R5J-5-GP"
			(at 0 -8.9535 90)
			(unlocked yes)
			(layer "B.Fab")
			(hide yes)
			(effects
				(font
					(size 1.27 1.016)
					(thickness 0.1524)
				)
				(justify mirror)
			)
		)
		(property "Device Type" "R805H24"
			(at 0 -10.6299 90)
			(unlocked yes)
			(layer "B.Fab")
			(hide yes)
			(effects
				(font
					(size 1.27 1.016)
					(thickness 0.1524)
				)
				(justify mirror)
			)
		)
		(duplicate_pad_numbers_are_jumpers no)
		(fp_line
			(start 0.889 -1.7018)
			(end 0.889 0.2794)
			(stroke
				(width 0.1524)
				(type default)
			)
			(layer "B.SilkS")
		)
		(fp_line
			(start -0.889 -1.7018)
			(end 0.889 -1.7018)
			(stroke
				(width 0.1524)
				(type default)
			)
			(layer "B.SilkS")
		)
		(fp_line
			(start -0.889 -1.7018)
			(end -0.889 -0.381)
			(stroke
				(width 0.1524)
				(type default)
			)
			(layer "B.SilkS")
		)
		(fp_line
			(start 0.889 0.0762)
			(end 0.889 1.7018)
			(stroke
				(width 0.1524)
				(type default)
			)
			(layer "B.SilkS")
		)
		(fp_line
			(start 0.889 1.7018)
			(end -0.889 1.7018)
			(stroke
				(width 0.1524)
				(type default)
			)
			(layer "B.SilkS")
		)
		(fp_line
			(start -0.889 1.7018)
			(end -0.889 -0.508)
			(stroke
				(width 0.1524)
				(type default)
			)
			(layer "B.SilkS")
		)
		(fp_poly
			(pts
				(xy -0.9652 -1.778) (xy -0.9652 1.778) (xy 0.9652 1.778) (xy 0.9652 -1.778)
			)
			(stroke
				(width 0)
				(type default)
			)
			(fill no)
			(layer "B.CrtYd")
		)
		(fp_rect
			(start 0.9652 1.778)
			(end -0.9652 -1.778)
			(stroke
				(width 0)
				(type default)
			)
			(fill no)
			(layer "B.Fab")
		)
		(pad "1" smd rect
			(at 0 -0.9652 270)
			(size 1.397 1.143)
			(layers "B.Cu" "B.Mask" "B.Paste")
			(net "P0V9_E_VBST_RC")
		)
		(pad "2" smd rect
			(at 0 0.9652 270)
			(size 1.397 1.143)
			(layers "B.Cu" "B.Mask" "B.Paste")
			(net "P0V9_E_LX")
		)
	)
	(footprint ""
		(layer "B.Cu")
		(at 101.61016 -31.640018)
		(property "Reference" "SC872"
			(at 0 0 0)
			(layer "B.SilkS")
			(hide yes)
			(effects
				(font
					(size 1.27 1.27)
				)
				(justify mirror)
			)
		)
		(property "Value" "SCD22U6D3V1MX-1-GP"
			(at 2.8321 -1.7399 0)
			(unlocked yes)
			(layer "B.Fab")
			(hide yes)
			(effects
				(font
					(size 1.016 1.016)
					(thickness 0.1524)
				)
				(justify mirror)
			)
		)
		(property "Device Type" "C0201H13"
			(at 2.8321 -3.2639 0)
			(unlocked yes)
			(layer "B.Fab")
			(hide yes)
			(effects
				(font
					(size 1.016 1.016)
					(thickness 0.1524)
				)
				(justify mirror)
			)
		)
		(duplicate_pad_numbers_are_jumpers no)
		(fp_rect
			(start 0.2794 0.6477)
			(end -0.2794 -0.6477)
			(stroke
				(width 0)
				(type default)
			)
			(fill no)
			(layer "B.CrtYd")
		)
		(fp_rect
			(start 0.2794 0.6477)
			(end -0.2794 -0.6477)
			(stroke
				(width 0)
				(type default)
			)
			(fill no)
			(layer "B.Fab")
		)
		(pad "1" smd custom
			(at 0 -0.2794 180)
			(size 0.0762 0.0762)
			(layers "B.Cu" "B.Mask" "B.Paste")
			(net "PCIE_SAS_C_CPU_RX_N5")
			(options
				(clearance outline)
				(anchor circle)
			)
			(primitives
				(gr_poly
					(pts
						(arc
							(start 0.1524 0.127)
							(mid 0.137521 0.162921)
							(end 0.1016 0.1778)
						)
						(arc
							(start -0.1016 0.1778)
							(mid -0.137521 0.162921)
							(end -0.1524 0.127)
						)
						(arc
							(start -0.1524 -0.127)
							(mid -0.137521 -0.162921)
							(end -0.1016 -0.1778)
						)
						(arc
							(start 0.1016 -0.1778)
							(mid 0.137521 -0.162921)
							(end 0.1524 -0.127)
						)
					)
					(width 0)
					(fill yes)
				)
			)
		)
		(pad "2" smd custom
			(at 0 0.2794 180)
			(size 0.0762 0.0762)
			(layers "B.Cu" "B.Mask" "B.Paste")
			(net "PCIE_SAS_CPU_RX_N5")
			(options
				(clearance outline)
				(anchor circle)
			)
			(primitives
				(gr_poly
					(pts
						(arc
							(start 0.1524 0.127)
							(mid 0.137521 0.162921)
							(end 0.1016 0.1778)
						)
						(arc
							(start -0.1016 0.1778)
							(mid -0.137521 0.162921)
							(end -0.1524 0.127)
						)
						(arc
							(start -0.1524 -0.127)
							(mid -0.137521 -0.162921)
							(end -0.1016 -0.1778)
						)
						(arc
							(start 0.1016 -0.1778)
							(mid 0.137521 -0.162921)
							(end 0.1524 -0.127)
						)
					)
					(width 0)
					(fill yes)
				)
			)
		)
	)
	(footprint ""
		(layer "B.Cu")
		(at 101.48697 -108.204)
		(property "Reference" "TP262"
			(at 0 0 0)
			(layer "B.SilkS")
			(hide yes)
			(effects
				(font
					(size 1.27 1.27)
				)
				(justify mirror)
			)
		)
		(property "Value" "TPAD28"
			(at -0.0127 -1.8034 0)
			(unlocked yes)
			(layer "B.Fab")
			(hide yes)
			(effects
				(font
					(size 1.016 1.016)
					(thickness 0.1524)
				)
				(justify mirror)
			)
		)
		(property "Device Type" "TPAD28"
			(at -0.0127 -3.3274 0)
			(unlocked yes)
			(layer "B.Fab")
			(hide yes)
			(effects
				(font
					(size 1.016 1.016)
					(thickness 0.1524)
				)
				(justify mirror)
			)
		)
		(duplicate_pad_numbers_are_jumpers no)
		(fp_poly
			(pts
				(arc
					(start 0.3556 0)
					(mid -0.3556 0)
					(end 0.3556 0)
				)
			)
			(stroke
				(width 0)
				(type default)
			)
			(fill no)
			(layer "B.CrtYd")
		)
		(fp_poly
			(pts
				(arc
					(start 0.6096 0)
					(mid -0.6096 0)
					(end 0.6096 0)
				)
			)
			(stroke
				(width 0)
				(type default)
			)
			(fill no)
			(layer "B.Fab")
		)
		(pad "1" smd circle
			(at 0 0 180)
			(size 0.7112 0.7112)
			(layers "B.Cu" "B.Mask" "B.Paste")
			(net "EXP_SIO_CLK_OUT")
		)
	)
	(footprint ""
		(layer "B.Cu")
		(at 106.353356 -40.3479)
		(property "Reference" "SC1041"
			(at 0 0 0)
			(layer "B.SilkS")
			(hide yes)
			(effects
				(font
					(size 1.27 1.27)
				)
				(justify mirror)
			)
		)
		(property "Value" "SCD1U16V2KX-3GP"
			(at -1.1811 -2.7051 0)
			(unlocked yes)
			(layer "B.Fab")
			(hide yes)
			(effects
				(font
					(size 1.016 1.016)
					(thickness 0.1524)
				)
				(justify mirror)
			)
		)
		(property "Device Type" "C402H22"
			(at -1.1811 -4.2291 0)
			(unlocked yes)
			(layer "B.Fab")
			(hide yes)
			(effects
				(font
					(size 1.016 1.016)
					(thickness 0.1524)
				)
				(justify mirror)
			)
		)
		(duplicate_pad_numbers_are_jumpers no)
		(fp_rect
			(start 0.4318 0.9525)
			(end -0.4318 -0.9525)
			(stroke
				(width 0)
				(type default)
			)
			(fill no)
			(layer "B.CrtYd")
		)
		(fp_rect
			(start 0.4318 0.9525)
			(end -0.4318 -0.9525)
			(stroke
				(width 0)
				(type default)
			)
			(fill no)
			(layer "B.Fab")
		)
		(pad "1" smd custom
			(at 0 -0.4445 180)
			(size 0.1524 0.1524)
			(layers "B.Cu" "B.Mask" "B.Paste")
			(net "P0V955_C")
			(options
				(clearance outline)
				(anchor circle)
			)
			(primitives
				(gr_poly
					(pts
						(arc
							(start 0.3048 0.2032)
							(mid 0.275042 0.275042)
							(end 0.2032 0.3048)
						)
						(arc
							(start -0.2032 0.3048)
							(mid -0.275042 0.275042)
							(end -0.3048 0.2032)
						)
						(arc
							(start -0.3048 -0.2032)
							(mid -0.275042 -0.275042)
							(end -0.2032 -0.3048)
						)
						(arc
							(start 0.2032 -0.3048)
							(mid 0.275042 -0.275042)
							(end 0.3048 -0.2032)
						)
					)
					(width 0)
					(fill yes)
				)
			)
		)
		(pad "2" smd custom
			(at 0 0.4445 180)
			(size 0.1524 0.1524)
			(layers "B.Cu" "B.Mask" "B.Paste")
			(net "GND")
			(options
				(clearance outline)
				(anchor circle)
			)
			(primitives
				(gr_poly
					(pts
						(arc
							(start 0.3048 0.2032)
							(mid 0.275042 0.275042)
							(end 0.2032 0.3048)
						)
						(arc
							(start -0.2032 0.3048)
							(mid -0.275042 0.275042)
							(end -0.3048 0.2032)
						)
						(arc
							(start -0.3048 -0.2032)
							(mid -0.275042 -0.275042)
							(end -0.2032 -0.3048)
						)
						(arc
							(start 0.2032 -0.3048)
							(mid 0.275042 -0.275042)
							(end 0.3048 -0.2032)
						)
					)
					(width 0)
					(fill yes)
				)
			)
		)
	)
	(footprint ""
		(layer "B.Cu")
		(at 121.412 -47.302674 90)
		(property "Reference" "SR583"
			(at 0 0 90)
			(layer "B.SilkS")
			(hide yes)
			(effects
				(font
					(size 1.27 1.27)
				)
				(justify mirror)
			)
		)
		(property "Value" "10KR2F-2-GP"
			(at -0.064008 -3.993896 90)
			(unlocked yes)
			(layer "B.Fab")
			(hide yes)
			(effects
				(font
					(size 1.016 1.016)
					(thickness 0.1524)
				)
				(justify mirror)
			)
		)
		(property "Device Type" "R402H16"
			(at -0.064008 -5.517896 90)
			(unlocked yes)
			(layer "B.Fab")
			(hide yes)
			(effects
				(font
					(size 1.016 1.016)
					(thickness 0.1524)
				)
				(justify mirror)
			)
		)
		(duplicate_pad_numbers_are_jumpers no)
		(fp_line
			(start 0.508 -0.9398)
			(end 0.508 0.9398)
			(stroke
				(width 0.1524)
				(type default)
			)
			(layer "B.SilkS")
		)
		(fp_line
			(start -0.508 -0.9398)
			(end 0.508 -0.9398)
			(stroke
				(width 0.1524)
				(type default)
			)
			(layer "B.SilkS")
		)
		(fp_rect
			(start 0.508 0.9398)
			(end -0.508 -0.9398)
			(stroke
				(width 0)
				(type default)
			)
			(fill no)
			(layer "B.CrtYd")
		)
		(fp_rect
			(start 0.508 0.9398)
			(end -0.508 -0.9398)
			(stroke
				(width 0)
				(type default)
			)
			(fill no)
			(layer "B.Fab")
		)
		(pad "1" smd custom
			(at 0 -0.4445 270)
			(size 0.1397 0.1397)
			(layers "B.Cu" "B.Mask" "B.Paste")
			(net "IOC_CLK_SEL0")
			(options
				(clearance outline)
				(anchor circle)
			)
			(primitives
				(gr_poly
					(pts
						(arc
							(start -0.1778 0.2794)
							(mid -0.249642 0.249642)
							(end -0.2794 0.1778)
						)
						(arc
							(start -0.2794 -0.1778)
							(mid -0.249642 -0.249642)
							(end -0.1778 -0.2794)
						)
						(arc
							(start 0.1778 -0.2794)
							(mid 0.249642 -0.249642)
							(end 0.2794 -0.1778)
						)
						(arc
							(start 0.2794 0.1778)
							(mid 0.249642 0.249642)
							(end 0.1778 0.2794)
						)
					)
					(width 0)
					(fill yes)
				)
			)
		)
		(pad "2" smd custom
			(at 0 0.4445 270)
			(size 0.1397 0.1397)
			(layers "B.Cu" "B.Mask" "B.Paste")
			(net "P1V8_C")
			(options
				(clearance outline)
				(anchor circle)
			)
			(primitives
				(gr_poly
					(pts
						(arc
							(start -0.1778 0.2794)
							(mid -0.249642 0.249642)
							(end -0.2794 0.1778)
						)
						(arc
							(start -0.2794 -0.1778)
							(mid -0.249642 -0.249642)
							(end -0.1778 -0.2794)
						)
						(arc
							(start 0.1778 -0.2794)
							(mid 0.249642 -0.249642)
							(end 0.2794 -0.1778)
						)
						(arc
							(start 0.2794 0.1778)
							(mid 0.249642 0.249642)
							(end 0.1778 0.2794)
						)
					)
					(width 0)
					(fill yes)
				)
			)
		)
	)
	(footprint ""
		(layer "B.Cu")
		(at 271.907 -35.687 90)
		(property "Reference" "PC47"
			(at 0 0 90)
			(layer "B.SilkS")
			(hide yes)
			(effects
				(font
					(size 1.27 1.27)
				)
				(justify mirror)
			)
		)
		(property "Value" "SCD1U50V3KX-GP"
			(at 0 -2.8194 90)
			(unlocked yes)
			(layer "B.Fab")
			(hide yes)
			(effects
				(font
					(size 1.016 1.016)
					(thickness 0.1524)
				)
				(justify mirror)
			)
		)
		(property "Device Type" "C603H36"
			(at 0 -4.3434 90)
			(unlocked yes)
			(layer "B.Fab")
			(hide yes)
			(effects
				(font
					(size 1.016 1.016)
					(thickness 0.1524)
				)
				(justify mirror)
			)
		)
		(duplicate_pad_numbers_are_jumpers no)
		(fp_line
			(start -0.508 0)
			(end 0.508 0)
			(stroke
				(width 0.2032)
				(type default)
			)
			(layer "B.SilkS")
		)
		(fp_rect
			(start 0.5842 1.3335)
			(end -0.5842 -1.3335)
			(stroke
				(width 0)
				(type default)
			)
			(fill no)
			(layer "B.CrtYd")
		)
		(fp_rect
			(start 0.5842 1.3335)
			(end -0.5842 -1.3335)
			(stroke
				(width 0)
				(type default)
			)
			(fill no)
			(layer "B.Fab")
		)
		(pad "1" smd custom
			(at 0 -0.762 270)
			(size 0.2159 0.2159)
			(layers "B.Cu" "B.Mask" "B.Paste")
			(net "P1V8_STBY_VBST_RC")
			(options
				(clearance outline)
				(anchor circle)
			)
			(primitives
				(gr_poly
					(pts
						(arc
							(start -0.3302 0.4318)
							(mid -0.402042 0.402042)
							(end -0.4318 0.3302)
						)
						(arc
							(start -0.4318 -0.3302)
							(mid -0.402042 -0.402042)
							(end -0.3302 -0.4318)
						)
						(arc
							(start 0.3302 -0.4318)
							(mid 0.402042 -0.402042)
							(end 0.4318 -0.3302)
						)
						(arc
							(start 0.4318 0.3302)
							(mid 0.402042 0.402042)
							(end 0.3302 0.4318)
						)
					)
					(width 0)
					(fill yes)
				)
			)
		)
		(pad "2" smd custom
			(at 0 0.762 270)
			(size 0.2159 0.2159)
			(layers "B.Cu" "B.Mask" "B.Paste")
			(net "P1V8_STBY_LL")
			(options
				(clearance outline)
				(anchor circle)
			)
			(primitives
				(gr_poly
					(pts
						(arc
							(start -0.3302 0.4318)
							(mid -0.402042 0.402042)
							(end -0.4318 0.3302)
						)
						(arc
							(start -0.4318 -0.3302)
							(mid -0.402042 -0.402042)
							(end -0.3302 -0.4318)
						)
						(arc
							(start 0.3302 -0.4318)
							(mid 0.402042 -0.402042)
							(end 0.4318 -0.3302)
						)
						(arc
							(start 0.4318 0.3302)
							(mid 0.402042 0.402042)
							(end 0.3302 0.4318)
						)
					)
					(width 0)
					(fill yes)
				)
			)
		)
	)
	(footprint ""
		(layer "B.Cu")
		(at 161.417 -89.154)
		(property "Reference" "PC177"
			(at 0 0 0)
			(layer "B.SilkS")
			(hide yes)
			(effects
				(font
					(size 1.27 1.27)
				)
				(justify mirror)
			)
		)
		(property "Value" "SC22U6D3V3MX-1-GP"
			(at 0 -2.8194 0)
			(unlocked yes)
			(layer "B.Fab")
			(hide yes)
			(effects
				(font
					(size 1.016 1.016)
					(thickness 0.1524)
				)
				(justify mirror)
			)
		)
		(property "Device Type" "C603H40"
			(at 0 -4.3434 0)
			(unlocked yes)
			(layer "B.Fab")
			(hide yes)
			(effects
				(font
					(size 1.016 1.016)
					(thickness 0.1524)
				)
				(justify mirror)
			)
		)
		(duplicate_pad_numbers_are_jumpers no)
		(fp_line
			(start -0.508 0)
			(end 0.508 0)
			(stroke
				(width 0.2032)
				(type default)
			)
			(layer "B.SilkS")
		)
		(fp_rect
			(start 0.5842 1.3335)
			(end -0.5842 -1.3335)
			(stroke
				(width 0)
				(type default)
			)
			(fill no)
			(layer "B.CrtYd")
		)
		(fp_rect
			(start 0.5842 1.3335)
			(end -0.5842 -1.3335)
			(stroke
				(width 0)
				(type default)
			)
			(fill no)
			(layer "B.Fab")
		)
		(pad "1" smd custom
			(at 0 -0.762 180)
			(size 0.2159 0.2159)
			(layers "B.Cu" "B.Mask" "B.Paste")
			(net "P0V9_E")
			(options
				(clearance outline)
				(anchor circle)
			)
			(primitives
				(gr_poly
					(pts
						(arc
							(start -0.3302 0.4318)
							(mid -0.402042 0.402042)
							(end -0.4318 0.3302)
						)
						(arc
							(start -0.4318 -0.3302)
							(mid -0.402042 -0.402042)
							(end -0.3302 -0.4318)
						)
						(arc
							(start 0.3302 -0.4318)
							(mid 0.402042 -0.402042)
							(end 0.4318 -0.3302)
						)
						(arc
							(start 0.4318 0.3302)
							(mid 0.402042 0.402042)
							(end 0.3302 0.4318)
						)
					)
					(width 0)
					(fill yes)
				)
			)
		)
		(pad "2" smd custom
			(at 0 0.762 180)
			(size 0.2159 0.2159)
			(layers "B.Cu" "B.Mask" "B.Paste")
			(net "GND")
			(options
				(clearance outline)
				(anchor circle)
			)
			(primitives
				(gr_poly
					(pts
						(arc
							(start -0.3302 0.4318)
							(mid -0.402042 0.402042)
							(end -0.4318 0.3302)
						)
						(arc
							(start -0.4318 -0.3302)
							(mid -0.402042 -0.402042)
							(end -0.3302 -0.4318)
						)
						(arc
							(start 0.3302 -0.4318)
							(mid 0.402042 -0.402042)
							(end 0.4318 -0.3302)
						)
						(arc
							(start 0.4318 0.3302)
							(mid 0.402042 0.402042)
							(end 0.3302 0.4318)
						)
					)
					(width 0)
					(fill yes)
				)
			)
		)
	)
	(footprint ""
		(layer "B.Cu")
		(at 108.020612 -212.725 -90)
		(property "Reference" "SR902"
			(at 0 0 90)
			(layer "B.SilkS")
			(hide yes)
			(effects
				(font
					(size 1.27 1.27)
				)
				(justify mirror)
			)
		)
		(property "Value" "4K7R2F-GP"
			(at -0.064008 -3.993896 270)
			(unlocked yes)
			(layer "B.Fab")
			(hide yes)
			(effects
				(font
					(size 1.016 1.016)
					(thickness 0.1524)
				)
				(justify mirror)
			)
		)
		(property "Device Type" "R402H16"
			(at -0.064008 -5.517896 270)
			(unlocked yes)
			(layer "B.Fab")
			(hide yes)
			(effects
				(font
					(size 1.016 1.016)
					(thickness 0.1524)
				)
				(justify mirror)
			)
		)
		(duplicate_pad_numbers_are_jumpers no)
		(fp_line
			(start -0.508 -0.9398)
			(end 0.508 -0.9398)
			(stroke
				(width 0.1524)
				(type default)
			)
			(layer "B.SilkS")
		)
		(fp_line
			(start 0.508 -0.9398)
			(end 0.508 0.9398)
			(stroke
				(width 0.1524)
				(type default)
			)
			(layer "B.SilkS")
		)
		(fp_rect
			(start 0.508 0.9398)
			(end -0.508 -0.9398)
			(stroke
				(width 0)
				(type default)
			)
			(fill no)
			(layer "B.CrtYd")
		)
		(fp_rect
			(start 0.508 0.9398)
			(end -0.508 -0.9398)
			(stroke
				(width 0)
				(type default)
			)
			(fill no)
			(layer "B.Fab")
		)
		(pad "1" smd custom
			(at 0 -0.4445 90)
			(size 0.1397 0.1397)
			(layers "B.Cu" "B.Mask" "B.Paste")
			(net "REDV_I2C_A4")
			(options
				(clearance outline)
				(anchor circle)
			)
			(primitives
				(gr_poly
					(pts
						(arc
							(start -0.1778 0.2794)
							(mid -0.249642 0.249642)
							(end -0.2794 0.1778)
						)
						(arc
							(start -0.2794 -0.1778)
							(mid -0.249642 -0.249642)
							(end -0.1778 -0.2794)
						)
						(arc
							(start 0.1778 -0.2794)
							(mid 0.249642 -0.249642)
							(end 0.2794 -0.1778)
						)
						(arc
							(start 0.2794 0.1778)
							(mid 0.249642 0.249642)
							(end 0.1778 0.2794)
						)
					)
					(width 0)
					(fill yes)
				)
			)
		)
		(pad "2" smd custom
			(at 0 0.4445 90)
			(size 0.1397 0.1397)
			(layers "B.Cu" "B.Mask" "B.Paste")
			(net "GND")
			(options
				(clearance outline)
				(anchor circle)
			)
			(primitives
				(gr_poly
					(pts
						(arc
							(start -0.1778 0.2794)
							(mid -0.249642 0.249642)
							(end -0.2794 0.1778)
						)
						(arc
							(start -0.2794 -0.1778)
							(mid -0.249642 -0.249642)
							(end -0.1778 -0.2794)
						)
						(arc
							(start 0.1778 -0.2794)
							(mid 0.249642 -0.249642)
							(end 0.2794 -0.1778)
						)
						(arc
							(start 0.2794 0.1778)
							(mid 0.249642 0.249642)
							(end 0.1778 0.2794)
						)
					)
					(width 0)
					(fill yes)
				)
			)
		)
	)
	(footprint ""
		(layer "B.Cu")
		(at 102.75697 -104.648)
		(property "Reference" "STP90"
			(at 0 0 0)
			(layer "B.SilkS")
			(hide yes)
			(effects
				(font
					(size 1.27 1.27)
				)
				(justify mirror)
			)
		)
		(property "Value" "TPAD28"
			(at -0.0127 -1.8034 0)
			(unlocked yes)
			(layer "B.Fab")
			(hide yes)
			(effects
				(font
					(size 1.016 1.016)
					(thickness 0.1524)
				)
				(justify mirror)
			)
		)
		(property "Device Type" "TPAD28"
			(at -0.0127 -3.3274 0)
			(unlocked yes)
			(layer "B.Fab")
			(hide yes)
			(effects
				(font
					(size 1.016 1.016)
					(thickness 0.1524)
				)
				(justify mirror)
			)
		)
		(duplicate_pad_numbers_are_jumpers no)
		(fp_poly
			(pts
				(arc
					(start 0.3556 0)
					(mid -0.3556 0)
					(end 0.3556 0)
				)
			)
			(stroke
				(width 0)
				(type default)
			)
			(fill no)
			(layer "B.CrtYd")
		)
		(fp_poly
			(pts
				(arc
					(start 0.6096 0)
					(mid -0.6096 0)
					(end 0.6096 0)
				)
			)
			(stroke
				(width 0)
				(type default)
			)
			(fill no)
			(layer "B.Fab")
		)
		(pad "1" smd circle
			(at 0 0 180)
			(size 0.7112 0.7112)
			(layers "B.Cu" "B.Mask" "B.Paste")
			(net "PHY_CLK")
		)
	)
	(footprint ""
		(layer "B.Cu")
		(at 97.03816 -31.623)
		(property "Reference" "SC866"
			(at 0 0 0)
			(layer "B.SilkS")
			(hide yes)
			(effects
				(font
					(size 1.27 1.27)
				)
				(justify mirror)
			)
		)
		(property "Value" "SCD22U6D3V1MX-1-GP"
			(at 2.8321 -1.7399 0)
			(unlocked yes)
			(layer "B.Fab")
			(hide yes)
			(effects
				(font
					(size 1.016 1.016)
					(thickness 0.1524)
				)
				(justify mirror)
			)
		)
		(property "Device Type" "C0201H13"
			(at 2.8321 -3.2639 0)
			(unlocked yes)
			(layer "B.Fab")
			(hide yes)
			(effects
				(font
					(size 1.016 1.016)
					(thickness 0.1524)
				)
				(justify mirror)
			)
		)
		(duplicate_pad_numbers_are_jumpers no)
		(fp_rect
			(start 0.2794 0.6477)
			(end -0.2794 -0.6477)
			(stroke
				(width 0)
				(type default)
			)
			(fill no)
			(layer "B.CrtYd")
		)
		(fp_rect
			(start 0.2794 0.6477)
			(end -0.2794 -0.6477)
			(stroke
				(width 0)
				(type default)
			)
			(fill no)
			(layer "B.Fab")
		)
		(pad "1" smd custom
			(at 0 -0.2794 180)
			(size 0.0762 0.0762)
			(layers "B.Cu" "B.Mask" "B.Paste")
			(net "PCIE_SAS_C_CPU_RX_N2")
			(options
				(clearance outline)
				(anchor circle)
			)
			(primitives
				(gr_poly
					(pts
						(arc
							(start 0.1524 0.127)
							(mid 0.137521 0.162921)
							(end 0.1016 0.1778)
						)
						(arc
							(start -0.1016 0.1778)
							(mid -0.137521 0.162921)
							(end -0.1524 0.127)
						)
						(arc
							(start -0.1524 -0.127)
							(mid -0.137521 -0.162921)
							(end -0.1016 -0.1778)
						)
						(arc
							(start 0.1016 -0.1778)
							(mid 0.137521 -0.162921)
							(end 0.1524 -0.127)
						)
					)
					(width 0)
					(fill yes)
				)
			)
		)
		(pad "2" smd custom
			(at 0 0.2794 180)
			(size 0.0762 0.0762)
			(layers "B.Cu" "B.Mask" "B.Paste")
			(net "PCIE_SAS_CPU_RX_N2")
			(options
				(clearance outline)
				(anchor circle)
			)
			(primitives
				(gr_poly
					(pts
						(arc
							(start 0.1524 0.127)
							(mid 0.137521 0.162921)
							(end 0.1016 0.1778)
						)
						(arc
							(start -0.1016 0.1778)
							(mid -0.137521 0.162921)
							(end -0.1524 0.127)
						)
						(arc
							(start -0.1524 -0.127)
							(mid -0.137521 -0.162921)
							(end -0.1016 -0.1778)
						)
						(arc
							(start 0.1016 -0.1778)
							(mid 0.137521 -0.162921)
							(end 0.1524 -0.127)
						)
					)
					(width 0)
					(fill yes)
				)
			)
		)
	)
	(footprint ""
		(layer "B.Cu")
		(at 295.021 -178.943 -90)
		(property "Reference" "C211"
			(at 0 0 90)
			(layer "B.SilkS")
			(hide yes)
			(effects
				(font
					(size 1.27 1.27)
				)
				(justify mirror)
			)
		)
		(property "Value" "SC220P50V2KX-3GP"
			(at -1.1811 -2.7051 270)
			(unlocked yes)
			(layer "B.Fab")
			(hide yes)
			(effects
				(font
					(size 1.016 1.016)
					(thickness 0.1524)
				)
				(justify mirror)
			)
		)
		(property "Device Type" "C402H22"
			(at -1.1811 -4.2291 270)
			(unlocked yes)
			(layer "B.Fab")
			(hide yes)
			(effects
				(font
					(size 1.016 1.016)
					(thickness 0.1524)
				)
				(justify mirror)
			)
		)
		(duplicate_pad_numbers_are_jumpers no)
		(fp_rect
			(start 0.4318 0.9525)
			(end -0.4318 -0.9525)
			(stroke
				(width 0)
				(type default)
			)
			(fill no)
			(layer "B.CrtYd")
		)
		(fp_rect
			(start 0.4318 0.9525)
			(end -0.4318 -0.9525)
			(stroke
				(width 0)
				(type default)
			)
			(fill no)
			(layer "B.Fab")
		)
		(pad "1" smd custom
			(at 0 -0.4445 90)
			(size 0.1524 0.1524)
			(layers "B.Cu" "B.Mask" "B.Paste")
			(net "P3V3_STBY")
			(options
				(clearance outline)
				(anchor circle)
			)
			(primitives
				(gr_poly
					(pts
						(arc
							(start 0.3048 0.2032)
							(mid 0.275042 0.275042)
							(end 0.2032 0.3048)
						)
						(arc
							(start -0.2032 0.3048)
							(mid -0.275042 0.275042)
							(end -0.3048 0.2032)
						)
						(arc
							(start -0.3048 -0.2032)
							(mid -0.275042 -0.275042)
							(end -0.2032 -0.3048)
						)
						(arc
							(start 0.2032 -0.3048)
							(mid 0.275042 -0.275042)
							(end 0.3048 -0.2032)
						)
					)
					(width 0)
					(fill yes)
				)
			)
		)
		(pad "2" smd custom
			(at 0 0.4445 90)
			(size 0.1524 0.1524)
			(layers "B.Cu" "B.Mask" "B.Paste")
			(net "GND")
			(options
				(clearance outline)
				(anchor circle)
			)
			(primitives
				(gr_poly
					(pts
						(arc
							(start 0.3048 0.2032)
							(mid 0.275042 0.275042)
							(end 0.2032 0.3048)
						)
						(arc
							(start -0.2032 0.3048)
							(mid -0.275042 0.275042)
							(end -0.3048 0.2032)
						)
						(arc
							(start -0.3048 -0.2032)
							(mid -0.275042 -0.275042)
							(end -0.2032 -0.3048)
						)
						(arc
							(start 0.2032 -0.3048)
							(mid 0.275042 -0.275042)
							(end 0.3048 -0.2032)
						)
					)
					(width 0)
					(fill yes)
				)
			)
		)
	)
	(footprint ""
		(layer "B.Cu")
		(at 318.008 -167.894 -90)
		(property "Reference" "R246"
			(at 0 0 90)
			(layer "B.SilkS")
			(hide yes)
			(effects
				(font
					(size 1.27 1.27)
				)
				(justify mirror)
			)
		)
		(property "Value" "0R2J-2-GP"
			(at -0.064008 -3.993896 270)
			(unlocked yes)
			(layer "B.Fab")
			(hide yes)
			(effects
				(font
					(size 1.016 1.016)
					(thickness 0.1524)
				)
				(justify mirror)
			)
		)
		(property "Device Type" "R402H16"
			(at -0.064008 -5.517896 270)
			(unlocked yes)
			(layer "B.Fab")
			(hide yes)
			(effects
				(font
					(size 1.016 1.016)
					(thickness 0.1524)
				)
				(justify mirror)
			)
		)
		(duplicate_pad_numbers_are_jumpers no)
		(fp_line
			(start -0.508 -0.9398)
			(end 0.508 -0.9398)
			(stroke
				(width 0.1524)
				(type default)
			)
			(layer "B.SilkS")
		)
		(fp_line
			(start 0.508 -0.9398)
			(end 0.508 0.9398)
			(stroke
				(width 0.1524)
				(type default)
			)
			(layer "B.SilkS")
		)
		(fp_rect
			(start 0.508 0.9398)
			(end -0.508 -0.9398)
			(stroke
				(width 0)
				(type default)
			)
			(fill no)
			(layer "B.CrtYd")
		)
		(fp_rect
			(start 0.508 0.9398)
			(end -0.508 -0.9398)
			(stroke
				(width 0)
				(type default)
			)
			(fill no)
			(layer "B.Fab")
		)
		(pad "1" smd custom
			(at 0 -0.4445 90)
			(size 0.1397 0.1397)
			(layers "B.Cu" "B.Mask" "B.Paste")
			(net "BMC_I2C_A_SCL")
			(options
				(clearance outline)
				(anchor circle)
			)
			(primitives
				(gr_poly
					(pts
						(arc
							(start -0.1778 0.2794)
							(mid -0.249642 0.249642)
							(end -0.2794 0.1778)
						)
						(arc
							(start -0.2794 -0.1778)
							(mid -0.249642 -0.249642)
							(end -0.1778 -0.2794)
						)
						(arc
							(start 0.1778 -0.2794)
							(mid 0.249642 -0.249642)
							(end 0.2794 -0.1778)
						)
						(arc
							(start 0.2794 0.1778)
							(mid 0.249642 0.249642)
							(end 0.1778 0.2794)
						)
					)
					(width 0)
					(fill yes)
				)
			)
		)
		(pad "2" smd custom
			(at 0 0.4445 90)
			(size 0.1397 0.1397)
			(layers "B.Cu" "B.Mask" "B.Paste")
			(net "BMC0_SMB5_CLK")
			(options
				(clearance outline)
				(anchor circle)
			)
			(primitives
				(gr_poly
					(pts
						(arc
							(start -0.1778 0.2794)
							(mid -0.249642 0.249642)
							(end -0.2794 0.1778)
						)
						(arc
							(start -0.2794 -0.1778)
							(mid -0.249642 -0.249642)
							(end -0.1778 -0.2794)
						)
						(arc
							(start 0.1778 -0.2794)
							(mid 0.249642 -0.249642)
							(end 0.2794 -0.1778)
						)
						(arc
							(start 0.2794 0.1778)
							(mid 0.249642 0.249642)
							(end 0.1778 0.2794)
						)
					)
					(width 0)
					(fill yes)
				)
			)
		)
	)
	(footprint ""
		(layer "B.Cu")
		(at 324.358 -175.006 180)
		(property "Reference" "R5766"
			(at 0 0 0)
			(layer "B.SilkS")
			(hide yes)
			(effects
				(font
					(size 1.27 1.27)
				)
				(justify mirror)
			)
		)
		(property "Value" "1KR2F-3-GP"
			(at -0.064008 -3.993896 180)
			(unlocked yes)
			(layer "B.Fab")
			(hide yes)
			(effects
				(font
					(size 1.016 1.016)
					(thickness 0.1524)
				)
				(justify mirror)
			)
		)
		(property "Device Type" "R402H16"
			(at -0.064008 -5.517896 180)
			(unlocked yes)
			(layer "B.Fab")
			(hide yes)
			(effects
				(font
					(size 1.016 1.016)
					(thickness 0.1524)
				)
				(justify mirror)
			)
		)
		(duplicate_pad_numbers_are_jumpers no)
		(fp_line
			(start 0.508 -0.9398)
			(end 0.508 0.9398)
			(stroke
				(width 0.1524)
				(type default)
			)
			(layer "B.SilkS")
		)
		(fp_line
			(start -0.508 -0.9398)
			(end 0.508 -0.9398)
			(stroke
				(width 0.1524)
				(type default)
			)
			(layer "B.SilkS")
		)
		(fp_rect
			(start 0.508 0.9398)
			(end -0.508 -0.9398)
			(stroke
				(width 0)
				(type default)
			)
			(fill no)
			(layer "B.CrtYd")
		)
		(fp_rect
			(start 0.508 0.9398)
			(end -0.508 -0.9398)
			(stroke
				(width 0)
				(type default)
			)
			(fill no)
			(layer "B.Fab")
		)
		(pad "1" smd custom
			(at 0 -0.4445)
			(size 0.1397 0.1397)
			(layers "B.Cu" "B.Mask" "B.Paste")
			(net "ADC_12V")
			(options
				(clearance outline)
				(anchor circle)
			)
			(primitives
				(gr_poly
					(pts
						(arc
							(start -0.1778 0.2794)
							(mid -0.249642 0.249642)
							(end -0.2794 0.1778)
						)
						(arc
							(start -0.2794 -0.1778)
							(mid -0.249642 -0.249642)
							(end -0.1778 -0.2794)
						)
						(arc
							(start 0.1778 -0.2794)
							(mid 0.249642 -0.249642)
							(end 0.2794 -0.1778)
						)
						(arc
							(start 0.2794 0.1778)
							(mid 0.249642 0.249642)
							(end 0.1778 0.2794)
						)
					)
					(width 0)
					(fill yes)
				)
			)
		)
		(pad "2" smd custom
			(at 0 0.4445)
			(size 0.1397 0.1397)
			(layers "B.Cu" "B.Mask" "B.Paste")
			(net "GND")
			(options
				(clearance outline)
				(anchor circle)
			)
			(primitives
				(gr_poly
					(pts
						(arc
							(start -0.1778 0.2794)
							(mid -0.249642 0.249642)
							(end -0.2794 0.1778)
						)
						(arc
							(start -0.2794 -0.1778)
							(mid -0.249642 -0.249642)
							(end -0.1778 -0.2794)
						)
						(arc
							(start 0.1778 -0.2794)
							(mid 0.249642 -0.249642)
							(end 0.2794 -0.1778)
						)
						(arc
							(start 0.2794 0.1778)
							(mid 0.249642 0.249642)
							(end 0.1778 0.2794)
						)
					)
					(width 0)
					(fill yes)
				)
			)
		)
	)
	(footprint ""
		(layer "B.Cu")
		(at 289.24504 -170.57624)
		(property "Reference" "TP137"
			(at 0 0 0)
			(layer "B.SilkS")
			(hide yes)
			(effects
				(font
					(size 1.27 1.27)
				)
				(justify mirror)
			)
		)
		(property "Value" "TPAD28"
			(at -0.0127 -1.8034 0)
			(unlocked yes)
			(layer "B.Fab")
			(hide yes)
			(effects
				(font
					(size 1.016 1.016)
					(thickness 0.1524)
				)
				(justify mirror)
			)
		)
		(property "Device Type" "TPAD28"
			(at -0.0127 -3.3274 0)
			(unlocked yes)
			(layer "B.Fab")
			(hide yes)
			(effects
				(font
					(size 1.016 1.016)
					(thickness 0.1524)
				)
				(justify mirror)
			)
		)
		(duplicate_pad_numbers_are_jumpers no)
		(fp_poly
			(pts
				(arc
					(start 0.3556 0)
					(mid -0.3556 0)
					(end 0.3556 0)
				)
			)
			(stroke
				(width 0)
				(type default)
			)
			(fill no)
			(layer "B.CrtYd")
		)
		(fp_poly
			(pts
				(arc
					(start 0.6096 0)
					(mid -0.6096 0)
					(end 0.6096 0)
				)
			)
			(stroke
				(width 0)
				(type default)
			)
			(fill no)
			(layer "B.Fab")
		)
		(pad "1" smd circle
			(at 0 0 180)
			(size 0.7112 0.7112)
			(layers "B.Cu" "B.Mask" "B.Paste")
			(net "TP_BMC_GPIOE0")
		)
	)
	(footprint ""
		(layer "B.Cu")
		(at 117.329966 -46.228 180)
		(property "Reference" "SC979"
			(at 0 0 0)
			(layer "B.SilkS")
			(hide yes)
			(effects
				(font
					(size 1.27 1.27)
				)
				(justify mirror)
			)
		)
		(property "Value" "SCD1U16V2KX-3GP"
			(at -1.1811 -2.7051 180)
			(unlocked yes)
			(layer "B.Fab")
			(hide yes)
			(effects
				(font
					(size 1.016 1.016)
					(thickness 0.1524)
				)
				(justify mirror)
			)
		)
		(property "Device Type" "C402H22"
			(at -1.1811 -4.2291 180)
			(unlocked yes)
			(layer "B.Fab")
			(hide yes)
			(effects
				(font
					(size 1.016 1.016)
					(thickness 0.1524)
				)
				(justify mirror)
			)
		)
		(duplicate_pad_numbers_are_jumpers no)
		(fp_rect
			(start 0.4318 0.9525)
			(end -0.4318 -0.9525)
			(stroke
				(width 0)
				(type default)
			)
			(fill no)
			(layer "B.CrtYd")
		)
		(fp_rect
			(start 0.4318 0.9525)
			(end -0.4318 -0.9525)
			(stroke
				(width 0)
				(type default)
			)
			(fill no)
			(layer "B.Fab")
		)
		(pad "1" smd custom
			(at 0 -0.4445)
			(size 0.1524 0.1524)
			(layers "B.Cu" "B.Mask" "B.Paste")
			(net "P1V8_C")
			(options
				(clearance outline)
				(anchor circle)
			)
			(primitives
				(gr_poly
					(pts
						(arc
							(start 0.3048 0.2032)
							(mid 0.275042 0.275042)
							(end 0.2032 0.3048)
						)
						(arc
							(start -0.2032 0.3048)
							(mid -0.275042 0.275042)
							(end -0.3048 0.2032)
						)
						(arc
							(start -0.3048 -0.2032)
							(mid -0.275042 -0.275042)
							(end -0.2032 -0.3048)
						)
						(arc
							(start 0.2032 -0.3048)
							(mid 0.275042 -0.275042)
							(end 0.3048 -0.2032)
						)
					)
					(width 0)
					(fill yes)
				)
			)
		)
		(pad "2" smd custom
			(at 0 0.4445)
			(size 0.1524 0.1524)
			(layers "B.Cu" "B.Mask" "B.Paste")
			(net "GND")
			(options
				(clearance outline)
				(anchor circle)
			)
			(primitives
				(gr_poly
					(pts
						(arc
							(start 0.3048 0.2032)
							(mid 0.275042 0.275042)
							(end 0.2032 0.3048)
						)
						(arc
							(start -0.2032 0.3048)
							(mid -0.275042 0.275042)
							(end -0.3048 0.2032)
						)
						(arc
							(start -0.3048 -0.2032)
							(mid -0.275042 -0.275042)
							(end -0.2032 -0.3048)
						)
						(arc
							(start 0.2032 -0.3048)
							(mid 0.275042 -0.275042)
							(end 0.3048 -0.2032)
						)
					)
					(width 0)
					(fill yes)
				)
			)
		)
	)
	(footprint ""
		(layer "B.Cu")
		(at 267.081 -16.891 180)
		(property "Reference" "C338"
			(at 0 0 0)
			(layer "B.SilkS")
			(hide yes)
			(effects
				(font
					(size 1.27 1.27)
				)
				(justify mirror)
			)
		)
		(property "Value" "SC1U10V3KX-4GP-U"
			(at 0 -2.8194 180)
			(unlocked yes)
			(layer "B.Fab")
			(hide yes)
			(effects
				(font
					(size 1.016 1.016)
					(thickness 0.1524)
				)
				(justify mirror)
			)
		)
		(property "Device Type" "C603H36"
			(at 0 -4.3434 180)
			(unlocked yes)
			(layer "B.Fab")
			(hide yes)
			(effects
				(font
					(size 1.016 1.016)
					(thickness 0.1524)
				)
				(justify mirror)
			)
		)
		(duplicate_pad_numbers_are_jumpers no)
		(fp_line
			(start -0.508 0)
			(end 0.508 0)
			(stroke
				(width 0.2032)
				(type default)
			)
			(layer "B.SilkS")
		)
		(fp_rect
			(start 0.5842 1.3335)
			(end -0.5842 -1.3335)
			(stroke
				(width 0)
				(type default)
			)
			(fill no)
			(layer "B.CrtYd")
		)
		(fp_rect
			(start 0.5842 1.3335)
			(end -0.5842 -1.3335)
			(stroke
				(width 0)
				(type default)
			)
			(fill no)
			(layer "B.Fab")
		)
		(pad "1" smd custom
			(at 0 -0.762)
			(size 0.2159 0.2159)
			(layers "B.Cu" "B.Mask" "B.Paste")
			(net "P5V_USB")
			(options
				(clearance outline)
				(anchor circle)
			)
			(primitives
				(gr_poly
					(pts
						(arc
							(start -0.3302 0.4318)
							(mid -0.402042 0.402042)
							(end -0.4318 0.3302)
						)
						(arc
							(start -0.4318 -0.3302)
							(mid -0.402042 -0.402042)
							(end -0.3302 -0.4318)
						)
						(arc
							(start 0.3302 -0.4318)
							(mid 0.402042 -0.402042)
							(end 0.4318 -0.3302)
						)
						(arc
							(start 0.4318 0.3302)
							(mid 0.402042 0.402042)
							(end 0.3302 0.4318)
						)
					)
					(width 0)
					(fill yes)
				)
			)
		)
		(pad "2" smd custom
			(at 0 0.762)
			(size 0.2159 0.2159)
			(layers "B.Cu" "B.Mask" "B.Paste")
			(net "GND")
			(options
				(clearance outline)
				(anchor circle)
			)
			(primitives
				(gr_poly
					(pts
						(arc
							(start -0.3302 0.4318)
							(mid -0.402042 0.402042)
							(end -0.4318 0.3302)
						)
						(arc
							(start -0.4318 -0.3302)
							(mid -0.402042 -0.402042)
							(end -0.3302 -0.4318)
						)
						(arc
							(start 0.3302 -0.4318)
							(mid 0.402042 -0.402042)
							(end 0.4318 -0.3302)
						)
						(arc
							(start 0.4318 0.3302)
							(mid 0.402042 0.402042)
							(end 0.3302 0.4318)
						)
					)
					(width 0)
					(fill yes)
				)
			)
		)
	)
	(footprint ""
		(layer "B.Cu")
		(at 102.343966 -58.928 180)
		(property "Reference" "SR864"
			(at 0 0 0)
			(layer "B.SilkS")
			(hide yes)
			(effects
				(font
					(size 1.27 1.27)
				)
				(justify mirror)
			)
		)
		(property "Value" "0R2J-2-GP"
			(at -0.064008 -3.993896 180)
			(unlocked yes)
			(layer "B.Fab")
			(hide yes)
			(effects
				(font
					(size 1.016 1.016)
					(thickness 0.1524)
				)
				(justify mirror)
			)
		)
		(property "Device Type" "R402H16"
			(at -0.064008 -5.517896 180)
			(unlocked yes)
			(layer "B.Fab")
			(hide yes)
			(effects
				(font
					(size 1.016 1.016)
					(thickness 0.1524)
				)
				(justify mirror)
			)
		)
		(duplicate_pad_numbers_are_jumpers no)
		(fp_line
			(start 0.508 -0.9398)
			(end 0.508 0.9398)
			(stroke
				(width 0.1524)
				(type default)
			)
			(layer "B.SilkS")
		)
		(fp_line
			(start -0.508 -0.9398)
			(end 0.508 -0.9398)
			(stroke
				(width 0.1524)
				(type default)
			)
			(layer "B.SilkS")
		)
		(fp_rect
			(start 0.508 0.9398)
			(end -0.508 -0.9398)
			(stroke
				(width 0)
				(type default)
			)
			(fill no)
			(layer "B.CrtYd")
		)
		(fp_rect
			(start 0.508 0.9398)
			(end -0.508 -0.9398)
			(stroke
				(width 0)
				(type default)
			)
			(fill no)
			(layer "B.Fab")
		)
		(pad "1" smd custom
			(at 0 -0.4445)
			(size 0.1397 0.1397)
			(layers "B.Cu" "B.Mask" "B.Paste")
			(net "JTAG_IOC_TCK")
			(options
				(clearance outline)
				(anchor circle)
			)
			(primitives
				(gr_poly
					(pts
						(arc
							(start -0.1778 0.2794)
							(mid -0.249642 0.249642)
							(end -0.2794 0.1778)
						)
						(arc
							(start -0.2794 -0.1778)
							(mid -0.249642 -0.249642)
							(end -0.1778 -0.2794)
						)
						(arc
							(start 0.1778 -0.2794)
							(mid 0.249642 -0.249642)
							(end 0.2794 -0.1778)
						)
						(arc
							(start 0.2794 0.1778)
							(mid 0.249642 0.249642)
							(end 0.1778 0.2794)
						)
					)
					(width 0)
					(fill yes)
				)
			)
		)
		(pad "2" smd custom
			(at 0 0.4445)
			(size 0.1397 0.1397)
			(layers "B.Cu" "B.Mask" "B.Paste")
			(net "JTAG_EXP_IOC_TCK")
			(options
				(clearance outline)
				(anchor circle)
			)
			(primitives
				(gr_poly
					(pts
						(arc
							(start -0.1778 0.2794)
							(mid -0.249642 0.249642)
							(end -0.2794 0.1778)
						)
						(arc
							(start -0.2794 -0.1778)
							(mid -0.249642 -0.249642)
							(end -0.1778 -0.2794)
						)
						(arc
							(start 0.1778 -0.2794)
							(mid 0.249642 -0.249642)
							(end 0.2794 -0.1778)
						)
						(arc
							(start 0.2794 0.1778)
							(mid 0.249642 0.249642)
							(end 0.1778 0.2794)
						)
					)
					(width 0)
					(fill yes)
				)
			)
		)
	)
	(footprint ""
		(layer "B.Cu")
		(at 103.886 -239.395)
		(property "Reference" "SR945"
			(at 0 0 0)
			(layer "B.SilkS")
			(hide yes)
			(effects
				(font
					(size 1.27 1.27)
				)
				(justify mirror)
			)
		)
		(property "Value" "4K7R2F-GP"
			(at -0.064008 -3.993896 0)
			(unlocked yes)
			(layer "B.Fab")
			(hide yes)
			(effects
				(font
					(size 1.016 1.016)
					(thickness 0.1524)
				)
				(justify mirror)
			)
		)
		(property "Device Type" "R402H16"
			(at -0.064008 -5.517896 0)
			(unlocked yes)
			(layer "B.Fab")
			(hide yes)
			(effects
				(font
					(size 1.016 1.016)
					(thickness 0.1524)
				)
				(justify mirror)
			)
		)
		(duplicate_pad_numbers_are_jumpers no)
		(fp_line
			(start -0.508 -0.9398)
			(end 0.508 -0.9398)
			(stroke
				(width 0.1524)
				(type default)
			)
			(layer "B.SilkS")
		)
		(fp_line
			(start 0.508 -0.9398)
			(end 0.508 0.9398)
			(stroke
				(width 0.1524)
				(type default)
			)
			(layer "B.SilkS")
		)
		(fp_rect
			(start 0.508 0.9398)
			(end -0.508 -0.9398)
			(stroke
				(width 0)
				(type default)
			)
			(fill no)
			(layer "B.CrtYd")
		)
		(fp_rect
			(start 0.508 0.9398)
			(end -0.508 -0.9398)
			(stroke
				(width 0)
				(type default)
			)
			(fill no)
			(layer "B.Fab")
		)
		(pad "1" smd custom
			(at 0 -0.4445 180)
			(size 0.1397 0.1397)
			(layers "B.Cu" "B.Mask" "B.Paste")
			(net "SAS_FAULT_LED4")
			(options
				(clearance outline)
				(anchor circle)
			)
			(primitives
				(gr_poly
					(pts
						(arc
							(start -0.1778 0.2794)
							(mid -0.249642 0.249642)
							(end -0.2794 0.1778)
						)
						(arc
							(start -0.2794 -0.1778)
							(mid -0.249642 -0.249642)
							(end -0.1778 -0.2794)
						)
						(arc
							(start 0.1778 -0.2794)
							(mid 0.249642 -0.249642)
							(end 0.2794 -0.1778)
						)
						(arc
							(start 0.2794 0.1778)
							(mid 0.249642 0.249642)
							(end 0.1778 0.2794)
						)
					)
					(width 0)
					(fill yes)
				)
			)
		)
		(pad "2" smd custom
			(at 0 0.4445 180)
			(size 0.1397 0.1397)
			(layers "B.Cu" "B.Mask" "B.Paste")
			(net "P3V3_STBY")
			(options
				(clearance outline)
				(anchor circle)
			)
			(primitives
				(gr_poly
					(pts
						(arc
							(start -0.1778 0.2794)
							(mid -0.249642 0.249642)
							(end -0.2794 0.1778)
						)
						(arc
							(start -0.2794 -0.1778)
							(mid -0.249642 -0.249642)
							(end -0.1778 -0.2794)
						)
						(arc
							(start 0.1778 -0.2794)
							(mid 0.249642 -0.249642)
							(end 0.2794 -0.1778)
						)
						(arc
							(start 0.2794 0.1778)
							(mid 0.249642 0.249642)
							(end 0.1778 0.2794)
						)
					)
					(width 0)
					(fill yes)
				)
			)
		)
	)
	(footprint ""
		(layer "B.Cu")
		(at 114.551206 -39.1033)
		(property "Reference" "STP19"
			(at 0 0 0)
			(layer "B.SilkS")
			(hide yes)
			(effects
				(font
					(size 1.27 1.27)
				)
				(justify mirror)
			)
		)
		(property "Value" "TPAD28"
			(at -0.0127 -1.8034 0)
			(unlocked yes)
			(layer "B.Fab")
			(hide yes)
			(effects
				(font
					(size 1.016 1.016)
					(thickness 0.1524)
				)
				(justify mirror)
			)
		)
		(property "Device Type" "TPAD28"
			(at -0.0127 -3.3274 0)
			(unlocked yes)
			(layer "B.Fab")
			(hide yes)
			(effects
				(font
					(size 1.016 1.016)
					(thickness 0.1524)
				)
				(justify mirror)
			)
		)
		(duplicate_pad_numbers_are_jumpers no)
		(fp_poly
			(pts
				(arc
					(start 0.3556 0)
					(mid -0.3556 0)
					(end 0.3556 0)
				)
			)
			(stroke
				(width 0)
				(type default)
			)
			(fill no)
			(layer "B.CrtYd")
		)
		(fp_poly
			(pts
				(arc
					(start 0.6096 0)
					(mid -0.6096 0)
					(end 0.6096 0)
				)
			)
			(stroke
				(width 0)
				(type default)
			)
			(fill no)
			(layer "B.Fab")
		)
		(pad "1" smd circle
			(at 0 0 180)
			(size 0.7112 0.7112)
			(layers "B.Cu" "B.Mask" "B.Paste")
			(net "IOC_GPIO_34")
		)
	)
	(footprint ""
		(layer "B.Cu")
		(at 42.11193 -77.650086)
		(property "Reference" "SC1274"
			(at 0 0 0)
			(layer "B.SilkS")
			(hide yes)
			(effects
				(font
					(size 1.27 1.27)
				)
				(justify mirror)
			)
		)
		(property "Value" "SCD01U50V2KX-1GP"
			(at -1.1811 -2.7051 0)
			(unlocked yes)
			(layer "B.Fab")
			(hide yes)
			(effects
				(font
					(size 1.016 1.016)
					(thickness 0.1524)
				)
				(justify mirror)
			)
		)
		(property "Device Type" "C402H22"
			(at -1.1811 -4.2291 0)
			(unlocked yes)
			(layer "B.Fab")
			(hide yes)
			(effects
				(font
					(size 1.016 1.016)
					(thickness 0.1524)
				)
				(justify mirror)
			)
		)
		(duplicate_pad_numbers_are_jumpers no)
		(fp_rect
			(start 0.4318 0.9525)
			(end -0.4318 -0.9525)
			(stroke
				(width 0)
				(type default)
			)
			(fill no)
			(layer "B.CrtYd")
		)
		(fp_rect
			(start 0.4318 0.9525)
			(end -0.4318 -0.9525)
			(stroke
				(width 0)
				(type default)
			)
			(fill no)
			(layer "B.Fab")
		)
		(pad "1" smd custom
			(at 0 -0.4445 180)
			(size 0.1524 0.1524)
			(layers "B.Cu" "B.Mask" "B.Paste")
			(net "SAS_EXP2CONN_RX_P_20")
			(options
				(clearance outline)
				(anchor circle)
			)
			(primitives
				(gr_poly
					(pts
						(arc
							(start 0.3048 0.2032)
							(mid 0.275042 0.275042)
							(end 0.2032 0.3048)
						)
						(arc
							(start -0.2032 0.3048)
							(mid -0.275042 0.275042)
							(end -0.3048 0.2032)
						)
						(arc
							(start -0.3048 -0.2032)
							(mid -0.275042 -0.275042)
							(end -0.2032 -0.3048)
						)
						(arc
							(start 0.2032 -0.3048)
							(mid 0.275042 -0.275042)
							(end 0.3048 -0.2032)
						)
					)
					(width 0)
					(fill yes)
				)
			)
		)
		(pad "2" smd custom
			(at 0 0.4445 180)
			(size 0.1524 0.1524)
			(layers "B.Cu" "B.Mask" "B.Paste")
			(net "MINI_RX_P_20")
			(options
				(clearance outline)
				(anchor circle)
			)
			(primitives
				(gr_poly
					(pts
						(arc
							(start 0.3048 0.2032)
							(mid 0.275042 0.275042)
							(end 0.2032 0.3048)
						)
						(arc
							(start -0.2032 0.3048)
							(mid -0.275042 0.275042)
							(end -0.3048 0.2032)
						)
						(arc
							(start -0.3048 -0.2032)
							(mid -0.275042 -0.275042)
							(end -0.2032 -0.3048)
						)
						(arc
							(start 0.2032 -0.3048)
							(mid 0.275042 -0.275042)
							(end 0.3048 -0.2032)
						)
					)
					(width 0)
					(fill yes)
				)
			)
		)
	)
	(footprint ""
		(layer "B.Cu")
		(at 79.883 -18.796 180)
		(property "Reference" "PC213"
			(at 0 0 0)
			(layer "B.SilkS")
			(hide yes)
			(effects
				(font
					(size 1.27 1.27)
				)
				(justify mirror)
			)
		)
		(property "Value" "SC1U25V3KX-GP"
			(at 0 -2.8194 180)
			(unlocked yes)
			(layer "B.Fab")
			(hide yes)
			(effects
				(font
					(size 1.016 1.016)
					(thickness 0.1524)
				)
				(justify mirror)
			)
		)
		(property "Device Type" "C603H36"
			(at 0 -4.3434 180)
			(unlocked yes)
			(layer "B.Fab")
			(hide yes)
			(effects
				(font
					(size 1.016 1.016)
					(thickness 0.1524)
				)
				(justify mirror)
			)
		)
		(duplicate_pad_numbers_are_jumpers no)
		(fp_line
			(start -0.508 0)
			(end 0.508 0)
			(stroke
				(width 0.2032)
				(type default)
			)
			(layer "B.SilkS")
		)
		(fp_rect
			(start 0.5842 1.3335)
			(end -0.5842 -1.3335)
			(stroke
				(width 0)
				(type default)
			)
			(fill no)
			(layer "B.CrtYd")
		)
		(fp_rect
			(start 0.5842 1.3335)
			(end -0.5842 -1.3335)
			(stroke
				(width 0)
				(type default)
			)
			(fill no)
			(layer "B.Fab")
		)
		(pad "1" smd custom
			(at 0 -0.762)
			(size 0.2159 0.2159)
			(layers "B.Cu" "B.Mask" "B.Paste")
			(net "VT235_AVDD")
			(options
				(clearance outline)
				(anchor circle)
			)
			(primitives
				(gr_poly
					(pts
						(arc
							(start -0.3302 0.4318)
							(mid -0.402042 0.402042)
							(end -0.4318 0.3302)
						)
						(arc
							(start -0.4318 -0.3302)
							(mid -0.402042 -0.402042)
							(end -0.3302 -0.4318)
						)
						(arc
							(start 0.3302 -0.4318)
							(mid 0.402042 -0.402042)
							(end 0.4318 -0.3302)
						)
						(arc
							(start 0.4318 0.3302)
							(mid 0.402042 0.402042)
							(end 0.3302 0.4318)
						)
					)
					(width 0)
					(fill yes)
				)
			)
		)
		(pad "2" smd custom
			(at 0 0.762)
			(size 0.2159 0.2159)
			(layers "B.Cu" "B.Mask" "B.Paste")
			(net "AGND_P0V9_C")
			(options
				(clearance outline)
				(anchor circle)
			)
			(primitives
				(gr_poly
					(pts
						(arc
							(start -0.3302 0.4318)
							(mid -0.402042 0.402042)
							(end -0.4318 0.3302)
						)
						(arc
							(start -0.4318 -0.3302)
							(mid -0.402042 -0.402042)
							(end -0.3302 -0.4318)
						)
						(arc
							(start 0.3302 -0.4318)
							(mid 0.402042 -0.402042)
							(end 0.4318 -0.3302)
						)
						(arc
							(start 0.4318 0.3302)
							(mid 0.402042 0.402042)
							(end 0.3302 0.4318)
						)
					)
					(width 0)
					(fill yes)
				)
			)
		)
	)
	(footprint ""
		(layer "B.Cu")
		(at 115.902486 -40.06596)
		(property "Reference" "STP17"
			(at 0 0 0)
			(layer "B.SilkS")
			(hide yes)
			(effects
				(font
					(size 1.27 1.27)
				)
				(justify mirror)
			)
		)
		(property "Value" "TPAD28"
			(at -0.0127 -1.8034 0)
			(unlocked yes)
			(layer "B.Fab")
			(hide yes)
			(effects
				(font
					(size 1.016 1.016)
					(thickness 0.1524)
				)
				(justify mirror)
			)
		)
		(property "Device Type" "TPAD28"
			(at -0.0127 -3.3274 0)
			(unlocked yes)
			(layer "B.Fab")
			(hide yes)
			(effects
				(font
					(size 1.016 1.016)
					(thickness 0.1524)
				)
				(justify mirror)
			)
		)
		(duplicate_pad_numbers_are_jumpers no)
		(fp_poly
			(pts
				(arc
					(start 0.3556 0)
					(mid -0.3556 0)
					(end 0.3556 0)
				)
			)
			(stroke
				(width 0)
				(type default)
			)
			(fill no)
			(layer "B.CrtYd")
		)
		(fp_poly
			(pts
				(arc
					(start 0.6096 0)
					(mid -0.6096 0)
					(end 0.6096 0)
				)
			)
			(stroke
				(width 0)
				(type default)
			)
			(fill no)
			(layer "B.Fab")
		)
		(pad "1" smd circle
			(at 0 0 180)
			(size 0.7112 0.7112)
			(layers "B.Cu" "B.Mask" "B.Paste")
			(net "IOC_GPIO_33")
		)
	)
	(footprint ""
		(layer "B.Cu")
		(at 13.582904 -100.400866)
		(property "Reference" "C131"
			(at 0 0 0)
			(layer "B.SilkS")
			(hide yes)
			(effects
				(font
					(size 1.27 1.27)
				)
				(justify mirror)
			)
		)
		(property "Value" "SCD01U50V2KX-1GP"
			(at -1.1811 -2.7051 0)
			(unlocked yes)
			(layer "B.Fab")
			(hide yes)
			(effects
				(font
					(size 1.016 1.016)
					(thickness 0.1524)
				)
				(justify mirror)
			)
		)
		(property "Device Type" "C402H22"
			(at -1.1811 -4.2291 0)
			(unlocked yes)
			(layer "B.Fab")
			(hide yes)
			(effects
				(font
					(size 1.016 1.016)
					(thickness 0.1524)
				)
				(justify mirror)
			)
		)
		(duplicate_pad_numbers_are_jumpers no)
		(fp_rect
			(start 0.4318 0.9525)
			(end -0.4318 -0.9525)
			(stroke
				(width 0)
				(type default)
			)
			(fill no)
			(layer "B.CrtYd")
		)
		(fp_rect
			(start 0.4318 0.9525)
			(end -0.4318 -0.9525)
			(stroke
				(width 0)
				(type default)
			)
			(fill no)
			(layer "B.Fab")
		)
		(pad "1" smd custom
			(at 0 -0.4445 180)
			(size 0.1524 0.1524)
			(layers "B.Cu" "B.Mask" "B.Paste")
			(net "IOC_SAS_RX_P5")
			(options
				(clearance outline)
				(anchor circle)
			)
			(primitives
				(gr_poly
					(pts
						(arc
							(start 0.3048 0.2032)
							(mid 0.275042 0.275042)
							(end 0.2032 0.3048)
						)
						(arc
							(start -0.2032 0.3048)
							(mid -0.275042 0.275042)
							(end -0.3048 0.2032)
						)
						(arc
							(start -0.3048 -0.2032)
							(mid -0.275042 -0.275042)
							(end -0.2032 -0.3048)
						)
						(arc
							(start 0.2032 -0.3048)
							(mid 0.275042 -0.275042)
							(end 0.3048 -0.2032)
						)
					)
					(width 0)
					(fill yes)
				)
			)
		)
		(pad "2" smd custom
			(at 0 0.4445 180)
			(size 0.1524 0.1524)
			(layers "B.Cu" "B.Mask" "B.Paste")
			(net "SAS_EXT_CONN_RX17_P")
			(options
				(clearance outline)
				(anchor circle)
			)
			(primitives
				(gr_poly
					(pts
						(arc
							(start 0.3048 0.2032)
							(mid 0.275042 0.275042)
							(end 0.2032 0.3048)
						)
						(arc
							(start -0.2032 0.3048)
							(mid -0.275042 0.275042)
							(end -0.3048 0.2032)
						)
						(arc
							(start -0.3048 -0.2032)
							(mid -0.275042 -0.275042)
							(end -0.2032 -0.3048)
						)
						(arc
							(start 0.2032 -0.3048)
							(mid 0.275042 -0.275042)
							(end 0.3048 -0.2032)
						)
					)
					(width 0)
					(fill yes)
				)
			)
		)
	)
	(footprint ""
		(layer "B.Cu")
		(at 103.01097 -96.266)
		(property "Reference" "STP82"
			(at 0 0 0)
			(layer "B.SilkS")
			(hide yes)
			(effects
				(font
					(size 1.27 1.27)
				)
				(justify mirror)
			)
		)
		(property "Value" "TPAD28"
			(at -0.0127 -1.8034 0)
			(unlocked yes)
			(layer "B.Fab")
			(hide yes)
			(effects
				(font
					(size 1.016 1.016)
					(thickness 0.1524)
				)
				(justify mirror)
			)
		)
		(property "Device Type" "TPAD28"
			(at -0.0127 -3.3274 0)
			(unlocked yes)
			(layer "B.Fab")
			(hide yes)
			(effects
				(font
					(size 1.016 1.016)
					(thickness 0.1524)
				)
				(justify mirror)
			)
		)
		(duplicate_pad_numbers_are_jumpers no)
		(fp_poly
			(pts
				(arc
					(start 0.3556 0)
					(mid -0.3556 0)
					(end 0.3556 0)
				)
			)
			(stroke
				(width 0)
				(type default)
			)
			(fill no)
			(layer "B.CrtYd")
		)
		(fp_poly
			(pts
				(arc
					(start 0.6096 0)
					(mid -0.6096 0)
					(end 0.6096 0)
				)
			)
			(stroke
				(width 0)
				(type default)
			)
			(fill no)
			(layer "B.Fab")
		)
		(pad "1" smd circle
			(at 0 0 180)
			(size 0.7112 0.7112)
			(layers "B.Cu" "B.Mask" "B.Paste")
			(net "EXP_TACH_IN2")
		)
	)
	(footprint ""
		(layer "B.Cu")
		(at 16.960088 -208.789016 90)
		(property "Reference" "SC860"
			(at 0 0 90)
			(layer "B.SilkS")
			(hide yes)
			(effects
				(font
					(size 1.27 1.27)
				)
				(justify mirror)
			)
		)
		(property "Value" "SCD1U16V2KX-3GP"
			(at -1.1811 -2.7051 90)
			(unlocked yes)
			(layer "B.Fab")
			(hide yes)
			(effects
				(font
					(size 1.016 1.016)
					(thickness 0.1524)
				)
				(justify mirror)
			)
		)
		(property "Device Type" "C402H22"
			(at -1.1811 -4.2291 90)
			(unlocked yes)
			(layer "B.Fab")
			(hide yes)
			(effects
				(font
					(size 1.016 1.016)
					(thickness 0.1524)
				)
				(justify mirror)
			)
		)
		(duplicate_pad_numbers_are_jumpers no)
		(fp_rect
			(start 0.4318 0.9525)
			(end -0.4318 -0.9525)
			(stroke
				(width 0)
				(type default)
			)
			(fill no)
			(layer "B.CrtYd")
		)
		(fp_rect
			(start 0.4318 0.9525)
			(end -0.4318 -0.9525)
			(stroke
				(width 0)
				(type default)
			)
			(fill no)
			(layer "B.Fab")
		)
		(pad "1" smd custom
			(at 0 -0.4445 270)
			(size 0.1524 0.1524)
			(layers "B.Cu" "B.Mask" "B.Paste")
			(net "P1V8_E")
			(options
				(clearance outline)
				(anchor circle)
			)
			(primitives
				(gr_poly
					(pts
						(arc
							(start 0.3048 0.2032)
							(mid 0.275042 0.275042)
							(end 0.2032 0.3048)
						)
						(arc
							(start -0.2032 0.3048)
							(mid -0.275042 0.275042)
							(end -0.3048 0.2032)
						)
						(arc
							(start -0.3048 -0.2032)
							(mid -0.275042 -0.275042)
							(end -0.2032 -0.3048)
						)
						(arc
							(start 0.2032 -0.3048)
							(mid 0.275042 -0.275042)
							(end 0.3048 -0.2032)
						)
					)
					(width 0)
					(fill yes)
				)
			)
		)
		(pad "2" smd custom
			(at 0 0.4445 270)
			(size 0.1524 0.1524)
			(layers "B.Cu" "B.Mask" "B.Paste")
			(net "GND")
			(options
				(clearance outline)
				(anchor circle)
			)
			(primitives
				(gr_poly
					(pts
						(arc
							(start 0.3048 0.2032)
							(mid 0.275042 0.275042)
							(end 0.2032 0.3048)
						)
						(arc
							(start -0.2032 0.3048)
							(mid -0.275042 0.275042)
							(end -0.3048 0.2032)
						)
						(arc
							(start -0.3048 -0.2032)
							(mid -0.275042 -0.275042)
							(end -0.2032 -0.3048)
						)
						(arc
							(start 0.2032 -0.3048)
							(mid 0.275042 -0.275042)
							(end 0.3048 -0.2032)
						)
					)
					(width 0)
					(fill yes)
				)
			)
		)
	)
	(footprint ""
		(layer "B.Cu")
		(at 94.309946 -50.22596)
		(property "Reference" "SC1015"
			(at 0 0 0)
			(layer "B.SilkS")
			(hide yes)
			(effects
				(font
					(size 1.27 1.27)
				)
				(justify mirror)
			)
		)
		(property "Value" "SC1KP50V2KX-1GP"
			(at -1.1811 -2.7051 0)
			(unlocked yes)
			(layer "B.Fab")
			(hide yes)
			(effects
				(font
					(size 1.016 1.016)
					(thickness 0.1524)
				)
				(justify mirror)
			)
		)
		(property "Device Type" "C402H22"
			(at -1.1811 -4.2291 0)
			(unlocked yes)
			(layer "B.Fab")
			(hide yes)
			(effects
				(font
					(size 1.016 1.016)
					(thickness 0.1524)
				)
				(justify mirror)
			)
		)
		(duplicate_pad_numbers_are_jumpers no)
		(fp_rect
			(start 0.4318 0.9525)
			(end -0.4318 -0.9525)
			(stroke
				(width 0)
				(type default)
			)
			(fill no)
			(layer "B.CrtYd")
		)
		(fp_rect
			(start 0.4318 0.9525)
			(end -0.4318 -0.9525)
			(stroke
				(width 0)
				(type default)
			)
			(fill no)
			(layer "B.Fab")
		)
		(pad "1" smd custom
			(at 0 -0.4445 180)
			(size 0.1524 0.1524)
			(layers "B.Cu" "B.Mask" "B.Paste")
			(net "P1V8_C")
			(options
				(clearance outline)
				(anchor circle)
			)
			(primitives
				(gr_poly
					(pts
						(arc
							(start 0.3048 0.2032)
							(mid 0.275042 0.275042)
							(end 0.2032 0.3048)
						)
						(arc
							(start -0.2032 0.3048)
							(mid -0.275042 0.275042)
							(end -0.3048 0.2032)
						)
						(arc
							(start -0.3048 -0.2032)
							(mid -0.275042 -0.275042)
							(end -0.2032 -0.3048)
						)
						(arc
							(start 0.2032 -0.3048)
							(mid 0.275042 -0.275042)
							(end 0.3048 -0.2032)
						)
					)
					(width 0)
					(fill yes)
				)
			)
		)
		(pad "2" smd custom
			(at 0 0.4445 180)
			(size 0.1524 0.1524)
			(layers "B.Cu" "B.Mask" "B.Paste")
			(net "GND")
			(options
				(clearance outline)
				(anchor circle)
			)
			(primitives
				(gr_poly
					(pts
						(arc
							(start 0.3048 0.2032)
							(mid 0.275042 0.275042)
							(end 0.2032 0.3048)
						)
						(arc
							(start -0.2032 0.3048)
							(mid -0.275042 0.275042)
							(end -0.3048 0.2032)
						)
						(arc
							(start -0.3048 -0.2032)
							(mid -0.275042 -0.275042)
							(end -0.2032 -0.3048)
						)
						(arc
							(start 0.2032 -0.3048)
							(mid 0.275042 -0.275042)
							(end 0.3048 -0.2032)
						)
					)
					(width 0)
					(fill yes)
				)
			)
		)
	)
	(footprint ""
		(layer "B.Cu")
		(at 90.68816 -53.086)
		(property "Reference" "SR628"
			(at 0 0 0)
			(layer "B.SilkS")
			(hide yes)
			(effects
				(font
					(size 1.27 1.27)
				)
				(justify mirror)
			)
		)
		(property "Value" "2K2R2F-GP"
			(at -0.064008 -3.993896 0)
			(unlocked yes)
			(layer "B.Fab")
			(hide yes)
			(effects
				(font
					(size 1.016 1.016)
					(thickness 0.1524)
				)
				(justify mirror)
			)
		)
		(property "Device Type" "R402H16"
			(at -0.064008 -5.517896 0)
			(unlocked yes)
			(layer "B.Fab")
			(hide yes)
			(effects
				(font
					(size 1.016 1.016)
					(thickness 0.1524)
				)
				(justify mirror)
			)
		)
		(duplicate_pad_numbers_are_jumpers no)
		(fp_line
			(start -0.508 -0.9398)
			(end 0.508 -0.9398)
			(stroke
				(width 0.1524)
				(type default)
			)
			(layer "B.SilkS")
		)
		(fp_line
			(start 0.508 -0.9398)
			(end 0.508 0.9398)
			(stroke
				(width 0.1524)
				(type default)
			)
			(layer "B.SilkS")
		)
		(fp_rect
			(start 0.508 0.9398)
			(end -0.508 -0.9398)
			(stroke
				(width 0)
				(type default)
			)
			(fill no)
			(layer "B.CrtYd")
		)
		(fp_rect
			(start 0.508 0.9398)
			(end -0.508 -0.9398)
			(stroke
				(width 0)
				(type default)
			)
			(fill no)
			(layer "B.Fab")
		)
		(pad "1" smd custom
			(at 0 -0.4445 180)
			(size 0.1397 0.1397)
			(layers "B.Cu" "B.Mask" "B.Paste")
			(net "P1V8_C")
			(options
				(clearance outline)
				(anchor circle)
			)
			(primitives
				(gr_poly
					(pts
						(arc
							(start -0.1778 0.2794)
							(mid -0.249642 0.249642)
							(end -0.2794 0.1778)
						)
						(arc
							(start -0.2794 -0.1778)
							(mid -0.249642 -0.249642)
							(end -0.1778 -0.2794)
						)
						(arc
							(start 0.1778 -0.2794)
							(mid 0.249642 -0.249642)
							(end 0.2794 -0.1778)
						)
						(arc
							(start 0.2794 0.1778)
							(mid 0.249642 0.249642)
							(end 0.1778 0.2794)
						)
					)
					(width 0)
					(fill yes)
				)
			)
		)
		(pad "2" smd custom
			(at 0 0.4445 180)
			(size 0.1397 0.1397)
			(layers "B.Cu" "B.Mask" "B.Paste")
			(net "SIO_DOUT_0")
			(options
				(clearance outline)
				(anchor circle)
			)
			(primitives
				(gr_poly
					(pts
						(arc
							(start -0.1778 0.2794)
							(mid -0.249642 0.249642)
							(end -0.2794 0.1778)
						)
						(arc
							(start -0.2794 -0.1778)
							(mid -0.249642 -0.249642)
							(end -0.1778 -0.2794)
						)
						(arc
							(start 0.1778 -0.2794)
							(mid 0.249642 -0.249642)
							(end 0.2794 -0.1778)
						)
						(arc
							(start 0.2794 0.1778)
							(mid 0.249642 0.249642)
							(end 0.1778 0.2794)
						)
					)
					(width 0)
					(fill yes)
				)
			)
		)
	)
	(footprint ""
		(layer "B.Cu")
		(at 118.472966 -26.416 -90)
		(property "Reference" "SR652"
			(at 0 0 90)
			(layer "B.SilkS")
			(hide yes)
			(effects
				(font
					(size 1.27 1.27)
				)
				(justify mirror)
			)
		)
		(property "Value" "150R2F-1-GP"
			(at -0.064008 -3.993896 270)
			(unlocked yes)
			(layer "B.Fab")
			(hide yes)
			(effects
				(font
					(size 1.016 1.016)
					(thickness 0.1524)
				)
				(justify mirror)
			)
		)
		(property "Device Type" "R402H16"
			(at -0.064008 -5.517896 270)
			(unlocked yes)
			(layer "B.Fab")
			(hide yes)
			(effects
				(font
					(size 1.016 1.016)
					(thickness 0.1524)
				)
				(justify mirror)
			)
		)
		(duplicate_pad_numbers_are_jumpers no)
		(fp_line
			(start -0.508 -0.9398)
			(end 0.508 -0.9398)
			(stroke
				(width 0.1524)
				(type default)
			)
			(layer "B.SilkS")
		)
		(fp_line
			(start 0.508 -0.9398)
			(end 0.508 0.9398)
			(stroke
				(width 0.1524)
				(type default)
			)
			(layer "B.SilkS")
		)
		(fp_rect
			(start 0.508 0.9398)
			(end -0.508 -0.9398)
			(stroke
				(width 0)
				(type default)
			)
			(fill no)
			(layer "B.CrtYd")
		)
		(fp_rect
			(start 0.508 0.9398)
			(end -0.508 -0.9398)
			(stroke
				(width 0)
				(type default)
			)
			(fill no)
			(layer "B.Fab")
		)
		(pad "1" smd custom
			(at 0 -0.4445 90)
			(size 0.1397 0.1397)
			(layers "B.Cu" "B.Mask" "B.Paste")
			(net "P3V3")
			(options
				(clearance outline)
				(anchor circle)
			)
			(primitives
				(gr_poly
					(pts
						(arc
							(start -0.1778 0.2794)
							(mid -0.249642 0.249642)
							(end -0.2794 0.1778)
						)
						(arc
							(start -0.2794 -0.1778)
							(mid -0.249642 -0.249642)
							(end -0.1778 -0.2794)
						)
						(arc
							(start 0.1778 -0.2794)
							(mid 0.249642 -0.249642)
							(end 0.2794 -0.1778)
						)
						(arc
							(start 0.2794 0.1778)
							(mid 0.249642 0.249642)
							(end 0.1778 0.2794)
						)
					)
					(width 0)
					(fill yes)
				)
			)
		)
		(pad "2" smd custom
			(at 0 0.4445 90)
			(size 0.1397 0.1397)
			(layers "B.Cu" "B.Mask" "B.Paste")
			(net "SYS_ERROR_LED_R")
			(options
				(clearance outline)
				(anchor circle)
			)
			(primitives
				(gr_poly
					(pts
						(arc
							(start -0.1778 0.2794)
							(mid -0.249642 0.249642)
							(end -0.2794 0.1778)
						)
						(arc
							(start -0.2794 -0.1778)
							(mid -0.249642 -0.249642)
							(end -0.1778 -0.2794)
						)
						(arc
							(start 0.1778 -0.2794)
							(mid 0.249642 -0.249642)
							(end 0.2794 -0.1778)
						)
						(arc
							(start 0.2794 0.1778)
							(mid 0.249642 0.249642)
							(end 0.1778 0.2794)
						)
					)
					(width 0)
					(fill yes)
				)
			)
		)
	)
	(footprint ""
		(layer "B.Cu")
		(at 158.42996 -106.121454 90)
		(property "Reference" "SC1242"
			(at 0 0 90)
			(layer "B.SilkS")
			(hide yes)
			(effects
				(font
					(size 1.27 1.27)
				)
				(justify mirror)
			)
		)
		(property "Value" "SCD1U6D3V1KX-GP"
			(at 2.8321 -1.7399 90)
			(unlocked yes)
			(layer "B.Fab")
			(hide yes)
			(effects
				(font
					(size 1.016 1.016)
					(thickness 0.1524)
				)
				(justify mirror)
			)
		)
		(property "Device Type" "C0201H13"
			(at 2.8321 -3.2639 90)
			(unlocked yes)
			(layer "B.Fab")
			(hide yes)
			(effects
				(font
					(size 1.016 1.016)
					(thickness 0.1524)
				)
				(justify mirror)
			)
		)
		(duplicate_pad_numbers_are_jumpers no)
		(fp_rect
			(start 0.2794 0.6477)
			(end -0.2794 -0.6477)
			(stroke
				(width 0)
				(type default)
			)
			(fill no)
			(layer "B.CrtYd")
		)
		(fp_rect
			(start 0.2794 0.6477)
			(end -0.2794 -0.6477)
			(stroke
				(width 0)
				(type default)
			)
			(fill no)
			(layer "B.Fab")
		)
		(pad "1" smd custom
			(at 0 -0.2794 270)
			(size 0.0762 0.0762)
			(layers "B.Cu" "B.Mask" "B.Paste")
			(net "P0V9_E")
			(options
				(clearance outline)
				(anchor circle)
			)
			(primitives
				(gr_poly
					(pts
						(arc
							(start 0.1524 0.127)
							(mid 0.137521 0.162921)
							(end 0.1016 0.1778)
						)
						(arc
							(start -0.1016 0.1778)
							(mid -0.137521 0.162921)
							(end -0.1524 0.127)
						)
						(arc
							(start -0.1524 -0.127)
							(mid -0.137521 -0.162921)
							(end -0.1016 -0.1778)
						)
						(arc
							(start 0.1016 -0.1778)
							(mid 0.137521 -0.162921)
							(end 0.1524 -0.127)
						)
					)
					(width 0)
					(fill yes)
				)
			)
		)
		(pad "2" smd custom
			(at 0 0.2794 270)
			(size 0.0762 0.0762)
			(layers "B.Cu" "B.Mask" "B.Paste")
			(net "GND")
			(options
				(clearance outline)
				(anchor circle)
			)
			(primitives
				(gr_poly
					(pts
						(arc
							(start 0.1524 0.127)
							(mid 0.137521 0.162921)
							(end 0.1016 0.1778)
						)
						(arc
							(start -0.1016 0.1778)
							(mid -0.137521 0.162921)
							(end -0.1524 0.127)
						)
						(arc
							(start -0.1524 -0.127)
							(mid -0.137521 -0.162921)
							(end -0.1016 -0.1778)
						)
						(arc
							(start 0.1016 -0.1778)
							(mid 0.137521 -0.162921)
							(end 0.1524 -0.127)
						)
					)
					(width 0)
					(fill yes)
				)
			)
		)
	)
	(footprint ""
		(layer "B.Cu")
		(at 84.455 -18.161 180)
		(property "Reference" "PC215"
			(at 0 0 0)
			(layer "B.SilkS")
			(hide yes)
			(effects
				(font
					(size 1.27 1.27)
				)
				(justify mirror)
			)
		)
		(property "Value" "SC1U25V3KX-GP"
			(at 0 -2.8194 180)
			(unlocked yes)
			(layer "B.Fab")
			(hide yes)
			(effects
				(font
					(size 1.016 1.016)
					(thickness 0.1524)
				)
				(justify mirror)
			)
		)
		(property "Device Type" "C603H36"
			(at 0 -4.3434 180)
			(unlocked yes)
			(layer "B.Fab")
			(hide yes)
			(effects
				(font
					(size 1.016 1.016)
					(thickness 0.1524)
				)
				(justify mirror)
			)
		)
		(duplicate_pad_numbers_are_jumpers no)
		(fp_line
			(start -0.508 0)
			(end 0.508 0)
			(stroke
				(width 0.2032)
				(type default)
			)
			(layer "B.SilkS")
		)
		(fp_rect
			(start 0.5842 1.3335)
			(end -0.5842 -1.3335)
			(stroke
				(width 0)
				(type default)
			)
			(fill no)
			(layer "B.CrtYd")
		)
		(fp_rect
			(start 0.5842 1.3335)
			(end -0.5842 -1.3335)
			(stroke
				(width 0)
				(type default)
			)
			(fill no)
			(layer "B.Fab")
		)
		(pad "1" smd custom
			(at 0 -0.762)
			(size 0.2159 0.2159)
			(layers "B.Cu" "B.Mask" "B.Paste")
			(net "VT235_VDDL")
			(options
				(clearance outline)
				(anchor circle)
			)
			(primitives
				(gr_poly
					(pts
						(arc
							(start -0.3302 0.4318)
							(mid -0.402042 0.402042)
							(end -0.4318 0.3302)
						)
						(arc
							(start -0.4318 -0.3302)
							(mid -0.402042 -0.402042)
							(end -0.3302 -0.4318)
						)
						(arc
							(start 0.3302 -0.4318)
							(mid 0.402042 -0.402042)
							(end 0.4318 -0.3302)
						)
						(arc
							(start 0.4318 0.3302)
							(mid 0.402042 0.402042)
							(end 0.3302 0.4318)
						)
					)
					(width 0)
					(fill yes)
				)
			)
		)
		(pad "2" smd custom
			(at 0 0.762)
			(size 0.2159 0.2159)
			(layers "B.Cu" "B.Mask" "B.Paste")
			(net "AGND_P0V9_C")
			(options
				(clearance outline)
				(anchor circle)
			)
			(primitives
				(gr_poly
					(pts
						(arc
							(start -0.3302 0.4318)
							(mid -0.402042 0.402042)
							(end -0.4318 0.3302)
						)
						(arc
							(start -0.4318 -0.3302)
							(mid -0.402042 -0.402042)
							(end -0.3302 -0.4318)
						)
						(arc
							(start 0.3302 -0.4318)
							(mid 0.402042 -0.402042)
							(end 0.4318 -0.3302)
						)
						(arc
							(start 0.4318 0.3302)
							(mid 0.402042 0.402042)
							(end 0.3302 0.4318)
						)
					)
					(width 0)
					(fill yes)
				)
			)
		)
	)
	(footprint ""
		(layer "B.Cu")
		(at 164.211 -114.427)
		(property "Reference" "SR854"
			(at 0 0 0)
			(layer "B.SilkS")
			(hide yes)
			(effects
				(font
					(size 1.27 1.27)
				)
				(justify mirror)
			)
		)
		(property "Value" "4K7R2F-GP"
			(at -0.064008 -3.993896 0)
			(unlocked yes)
			(layer "B.Fab")
			(hide yes)
			(effects
				(font
					(size 1.016 1.016)
					(thickness 0.1524)
				)
				(justify mirror)
			)
		)
		(property "Device Type" "R402H16"
			(at -0.064008 -5.517896 0)
			(unlocked yes)
			(layer "B.Fab")
			(hide yes)
			(effects
				(font
					(size 1.016 1.016)
					(thickness 0.1524)
				)
				(justify mirror)
			)
		)
		(duplicate_pad_numbers_are_jumpers no)
		(fp_line
			(start -0.508 -0.9398)
			(end 0.508 -0.9398)
			(stroke
				(width 0.1524)
				(type default)
			)
			(layer "B.SilkS")
		)
		(fp_line
			(start 0.508 -0.9398)
			(end 0.508 0.9398)
			(stroke
				(width 0.1524)
				(type default)
			)
			(layer "B.SilkS")
		)
		(fp_rect
			(start 0.508 0.9398)
			(end -0.508 -0.9398)
			(stroke
				(width 0)
				(type default)
			)
			(fill no)
			(layer "B.CrtYd")
		)
		(fp_rect
			(start 0.508 0.9398)
			(end -0.508 -0.9398)
			(stroke
				(width 0)
				(type default)
			)
			(fill no)
			(layer "B.Fab")
		)
		(pad "1" smd custom
			(at 0 -0.4445 180)
			(size 0.1397 0.1397)
			(layers "B.Cu" "B.Mask" "B.Paste")
			(net "P3V3_STBY")
			(options
				(clearance outline)
				(anchor circle)
			)
			(primitives
				(gr_poly
					(pts
						(arc
							(start -0.1778 0.2794)
							(mid -0.249642 0.249642)
							(end -0.2794 0.1778)
						)
						(arc
							(start -0.2794 -0.1778)
							(mid -0.249642 -0.249642)
							(end -0.1778 -0.2794)
						)
						(arc
							(start 0.1778 -0.2794)
							(mid 0.249642 -0.249642)
							(end 0.2794 -0.1778)
						)
						(arc
							(start 0.2794 0.1778)
							(mid 0.249642 0.249642)
							(end 0.1778 0.2794)
						)
					)
					(width 0)
					(fill yes)
				)
			)
		)
		(pad "2" smd custom
			(at 0 0.4445 180)
			(size 0.1397 0.1397)
			(layers "B.Cu" "B.Mask" "B.Paste")
			(net "P3V3_STBY_R4")
			(options
				(clearance outline)
				(anchor circle)
			)
			(primitives
				(gr_poly
					(pts
						(arc
							(start -0.1778 0.2794)
							(mid -0.249642 0.249642)
							(end -0.2794 0.1778)
						)
						(arc
							(start -0.2794 -0.1778)
							(mid -0.249642 -0.249642)
							(end -0.1778 -0.2794)
						)
						(arc
							(start 0.1778 -0.2794)
							(mid 0.249642 -0.249642)
							(end 0.2794 -0.1778)
						)
						(arc
							(start 0.2794 0.1778)
							(mid 0.249642 0.249642)
							(end 0.1778 0.2794)
						)
					)
					(width 0)
					(fill yes)
				)
			)
		)
	)
	(footprint ""
		(layer "B.Cu")
		(at 350.393 -81.534 180)
		(property "Reference" "C186"
			(at 0 0 0)
			(layer "B.SilkS")
			(hide yes)
			(effects
				(font
					(size 1.27 1.27)
				)
				(justify mirror)
			)
		)
		(property "Value" "SCD1U16V2KX-3GP"
			(at -1.1811 -2.7051 180)
			(unlocked yes)
			(layer "B.Fab")
			(hide yes)
			(effects
				(font
					(size 1.016 1.016)
					(thickness 0.1524)
				)
				(justify mirror)
			)
		)
		(property "Device Type" "C402H22"
			(at -1.1811 -4.2291 180)
			(unlocked yes)
			(layer "B.Fab")
			(hide yes)
			(effects
				(font
					(size 1.016 1.016)
					(thickness 0.1524)
				)
				(justify mirror)
			)
		)
		(duplicate_pad_numbers_are_jumpers no)
		(fp_rect
			(start 0.4318 0.9525)
			(end -0.4318 -0.9525)
			(stroke
				(width 0)
				(type default)
			)
			(fill no)
			(layer "B.CrtYd")
		)
		(fp_rect
			(start 0.4318 0.9525)
			(end -0.4318 -0.9525)
			(stroke
				(width 0)
				(type default)
			)
			(fill no)
			(layer "B.Fab")
		)
		(pad "1" smd custom
			(at 0 -0.4445)
			(size 0.1524 0.1524)
			(layers "B.Cu" "B.Mask" "B.Paste")
			(net "P3V3_STBY")
			(options
				(clearance outline)
				(anchor circle)
			)
			(primitives
				(gr_poly
					(pts
						(arc
							(start 0.3048 0.2032)
							(mid 0.275042 0.275042)
							(end 0.2032 0.3048)
						)
						(arc
							(start -0.2032 0.3048)
							(mid -0.275042 0.275042)
							(end -0.3048 0.2032)
						)
						(arc
							(start -0.3048 -0.2032)
							(mid -0.275042 -0.275042)
							(end -0.2032 -0.3048)
						)
						(arc
							(start 0.2032 -0.3048)
							(mid 0.275042 -0.275042)
							(end 0.3048 -0.2032)
						)
					)
					(width 0)
					(fill yes)
				)
			)
		)
		(pad "2" smd custom
			(at 0 0.4445)
			(size 0.1524 0.1524)
			(layers "B.Cu" "B.Mask" "B.Paste")
			(net "GND")
			(options
				(clearance outline)
				(anchor circle)
			)
			(primitives
				(gr_poly
					(pts
						(arc
							(start 0.3048 0.2032)
							(mid 0.275042 0.275042)
							(end 0.2032 0.3048)
						)
						(arc
							(start -0.2032 0.3048)
							(mid -0.275042 0.275042)
							(end -0.3048 0.2032)
						)
						(arc
							(start -0.3048 -0.2032)
							(mid -0.275042 -0.275042)
							(end -0.2032 -0.3048)
						)
						(arc
							(start 0.2032 -0.3048)
							(mid 0.275042 -0.275042)
							(end 0.3048 -0.2032)
						)
					)
					(width 0)
					(fill yes)
				)
			)
		)
	)
	(footprint ""
		(layer "B.Cu")
		(at 103.359966 -58.928 180)
		(property "Reference" "SR682"
			(at 0 0 0)
			(layer "B.SilkS")
			(hide yes)
			(effects
				(font
					(size 1.27 1.27)
				)
				(justify mirror)
			)
		)
		(property "Value" "10KR2F-2-GP"
			(at -0.064008 -3.993896 180)
			(unlocked yes)
			(layer "B.Fab")
			(hide yes)
			(effects
				(font
					(size 1.016 1.016)
					(thickness 0.1524)
				)
				(justify mirror)
			)
		)
		(property "Device Type" "R402H16"
			(at -0.064008 -5.517896 180)
			(unlocked yes)
			(layer "B.Fab")
			(hide yes)
			(effects
				(font
					(size 1.016 1.016)
					(thickness 0.1524)
				)
				(justify mirror)
			)
		)
		(duplicate_pad_numbers_are_jumpers no)
		(fp_line
			(start 0.508 -0.9398)
			(end 0.508 0.9398)
			(stroke
				(width 0.1524)
				(type default)
			)
			(layer "B.SilkS")
		)
		(fp_line
			(start -0.508 -0.9398)
			(end 0.508 -0.9398)
			(stroke
				(width 0.1524)
				(type default)
			)
			(layer "B.SilkS")
		)
		(fp_rect
			(start 0.508 0.9398)
			(end -0.508 -0.9398)
			(stroke
				(width 0)
				(type default)
			)
			(fill no)
			(layer "B.CrtYd")
		)
		(fp_rect
			(start 0.508 0.9398)
			(end -0.508 -0.9398)
			(stroke
				(width 0)
				(type default)
			)
			(fill no)
			(layer "B.Fab")
		)
		(pad "1" smd custom
			(at 0 -0.4445)
			(size 0.1397 0.1397)
			(layers "B.Cu" "B.Mask" "B.Paste")
			(net "LSI_IDDT")
			(options
				(clearance outline)
				(anchor circle)
			)
			(primitives
				(gr_poly
					(pts
						(arc
							(start -0.1778 0.2794)
							(mid -0.249642 0.249642)
							(end -0.2794 0.1778)
						)
						(arc
							(start -0.2794 -0.1778)
							(mid -0.249642 -0.249642)
							(end -0.1778 -0.2794)
						)
						(arc
							(start 0.1778 -0.2794)
							(mid 0.249642 -0.249642)
							(end 0.2794 -0.1778)
						)
						(arc
							(start 0.2794 0.1778)
							(mid 0.249642 0.249642)
							(end 0.1778 0.2794)
						)
					)
					(width 0)
					(fill yes)
				)
			)
		)
		(pad "2" smd custom
			(at 0 0.4445)
			(size 0.1397 0.1397)
			(layers "B.Cu" "B.Mask" "B.Paste")
			(net "GND")
			(options
				(clearance outline)
				(anchor circle)
			)
			(primitives
				(gr_poly
					(pts
						(arc
							(start -0.1778 0.2794)
							(mid -0.249642 0.249642)
							(end -0.2794 0.1778)
						)
						(arc
							(start -0.2794 -0.1778)
							(mid -0.249642 -0.249642)
							(end -0.1778 -0.2794)
						)
						(arc
							(start 0.1778 -0.2794)
							(mid 0.249642 -0.249642)
							(end 0.2794 -0.1778)
						)
						(arc
							(start 0.2794 0.1778)
							(mid 0.249642 0.249642)
							(end 0.1778 0.2794)
						)
					)
					(width 0)
					(fill yes)
				)
			)
		)
	)
	(footprint ""
		(layer "B.Cu")
		(at 269.748 -30.607 -90)
		(property "Reference" "PC50"
			(at 0 0 90)
			(layer "B.SilkS")
			(hide yes)
			(effects
				(font
					(size 1.27 1.27)
				)
				(justify mirror)
			)
		)
		(property "Value" "SCD1U25V2KX-2-GP"
			(at -1.1811 -2.7051 270)
			(unlocked yes)
			(layer "B.Fab")
			(hide yes)
			(effects
				(font
					(size 1.016 1.016)
					(thickness 0.1524)
				)
				(justify mirror)
			)
		)
		(property "Device Type" "C402H22"
			(at -1.1811 -4.2291 270)
			(unlocked yes)
			(layer "B.Fab")
			(hide yes)
			(effects
				(font
					(size 1.016 1.016)
					(thickness 0.1524)
				)
				(justify mirror)
			)
		)
		(duplicate_pad_numbers_are_jumpers no)
		(fp_rect
			(start 0.4318 0.9525)
			(end -0.4318 -0.9525)
			(stroke
				(width 0)
				(type default)
			)
			(fill no)
			(layer "B.CrtYd")
		)
		(fp_rect
			(start 0.4318 0.9525)
			(end -0.4318 -0.9525)
			(stroke
				(width 0)
				(type default)
			)
			(fill no)
			(layer "B.Fab")
		)
		(pad "1" smd custom
			(at 0 -0.4445 90)
			(size 0.1524 0.1524)
			(layers "B.Cu" "B.Mask" "B.Paste")
			(net "P1V8_STBY")
			(options
				(clearance outline)
				(anchor circle)
			)
			(primitives
				(gr_poly
					(pts
						(arc
							(start 0.3048 0.2032)
							(mid 0.275042 0.275042)
							(end 0.2032 0.3048)
						)
						(arc
							(start -0.2032 0.3048)
							(mid -0.275042 0.275042)
							(end -0.3048 0.2032)
						)
						(arc
							(start -0.3048 -0.2032)
							(mid -0.275042 -0.275042)
							(end -0.2032 -0.3048)
						)
						(arc
							(start 0.2032 -0.3048)
							(mid 0.275042 -0.275042)
							(end 0.3048 -0.2032)
						)
					)
					(width 0)
					(fill yes)
				)
			)
		)
		(pad "2" smd custom
			(at 0 0.4445 90)
			(size 0.1524 0.1524)
			(layers "B.Cu" "B.Mask" "B.Paste")
			(net "P1V8_STBY_LL_R")
			(options
				(clearance outline)
				(anchor circle)
			)
			(primitives
				(gr_poly
					(pts
						(arc
							(start 0.3048 0.2032)
							(mid 0.275042 0.275042)
							(end 0.2032 0.3048)
						)
						(arc
							(start -0.2032 0.3048)
							(mid -0.275042 0.275042)
							(end -0.3048 0.2032)
						)
						(arc
							(start -0.3048 -0.2032)
							(mid -0.275042 -0.275042)
							(end -0.2032 -0.3048)
						)
						(arc
							(start 0.2032 -0.3048)
							(mid 0.275042 -0.275042)
							(end 0.3048 -0.2032)
						)
					)
					(width 0)
					(fill yes)
				)
			)
		)
	)
	(footprint ""
		(layer "B.Cu")
		(at 115.894612 -204.978 180)
		(property "Reference" "SR892"
			(at 0 0 0)
			(layer "B.SilkS")
			(hide yes)
			(effects
				(font
					(size 1.27 1.27)
				)
				(justify mirror)
			)
		)
		(property "Value" "0R2J-2-GP"
			(at -0.064008 -3.993896 180)
			(unlocked yes)
			(layer "B.Fab")
			(hide yes)
			(effects
				(font
					(size 1.016 1.016)
					(thickness 0.1524)
				)
				(justify mirror)
			)
		)
		(property "Device Type" "R402H16"
			(at -0.064008 -5.517896 180)
			(unlocked yes)
			(layer "B.Fab")
			(hide yes)
			(effects
				(font
					(size 1.016 1.016)
					(thickness 0.1524)
				)
				(justify mirror)
			)
		)
		(duplicate_pad_numbers_are_jumpers no)
		(fp_line
			(start 0.508 -0.9398)
			(end 0.508 0.9398)
			(stroke
				(width 0.1524)
				(type default)
			)
			(layer "B.SilkS")
		)
		(fp_line
			(start -0.508 -0.9398)
			(end 0.508 -0.9398)
			(stroke
				(width 0.1524)
				(type default)
			)
			(layer "B.SilkS")
		)
		(fp_rect
			(start 0.508 0.9398)
			(end -0.508 -0.9398)
			(stroke
				(width 0)
				(type default)
			)
			(fill no)
			(layer "B.CrtYd")
		)
		(fp_rect
			(start 0.508 0.9398)
			(end -0.508 -0.9398)
			(stroke
				(width 0)
				(type default)
			)
			(fill no)
			(layer "B.Fab")
		)
		(pad "1" smd custom
			(at 0 -0.4445)
			(size 0.1397 0.1397)
			(layers "B.Cu" "B.Mask" "B.Paste")
			(net "REDV_RX7_N")
			(options
				(clearance outline)
				(anchor circle)
			)
			(primitives
				(gr_poly
					(pts
						(arc
							(start -0.1778 0.2794)
							(mid -0.249642 0.249642)
							(end -0.2794 0.1778)
						)
						(arc
							(start -0.2794 -0.1778)
							(mid -0.249642 -0.249642)
							(end -0.1778 -0.2794)
						)
						(arc
							(start 0.1778 -0.2794)
							(mid 0.249642 -0.249642)
							(end 0.2794 -0.1778)
						)
						(arc
							(start 0.2794 0.1778)
							(mid 0.249642 0.249642)
							(end 0.1778 0.2794)
						)
					)
					(width 0)
					(fill yes)
				)
			)
		)
		(pad "2" smd custom
			(at 0 0.4445)
			(size 0.1397 0.1397)
			(layers "B.Cu" "B.Mask" "B.Paste")
			(net "SAS_HDD_CONN_RX7_N")
			(options
				(clearance outline)
				(anchor circle)
			)
			(primitives
				(gr_poly
					(pts
						(arc
							(start -0.1778 0.2794)
							(mid -0.249642 0.249642)
							(end -0.2794 0.1778)
						)
						(arc
							(start -0.2794 -0.1778)
							(mid -0.249642 -0.249642)
							(end -0.1778 -0.2794)
						)
						(arc
							(start 0.1778 -0.2794)
							(mid 0.249642 -0.249642)
							(end 0.2794 -0.1778)
						)
						(arc
							(start 0.2794 0.1778)
							(mid 0.249642 0.249642)
							(end 0.1778 0.2794)
						)
					)
					(width 0)
					(fill yes)
				)
			)
		)
	)
	(footprint ""
		(layer "B.Cu")
		(at 125.99797 -102.997 90)
		(property "Reference" "SC1162"
			(at 0 0 90)
			(layer "B.SilkS")
			(hide yes)
			(effects
				(font
					(size 1.27 1.27)
				)
				(justify mirror)
			)
		)
		(property "Value" "SCD1U6D3V1KX-GP"
			(at 2.8321 -1.7399 90)
			(unlocked yes)
			(layer "B.Fab")
			(hide yes)
			(effects
				(font
					(size 1.016 1.016)
					(thickness 0.1524)
				)
				(justify mirror)
			)
		)
		(property "Device Type" "C0201H13"
			(at 2.8321 -3.2639 90)
			(unlocked yes)
			(layer "B.Fab")
			(hide yes)
			(effects
				(font
					(size 1.016 1.016)
					(thickness 0.1524)
				)
				(justify mirror)
			)
		)
		(duplicate_pad_numbers_are_jumpers no)
		(fp_rect
			(start 0.2794 0.6477)
			(end -0.2794 -0.6477)
			(stroke
				(width 0)
				(type default)
			)
			(fill no)
			(layer "B.CrtYd")
		)
		(fp_rect
			(start 0.2794 0.6477)
			(end -0.2794 -0.6477)
			(stroke
				(width 0)
				(type default)
			)
			(fill no)
			(layer "B.Fab")
		)
		(pad "1" smd custom
			(at 0 -0.2794 270)
			(size 0.0762 0.0762)
			(layers "B.Cu" "B.Mask" "B.Paste")
			(net "GB_VDDA")
			(options
				(clearance outline)
				(anchor circle)
			)
			(primitives
				(gr_poly
					(pts
						(arc
							(start 0.1524 0.127)
							(mid 0.137521 0.162921)
							(end 0.1016 0.1778)
						)
						(arc
							(start -0.1016 0.1778)
							(mid -0.137521 0.162921)
							(end -0.1524 0.127)
						)
						(arc
							(start -0.1524 -0.127)
							(mid -0.137521 -0.162921)
							(end -0.1016 -0.1778)
						)
						(arc
							(start 0.1016 -0.1778)
							(mid 0.137521 -0.162921)
							(end 0.1524 -0.127)
						)
					)
					(width 0)
					(fill yes)
				)
			)
		)
		(pad "2" smd custom
			(at 0 0.2794 270)
			(size 0.0762 0.0762)
			(layers "B.Cu" "B.Mask" "B.Paste")
			(net "GND")
			(options
				(clearance outline)
				(anchor circle)
			)
			(primitives
				(gr_poly
					(pts
						(arc
							(start 0.1524 0.127)
							(mid 0.137521 0.162921)
							(end 0.1016 0.1778)
						)
						(arc
							(start -0.1016 0.1778)
							(mid -0.137521 0.162921)
							(end -0.1524 0.127)
						)
						(arc
							(start -0.1524 -0.127)
							(mid -0.137521 -0.162921)
							(end -0.1016 -0.1778)
						)
						(arc
							(start 0.1016 -0.1778)
							(mid 0.137521 -0.162921)
							(end 0.1524 -0.127)
						)
					)
					(width 0)
					(fill yes)
				)
			)
		)
	)
	(footprint ""
		(layer "B.Cu")
		(at 141.36497 -87.249 180)
		(property "Reference" "R176"
			(at 0 0 0)
			(layer "B.SilkS")
			(hide yes)
			(effects
				(font
					(size 1.27 1.27)
				)
				(justify mirror)
			)
		)
		(property "Value" "4K7R2F-GP"
			(at -0.064008 -3.993896 180)
			(unlocked yes)
			(layer "B.Fab")
			(hide yes)
			(effects
				(font
					(size 1.016 1.016)
					(thickness 0.1524)
				)
				(justify mirror)
			)
		)
		(property "Device Type" "R402H16"
			(at -0.064008 -5.517896 180)
			(unlocked yes)
			(layer "B.Fab")
			(hide yes)
			(effects
				(font
					(size 1.016 1.016)
					(thickness 0.1524)
				)
				(justify mirror)
			)
		)
		(duplicate_pad_numbers_are_jumpers no)
		(fp_line
			(start 0.508 -0.9398)
			(end 0.508 0.9398)
			(stroke
				(width 0.1524)
				(type default)
			)
			(layer "B.SilkS")
		)
		(fp_line
			(start -0.508 -0.9398)
			(end 0.508 -0.9398)
			(stroke
				(width 0.1524)
				(type default)
			)
			(layer "B.SilkS")
		)
		(fp_rect
			(start 0.508 0.9398)
			(end -0.508 -0.9398)
			(stroke
				(width 0)
				(type default)
			)
			(fill no)
			(layer "B.CrtYd")
		)
		(fp_rect
			(start 0.508 0.9398)
			(end -0.508 -0.9398)
			(stroke
				(width 0)
				(type default)
			)
			(fill no)
			(layer "B.Fab")
		)
		(pad "1" smd custom
			(at 0 -0.4445)
			(size 0.1397 0.1397)
			(layers "B.Cu" "B.Mask" "B.Paste")
			(net "TEMP_3_A0")
			(options
				(clearance outline)
				(anchor circle)
			)
			(primitives
				(gr_poly
					(pts
						(arc
							(start -0.1778 0.2794)
							(mid -0.249642 0.249642)
							(end -0.2794 0.1778)
						)
						(arc
							(start -0.2794 -0.1778)
							(mid -0.249642 -0.249642)
							(end -0.1778 -0.2794)
						)
						(arc
							(start 0.1778 -0.2794)
							(mid 0.249642 -0.249642)
							(end 0.2794 -0.1778)
						)
						(arc
							(start 0.2794 0.1778)
							(mid 0.249642 0.249642)
							(end 0.1778 0.2794)
						)
					)
					(width 0)
					(fill yes)
				)
			)
		)
		(pad "2" smd custom
			(at 0 0.4445)
			(size 0.1397 0.1397)
			(layers "B.Cu" "B.Mask" "B.Paste")
			(net "GND")
			(options
				(clearance outline)
				(anchor circle)
			)
			(primitives
				(gr_poly
					(pts
						(arc
							(start -0.1778 0.2794)
							(mid -0.249642 0.249642)
							(end -0.2794 0.1778)
						)
						(arc
							(start -0.2794 -0.1778)
							(mid -0.249642 -0.249642)
							(end -0.1778 -0.2794)
						)
						(arc
							(start 0.1778 -0.2794)
							(mid 0.249642 -0.249642)
							(end 0.2794 -0.1778)
						)
						(arc
							(start 0.2794 0.1778)
							(mid 0.249642 0.249642)
							(end 0.1778 0.2794)
						)
					)
					(width 0)
					(fill yes)
				)
			)
		)
	)
	(footprint ""
		(layer "B.Cu")
		(at 110.83417 -99.8474)
		(property "Reference" "SC1135"
			(at 0 0 0)
			(layer "B.SilkS")
			(hide yes)
			(effects
				(font
					(size 1.27 1.27)
				)
				(justify mirror)
			)
		)
		(property "Value" "SCD1U6D3V1KX-GP"
			(at 2.8321 -1.7399 0)
			(unlocked yes)
			(layer "B.Fab")
			(hide yes)
			(effects
				(font
					(size 1.016 1.016)
					(thickness 0.1524)
				)
				(justify mirror)
			)
		)
		(property "Device Type" "C0201H13"
			(at 2.8321 -3.2639 0)
			(unlocked yes)
			(layer "B.Fab")
			(hide yes)
			(effects
				(font
					(size 1.016 1.016)
					(thickness 0.1524)
				)
				(justify mirror)
			)
		)
		(duplicate_pad_numbers_are_jumpers no)
		(fp_rect
			(start 0.2794 0.6477)
			(end -0.2794 -0.6477)
			(stroke
				(width 0)
				(type default)
			)
			(fill no)
			(layer "B.CrtYd")
		)
		(fp_rect
			(start 0.2794 0.6477)
			(end -0.2794 -0.6477)
			(stroke
				(width 0)
				(type default)
			)
			(fill no)
			(layer "B.Fab")
		)
		(pad "1" smd custom
			(at 0 -0.2794 180)
			(size 0.0762 0.0762)
			(layers "B.Cu" "B.Mask" "B.Paste")
			(net "GB_VDDH2")
			(options
				(clearance outline)
				(anchor circle)
			)
			(primitives
				(gr_poly
					(pts
						(arc
							(start 0.1524 0.127)
							(mid 0.137521 0.162921)
							(end 0.1016 0.1778)
						)
						(arc
							(start -0.1016 0.1778)
							(mid -0.137521 0.162921)
							(end -0.1524 0.127)
						)
						(arc
							(start -0.1524 -0.127)
							(mid -0.137521 -0.162921)
							(end -0.1016 -0.1778)
						)
						(arc
							(start 0.1016 -0.1778)
							(mid 0.137521 -0.162921)
							(end 0.1524 -0.127)
						)
					)
					(width 0)
					(fill yes)
				)
			)
		)
		(pad "2" smd custom
			(at 0 0.2794 180)
			(size 0.0762 0.0762)
			(layers "B.Cu" "B.Mask" "B.Paste")
			(net "GND")
			(options
				(clearance outline)
				(anchor circle)
			)
			(primitives
				(gr_poly
					(pts
						(arc
							(start 0.1524 0.127)
							(mid 0.137521 0.162921)
							(end 0.1016 0.1778)
						)
						(arc
							(start -0.1016 0.1778)
							(mid -0.137521 0.162921)
							(end -0.1524 0.127)
						)
						(arc
							(start -0.1524 -0.127)
							(mid -0.137521 -0.162921)
							(end -0.1016 -0.1778)
						)
						(arc
							(start 0.1016 -0.1778)
							(mid 0.137521 -0.162921)
							(end 0.1524 -0.127)
						)
					)
					(width 0)
					(fill yes)
				)
			)
		)
	)
	(footprint ""
		(layer "B.Cu")
		(at 119.01297 -82.042)
		(property "Reference" "STP111"
			(at 0 0 0)
			(layer "B.SilkS")
			(hide yes)
			(effects
				(font
					(size 1.27 1.27)
				)
				(justify mirror)
			)
		)
		(property "Value" "TPAD28"
			(at -0.0127 -1.8034 0)
			(unlocked yes)
			(layer "B.Fab")
			(hide yes)
			(effects
				(font
					(size 1.016 1.016)
					(thickness 0.1524)
				)
				(justify mirror)
			)
		)
		(property "Device Type" "TPAD28"
			(at -0.0127 -3.3274 0)
			(unlocked yes)
			(layer "B.Fab")
			(hide yes)
			(effects
				(font
					(size 1.016 1.016)
					(thickness 0.1524)
				)
				(justify mirror)
			)
		)
		(duplicate_pad_numbers_are_jumpers no)
		(fp_poly
			(pts
				(arc
					(start 0.3556 0)
					(mid -0.3556 0)
					(end 0.3556 0)
				)
			)
			(stroke
				(width 0)
				(type default)
			)
			(fill no)
			(layer "B.CrtYd")
		)
		(fp_poly
			(pts
				(arc
					(start 0.6096 0)
					(mid -0.6096 0)
					(end 0.6096 0)
				)
			)
			(stroke
				(width 0)
				(type default)
			)
			(fill no)
			(layer "B.Fab")
		)
		(pad "1" smd circle
			(at 0 0 180)
			(size 0.7112 0.7112)
			(layers "B.Cu" "B.Mask" "B.Paste")
			(net "TEST_MUX_44")
		)
	)
	(footprint ""
		(layer "B.Cu")
		(at 274.193 -176.657 90)
		(property "Reference" "R344"
			(at 0 0 90)
			(layer "B.SilkS")
			(hide yes)
			(effects
				(font
					(size 1.27 1.27)
				)
				(justify mirror)
			)
		)
		(property "Value" "3K3R2F-2-GP"
			(at -0.064008 -3.993896 90)
			(unlocked yes)
			(layer "B.Fab")
			(hide yes)
			(effects
				(font
					(size 1.016 1.016)
					(thickness 0.1524)
				)
				(justify mirror)
			)
		)
		(property "Device Type" "R402H16"
			(at -0.064008 -5.517896 90)
			(unlocked yes)
			(layer "B.Fab")
			(hide yes)
			(effects
				(font
					(size 1.016 1.016)
					(thickness 0.1524)
				)
				(justify mirror)
			)
		)
		(duplicate_pad_numbers_are_jumpers no)
		(fp_line
			(start 0.508 -0.9398)
			(end 0.508 0.9398)
			(stroke
				(width 0.1524)
				(type default)
			)
			(layer "B.SilkS")
		)
		(fp_line
			(start -0.508 -0.9398)
			(end 0.508 -0.9398)
			(stroke
				(width 0.1524)
				(type default)
			)
			(layer "B.SilkS")
		)
		(fp_rect
			(start 0.508 0.9398)
			(end -0.508 -0.9398)
			(stroke
				(width 0)
				(type default)
			)
			(fill no)
			(layer "B.CrtYd")
		)
		(fp_rect
			(start 0.508 0.9398)
			(end -0.508 -0.9398)
			(stroke
				(width 0)
				(type default)
			)
			(fill no)
			(layer "B.Fab")
		)
		(pad "1" smd custom
			(at 0 -0.4445 270)
			(size 0.1397 0.1397)
			(layers "B.Cu" "B.Mask" "B.Paste")
			(net "P3V3_STBY")
			(options
				(clearance outline)
				(anchor circle)
			)
			(primitives
				(gr_poly
					(pts
						(arc
							(start -0.1778 0.2794)
							(mid -0.249642 0.249642)
							(end -0.2794 0.1778)
						)
						(arc
							(start -0.2794 -0.1778)
							(mid -0.249642 -0.249642)
							(end -0.1778 -0.2794)
						)
						(arc
							(start 0.1778 -0.2794)
							(mid 0.249642 -0.249642)
							(end 0.2794 -0.1778)
						)
						(arc
							(start 0.2794 0.1778)
							(mid 0.249642 0.249642)
							(end 0.1778 0.2794)
						)
					)
					(width 0)
					(fill yes)
				)
			)
		)
		(pad "2" smd custom
			(at 0 0.4445 270)
			(size 0.1397 0.1397)
			(layers "B.Cu" "B.Mask" "B.Paste")
			(net "ROMA9")
			(options
				(clearance outline)
				(anchor circle)
			)
			(primitives
				(gr_poly
					(pts
						(arc
							(start -0.1778 0.2794)
							(mid -0.249642 0.249642)
							(end -0.2794 0.1778)
						)
						(arc
							(start -0.2794 -0.1778)
							(mid -0.249642 -0.249642)
							(end -0.1778 -0.2794)
						)
						(arc
							(start 0.1778 -0.2794)
							(mid 0.249642 -0.249642)
							(end 0.2794 -0.1778)
						)
						(arc
							(start 0.2794 0.1778)
							(mid 0.249642 0.249642)
							(end 0.1778 0.2794)
						)
					)
					(width 0)
					(fill yes)
				)
			)
		)
	)
	(footprint ""
		(layer "B.Cu")
		(at 256.159 -16.891 -90)
		(property "Reference" "R408"
			(at 0 0 90)
			(layer "B.SilkS")
			(hide yes)
			(effects
				(font
					(size 1.27 1.27)
				)
				(justify mirror)
			)
		)
		(property "Value" "15KR2F-GP"
			(at -0.064008 -3.993896 270)
			(unlocked yes)
			(layer "B.Fab")
			(hide yes)
			(effects
				(font
					(size 1.016 1.016)
					(thickness 0.1524)
				)
				(justify mirror)
			)
		)
		(property "Device Type" "R402H16"
			(at -0.064008 -5.517896 270)
			(unlocked yes)
			(layer "B.Fab")
			(hide yes)
			(effects
				(font
					(size 1.016 1.016)
					(thickness 0.1524)
				)
				(justify mirror)
			)
		)
		(duplicate_pad_numbers_are_jumpers no)
		(fp_line
			(start -0.508 -0.9398)
			(end 0.508 -0.9398)
			(stroke
				(width 0.1524)
				(type default)
			)
			(layer "B.SilkS")
		)
		(fp_line
			(start 0.508 -0.9398)
			(end 0.508 0.9398)
			(stroke
				(width 0.1524)
				(type default)
			)
			(layer "B.SilkS")
		)
		(fp_rect
			(start 0.508 0.9398)
			(end -0.508 -0.9398)
			(stroke
				(width 0)
				(type default)
			)
			(fill no)
			(layer "B.CrtYd")
		)
		(fp_rect
			(start 0.508 0.9398)
			(end -0.508 -0.9398)
			(stroke
				(width 0)
				(type default)
			)
			(fill no)
			(layer "B.Fab")
		)
		(pad "1" smd custom
			(at 0 -0.4445 90)
			(size 0.1397 0.1397)
			(layers "B.Cu" "B.Mask" "B.Paste")
			(net "USB_OCS_N1")
			(options
				(clearance outline)
				(anchor circle)
			)
			(primitives
				(gr_poly
					(pts
						(arc
							(start -0.1778 0.2794)
							(mid -0.249642 0.249642)
							(end -0.2794 0.1778)
						)
						(arc
							(start -0.2794 -0.1778)
							(mid -0.249642 -0.249642)
							(end -0.1778 -0.2794)
						)
						(arc
							(start 0.1778 -0.2794)
							(mid 0.249642 -0.249642)
							(end 0.2794 -0.1778)
						)
						(arc
							(start 0.2794 0.1778)
							(mid 0.249642 0.249642)
							(end 0.1778 0.2794)
						)
					)
					(width 0)
					(fill yes)
				)
			)
		)
		(pad "2" smd custom
			(at 0 0.4445 90)
			(size 0.1397 0.1397)
			(layers "B.Cu" "B.Mask" "B.Paste")
			(net "GND")
			(options
				(clearance outline)
				(anchor circle)
			)
			(primitives
				(gr_poly
					(pts
						(arc
							(start -0.1778 0.2794)
							(mid -0.249642 0.249642)
							(end -0.2794 0.1778)
						)
						(arc
							(start -0.2794 -0.1778)
							(mid -0.249642 -0.249642)
							(end -0.1778 -0.2794)
						)
						(arc
							(start 0.1778 -0.2794)
							(mid 0.249642 -0.249642)
							(end 0.2794 -0.1778)
						)
						(arc
							(start 0.2794 0.1778)
							(mid 0.249642 0.249642)
							(end 0.1778 0.2794)
						)
					)
					(width 0)
					(fill yes)
				)
			)
		)
	)
	(footprint ""
		(layer "B.Cu")
		(at 129.648966 -35.814 90)
		(property "Reference" "SL6"
			(at 0 0 90)
			(layer "B.SilkS")
			(hide yes)
			(effects
				(font
					(size 1.27 1.27)
				)
				(justify mirror)
			)
		)
		(property "Value" "MPZ2012S601AT-GP"
			(at 0 -4.2418 90)
			(unlocked yes)
			(layer "B.Fab")
			(hide yes)
			(effects
				(font
					(size 1.016 1.016)
					(thickness 0.1524)
				)
				(justify mirror)
			)
		)
		(property "Device Type" "L805H42"
			(at 0 -5.7912 90)
			(unlocked yes)
			(layer "B.Fab")
			(hide yes)
			(effects
				(font
					(size 1.016 1.016)
					(thickness 0.1524)
				)
				(justify mirror)
			)
		)
		(duplicate_pad_numbers_are_jumpers no)
		(fp_line
			(start 0.889 -1.7018)
			(end -0.889 -1.7018)
			(stroke
				(width 0.1524)
				(type default)
			)
			(layer "B.SilkS")
		)
		(fp_line
			(start -0.889 -1.7018)
			(end -0.889 1.7018)
			(stroke
				(width 0.1524)
				(type default)
			)
			(layer "B.SilkS")
		)
		(fp_line
			(start 0.889 1.7018)
			(end 0.889 -1.7018)
			(stroke
				(width 0.1524)
				(type default)
			)
			(layer "B.SilkS")
		)
		(fp_line
			(start -0.889 1.7018)
			(end 0.889 1.7018)
			(stroke
				(width 0.1524)
				(type default)
			)
			(layer "B.SilkS")
		)
		(fp_rect
			(start 0.9652 1.778)
			(end -0.9652 -1.778)
			(stroke
				(width 0)
				(type default)
			)
			(fill no)
			(layer "B.CrtYd")
		)
		(fp_rect
			(start 0.9652 1.778)
			(end -0.9652 -1.778)
			(stroke
				(width 0)
				(type default)
			)
			(fill no)
			(layer "B.Fab")
		)
		(pad "1" smd rect
			(at 0 -0.9652 270)
			(size 1.397 1.143)
			(layers "B.Cu" "B.Mask" "B.Paste")
			(net "PLL_VDD")
		)
		(pad "2" smd rect
			(at 0 0.9652 270)
			(size 1.397 1.143)
			(layers "B.Cu" "B.Mask" "B.Paste")
			(net "P1V8_C")
		)
	)
	(footprint ""
		(layer "B.Cu")
		(at 113.773966 -28.829 -90)
		(property "Reference" "SR654"
			(at 0 0 90)
			(layer "B.SilkS")
			(hide yes)
			(effects
				(font
					(size 1.27 1.27)
				)
				(justify mirror)
			)
		)
		(property "Value" "4K7R2F-GP"
			(at -0.064008 -3.993896 270)
			(unlocked yes)
			(layer "B.Fab")
			(hide yes)
			(effects
				(font
					(size 1.016 1.016)
					(thickness 0.1524)
				)
				(justify mirror)
			)
		)
		(property "Device Type" "R402H16"
			(at -0.064008 -5.517896 270)
			(unlocked yes)
			(layer "B.Fab")
			(hide yes)
			(effects
				(font
					(size 1.016 1.016)
					(thickness 0.1524)
				)
				(justify mirror)
			)
		)
		(duplicate_pad_numbers_are_jumpers no)
		(fp_line
			(start -0.508 -0.9398)
			(end 0.508 -0.9398)
			(stroke
				(width 0.1524)
				(type default)
			)
			(layer "B.SilkS")
		)
		(fp_line
			(start 0.508 -0.9398)
			(end 0.508 0.9398)
			(stroke
				(width 0.1524)
				(type default)
			)
			(layer "B.SilkS")
		)
		(fp_rect
			(start 0.508 0.9398)
			(end -0.508 -0.9398)
			(stroke
				(width 0)
				(type default)
			)
			(fill no)
			(layer "B.CrtYd")
		)
		(fp_rect
			(start 0.508 0.9398)
			(end -0.508 -0.9398)
			(stroke
				(width 0)
				(type default)
			)
			(fill no)
			(layer "B.Fab")
		)
		(pad "1" smd custom
			(at 0 -0.4445 90)
			(size 0.1397 0.1397)
			(layers "B.Cu" "B.Mask" "B.Paste")
			(net "P1V8_C")
			(options
				(clearance outline)
				(anchor circle)
			)
			(primitives
				(gr_poly
					(pts
						(arc
							(start -0.1778 0.2794)
							(mid -0.249642 0.249642)
							(end -0.2794 0.1778)
						)
						(arc
							(start -0.2794 -0.1778)
							(mid -0.249642 -0.249642)
							(end -0.1778 -0.2794)
						)
						(arc
							(start 0.1778 -0.2794)
							(mid 0.249642 -0.249642)
							(end 0.2794 -0.1778)
						)
						(arc
							(start 0.2794 0.1778)
							(mid 0.249642 0.249642)
							(end 0.1778 0.2794)
						)
					)
					(width 0)
					(fill yes)
				)
			)
		)
		(pad "2" smd custom
			(at 0 0.4445 90)
			(size 0.1397 0.1397)
			(layers "B.Cu" "B.Mask" "B.Paste")
			(net "SYS_RST")
			(options
				(clearance outline)
				(anchor circle)
			)
			(primitives
				(gr_poly
					(pts
						(arc
							(start -0.1778 0.2794)
							(mid -0.249642 0.249642)
							(end -0.2794 0.1778)
						)
						(arc
							(start -0.2794 -0.1778)
							(mid -0.249642 -0.249642)
							(end -0.1778 -0.2794)
						)
						(arc
							(start 0.1778 -0.2794)
							(mid 0.249642 -0.249642)
							(end 0.2794 -0.1778)
						)
						(arc
							(start 0.2794 0.1778)
							(mid 0.249642 0.249642)
							(end 0.1778 0.2794)
						)
					)
					(width 0)
					(fill yes)
				)
			)
		)
	)
	(footprint ""
		(layer "B.Cu")
		(at 102.37597 -82.55)
		(property "Reference" "SC1232"
			(at 0 0 0)
			(layer "B.SilkS")
			(hide yes)
			(effects
				(font
					(size 1.27 1.27)
				)
				(justify mirror)
			)
		)
		(property "Value" "SCD1U6D3V1KX-GP"
			(at 2.8321 -1.7399 0)
			(unlocked yes)
			(layer "B.Fab")
			(hide yes)
			(effects
				(font
					(size 1.016 1.016)
					(thickness 0.1524)
				)
				(justify mirror)
			)
		)
		(property "Device Type" "C0201H13"
			(at 2.8321 -3.2639 0)
			(unlocked yes)
			(layer "B.Fab")
			(hide yes)
			(effects
				(font
					(size 1.016 1.016)
					(thickness 0.1524)
				)
				(justify mirror)
			)
		)
		(duplicate_pad_numbers_are_jumpers no)
		(fp_rect
			(start 0.2794 0.6477)
			(end -0.2794 -0.6477)
			(stroke
				(width 0)
				(type default)
			)
			(fill no)
			(layer "B.CrtYd")
		)
		(fp_rect
			(start 0.2794 0.6477)
			(end -0.2794 -0.6477)
			(stroke
				(width 0)
				(type default)
			)
			(fill no)
			(layer "B.Fab")
		)
		(pad "1" smd custom
			(at 0 -0.2794 180)
			(size 0.0762 0.0762)
			(layers "B.Cu" "B.Mask" "B.Paste")
			(net "P1V8_E")
			(options
				(clearance outline)
				(anchor circle)
			)
			(primitives
				(gr_poly
					(pts
						(arc
							(start 0.1524 0.127)
							(mid 0.137521 0.162921)
							(end 0.1016 0.1778)
						)
						(arc
							(start -0.1016 0.1778)
							(mid -0.137521 0.162921)
							(end -0.1524 0.127)
						)
						(arc
							(start -0.1524 -0.127)
							(mid -0.137521 -0.162921)
							(end -0.1016 -0.1778)
						)
						(arc
							(start 0.1016 -0.1778)
							(mid 0.137521 -0.162921)
							(end 0.1524 -0.127)
						)
					)
					(width 0)
					(fill yes)
				)
			)
		)
		(pad "2" smd custom
			(at 0 0.2794 180)
			(size 0.0762 0.0762)
			(layers "B.Cu" "B.Mask" "B.Paste")
			(net "GND")
			(options
				(clearance outline)
				(anchor circle)
			)
			(primitives
				(gr_poly
					(pts
						(arc
							(start 0.1524 0.127)
							(mid 0.137521 0.162921)
							(end 0.1016 0.1778)
						)
						(arc
							(start -0.1016 0.1778)
							(mid -0.137521 0.162921)
							(end -0.1524 0.127)
						)
						(arc
							(start -0.1524 -0.127)
							(mid -0.137521 -0.162921)
							(end -0.1016 -0.1778)
						)
						(arc
							(start 0.1016 -0.1778)
							(mid 0.137521 -0.162921)
							(end 0.1524 -0.127)
						)
					)
					(width 0)
					(fill yes)
				)
			)
		)
	)
	(footprint ""
		(layer "B.Cu")
		(at 331.499718 -66.73723)
		(property "Reference" ""
			(at 0 0 0)
			(layer "B.SilkS")
			(hide yes)
			(effects
				(font
					(size 1.27 1.27)
				)
				(justify mirror)
			)
		)
		(property "Value" "*"
			(at 5.5753 -0.4572 0)
			(unlocked yes)
			(layer "B.Fab")
			(hide yes)
			(effects
				(font
					(size 1.016 1.016)
					(thickness 0.1524)
				)
				(justify mirror)
			)
		)
		(duplicate_pad_numbers_are_jumpers no)
		(fp_poly
			(pts
				(arc
					(start 4.3053 0)
					(mid -4.3053 0)
					(end 4.3053 0)
				)
			)
			(stroke
				(width 0)
				(type default)
			)
			(fill no)
			(layer "B.CrtYd")
		)
		(fp_poly
			(pts
				(arc
					(start 4.3053 0)
					(mid -4.3053 0)
					(end 4.3053 0)
				)
			)
			(stroke
				(width 0)
				(type default)
			)
			(fill no)
			(layer "B.Fab")
		)
		(pad "1" smd custom
			(at 2.95275 0 180)
			(size 2.000013 2.000013)
			(layers "B.Cu" "B.Mask" "B.Paste")
			(net "Net_54")
			(options
				(clearance outline)
				(anchor circle)
			)
			(primitives
				(gr_poly
					(pts
						(arc
							(start 4.0005 -0.00254)
							(mid -4.000501 0)
							(end 4.0005 0.00254)
						)
						(arc
							(start 1.905 0.00254)
							(mid -1.905002 0)
							(end 1.905 -0.00254)
						)
					)
					(width 0)
					(fill yes)
				)
			)
		)
	)
	(footprint ""
		(layer "B.Cu")
		(at 296.790872 -175.078136 -90)
		(property "Reference" "C206"
			(at 0 0 90)
			(layer "B.SilkS")
			(hide yes)
			(effects
				(font
					(size 1.27 1.27)
				)
				(justify mirror)
			)
		)
		(property "Value" "SC1U10V2KX-1GP"
			(at -1.1811 -2.7051 270)
			(unlocked yes)
			(layer "B.Fab")
			(hide yes)
			(effects
				(font
					(size 1.016 1.016)
					(thickness 0.1524)
				)
				(justify mirror)
			)
		)
		(property "Device Type" "C402H22"
			(at -1.1811 -4.2291 270)
			(unlocked yes)
			(layer "B.Fab")
			(hide yes)
			(effects
				(font
					(size 1.016 1.016)
					(thickness 0.1524)
				)
				(justify mirror)
			)
		)
		(duplicate_pad_numbers_are_jumpers no)
		(fp_rect
			(start 0.4318 0.9525)
			(end -0.4318 -0.9525)
			(stroke
				(width 0)
				(type default)
			)
			(fill no)
			(layer "B.CrtYd")
		)
		(fp_rect
			(start 0.4318 0.9525)
			(end -0.4318 -0.9525)
			(stroke
				(width 0)
				(type default)
			)
			(fill no)
			(layer "B.Fab")
		)
		(pad "1" smd custom
			(at 0 -0.4445 90)
			(size 0.1524 0.1524)
			(layers "B.Cu" "B.Mask" "B.Paste")
			(net "P1V26_STBY")
			(options
				(clearance outline)
				(anchor circle)
			)
			(primitives
				(gr_poly
					(pts
						(arc
							(start 0.3048 0.2032)
							(mid 0.275042 0.275042)
							(end 0.2032 0.3048)
						)
						(arc
							(start -0.2032 0.3048)
							(mid -0.275042 0.275042)
							(end -0.3048 0.2032)
						)
						(arc
							(start -0.3048 -0.2032)
							(mid -0.275042 -0.275042)
							(end -0.2032 -0.3048)
						)
						(arc
							(start 0.2032 -0.3048)
							(mid 0.275042 -0.275042)
							(end 0.3048 -0.2032)
						)
					)
					(width 0)
					(fill yes)
				)
			)
		)
		(pad "2" smd custom
			(at 0 0.4445 90)
			(size 0.1524 0.1524)
			(layers "B.Cu" "B.Mask" "B.Paste")
			(net "GND")
			(options
				(clearance outline)
				(anchor circle)
			)
			(primitives
				(gr_poly
					(pts
						(arc
							(start 0.3048 0.2032)
							(mid 0.275042 0.275042)
							(end 0.2032 0.3048)
						)
						(arc
							(start -0.2032 0.3048)
							(mid -0.275042 0.275042)
							(end -0.3048 0.2032)
						)
						(arc
							(start -0.3048 -0.2032)
							(mid -0.275042 -0.275042)
							(end -0.2032 -0.3048)
						)
						(arc
							(start 0.2032 -0.3048)
							(mid 0.275042 -0.275042)
							(end 0.3048 -0.2032)
						)
					)
					(width 0)
					(fill yes)
				)
			)
		)
	)
	(footprint ""
		(layer "B.Cu")
		(at 120.904 -35.56 -90)
		(property "Reference" "SR616"
			(at 0 0 90)
			(layer "B.SilkS")
			(hide yes)
			(effects
				(font
					(size 1.27 1.27)
				)
				(justify mirror)
			)
		)
		(property "Value" "2K2R2F-GP"
			(at -0.064008 -3.993896 270)
			(unlocked yes)
			(layer "B.Fab")
			(hide yes)
			(effects
				(font
					(size 1.016 1.016)
					(thickness 0.1524)
				)
				(justify mirror)
			)
		)
		(property "Device Type" "R402H16"
			(at -0.064008 -5.517896 270)
			(unlocked yes)
			(layer "B.Fab")
			(hide yes)
			(effects
				(font
					(size 1.016 1.016)
					(thickness 0.1524)
				)
				(justify mirror)
			)
		)
		(duplicate_pad_numbers_are_jumpers no)
		(fp_line
			(start -0.508 -0.9398)
			(end 0.508 -0.9398)
			(stroke
				(width 0.1524)
				(type default)
			)
			(layer "B.SilkS")
		)
		(fp_line
			(start 0.508 -0.9398)
			(end 0.508 0.9398)
			(stroke
				(width 0.1524)
				(type default)
			)
			(layer "B.SilkS")
		)
		(fp_rect
			(start 0.508 0.9398)
			(end -0.508 -0.9398)
			(stroke
				(width 0)
				(type default)
			)
			(fill no)
			(layer "B.CrtYd")
		)
		(fp_rect
			(start 0.508 0.9398)
			(end -0.508 -0.9398)
			(stroke
				(width 0)
				(type default)
			)
			(fill no)
			(layer "B.Fab")
		)
		(pad "1" smd custom
			(at 0 -0.4445 90)
			(size 0.1397 0.1397)
			(layers "B.Cu" "B.Mask" "B.Paste")
			(net "P1V8_C")
			(options
				(clearance outline)
				(anchor circle)
			)
			(primitives
				(gr_poly
					(pts
						(arc
							(start -0.1778 0.2794)
							(mid -0.249642 0.249642)
							(end -0.2794 0.1778)
						)
						(arc
							(start -0.2794 -0.1778)
							(mid -0.249642 -0.249642)
							(end -0.1778 -0.2794)
						)
						(arc
							(start 0.1778 -0.2794)
							(mid 0.249642 -0.249642)
							(end 0.2794 -0.1778)
						)
						(arc
							(start 0.2794 0.1778)
							(mid 0.249642 0.249642)
							(end 0.1778 0.2794)
						)
					)
					(width 0)
					(fill yes)
				)
			)
		)
		(pad "2" smd custom
			(at 0 0.4445 90)
			(size 0.1397 0.1397)
			(layers "B.Cu" "B.Mask" "B.Paste")
			(net "IOC_SCL_0")
			(options
				(clearance outline)
				(anchor circle)
			)
			(primitives
				(gr_poly
					(pts
						(arc
							(start -0.1778 0.2794)
							(mid -0.249642 0.249642)
							(end -0.2794 0.1778)
						)
						(arc
							(start -0.2794 -0.1778)
							(mid -0.249642 -0.249642)
							(end -0.1778 -0.2794)
						)
						(arc
							(start 0.1778 -0.2794)
							(mid 0.249642 -0.249642)
							(end 0.2794 -0.1778)
						)
						(arc
							(start 0.2794 0.1778)
							(mid 0.249642 0.249642)
							(end 0.1778 0.2794)
						)
					)
					(width 0)
					(fill yes)
				)
			)
		)
	)
	(footprint ""
		(layer "B.Cu")
		(at 298.577 -167.64)
		(property "Reference" "TP155"
			(at 0 0 0)
			(layer "B.SilkS")
			(hide yes)
			(effects
				(font
					(size 1.27 1.27)
				)
				(justify mirror)
			)
		)
		(property "Value" "TPAD28"
			(at -0.0127 -1.8034 0)
			(unlocked yes)
			(layer "B.Fab")
			(hide yes)
			(effects
				(font
					(size 1.016 1.016)
					(thickness 0.1524)
				)
				(justify mirror)
			)
		)
		(property "Device Type" "TPAD28"
			(at -0.0127 -3.3274 0)
			(unlocked yes)
			(layer "B.Fab")
			(hide yes)
			(effects
				(font
					(size 1.016 1.016)
					(thickness 0.1524)
				)
				(justify mirror)
			)
		)
		(duplicate_pad_numbers_are_jumpers no)
		(fp_poly
			(pts
				(arc
					(start 0.3556 0)
					(mid -0.3556 0)
					(end 0.3556 0)
				)
			)
			(stroke
				(width 0)
				(type default)
			)
			(fill no)
			(layer "B.CrtYd")
		)
		(fp_poly
			(pts
				(arc
					(start 0.6096 0)
					(mid -0.6096 0)
					(end 0.6096 0)
				)
			)
			(stroke
				(width 0)
				(type default)
			)
			(fill no)
			(layer "B.Fab")
		)
		(pad "1" smd circle
			(at 0 0 180)
			(size 0.7112 0.7112)
			(layers "B.Cu" "B.Mask" "B.Paste")
			(net "TP_BMC_GPIOA7")
		)
	)
	(footprint ""
		(layer "B.Cu")
		(at 98.264726 -54.7116 90)
		(property "Reference" "SC1004"
			(at 0 0 90)
			(layer "B.SilkS")
			(hide yes)
			(effects
				(font
					(size 1.27 1.27)
				)
				(justify mirror)
			)
		)
		(property "Value" "SCD1U16V2KX-3GP"
			(at -1.1811 -2.7051 90)
			(unlocked yes)
			(layer "B.Fab")
			(hide yes)
			(effects
				(font
					(size 1.016 1.016)
					(thickness 0.1524)
				)
				(justify mirror)
			)
		)
		(property "Device Type" "C402H22"
			(at -1.1811 -4.2291 90)
			(unlocked yes)
			(layer "B.Fab")
			(hide yes)
			(effects
				(font
					(size 1.016 1.016)
					(thickness 0.1524)
				)
				(justify mirror)
			)
		)
		(duplicate_pad_numbers_are_jumpers no)
		(fp_rect
			(start 0.4318 0.9525)
			(end -0.4318 -0.9525)
			(stroke
				(width 0)
				(type default)
			)
			(fill no)
			(layer "B.CrtYd")
		)
		(fp_rect
			(start 0.4318 0.9525)
			(end -0.4318 -0.9525)
			(stroke
				(width 0)
				(type default)
			)
			(fill no)
			(layer "B.Fab")
		)
		(pad "1" smd custom
			(at 0 -0.4445 270)
			(size 0.1524 0.1524)
			(layers "B.Cu" "B.Mask" "B.Paste")
			(net "P1V8_C")
			(options
				(clearance outline)
				(anchor circle)
			)
			(primitives
				(gr_poly
					(pts
						(arc
							(start 0.3048 0.2032)
							(mid 0.275042 0.275042)
							(end 0.2032 0.3048)
						)
						(arc
							(start -0.2032 0.3048)
							(mid -0.275042 0.275042)
							(end -0.3048 0.2032)
						)
						(arc
							(start -0.3048 -0.2032)
							(mid -0.275042 -0.275042)
							(end -0.2032 -0.3048)
						)
						(arc
							(start 0.2032 -0.3048)
							(mid 0.275042 -0.275042)
							(end 0.3048 -0.2032)
						)
					)
					(width 0)
					(fill yes)
				)
			)
		)
		(pad "2" smd custom
			(at 0 0.4445 270)
			(size 0.1524 0.1524)
			(layers "B.Cu" "B.Mask" "B.Paste")
			(net "GND")
			(options
				(clearance outline)
				(anchor circle)
			)
			(primitives
				(gr_poly
					(pts
						(arc
							(start 0.3048 0.2032)
							(mid 0.275042 0.275042)
							(end 0.2032 0.3048)
						)
						(arc
							(start -0.2032 0.3048)
							(mid -0.275042 0.275042)
							(end -0.3048 0.2032)
						)
						(arc
							(start -0.3048 -0.2032)
							(mid -0.275042 -0.275042)
							(end -0.2032 -0.3048)
						)
						(arc
							(start 0.2032 -0.3048)
							(mid 0.275042 -0.275042)
							(end 0.3048 -0.2032)
						)
					)
					(width 0)
					(fill yes)
				)
			)
		)
	)
	(footprint ""
		(layer "B.Cu")
		(at 102.997 -228.981 -90)
		(property "Reference" "R665"
			(at 0 0 90)
			(layer "B.SilkS")
			(hide yes)
			(effects
				(font
					(size 1.27 1.27)
				)
				(justify mirror)
			)
		)
		(property "Value" "0R2J-2-GP"
			(at -0.064008 -3.993896 270)
			(unlocked yes)
			(layer "B.Fab")
			(hide yes)
			(effects
				(font
					(size 1.016 1.016)
					(thickness 0.1524)
				)
				(justify mirror)
			)
		)
		(property "Device Type" "R402H16"
			(at -0.064008 -5.517896 270)
			(unlocked yes)
			(layer "B.Fab")
			(hide yes)
			(effects
				(font
					(size 1.016 1.016)
					(thickness 0.1524)
				)
				(justify mirror)
			)
		)
		(duplicate_pad_numbers_are_jumpers no)
		(fp_line
			(start -0.508 -0.9398)
			(end 0.508 -0.9398)
			(stroke
				(width 0.1524)
				(type default)
			)
			(layer "B.SilkS")
		)
		(fp_line
			(start 0.508 -0.9398)
			(end 0.508 0.9398)
			(stroke
				(width 0.1524)
				(type default)
			)
			(layer "B.SilkS")
		)
		(fp_rect
			(start 0.508 0.9398)
			(end -0.508 -0.9398)
			(stroke
				(width 0)
				(type default)
			)
			(fill no)
			(layer "B.CrtYd")
		)
		(fp_rect
			(start 0.508 0.9398)
			(end -0.508 -0.9398)
			(stroke
				(width 0)
				(type default)
			)
			(fill no)
			(layer "B.Fab")
		)
		(pad "1" smd custom
			(at 0 -0.4445 90)
			(size 0.1397 0.1397)
			(layers "B.Cu" "B.Mask" "B.Paste")
			(net "SAS_FAULT_LED3")
			(options
				(clearance outline)
				(anchor circle)
			)
			(primitives
				(gr_poly
					(pts
						(arc
							(start -0.1778 0.2794)
							(mid -0.249642 0.249642)
							(end -0.2794 0.1778)
						)
						(arc
							(start -0.2794 -0.1778)
							(mid -0.249642 -0.249642)
							(end -0.1778 -0.2794)
						)
						(arc
							(start 0.1778 -0.2794)
							(mid 0.249642 -0.249642)
							(end 0.2794 -0.1778)
						)
						(arc
							(start 0.2794 0.1778)
							(mid 0.249642 0.249642)
							(end 0.1778 0.2794)
						)
					)
					(width 0)
					(fill yes)
				)
			)
		)
		(pad "2" smd custom
			(at 0 0.4445 90)
			(size 0.1397 0.1397)
			(layers "B.Cu" "B.Mask" "B.Paste")
			(net "SAS_HDD_LED_3")
			(options
				(clearance outline)
				(anchor circle)
			)
			(primitives
				(gr_poly
					(pts
						(arc
							(start -0.1778 0.2794)
							(mid -0.249642 0.249642)
							(end -0.2794 0.1778)
						)
						(arc
							(start -0.2794 -0.1778)
							(mid -0.249642 -0.249642)
							(end -0.1778 -0.2794)
						)
						(arc
							(start 0.1778 -0.2794)
							(mid 0.249642 -0.249642)
							(end 0.2794 -0.1778)
						)
						(arc
							(start 0.2794 0.1778)
							(mid 0.249642 0.249642)
							(end 0.1778 0.2794)
						)
					)
					(width 0)
					(fill yes)
				)
			)
		)
	)
	(footprint ""
		(layer "B.Cu")
		(at 255.651 -19.431)
		(property "Reference" "C332"
			(at 0 0 0)
			(layer "B.SilkS")
			(hide yes)
			(effects
				(font
					(size 1.27 1.27)
				)
				(justify mirror)
			)
		)
		(property "Value" "SCD1U16V2JX-1-GP"
			(at -1.1811 -2.7051 0)
			(unlocked yes)
			(layer "B.Fab")
			(hide yes)
			(effects
				(font
					(size 1.016 1.016)
					(thickness 0.1524)
				)
				(justify mirror)
			)
		)
		(property "Device Type" "C402H22"
			(at -1.1811 -4.2291 0)
			(unlocked yes)
			(layer "B.Fab")
			(hide yes)
			(effects
				(font
					(size 1.016 1.016)
					(thickness 0.1524)
				)
				(justify mirror)
			)
		)
		(duplicate_pad_numbers_are_jumpers no)
		(fp_rect
			(start 0.4318 0.9525)
			(end -0.4318 -0.9525)
			(stroke
				(width 0)
				(type default)
			)
			(fill no)
			(layer "B.CrtYd")
		)
		(fp_rect
			(start 0.4318 0.9525)
			(end -0.4318 -0.9525)
			(stroke
				(width 0)
				(type default)
			)
			(fill no)
			(layer "B.Fab")
		)
		(pad "1" smd custom
			(at 0 -0.4445 180)
			(size 0.1524 0.1524)
			(layers "B.Cu" "B.Mask" "B.Paste")
			(net "P5V_STBY")
			(options
				(clearance outline)
				(anchor circle)
			)
			(primitives
				(gr_poly
					(pts
						(arc
							(start 0.3048 0.2032)
							(mid 0.275042 0.275042)
							(end 0.2032 0.3048)
						)
						(arc
							(start -0.2032 0.3048)
							(mid -0.275042 0.275042)
							(end -0.3048 0.2032)
						)
						(arc
							(start -0.3048 -0.2032)
							(mid -0.275042 -0.275042)
							(end -0.2032 -0.3048)
						)
						(arc
							(start 0.2032 -0.3048)
							(mid 0.275042 -0.275042)
							(end 0.3048 -0.2032)
						)
					)
					(width 0)
					(fill yes)
				)
			)
		)
		(pad "2" smd custom
			(at 0 0.4445 180)
			(size 0.1524 0.1524)
			(layers "B.Cu" "B.Mask" "B.Paste")
			(net "GND")
			(options
				(clearance outline)
				(anchor circle)
			)
			(primitives
				(gr_poly
					(pts
						(arc
							(start 0.3048 0.2032)
							(mid 0.275042 0.275042)
							(end 0.2032 0.3048)
						)
						(arc
							(start -0.2032 0.3048)
							(mid -0.275042 0.275042)
							(end -0.3048 0.2032)
						)
						(arc
							(start -0.3048 -0.2032)
							(mid -0.275042 -0.275042)
							(end -0.2032 -0.3048)
						)
						(arc
							(start 0.2032 -0.3048)
							(mid 0.275042 -0.275042)
							(end 0.3048 -0.2032)
						)
					)
					(width 0)
					(fill yes)
				)
			)
		)
	)
	(footprint ""
		(layer "B.Cu")
		(at 323.342 -177.8)
		(property "Reference" "R5771"
			(at 0 0 0)
			(layer "B.SilkS")
			(hide yes)
			(effects
				(font
					(size 1.27 1.27)
				)
				(justify mirror)
			)
		)
		(property "Value" "1KR2F-3-GP"
			(at -0.064008 -3.993896 0)
			(unlocked yes)
			(layer "B.Fab")
			(hide yes)
			(effects
				(font
					(size 1.016 1.016)
					(thickness 0.1524)
				)
				(justify mirror)
			)
		)
		(property "Device Type" "R402H16"
			(at -0.064008 -5.517896 0)
			(unlocked yes)
			(layer "B.Fab")
			(hide yes)
			(effects
				(font
					(size 1.016 1.016)
					(thickness 0.1524)
				)
				(justify mirror)
			)
		)
		(duplicate_pad_numbers_are_jumpers no)
		(fp_line
			(start -0.508 -0.9398)
			(end 0.508 -0.9398)
			(stroke
				(width 0.1524)
				(type default)
			)
			(layer "B.SilkS")
		)
		(fp_line
			(start 0.508 -0.9398)
			(end 0.508 0.9398)
			(stroke
				(width 0.1524)
				(type default)
			)
			(layer "B.SilkS")
		)
		(fp_rect
			(start 0.508 0.9398)
			(end -0.508 -0.9398)
			(stroke
				(width 0)
				(type default)
			)
			(fill no)
			(layer "B.CrtYd")
		)
		(fp_rect
			(start 0.508 0.9398)
			(end -0.508 -0.9398)
			(stroke
				(width 0)
				(type default)
			)
			(fill no)
			(layer "B.Fab")
		)
		(pad "1" smd custom
			(at 0 -0.4445 180)
			(size 0.1397 0.1397)
			(layers "B.Cu" "B.Mask" "B.Paste")
			(net "ADC_P5V_STBY")
			(options
				(clearance outline)
				(anchor circle)
			)
			(primitives
				(gr_poly
					(pts
						(arc
							(start -0.1778 0.2794)
							(mid -0.249642 0.249642)
							(end -0.2794 0.1778)
						)
						(arc
							(start -0.2794 -0.1778)
							(mid -0.249642 -0.249642)
							(end -0.1778 -0.2794)
						)
						(arc
							(start 0.1778 -0.2794)
							(mid 0.249642 -0.249642)
							(end 0.2794 -0.1778)
						)
						(arc
							(start 0.2794 0.1778)
							(mid 0.249642 0.249642)
							(end 0.1778 0.2794)
						)
					)
					(width 0)
					(fill yes)
				)
			)
		)
		(pad "2" smd custom
			(at 0 0.4445 180)
			(size 0.1397 0.1397)
			(layers "B.Cu" "B.Mask" "B.Paste")
			(net "GND")
			(options
				(clearance outline)
				(anchor circle)
			)
			(primitives
				(gr_poly
					(pts
						(arc
							(start -0.1778 0.2794)
							(mid -0.249642 0.249642)
							(end -0.2794 0.1778)
						)
						(arc
							(start -0.2794 -0.1778)
							(mid -0.249642 -0.249642)
							(end -0.1778 -0.2794)
						)
						(arc
							(start 0.1778 -0.2794)
							(mid 0.249642 -0.249642)
							(end 0.2794 -0.1778)
						)
						(arc
							(start 0.2794 0.1778)
							(mid 0.249642 0.249642)
							(end 0.1778 0.2794)
						)
					)
					(width 0)
					(fill yes)
				)
			)
		)
	)
	(footprint ""
		(layer "B.Cu")
		(at 78.105 -74.041 180)
		(property "Reference" "PC223"
			(at 0 0 0)
			(layer "B.SilkS")
			(hide yes)
			(effects
				(font
					(size 1.27 1.27)
				)
				(justify mirror)
			)
		)
		(property "Value" "SCD1U50V3KX-GP"
			(at 0 -2.8194 180)
			(unlocked yes)
			(layer "B.Fab")
			(hide yes)
			(effects
				(font
					(size 1.016 1.016)
					(thickness 0.1524)
				)
				(justify mirror)
			)
		)
		(property "Device Type" "C603H36"
			(at 0 -4.3434 180)
			(unlocked yes)
			(layer "B.Fab")
			(hide yes)
			(effects
				(font
					(size 1.016 1.016)
					(thickness 0.1524)
				)
				(justify mirror)
			)
		)
		(duplicate_pad_numbers_are_jumpers no)
		(fp_line
			(start -0.508 0)
			(end 0.508 0)
			(stroke
				(width 0.2032)
				(type default)
			)
			(layer "B.SilkS")
		)
		(fp_rect
			(start 0.5842 1.3335)
			(end -0.5842 -1.3335)
			(stroke
				(width 0)
				(type default)
			)
			(fill no)
			(layer "B.CrtYd")
		)
		(fp_rect
			(start 0.5842 1.3335)
			(end -0.5842 -1.3335)
			(stroke
				(width 0)
				(type default)
			)
			(fill no)
			(layer "B.Fab")
		)
		(pad "1" smd custom
			(at 0 -0.762)
			(size 0.2159 0.2159)
			(layers "B.Cu" "B.Mask" "B.Paste")
			(net "P1V8_C")
			(options
				(clearance outline)
				(anchor circle)
			)
			(primitives
				(gr_poly
					(pts
						(arc
							(start -0.3302 0.4318)
							(mid -0.402042 0.402042)
							(end -0.4318 0.3302)
						)
						(arc
							(start -0.4318 -0.3302)
							(mid -0.402042 -0.402042)
							(end -0.3302 -0.4318)
						)
						(arc
							(start 0.3302 -0.4318)
							(mid 0.402042 -0.402042)
							(end 0.4318 -0.3302)
						)
						(arc
							(start 0.4318 0.3302)
							(mid 0.402042 0.402042)
							(end 0.3302 0.4318)
						)
					)
					(width 0)
					(fill yes)
				)
			)
		)
		(pad "2" smd custom
			(at 0 0.762)
			(size 0.2159 0.2159)
			(layers "B.Cu" "B.Mask" "B.Paste")
			(net "GND")
			(options
				(clearance outline)
				(anchor circle)
			)
			(primitives
				(gr_poly
					(pts
						(arc
							(start -0.3302 0.4318)
							(mid -0.402042 0.402042)
							(end -0.4318 0.3302)
						)
						(arc
							(start -0.4318 -0.3302)
							(mid -0.402042 -0.402042)
							(end -0.3302 -0.4318)
						)
						(arc
							(start 0.3302 -0.4318)
							(mid 0.402042 -0.402042)
							(end 0.4318 -0.3302)
						)
						(arc
							(start 0.4318 0.3302)
							(mid 0.402042 0.402042)
							(end 0.3302 0.4318)
						)
					)
					(width 0)
					(fill yes)
				)
			)
		)
	)
	(footprint ""
		(layer "B.Cu")
		(at 90.913966 -32.639 -90)
		(property "Reference" "SC958"
			(at 0 0 90)
			(layer "B.SilkS")
			(hide yes)
			(effects
				(font
					(size 1.27 1.27)
				)
				(justify mirror)
			)
		)
		(property "Value" "SC1U6D3V1MX-GP"
			(at -1.9177 2.0193 270)
			(unlocked yes)
			(layer "B.Fab")
			(hide yes)
			(effects
				(font
					(size 1.016 1.016)
					(thickness 0.1524)
				)
				(justify mirror)
			)
		)
		(property "Device Type" "C0201H14"
			(at -1.9177 0.4953 270)
			(unlocked yes)
			(layer "B.Fab")
			(hide yes)
			(effects
				(font
					(size 1.016 1.016)
					(thickness 0.1524)
				)
				(justify mirror)
			)
		)
		(duplicate_pad_numbers_are_jumpers no)
		(fp_rect
			(start 0.1524 0.3048)
			(end -0.1524 -0.3048)
			(stroke
				(width 0)
				(type default)
			)
			(fill no)
			(layer "B.CrtYd")
		)
		(fp_poly
			(pts
				(xy 0.2794 0.6477) (xy 0.2794 -0.6477) (xy -0.2794 -0.6477) (xy -0.2794 -0.1905) (xy -0.1524 -0.1905)
				(xy -0.1524 -0.3048) (xy 0.1524 -0.3048) (xy 0.1524 0.3048) (xy -0.1524 0.3048) (xy -0.1524 -0.1778)
				(xy -0.2794 -0.1778) (xy -0.2794 0.6477)
			)
			(stroke
				(width 0)
				(type default)
			)
			(fill no)
			(layer "B.CrtYd")
		)
		(fp_rect
			(start 0.2794 0.6477)
			(end -0.2794 -0.6477)
			(stroke
				(width 0)
				(type default)
			)
			(fill no)
			(layer "B.Fab")
		)
		(pad "1" smd custom
			(at 0 -0.2794 90)
			(size 0.0762 0.0762)
			(layers "B.Cu" "B.Mask" "B.Paste")
			(net "SAS0_AVDD")
			(options
				(clearance outline)
				(anchor circle)
			)
			(primitives
				(gr_poly
					(pts
						(arc
							(start 0.1524 0.127)
							(mid 0.137521 0.162921)
							(end 0.1016 0.1778)
						)
						(arc
							(start -0.1016 0.1778)
							(mid -0.137521 0.162921)
							(end -0.1524 0.127)
						)
						(arc
							(start -0.1524 -0.127)
							(mid -0.137521 -0.162921)
							(end -0.1016 -0.1778)
						)
						(arc
							(start 0.1016 -0.1778)
							(mid 0.137521 -0.162921)
							(end 0.1524 -0.127)
						)
					)
					(width 0)
					(fill yes)
				)
			)
		)
		(pad "2" smd custom
			(at 0 0.2794 90)
			(size 0.0762 0.0762)
			(layers "B.Cu" "B.Mask" "B.Paste")
			(net "GND")
			(options
				(clearance outline)
				(anchor circle)
			)
			(primitives
				(gr_poly
					(pts
						(arc
							(start 0.1524 0.127)
							(mid 0.137521 0.162921)
							(end 0.1016 0.1778)
						)
						(arc
							(start -0.1016 0.1778)
							(mid -0.137521 0.162921)
							(end -0.1524 0.127)
						)
						(arc
							(start -0.1524 -0.127)
							(mid -0.137521 -0.162921)
							(end -0.1016 -0.1778)
						)
						(arc
							(start 0.1016 -0.1778)
							(mid 0.137521 -0.162921)
							(end 0.1524 -0.127)
						)
					)
					(width 0)
					(fill yes)
				)
			)
		)
	)
	(footprint ""
		(layer "B.Cu")
		(at 92.056966 -35.433 -90)
		(property "Reference" "SC960"
			(at 0 0 90)
			(layer "B.SilkS")
			(hide yes)
			(effects
				(font
					(size 1.27 1.27)
				)
				(justify mirror)
			)
		)
		(property "Value" "SCD1U6D3V1KX-GP"
			(at 2.8321 -1.7399 270)
			(unlocked yes)
			(layer "B.Fab")
			(hide yes)
			(effects
				(font
					(size 1.016 1.016)
					(thickness 0.1524)
				)
				(justify mirror)
			)
		)
		(property "Device Type" "C0201H13"
			(at 2.8321 -3.2639 270)
			(unlocked yes)
			(layer "B.Fab")
			(hide yes)
			(effects
				(font
					(size 1.016 1.016)
					(thickness 0.1524)
				)
				(justify mirror)
			)
		)
		(duplicate_pad_numbers_are_jumpers no)
		(fp_rect
			(start 0.2794 0.6477)
			(end -0.2794 -0.6477)
			(stroke
				(width 0)
				(type default)
			)
			(fill no)
			(layer "B.CrtYd")
		)
		(fp_rect
			(start 0.2794 0.6477)
			(end -0.2794 -0.6477)
			(stroke
				(width 0)
				(type default)
			)
			(fill no)
			(layer "B.Fab")
		)
		(pad "1" smd custom
			(at 0 -0.2794 90)
			(size 0.0762 0.0762)
			(layers "B.Cu" "B.Mask" "B.Paste")
			(net "SAS0_AVDD")
			(options
				(clearance outline)
				(anchor circle)
			)
			(primitives
				(gr_poly
					(pts
						(arc
							(start 0.1524 0.127)
							(mid 0.137521 0.162921)
							(end 0.1016 0.1778)
						)
						(arc
							(start -0.1016 0.1778)
							(mid -0.137521 0.162921)
							(end -0.1524 0.127)
						)
						(arc
							(start -0.1524 -0.127)
							(mid -0.137521 -0.162921)
							(end -0.1016 -0.1778)
						)
						(arc
							(start 0.1016 -0.1778)
							(mid 0.137521 -0.162921)
							(end 0.1524 -0.127)
						)
					)
					(width 0)
					(fill yes)
				)
			)
		)
		(pad "2" smd custom
			(at 0 0.2794 90)
			(size 0.0762 0.0762)
			(layers "B.Cu" "B.Mask" "B.Paste")
			(net "GND")
			(options
				(clearance outline)
				(anchor circle)
			)
			(primitives
				(gr_poly
					(pts
						(arc
							(start 0.1524 0.127)
							(mid 0.137521 0.162921)
							(end 0.1016 0.1778)
						)
						(arc
							(start -0.1016 0.1778)
							(mid -0.137521 0.162921)
							(end -0.1524 0.127)
						)
						(arc
							(start -0.1524 -0.127)
							(mid -0.137521 -0.162921)
							(end -0.1016 -0.1778)
						)
						(arc
							(start 0.1016 -0.1778)
							(mid 0.137521 -0.162921)
							(end 0.1524 -0.127)
						)
					)
					(width 0)
					(fill yes)
				)
			)
		)
	)
	(footprint ""
		(layer "B.Cu")
		(at 120.96877 -79.9084 90)
		(property "Reference" "SC1151"
			(at 0 0 90)
			(layer "B.SilkS")
			(hide yes)
			(effects
				(font
					(size 1.27 1.27)
				)
				(justify mirror)
			)
		)
		(property "Value" "SC10U6D3V5KX-4GP"
			(at 0.0762 -6.1214 90)
			(unlocked yes)
			(layer "B.Fab")
			(hide yes)
			(effects
				(font
					(size 1.016 1.016)
					(thickness 0.1524)
				)
				(justify mirror)
			)
		)
		(property "Device Type" "C805H58"
			(at 0.0762 -8.1534 90)
			(unlocked yes)
			(layer "B.Fab")
			(hide yes)
			(effects
				(font
					(size 1.016 1.016)
					(thickness 0.1524)
				)
				(justify mirror)
			)
		)
		(duplicate_pad_numbers_are_jumpers no)
		(fp_line
			(start -0.635 0)
			(end 0.635 0)
			(stroke
				(width 0.508)
				(type default)
			)
			(layer "B.SilkS")
		)
		(fp_rect
			(start 0.9652 1.778)
			(end -0.9652 -1.778)
			(stroke
				(width 0)
				(type default)
			)
			(fill no)
			(layer "B.CrtYd")
		)
		(fp_poly
			(pts
				(xy 0.9652 -1.778) (xy -0.9652 -1.778) (xy -0.9652 1.778) (xy 0.9652 1.778)
			)
			(stroke
				(width 0)
				(type default)
			)
			(fill no)
			(layer "B.Fab")
		)
		(pad "1" smd rect
			(at 0 -0.9652 270)
			(size 1.397 1.143)
			(layers "B.Cu" "B.Mask" "B.Paste")
			(net "XTAL_VDDA18")
		)
		(pad "2" smd rect
			(at 0 0.9652 270)
			(size 1.397 1.143)
			(layers "B.Cu" "B.Mask" "B.Paste")
			(net "GND")
		)
	)
	(footprint ""
		(layer "B.Cu")
		(at 47.82693 -80.063086)
		(property "Reference" "TP147"
			(at 0 0 0)
			(layer "B.SilkS")
			(hide yes)
			(effects
				(font
					(size 1.27 1.27)
				)
				(justify mirror)
			)
		)
		(property "Value" "TPAD32-GP"
			(at 0 -3.166364 0)
			(unlocked yes)
			(layer "B.Fab")
			(hide yes)
			(effects
				(font
					(size 1.016 1.016)
					(thickness 0.1524)
				)
				(justify mirror)
			)
		)
		(property "Device Type" "TPAD32"
			(at 0 -4.690618 0)
			(unlocked yes)
			(layer "B.Fab")
			(hide yes)
			(effects
				(font
					(size 1.016 1.016)
					(thickness 0.1524)
				)
				(justify mirror)
			)
		)
		(duplicate_pad_numbers_are_jumpers no)
		(fp_poly
			(pts
				(arc
					(start 0.4064 0)
					(mid -0.4064 0)
					(end 0.4064 0)
				)
			)
			(stroke
				(width 0)
				(type default)
			)
			(fill no)
			(layer "B.CrtYd")
		)
		(fp_poly
			(pts
				(arc
					(start 0.7112 0)
					(mid -0.7112 0)
					(end 0.7112 0)
				)
			)
			(stroke
				(width 0)
				(type default)
			)
			(fill no)
			(layer "B.Fab")
		)
		(pad "1" smd circle
			(at 0 0 180)
			(size 0.8128 0.8128)
			(layers "B.Cu" "B.Mask" "B.Paste")
			(net "INT_CONN_A_SB1")
		)
	)
	(footprint ""
		(layer "B.Cu")
		(at 20.135088 -185.421016 90)
		(property "Reference" "SC547"
			(at 0 0 90)
			(layer "B.SilkS")
			(hide yes)
			(effects
				(font
					(size 1.27 1.27)
				)
				(justify mirror)
			)
		)
		(property "Value" "SCD1U16V2KX-3GP"
			(at -1.1811 -2.7051 90)
			(unlocked yes)
			(layer "B.Fab")
			(hide yes)
			(effects
				(font
					(size 1.016 1.016)
					(thickness 0.1524)
				)
				(justify mirror)
			)
		)
		(property "Device Type" "C402H22"
			(at -1.1811 -4.2291 90)
			(unlocked yes)
			(layer "B.Fab")
			(hide yes)
			(effects
				(font
					(size 1.016 1.016)
					(thickness 0.1524)
				)
				(justify mirror)
			)
		)
		(duplicate_pad_numbers_are_jumpers no)
		(fp_rect
			(start 0.4318 0.9525)
			(end -0.4318 -0.9525)
			(stroke
				(width 0)
				(type default)
			)
			(fill no)
			(layer "B.CrtYd")
		)
		(fp_rect
			(start 0.4318 0.9525)
			(end -0.4318 -0.9525)
			(stroke
				(width 0)
				(type default)
			)
			(fill no)
			(layer "B.Fab")
		)
		(pad "1" smd custom
			(at 0 -0.4445 270)
			(size 0.1524 0.1524)
			(layers "B.Cu" "B.Mask" "B.Paste")
			(net "P3V3_STBY")
			(options
				(clearance outline)
				(anchor circle)
			)
			(primitives
				(gr_poly
					(pts
						(arc
							(start 0.3048 0.2032)
							(mid 0.275042 0.275042)
							(end 0.2032 0.3048)
						)
						(arc
							(start -0.2032 0.3048)
							(mid -0.275042 0.275042)
							(end -0.3048 0.2032)
						)
						(arc
							(start -0.3048 -0.2032)
							(mid -0.275042 -0.275042)
							(end -0.2032 -0.3048)
						)
						(arc
							(start 0.2032 -0.3048)
							(mid 0.275042 -0.275042)
							(end 0.3048 -0.2032)
						)
					)
					(width 0)
					(fill yes)
				)
			)
		)
		(pad "2" smd custom
			(at 0 0.4445 270)
			(size 0.1524 0.1524)
			(layers "B.Cu" "B.Mask" "B.Paste")
			(net "GND")
			(options
				(clearance outline)
				(anchor circle)
			)
			(primitives
				(gr_poly
					(pts
						(arc
							(start 0.3048 0.2032)
							(mid 0.275042 0.275042)
							(end 0.2032 0.3048)
						)
						(arc
							(start -0.2032 0.3048)
							(mid -0.275042 0.275042)
							(end -0.3048 0.2032)
						)
						(arc
							(start -0.3048 -0.2032)
							(mid -0.275042 -0.275042)
							(end -0.2032 -0.3048)
						)
						(arc
							(start 0.2032 -0.3048)
							(mid 0.275042 -0.275042)
							(end 0.3048 -0.2032)
						)
					)
					(width 0)
					(fill yes)
				)
			)
		)
	)
	(footprint ""
		(layer "B.Cu")
		(at 114.41557 -92.3798)
		(property "Reference" "SC1256"
			(at 0 0 0)
			(layer "B.SilkS")
			(hide yes)
			(effects
				(font
					(size 1.27 1.27)
				)
				(justify mirror)
			)
		)
		(property "Value" "SCD1U6D3V1KX-GP"
			(at 2.8321 -1.7399 0)
			(unlocked yes)
			(layer "B.Fab")
			(hide yes)
			(effects
				(font
					(size 1.016 1.016)
					(thickness 0.1524)
				)
				(justify mirror)
			)
		)
		(property "Device Type" "C0201H13"
			(at 2.8321 -3.2639 0)
			(unlocked yes)
			(layer "B.Fab")
			(hide yes)
			(effects
				(font
					(size 1.016 1.016)
					(thickness 0.1524)
				)
				(justify mirror)
			)
		)
		(duplicate_pad_numbers_are_jumpers no)
		(fp_rect
			(start 0.2794 0.6477)
			(end -0.2794 -0.6477)
			(stroke
				(width 0)
				(type default)
			)
			(fill no)
			(layer "B.CrtYd")
		)
		(fp_rect
			(start 0.2794 0.6477)
			(end -0.2794 -0.6477)
			(stroke
				(width 0)
				(type default)
			)
			(fill no)
			(layer "B.Fab")
		)
		(pad "1" smd custom
			(at 0 -0.2794 180)
			(size 0.0762 0.0762)
			(layers "B.Cu" "B.Mask" "B.Paste")
			(net "P0V9_E")
			(options
				(clearance outline)
				(anchor circle)
			)
			(primitives
				(gr_poly
					(pts
						(arc
							(start 0.1524 0.127)
							(mid 0.137521 0.162921)
							(end 0.1016 0.1778)
						)
						(arc
							(start -0.1016 0.1778)
							(mid -0.137521 0.162921)
							(end -0.1524 0.127)
						)
						(arc
							(start -0.1524 -0.127)
							(mid -0.137521 -0.162921)
							(end -0.1016 -0.1778)
						)
						(arc
							(start 0.1016 -0.1778)
							(mid 0.137521 -0.162921)
							(end 0.1524 -0.127)
						)
					)
					(width 0)
					(fill yes)
				)
			)
		)
		(pad "2" smd custom
			(at 0 0.2794 180)
			(size 0.0762 0.0762)
			(layers "B.Cu" "B.Mask" "B.Paste")
			(net "GND")
			(options
				(clearance outline)
				(anchor circle)
			)
			(primitives
				(gr_poly
					(pts
						(arc
							(start 0.1524 0.127)
							(mid 0.137521 0.162921)
							(end 0.1016 0.1778)
						)
						(arc
							(start -0.1016 0.1778)
							(mid -0.137521 0.162921)
							(end -0.1524 0.127)
						)
						(arc
							(start -0.1524 -0.127)
							(mid -0.137521 -0.162921)
							(end -0.1016 -0.1778)
						)
						(arc
							(start 0.1016 -0.1778)
							(mid 0.137521 -0.162921)
							(end 0.1524 -0.127)
						)
					)
					(width 0)
					(fill yes)
				)
			)
		)
	)
	(footprint ""
		(layer "B.Cu")
		(at 109.671612 -204.978 180)
		(property "Reference" "SR895"
			(at 0 0 0)
			(layer "B.SilkS")
			(hide yes)
			(effects
				(font
					(size 1.27 1.27)
				)
				(justify mirror)
			)
		)
		(property "Value" "0R2J-2-GP"
			(at -0.064008 -3.993896 180)
			(unlocked yes)
			(layer "B.Fab")
			(hide yes)
			(effects
				(font
					(size 1.016 1.016)
					(thickness 0.1524)
				)
				(justify mirror)
			)
		)
		(property "Device Type" "R402H16"
			(at -0.064008 -5.517896 180)
			(unlocked yes)
			(layer "B.Fab")
			(hide yes)
			(effects
				(font
					(size 1.016 1.016)
					(thickness 0.1524)
				)
				(justify mirror)
			)
		)
		(duplicate_pad_numbers_are_jumpers no)
		(fp_line
			(start 0.508 -0.9398)
			(end 0.508 0.9398)
			(stroke
				(width 0.1524)
				(type default)
			)
			(layer "B.SilkS")
		)
		(fp_line
			(start -0.508 -0.9398)
			(end 0.508 -0.9398)
			(stroke
				(width 0.1524)
				(type default)
			)
			(layer "B.SilkS")
		)
		(fp_rect
			(start 0.508 0.9398)
			(end -0.508 -0.9398)
			(stroke
				(width 0)
				(type default)
			)
			(fill no)
			(layer "B.CrtYd")
		)
		(fp_rect
			(start 0.508 0.9398)
			(end -0.508 -0.9398)
			(stroke
				(width 0)
				(type default)
			)
			(fill no)
			(layer "B.Fab")
		)
		(pad "1" smd custom
			(at 0 -0.4445)
			(size 0.1397 0.1397)
			(layers "B.Cu" "B.Mask" "B.Paste")
			(net "REDV_RX8_P")
			(options
				(clearance outline)
				(anchor circle)
			)
			(primitives
				(gr_poly
					(pts
						(arc
							(start -0.1778 0.2794)
							(mid -0.249642 0.249642)
							(end -0.2794 0.1778)
						)
						(arc
							(start -0.2794 -0.1778)
							(mid -0.249642 -0.249642)
							(end -0.1778 -0.2794)
						)
						(arc
							(start 0.1778 -0.2794)
							(mid 0.249642 -0.249642)
							(end 0.2794 -0.1778)
						)
						(arc
							(start 0.2794 0.1778)
							(mid 0.249642 0.249642)
							(end 0.1778 0.2794)
						)
					)
					(width 0)
					(fill yes)
				)
			)
		)
		(pad "2" smd custom
			(at 0 0.4445)
			(size 0.1397 0.1397)
			(layers "B.Cu" "B.Mask" "B.Paste")
			(net "SAS_HDD_CONN_RX8_P")
			(options
				(clearance outline)
				(anchor circle)
			)
			(primitives
				(gr_poly
					(pts
						(arc
							(start -0.1778 0.2794)
							(mid -0.249642 0.249642)
							(end -0.2794 0.1778)
						)
						(arc
							(start -0.2794 -0.1778)
							(mid -0.249642 -0.249642)
							(end -0.1778 -0.2794)
						)
						(arc
							(start 0.1778 -0.2794)
							(mid 0.249642 -0.249642)
							(end 0.2794 -0.1778)
						)
						(arc
							(start 0.2794 0.1778)
							(mid 0.249642 0.249642)
							(end 0.1778 0.2794)
						)
					)
					(width 0)
					(fill yes)
				)
			)
		)
	)
	(footprint ""
		(layer "B.Cu")
		(at 262.001 -16.891 180)
		(property "Reference" "C334"
			(at 0 0 0)
			(layer "B.SilkS")
			(hide yes)
			(effects
				(font
					(size 1.27 1.27)
				)
				(justify mirror)
			)
		)
		(property "Value" "SC1U10V3KX-4GP-U"
			(at 0 -2.8194 180)
			(unlocked yes)
			(layer "B.Fab")
			(hide yes)
			(effects
				(font
					(size 1.016 1.016)
					(thickness 0.1524)
				)
				(justify mirror)
			)
		)
		(property "Device Type" "C603H36"
			(at 0 -4.3434 180)
			(unlocked yes)
			(layer "B.Fab")
			(hide yes)
			(effects
				(font
					(size 1.016 1.016)
					(thickness 0.1524)
				)
				(justify mirror)
			)
		)
		(duplicate_pad_numbers_are_jumpers no)
		(fp_line
			(start -0.508 0)
			(end 0.508 0)
			(stroke
				(width 0.2032)
				(type default)
			)
			(layer "B.SilkS")
		)
		(fp_rect
			(start 0.5842 1.3335)
			(end -0.5842 -1.3335)
			(stroke
				(width 0)
				(type default)
			)
			(fill no)
			(layer "B.CrtYd")
		)
		(fp_rect
			(start 0.5842 1.3335)
			(end -0.5842 -1.3335)
			(stroke
				(width 0)
				(type default)
			)
			(fill no)
			(layer "B.Fab")
		)
		(pad "1" smd custom
			(at 0 -0.762)
			(size 0.2159 0.2159)
			(layers "B.Cu" "B.Mask" "B.Paste")
			(net "P5V_USB")
			(options
				(clearance outline)
				(anchor circle)
			)
			(primitives
				(gr_poly
					(pts
						(arc
							(start -0.3302 0.4318)
							(mid -0.402042 0.402042)
							(end -0.4318 0.3302)
						)
						(arc
							(start -0.4318 -0.3302)
							(mid -0.402042 -0.402042)
							(end -0.3302 -0.4318)
						)
						(arc
							(start 0.3302 -0.4318)
							(mid 0.402042 -0.402042)
							(end 0.4318 -0.3302)
						)
						(arc
							(start 0.4318 0.3302)
							(mid 0.402042 0.402042)
							(end 0.3302 0.4318)
						)
					)
					(width 0)
					(fill yes)
				)
			)
		)
		(pad "2" smd custom
			(at 0 0.762)
			(size 0.2159 0.2159)
			(layers "B.Cu" "B.Mask" "B.Paste")
			(net "GND")
			(options
				(clearance outline)
				(anchor circle)
			)
			(primitives
				(gr_poly
					(pts
						(arc
							(start -0.3302 0.4318)
							(mid -0.402042 0.402042)
							(end -0.4318 0.3302)
						)
						(arc
							(start -0.4318 -0.3302)
							(mid -0.402042 -0.402042)
							(end -0.3302 -0.4318)
						)
						(arc
							(start 0.3302 -0.4318)
							(mid 0.402042 -0.402042)
							(end 0.4318 -0.3302)
						)
						(arc
							(start 0.4318 0.3302)
							(mid 0.402042 0.402042)
							(end 0.3302 0.4318)
						)
					)
					(width 0)
					(fill yes)
				)
			)
		)
	)
	(footprint ""
		(layer "B.Cu")
		(at 324.358 -177.8)
		(property "Reference" "C8088"
			(at 0 0 0)
			(layer "B.SilkS")
			(hide yes)
			(effects
				(font
					(size 1.27 1.27)
				)
				(justify mirror)
			)
		)
		(property "Value" "SCD1U25V2KX-2-GP"
			(at -1.1811 -2.7051 0)
			(unlocked yes)
			(layer "B.Fab")
			(hide yes)
			(effects
				(font
					(size 1.016 1.016)
					(thickness 0.1524)
				)
				(justify mirror)
			)
		)
		(property "Device Type" "C402H22"
			(at -1.1811 -4.2291 0)
			(unlocked yes)
			(layer "B.Fab")
			(hide yes)
			(effects
				(font
					(size 1.016 1.016)
					(thickness 0.1524)
				)
				(justify mirror)
			)
		)
		(duplicate_pad_numbers_are_jumpers no)
		(fp_rect
			(start 0.4318 0.9525)
			(end -0.4318 -0.9525)
			(stroke
				(width 0)
				(type default)
			)
			(fill no)
			(layer "B.CrtYd")
		)
		(fp_rect
			(start 0.4318 0.9525)
			(end -0.4318 -0.9525)
			(stroke
				(width 0)
				(type default)
			)
			(fill no)
			(layer "B.Fab")
		)
		(pad "1" smd custom
			(at 0 -0.4445 180)
			(size 0.1524 0.1524)
			(layers "B.Cu" "B.Mask" "B.Paste")
			(net "ADC_P5V_STBY")
			(options
				(clearance outline)
				(anchor circle)
			)
			(primitives
				(gr_poly
					(pts
						(arc
							(start 0.3048 0.2032)
							(mid 0.275042 0.275042)
							(end 0.2032 0.3048)
						)
						(arc
							(start -0.2032 0.3048)
							(mid -0.275042 0.275042)
							(end -0.3048 0.2032)
						)
						(arc
							(start -0.3048 -0.2032)
							(mid -0.275042 -0.275042)
							(end -0.2032 -0.3048)
						)
						(arc
							(start 0.2032 -0.3048)
							(mid 0.275042 -0.275042)
							(end 0.3048 -0.2032)
						)
					)
					(width 0)
					(fill yes)
				)
			)
		)
		(pad "2" smd custom
			(at 0 0.4445 180)
			(size 0.1524 0.1524)
			(layers "B.Cu" "B.Mask" "B.Paste")
			(net "GND")
			(options
				(clearance outline)
				(anchor circle)
			)
			(primitives
				(gr_poly
					(pts
						(arc
							(start 0.3048 0.2032)
							(mid 0.275042 0.275042)
							(end 0.2032 0.3048)
						)
						(arc
							(start -0.2032 0.3048)
							(mid -0.275042 0.275042)
							(end -0.3048 0.2032)
						)
						(arc
							(start -0.3048 -0.2032)
							(mid -0.275042 -0.275042)
							(end -0.2032 -0.3048)
						)
						(arc
							(start 0.2032 -0.3048)
							(mid 0.275042 -0.275042)
							(end 0.3048 -0.2032)
						)
					)
					(width 0)
					(fill yes)
				)
			)
		)
	)
	(footprint ""
		(layer "B.Cu")
		(at 68.599812 -39.399718)
		(property "Reference" ""
			(at 0 0 0)
			(layer "B.SilkS")
			(hide yes)
			(effects
				(font
					(size 1.27 1.27)
				)
				(justify mirror)
			)
		)
		(property "Value" "*"
			(at 5.5753 -0.4572 0)
			(unlocked yes)
			(layer "B.Fab")
			(hide yes)
			(effects
				(font
					(size 1.016 1.016)
					(thickness 0.1524)
				)
				(justify mirror)
			)
		)
		(duplicate_pad_numbers_are_jumpers no)
		(fp_poly
			(pts
				(arc
					(start 4.3053 0)
					(mid -4.3053 0)
					(end 4.3053 0)
				)
			)
			(stroke
				(width 0)
				(type default)
			)
			(fill no)
			(layer "B.CrtYd")
		)
		(fp_poly
			(pts
				(arc
					(start 4.3053 0)
					(mid -4.3053 0)
					(end 4.3053 0)
				)
			)
			(stroke
				(width 0)
				(type default)
			)
			(fill no)
			(layer "B.Fab")
		)
		(pad "1" smd custom
			(at 2.95275 0 180)
			(size 2.000013 2.000013)
			(layers "B.Cu" "B.Mask" "B.Paste")
			(net "Net_56")
			(options
				(clearance outline)
				(anchor circle)
			)
			(primitives
				(gr_poly
					(pts
						(arc
							(start 4.0005 -0.00254)
							(mid -4.000501 0)
							(end 4.0005 0.00254)
						)
						(arc
							(start 1.905 0.00254)
							(mid -1.905002 0)
							(end 1.905 -0.00254)
						)
					)
					(width 0)
					(fill yes)
				)
			)
		)
	)
	(footprint ""
		(layer "B.Cu")
		(at 115.551966 -33.02)
		(property "Reference" "STP140"
			(at 0 0 0)
			(layer "B.SilkS")
			(hide yes)
			(effects
				(font
					(size 1.27 1.27)
				)
				(justify mirror)
			)
		)
		(property "Value" "TPAD28"
			(at -0.0127 -1.8034 0)
			(unlocked yes)
			(layer "B.Fab")
			(hide yes)
			(effects
				(font
					(size 1.016 1.016)
					(thickness 0.1524)
				)
				(justify mirror)
			)
		)
		(property "Device Type" "TPAD28"
			(at -0.0127 -3.3274 0)
			(unlocked yes)
			(layer "B.Fab")
			(hide yes)
			(effects
				(font
					(size 1.016 1.016)
					(thickness 0.1524)
				)
				(justify mirror)
			)
		)
		(duplicate_pad_numbers_are_jumpers no)
		(fp_poly
			(pts
				(arc
					(start 0.3556 0)
					(mid -0.3556 0)
					(end 0.3556 0)
				)
			)
			(stroke
				(width 0)
				(type default)
			)
			(fill no)
			(layer "B.CrtYd")
		)
		(fp_poly
			(pts
				(arc
					(start 0.6096 0)
					(mid -0.6096 0)
					(end 0.6096 0)
				)
			)
			(stroke
				(width 0)
				(type default)
			)
			(fill no)
			(layer "B.Fab")
		)
		(pad "1" smd circle
			(at 0 0 180)
			(size 0.7112 0.7112)
			(layers "B.Cu" "B.Mask" "B.Paste")
			(net "IOC_GPIO_21")
		)
	)
	(footprint ""
		(layer "B.Cu")
		(at 81.407 -73.279)
		(property "Reference" "PU99"
			(at 0 0 0)
			(layer "B.SilkS")
			(hide yes)
			(effects
				(font
					(size 1.27 1.27)
				)
				(justify mirror)
			)
		)
		(property "Value" "SNLVC1G17DCKR-GP"
			(at 2.3368 -8.6868 0)
			(unlocked yes)
			(layer "B.Fab")
			(hide yes)
			(effects
				(font
					(size 1.016 1.016)
					(thickness 0.1524)
				)
				(justify mirror)
			)
		)
		(property "Device Type" "SC70-5H44"
			(at 2.3114 -10.414 0)
			(unlocked yes)
			(layer "B.Fab")
			(hide yes)
			(effects
				(font
					(size 1.016 1.016)
					(thickness 0.1524)
				)
				(justify mirror)
			)
		)
		(duplicate_pad_numbers_are_jumpers no)
		(fp_line
			(start -1.3843 -1.8034)
			(end -1.3843 -1.1176)
			(stroke
				(width 0.3302)
				(type default)
			)
			(layer "B.SilkS")
		)
		(fp_line
			(start -1.27 -1.7018)
			(end -1.27 1.7018)
			(stroke
				(width 0.1524)
				(type default)
			)
			(layer "B.SilkS")
		)
		(fp_line
			(start -1.27 1.7018)
			(end 1.27 1.7018)
			(stroke
				(width 0.1524)
				(type default)
			)
			(layer "B.SilkS")
		)
		(fp_line
			(start -0.6604 -1.8034)
			(end -1.3843 -1.8034)
			(stroke
				(width 0.3302)
				(type default)
			)
			(layer "B.SilkS")
		)
		(fp_line
			(start 1.27 -1.7018)
			(end -1.27 -1.7018)
			(stroke
				(width 0.1524)
				(type default)
			)
			(layer "B.SilkS")
		)
		(fp_line
			(start 1.27 1.7018)
			(end 1.27 -1.7018)
			(stroke
				(width 0.1524)
				(type default)
			)
			(layer "B.SilkS")
		)
		(fp_rect
			(start 1.524 1.9558)
			(end -1.524 -1.9558)
			(stroke
				(width 0)
				(type default)
			)
			(fill no)
			(layer "B.CrtYd")
		)
		(fp_poly
			(pts
				(xy 1.524 -1.9558) (xy -1.524 -1.9558) (xy -1.524 1.9558) (xy 1.524 1.9558)
			)
			(stroke
				(width 0)
				(type default)
			)
			(fill no)
			(layer "B.Fab")
		)
		(pad "1" smd rect
			(at -0.65024 -0.8255 180)
			(size 0.4064 1.2192)
			(layers "B.Cu" "B.Mask" "B.Paste")
			(net "Net_287")
		)
		(pad "2" smd rect
			(at 0 -0.8255 180)
			(size 0.4064 1.2192)
			(layers "B.Cu" "B.Mask" "B.Paste")
			(net "PG_STAT")
		)
		(pad "3" smd rect
			(at 0.65024 -0.8255 180)
			(size 0.4064 1.2192)
			(layers "B.Cu" "B.Mask" "B.Paste")
			(net "GND")
		)
		(pad "4" smd rect
			(at 0.65024 0.8255 180)
			(size 0.4064 1.2192)
			(layers "B.Cu" "B.Mask" "B.Paste")
			(net "PWRGD_P0V955_C")
		)
		(pad "5" smd rect
			(at -0.65024 0.8255 180)
			(size 0.4064 1.2192)
			(layers "B.Cu" "B.Mask" "B.Paste")
			(net "P1V8_C")
		)
	)
	(footprint ""
		(layer "B.Cu")
		(at 290.771072 -172.538136 180)
		(property "Reference" "C213"
			(at 0 0 0)
			(layer "B.SilkS")
			(hide yes)
			(effects
				(font
					(size 1.27 1.27)
				)
				(justify mirror)
			)
		)
		(property "Value" "SC1U10V2KX-1GP"
			(at -1.1811 -2.7051 180)
			(unlocked yes)
			(layer "B.Fab")
			(hide yes)
			(effects
				(font
					(size 1.016 1.016)
					(thickness 0.1524)
				)
				(justify mirror)
			)
		)
		(property "Device Type" "C402H22"
			(at -1.1811 -4.2291 180)
			(unlocked yes)
			(layer "B.Fab")
			(hide yes)
			(effects
				(font
					(size 1.016 1.016)
					(thickness 0.1524)
				)
				(justify mirror)
			)
		)
		(duplicate_pad_numbers_are_jumpers no)
		(fp_rect
			(start 0.4318 0.9525)
			(end -0.4318 -0.9525)
			(stroke
				(width 0)
				(type default)
			)
			(fill no)
			(layer "B.CrtYd")
		)
		(fp_rect
			(start 0.4318 0.9525)
			(end -0.4318 -0.9525)
			(stroke
				(width 0)
				(type default)
			)
			(fill no)
			(layer "B.Fab")
		)
		(pad "1" smd custom
			(at 0 -0.4445)
			(size 0.1524 0.1524)
			(layers "B.Cu" "B.Mask" "B.Paste")
			(net "P1V26_STBY")
			(options
				(clearance outline)
				(anchor circle)
			)
			(primitives
				(gr_poly
					(pts
						(arc
							(start 0.3048 0.2032)
							(mid 0.275042 0.275042)
							(end 0.2032 0.3048)
						)
						(arc
							(start -0.2032 0.3048)
							(mid -0.275042 0.275042)
							(end -0.3048 0.2032)
						)
						(arc
							(start -0.3048 -0.2032)
							(mid -0.275042 -0.275042)
							(end -0.2032 -0.3048)
						)
						(arc
							(start 0.2032 -0.3048)
							(mid 0.275042 -0.275042)
							(end 0.3048 -0.2032)
						)
					)
					(width 0)
					(fill yes)
				)
			)
		)
		(pad "2" smd custom
			(at 0 0.4445)
			(size 0.1524 0.1524)
			(layers "B.Cu" "B.Mask" "B.Paste")
			(net "GND")
			(options
				(clearance outline)
				(anchor circle)
			)
			(primitives
				(gr_poly
					(pts
						(arc
							(start 0.3048 0.2032)
							(mid 0.275042 0.275042)
							(end 0.2032 0.3048)
						)
						(arc
							(start -0.2032 0.3048)
							(mid -0.275042 0.275042)
							(end -0.3048 0.2032)
						)
						(arc
							(start -0.3048 -0.2032)
							(mid -0.275042 -0.275042)
							(end -0.2032 -0.3048)
						)
						(arc
							(start 0.2032 -0.3048)
							(mid 0.275042 -0.275042)
							(end 0.3048 -0.2032)
						)
					)
					(width 0)
					(fill yes)
				)
			)
		)
	)
	(footprint ""
		(layer "B.Cu")
		(at 96.715326 -38.94836 180)
		(property "Reference" "SC954"
			(at 0 0 0)
			(layer "B.SilkS")
			(hide yes)
			(effects
				(font
					(size 1.27 1.27)
				)
				(justify mirror)
			)
		)
		(property "Value" "SCD1U6D3V1KX-GP"
			(at 2.8321 -1.7399 180)
			(unlocked yes)
			(layer "B.Fab")
			(hide yes)
			(effects
				(font
					(size 1.016 1.016)
					(thickness 0.1524)
				)
				(justify mirror)
			)
		)
		(property "Device Type" "C0201H13"
			(at 2.8321 -3.2639 180)
			(unlocked yes)
			(layer "B.Fab")
			(hide yes)
			(effects
				(font
					(size 1.016 1.016)
					(thickness 0.1524)
				)
				(justify mirror)
			)
		)
		(duplicate_pad_numbers_are_jumpers no)
		(fp_rect
			(start 0.2794 0.6477)
			(end -0.2794 -0.6477)
			(stroke
				(width 0)
				(type default)
			)
			(fill no)
			(layer "B.CrtYd")
		)
		(fp_rect
			(start 0.2794 0.6477)
			(end -0.2794 -0.6477)
			(stroke
				(width 0)
				(type default)
			)
			(fill no)
			(layer "B.Fab")
		)
		(pad "1" smd custom
			(at 0 -0.2794)
			(size 0.0762 0.0762)
			(layers "B.Cu" "B.Mask" "B.Paste")
			(net "PCE_AVDD")
			(options
				(clearance outline)
				(anchor circle)
			)
			(primitives
				(gr_poly
					(pts
						(arc
							(start 0.1524 0.127)
							(mid 0.137521 0.162921)
							(end 0.1016 0.1778)
						)
						(arc
							(start -0.1016 0.1778)
							(mid -0.137521 0.162921)
							(end -0.1524 0.127)
						)
						(arc
							(start -0.1524 -0.127)
							(mid -0.137521 -0.162921)
							(end -0.1016 -0.1778)
						)
						(arc
							(start 0.1016 -0.1778)
							(mid 0.137521 -0.162921)
							(end 0.1524 -0.127)
						)
					)
					(width 0)
					(fill yes)
				)
			)
		)
		(pad "2" smd custom
			(at 0 0.2794)
			(size 0.0762 0.0762)
			(layers "B.Cu" "B.Mask" "B.Paste")
			(net "GND")
			(options
				(clearance outline)
				(anchor circle)
			)
			(primitives
				(gr_poly
					(pts
						(arc
							(start 0.1524 0.127)
							(mid 0.137521 0.162921)
							(end 0.1016 0.1778)
						)
						(arc
							(start -0.1016 0.1778)
							(mid -0.137521 0.162921)
							(end -0.1524 0.127)
						)
						(arc
							(start -0.1524 -0.127)
							(mid -0.137521 -0.162921)
							(end -0.1016 -0.1778)
						)
						(arc
							(start 0.1016 -0.1778)
							(mid 0.137521 -0.162921)
							(end 0.1524 -0.127)
						)
					)
					(width 0)
					(fill yes)
				)
			)
		)
	)
	(footprint ""
		(layer "B.Cu")
		(at 141.351 -46.863)
		(property "Reference" "STP121"
			(at 0 0 0)
			(layer "B.SilkS")
			(hide yes)
			(effects
				(font
					(size 1.27 1.27)
				)
				(justify mirror)
			)
		)
		(property "Value" "TPAD28"
			(at -0.0127 -1.8034 0)
			(unlocked yes)
			(layer "B.Fab")
			(hide yes)
			(effects
				(font
					(size 1.016 1.016)
					(thickness 0.1524)
				)
				(justify mirror)
			)
		)
		(property "Device Type" "TPAD28"
			(at -0.0127 -3.3274 0)
			(unlocked yes)
			(layer "B.Fab")
			(hide yes)
			(effects
				(font
					(size 1.016 1.016)
					(thickness 0.1524)
				)
				(justify mirror)
			)
		)
		(duplicate_pad_numbers_are_jumpers no)
		(fp_poly
			(pts
				(arc
					(start 0.3556 0)
					(mid -0.3556 0)
					(end 0.3556 0)
				)
			)
			(stroke
				(width 0)
				(type default)
			)
			(fill no)
			(layer "B.CrtYd")
		)
		(fp_poly
			(pts
				(arc
					(start 0.6096 0)
					(mid -0.6096 0)
					(end 0.6096 0)
				)
			)
			(stroke
				(width 0)
				(type default)
			)
			(fill no)
			(layer "B.Fab")
		)
		(pad "1" smd circle
			(at 0 0 180)
			(size 0.7112 0.7112)
			(layers "B.Cu" "B.Mask" "B.Paste")
			(net "XM_ADDR_21")
		)
	)
	(footprint ""
		(layer "B.Cu")
		(at 331.851 -164.338 180)
		(property "Reference" "C4"
			(at 0 0 0)
			(layer "B.SilkS")
			(hide yes)
			(effects
				(font
					(size 1.27 1.27)
				)
				(justify mirror)
			)
		)
		(property "Value" "SCD1U16V2KX-3GP"
			(at -1.1811 -2.7051 180)
			(unlocked yes)
			(layer "B.Fab")
			(hide yes)
			(effects
				(font
					(size 1.016 1.016)
					(thickness 0.1524)
				)
				(justify mirror)
			)
		)
		(property "Device Type" "C402H22"
			(at -1.1811 -4.2291 180)
			(unlocked yes)
			(layer "B.Fab")
			(hide yes)
			(effects
				(font
					(size 1.016 1.016)
					(thickness 0.1524)
				)
				(justify mirror)
			)
		)
		(duplicate_pad_numbers_are_jumpers no)
		(fp_rect
			(start 0.4318 0.9525)
			(end -0.4318 -0.9525)
			(stroke
				(width 0)
				(type default)
			)
			(fill no)
			(layer "B.CrtYd")
		)
		(fp_rect
			(start 0.4318 0.9525)
			(end -0.4318 -0.9525)
			(stroke
				(width 0)
				(type default)
			)
			(fill no)
			(layer "B.Fab")
		)
		(pad "1" smd custom
			(at 0 -0.4445)
			(size 0.1524 0.1524)
			(layers "B.Cu" "B.Mask" "B.Paste")
			(net "P3V3_STBY")
			(options
				(clearance outline)
				(anchor circle)
			)
			(primitives
				(gr_poly
					(pts
						(arc
							(start 0.3048 0.2032)
							(mid 0.275042 0.275042)
							(end 0.2032 0.3048)
						)
						(arc
							(start -0.2032 0.3048)
							(mid -0.275042 0.275042)
							(end -0.3048 0.2032)
						)
						(arc
							(start -0.3048 -0.2032)
							(mid -0.275042 -0.275042)
							(end -0.2032 -0.3048)
						)
						(arc
							(start 0.2032 -0.3048)
							(mid 0.275042 -0.275042)
							(end 0.3048 -0.2032)
						)
					)
					(width 0)
					(fill yes)
				)
			)
		)
		(pad "2" smd custom
			(at 0 0.4445)
			(size 0.1524 0.1524)
			(layers "B.Cu" "B.Mask" "B.Paste")
			(net "GND")
			(options
				(clearance outline)
				(anchor circle)
			)
			(primitives
				(gr_poly
					(pts
						(arc
							(start 0.3048 0.2032)
							(mid 0.275042 0.275042)
							(end 0.2032 0.3048)
						)
						(arc
							(start -0.2032 0.3048)
							(mid -0.275042 0.275042)
							(end -0.3048 0.2032)
						)
						(arc
							(start -0.3048 -0.2032)
							(mid -0.275042 -0.275042)
							(end -0.2032 -0.3048)
						)
						(arc
							(start 0.2032 -0.3048)
							(mid 0.275042 -0.275042)
							(end 0.3048 -0.2032)
						)
					)
					(width 0)
					(fill yes)
				)
			)
		)
	)
	(footprint ""
		(layer "B.Cu")
		(at 185.855864 -28.266136 180)
		(property "Reference" "C231"
			(at 0 0 0)
			(layer "B.SilkS")
			(hide yes)
			(effects
				(font
					(size 1.27 1.27)
				)
				(justify mirror)
			)
		)
		(property "Value" "SCD1U16V2KX-3GP"
			(at -1.1811 -2.7051 180)
			(unlocked yes)
			(layer "B.Fab")
			(hide yes)
			(effects
				(font
					(size 1.016 1.016)
					(thickness 0.1524)
				)
				(justify mirror)
			)
		)
		(property "Device Type" "C402H22"
			(at -1.1811 -4.2291 180)
			(unlocked yes)
			(layer "B.Fab")
			(hide yes)
			(effects
				(font
					(size 1.016 1.016)
					(thickness 0.1524)
				)
				(justify mirror)
			)
		)
		(duplicate_pad_numbers_are_jumpers no)
		(fp_rect
			(start 0.4318 0.9525)
			(end -0.4318 -0.9525)
			(stroke
				(width 0)
				(type default)
			)
			(fill no)
			(layer "B.CrtYd")
		)
		(fp_rect
			(start 0.4318 0.9525)
			(end -0.4318 -0.9525)
			(stroke
				(width 0)
				(type default)
			)
			(fill no)
			(layer "B.Fab")
		)
		(pad "1" smd custom
			(at 0 -0.4445)
			(size 0.1524 0.1524)
			(layers "B.Cu" "B.Mask" "B.Paste")
			(net "P3V3_STBY")
			(options
				(clearance outline)
				(anchor circle)
			)
			(primitives
				(gr_poly
					(pts
						(arc
							(start 0.3048 0.2032)
							(mid 0.275042 0.275042)
							(end 0.2032 0.3048)
						)
						(arc
							(start -0.2032 0.3048)
							(mid -0.275042 0.275042)
							(end -0.3048 0.2032)
						)
						(arc
							(start -0.3048 -0.2032)
							(mid -0.275042 -0.275042)
							(end -0.2032 -0.3048)
						)
						(arc
							(start 0.2032 -0.3048)
							(mid 0.275042 -0.275042)
							(end 0.3048 -0.2032)
						)
					)
					(width 0)
					(fill yes)
				)
			)
		)
		(pad "2" smd custom
			(at 0 0.4445)
			(size 0.1524 0.1524)
			(layers "B.Cu" "B.Mask" "B.Paste")
			(net "GND")
			(options
				(clearance outline)
				(anchor circle)
			)
			(primitives
				(gr_poly
					(pts
						(arc
							(start 0.3048 0.2032)
							(mid 0.275042 0.275042)
							(end 0.2032 0.3048)
						)
						(arc
							(start -0.2032 0.3048)
							(mid -0.275042 0.275042)
							(end -0.3048 0.2032)
						)
						(arc
							(start -0.3048 -0.2032)
							(mid -0.275042 -0.275042)
							(end -0.2032 -0.3048)
						)
						(arc
							(start 0.2032 -0.3048)
							(mid 0.275042 -0.275042)
							(end 0.3048 -0.2032)
						)
					)
					(width 0)
					(fill yes)
				)
			)
		)
	)
	(footprint ""
		(layer "B.Cu")
		(at 103.26497 -82.55)
		(property "Reference" "SR794"
			(at 0 0 0)
			(layer "B.SilkS")
			(hide yes)
			(effects
				(font
					(size 1.27 1.27)
				)
				(justify mirror)
			)
		)
		(property "Value" "10KR2F-2-GP"
			(at -0.064008 -3.993896 0)
			(unlocked yes)
			(layer "B.Fab")
			(hide yes)
			(effects
				(font
					(size 1.016 1.016)
					(thickness 0.1524)
				)
				(justify mirror)
			)
		)
		(property "Device Type" "R402H16"
			(at -0.064008 -5.517896 0)
			(unlocked yes)
			(layer "B.Fab")
			(hide yes)
			(effects
				(font
					(size 1.016 1.016)
					(thickness 0.1524)
				)
				(justify mirror)
			)
		)
		(duplicate_pad_numbers_are_jumpers no)
		(fp_line
			(start -0.508 -0.9398)
			(end 0.508 -0.9398)
			(stroke
				(width 0.1524)
				(type default)
			)
			(layer "B.SilkS")
		)
		(fp_line
			(start 0.508 -0.9398)
			(end 0.508 0.9398)
			(stroke
				(width 0.1524)
				(type default)
			)
			(layer "B.SilkS")
		)
		(fp_rect
			(start 0.508 0.9398)
			(end -0.508 -0.9398)
			(stroke
				(width 0)
				(type default)
			)
			(fill no)
			(layer "B.CrtYd")
		)
		(fp_rect
			(start 0.508 0.9398)
			(end -0.508 -0.9398)
			(stroke
				(width 0)
				(type default)
			)
			(fill no)
			(layer "B.Fab")
		)
		(pad "1" smd custom
			(at 0 -0.4445 180)
			(size 0.1397 0.1397)
			(layers "B.Cu" "B.Mask" "B.Paste")
			(net "SOFT_RESET_N")
			(options
				(clearance outline)
				(anchor circle)
			)
			(primitives
				(gr_poly
					(pts
						(arc
							(start -0.1778 0.2794)
							(mid -0.249642 0.249642)
							(end -0.2794 0.1778)
						)
						(arc
							(start -0.2794 -0.1778)
							(mid -0.249642 -0.249642)
							(end -0.1778 -0.2794)
						)
						(arc
							(start 0.1778 -0.2794)
							(mid 0.249642 -0.249642)
							(end 0.2794 -0.1778)
						)
						(arc
							(start 0.2794 0.1778)
							(mid 0.249642 0.249642)
							(end 0.1778 0.2794)
						)
					)
					(width 0)
					(fill yes)
				)
			)
		)
		(pad "2" smd custom
			(at 0 0.4445 180)
			(size 0.1397 0.1397)
			(layers "B.Cu" "B.Mask" "B.Paste")
			(net "P1V8_E")
			(options
				(clearance outline)
				(anchor circle)
			)
			(primitives
				(gr_poly
					(pts
						(arc
							(start -0.1778 0.2794)
							(mid -0.249642 0.249642)
							(end -0.2794 0.1778)
						)
						(arc
							(start -0.2794 -0.1778)
							(mid -0.249642 -0.249642)
							(end -0.1778 -0.2794)
						)
						(arc
							(start 0.1778 -0.2794)
							(mid 0.249642 -0.249642)
							(end 0.2794 -0.1778)
						)
						(arc
							(start 0.2794 0.1778)
							(mid 0.249642 0.249642)
							(end 0.1778 0.2794)
						)
					)
					(width 0)
					(fill yes)
				)
			)
		)
	)
	(footprint ""
		(layer "B.Cu")
		(at 165.354 -111.379)
		(property "Reference" "Q14"
			(at 0 0 0)
			(layer "B.SilkS")
			(hide yes)
			(effects
				(font
					(size 1.27 1.27)
				)
				(justify mirror)
			)
		)
		(property "Value" "2N7002A-7-GP"
			(at -0.127 -8.9662 0)
			(unlocked yes)
			(layer "B.Fab")
			(hide yes)
			(effects
				(font
					(size 1.016 1.016)
					(thickness 0.1524)
				)
				(justify mirror)
			)
		)
		(property "Device Type" "SOT23DGS2D4H48"
			(at -0.127 -10.4902 0)
			(unlocked yes)
			(layer "B.Fab")
			(hide yes)
			(effects
				(font
					(size 1.016 1.016)
					(thickness 0.1524)
				)
				(justify mirror)
			)
		)
		(duplicate_pad_numbers_are_jumpers no)
		(fp_line
			(start -1.651 -1.778)
			(end 1.651 -1.778)
			(stroke
				(width 0.1524)
				(type default)
			)
			(layer "B.SilkS")
		)
		(fp_line
			(start -1.651 1.778)
			(end -1.651 -1.778)
			(stroke
				(width 0.1524)
				(type default)
			)
			(layer "B.SilkS")
		)
		(fp_line
			(start 1.651 -1.778)
			(end 1.651 1.778)
			(stroke
				(width 0.1524)
				(type default)
			)
			(layer "B.SilkS")
		)
		(fp_line
			(start 1.651 1.778)
			(end -1.651 1.778)
			(stroke
				(width 0.1524)
				(type default)
			)
			(layer "B.SilkS")
		)
		(fp_poly
			(pts
				(xy 1.778 1.8796) (xy 1.778 -1.8796) (xy -1.778 -1.8796) (xy -1.778 1.8796)
			)
			(stroke
				(width 0)
				(type default)
			)
			(fill no)
			(layer "B.CrtYd")
		)
		(fp_poly
			(pts
				(xy 1.778 1.8796) (xy 1.778 -1.8796) (xy -1.778 -1.8796) (xy -1.778 1.8796)
			)
			(stroke
				(width 0)
				(type default)
			)
			(fill no)
			(layer "B.Fab")
		)
		(pad "D" smd custom
			(at 0 -0.9525 180)
			(size 0.1905 0.1905)
			(layers "B.Cu" "B.Mask" "B.Paste")
			(net "P3V3_STBY_R4")
			(options
				(clearance outline)
				(anchor circle)
			)
			(primitives
				(gr_poly
					(pts
						(arc
							(start -0.1778 -0.5715)
							(mid -0.321484 -0.511984)
							(end -0.381 -0.3683)
						)
						(arc
							(start -0.381 0.3683)
							(mid -0.321484 0.511984)
							(end -0.1778 0.5715)
						)
						(arc
							(start 0.1778 0.5715)
							(mid 0.321484 0.511984)
							(end 0.381 0.3683)
						)
						(arc
							(start 0.381 -0.3683)
							(mid 0.321484 -0.511984)
							(end 0.1778 -0.5715)
						)
					)
					(width 0)
					(fill yes)
				)
			)
		)
		(pad "G" smd custom
			(at 0.98425 0.9525 180)
			(size 0.1905 0.1905)
			(layers "B.Cu" "B.Mask" "B.Paste")
			(net "P0V9_E_PG")
			(options
				(clearance outline)
				(anchor circle)
			)
			(primitives
				(gr_poly
					(pts
						(arc
							(start -0.1778 -0.5715)
							(mid -0.321484 -0.511984)
							(end -0.381 -0.3683)
						)
						(arc
							(start -0.381 0.3683)
							(mid -0.321484 0.511984)
							(end -0.1778 0.5715)
						)
						(arc
							(start 0.1778 0.5715)
							(mid 0.321484 0.511984)
							(end 0.381 0.3683)
						)
						(arc
							(start 0.381 -0.3683)
							(mid 0.321484 -0.511984)
							(end 0.1778 -0.5715)
						)
					)
					(width 0)
					(fill yes)
				)
			)
		)
		(pad "S" smd custom
			(at -0.98425 0.9525 180)
			(size 0.1905 0.1905)
			(layers "B.Cu" "B.Mask" "B.Paste")
			(net "GND")
			(options
				(clearance outline)
				(anchor circle)
			)
			(primitives
				(gr_poly
					(pts
						(arc
							(start -0.1778 -0.5715)
							(mid -0.321484 -0.511984)
							(end -0.381 -0.3683)
						)
						(arc
							(start -0.381 0.3683)
							(mid -0.321484 0.511984)
							(end -0.1778 0.5715)
						)
						(arc
							(start 0.1778 0.5715)
							(mid 0.321484 0.511984)
							(end 0.381 0.3683)
						)
						(arc
							(start 0.381 -0.3683)
							(mid 0.321484 -0.511984)
							(end 0.1778 -0.5715)
						)
					)
					(width 0)
					(fill yes)
				)
			)
		)
	)
	(footprint ""
		(layer "B.Cu")
		(at 109.99216 -33.655)
		(property "Reference" "STP26"
			(at 0 0 0)
			(layer "B.SilkS")
			(hide yes)
			(effects
				(font
					(size 1.27 1.27)
				)
				(justify mirror)
			)
		)
		(property "Value" "TPAD28"
			(at -0.0127 -1.8034 0)
			(unlocked yes)
			(layer "B.Fab")
			(hide yes)
			(effects
				(font
					(size 1.016 1.016)
					(thickness 0.1524)
				)
				(justify mirror)
			)
		)
		(property "Device Type" "TPAD28"
			(at -0.0127 -3.3274 0)
			(unlocked yes)
			(layer "B.Fab")
			(hide yes)
			(effects
				(font
					(size 1.016 1.016)
					(thickness 0.1524)
				)
				(justify mirror)
			)
		)
		(duplicate_pad_numbers_are_jumpers no)
		(fp_poly
			(pts
				(arc
					(start 0.3556 0)
					(mid -0.3556 0)
					(end 0.3556 0)
				)
			)
			(stroke
				(width 0)
				(type default)
			)
			(fill no)
			(layer "B.CrtYd")
		)
		(fp_poly
			(pts
				(arc
					(start 0.6096 0)
					(mid -0.6096 0)
					(end 0.6096 0)
				)
			)
			(stroke
				(width 0)
				(type default)
			)
			(fill no)
			(layer "B.Fab")
		)
		(pad "1" smd circle
			(at 0 0 180)
			(size 0.7112 0.7112)
			(layers "B.Cu" "B.Mask" "B.Paste")
			(net "IOC_UART_1_RX")
		)
	)
	(footprint ""
		(layer "B.Cu")
		(at 114.94897 -80.391)
		(property "Reference" "STP107"
			(at 0 0 0)
			(layer "B.SilkS")
			(hide yes)
			(effects
				(font
					(size 1.27 1.27)
				)
				(justify mirror)
			)
		)
		(property "Value" "TPAD28"
			(at -0.0127 -1.8034 0)
			(unlocked yes)
			(layer "B.Fab")
			(hide yes)
			(effects
				(font
					(size 1.016 1.016)
					(thickness 0.1524)
				)
				(justify mirror)
			)
		)
		(property "Device Type" "TPAD28"
			(at -0.0127 -3.3274 0)
			(unlocked yes)
			(layer "B.Fab")
			(hide yes)
			(effects
				(font
					(size 1.016 1.016)
					(thickness 0.1524)
				)
				(justify mirror)
			)
		)
		(duplicate_pad_numbers_are_jumpers no)
		(fp_poly
			(pts
				(arc
					(start 0.3556 0)
					(mid -0.3556 0)
					(end 0.3556 0)
				)
			)
			(stroke
				(width 0)
				(type default)
			)
			(fill no)
			(layer "B.CrtYd")
		)
		(fp_poly
			(pts
				(arc
					(start 0.6096 0)
					(mid -0.6096 0)
					(end 0.6096 0)
				)
			)
			(stroke
				(width 0)
				(type default)
			)
			(fill no)
			(layer "B.Fab")
		)
		(pad "1" smd circle
			(at 0 0 180)
			(size 0.7112 0.7112)
			(layers "B.Cu" "B.Mask" "B.Paste")
			(net "TEST_MUX_40")
		)
	)
	(footprint ""
		(layer "B.Cu")
		(at 96.774 -3.429)
		(property "Reference" "PC195"
			(at 0 0 0)
			(layer "B.SilkS")
			(hide yes)
			(effects
				(font
					(size 1.27 1.27)
				)
				(justify mirror)
			)
		)
		(property "Value" "SCD1U50V3KX-GP"
			(at 0 -2.8194 0)
			(unlocked yes)
			(layer "B.Fab")
			(hide yes)
			(effects
				(font
					(size 1.016 1.016)
					(thickness 0.1524)
				)
				(justify mirror)
			)
		)
		(property "Device Type" "C603H36"
			(at 0 -4.3434 0)
			(unlocked yes)
			(layer "B.Fab")
			(hide yes)
			(effects
				(font
					(size 1.016 1.016)
					(thickness 0.1524)
				)
				(justify mirror)
			)
		)
		(duplicate_pad_numbers_are_jumpers no)
		(fp_line
			(start -0.508 0)
			(end 0.508 0)
			(stroke
				(width 0.2032)
				(type default)
			)
			(layer "B.SilkS")
		)
		(fp_rect
			(start 0.5842 1.3335)
			(end -0.5842 -1.3335)
			(stroke
				(width 0)
				(type default)
			)
			(fill no)
			(layer "B.CrtYd")
		)
		(fp_rect
			(start 0.5842 1.3335)
			(end -0.5842 -1.3335)
			(stroke
				(width 0)
				(type default)
			)
			(fill no)
			(layer "B.Fab")
		)
		(pad "1" smd custom
			(at 0 -0.762 180)
			(size 0.2159 0.2159)
			(layers "B.Cu" "B.Mask" "B.Paste")
			(net "P0V955_C")
			(options
				(clearance outline)
				(anchor circle)
			)
			(primitives
				(gr_poly
					(pts
						(arc
							(start -0.3302 0.4318)
							(mid -0.402042 0.402042)
							(end -0.4318 0.3302)
						)
						(arc
							(start -0.4318 -0.3302)
							(mid -0.402042 -0.402042)
							(end -0.3302 -0.4318)
						)
						(arc
							(start 0.3302 -0.4318)
							(mid 0.402042 -0.402042)
							(end 0.4318 -0.3302)
						)
						(arc
							(start 0.4318 0.3302)
							(mid 0.402042 0.402042)
							(end 0.3302 0.4318)
						)
					)
					(width 0)
					(fill yes)
				)
			)
		)
		(pad "2" smd custom
			(at 0 0.762 180)
			(size 0.2159 0.2159)
			(layers "B.Cu" "B.Mask" "B.Paste")
			(net "GND")
			(options
				(clearance outline)
				(anchor circle)
			)
			(primitives
				(gr_poly
					(pts
						(arc
							(start -0.3302 0.4318)
							(mid -0.402042 0.402042)
							(end -0.4318 0.3302)
						)
						(arc
							(start -0.4318 -0.3302)
							(mid -0.402042 -0.402042)
							(end -0.3302 -0.4318)
						)
						(arc
							(start 0.3302 -0.4318)
							(mid 0.402042 -0.402042)
							(end 0.4318 -0.3302)
						)
						(arc
							(start 0.4318 0.3302)
							(mid 0.402042 0.402042)
							(end 0.3302 0.4318)
						)
					)
					(width 0)
					(fill yes)
				)
			)
		)
	)
	(footprint ""
		(layer "B.Cu")
		(at 111.26597 -81.534 180)
		(property "Reference" "SC1215"
			(at 0 0 0)
			(layer "B.SilkS")
			(hide yes)
			(effects
				(font
					(size 1.27 1.27)
				)
				(justify mirror)
			)
		)
		(property "Value" "SC1KP50V2KX-1GP"
			(at -1.1811 -2.7051 180)
			(unlocked yes)
			(layer "B.Fab")
			(hide yes)
			(effects
				(font
					(size 1.016 1.016)
					(thickness 0.1524)
				)
				(justify mirror)
			)
		)
		(property "Device Type" "C402H22"
			(at -1.1811 -4.2291 180)
			(unlocked yes)
			(layer "B.Fab")
			(hide yes)
			(effects
				(font
					(size 1.016 1.016)
					(thickness 0.1524)
				)
				(justify mirror)
			)
		)
		(duplicate_pad_numbers_are_jumpers no)
		(fp_rect
			(start 0.4318 0.9525)
			(end -0.4318 -0.9525)
			(stroke
				(width 0)
				(type default)
			)
			(fill no)
			(layer "B.CrtYd")
		)
		(fp_rect
			(start 0.4318 0.9525)
			(end -0.4318 -0.9525)
			(stroke
				(width 0)
				(type default)
			)
			(fill no)
			(layer "B.Fab")
		)
		(pad "1" smd custom
			(at 0 -0.4445)
			(size 0.1524 0.1524)
			(layers "B.Cu" "B.Mask" "B.Paste")
			(net "P1V8_E")
			(options
				(clearance outline)
				(anchor circle)
			)
			(primitives
				(gr_poly
					(pts
						(arc
							(start 0.3048 0.2032)
							(mid 0.275042 0.275042)
							(end 0.2032 0.3048)
						)
						(arc
							(start -0.2032 0.3048)
							(mid -0.275042 0.275042)
							(end -0.3048 0.2032)
						)
						(arc
							(start -0.3048 -0.2032)
							(mid -0.275042 -0.275042)
							(end -0.2032 -0.3048)
						)
						(arc
							(start 0.2032 -0.3048)
							(mid 0.275042 -0.275042)
							(end 0.3048 -0.2032)
						)
					)
					(width 0)
					(fill yes)
				)
			)
		)
		(pad "2" smd custom
			(at 0 0.4445)
			(size 0.1524 0.1524)
			(layers "B.Cu" "B.Mask" "B.Paste")
			(net "GND")
			(options
				(clearance outline)
				(anchor circle)
			)
			(primitives
				(gr_poly
					(pts
						(arc
							(start 0.3048 0.2032)
							(mid 0.275042 0.275042)
							(end 0.2032 0.3048)
						)
						(arc
							(start -0.2032 0.3048)
							(mid -0.275042 0.275042)
							(end -0.3048 0.2032)
						)
						(arc
							(start -0.3048 -0.2032)
							(mid -0.275042 -0.275042)
							(end -0.2032 -0.3048)
						)
						(arc
							(start 0.2032 -0.3048)
							(mid 0.275042 -0.275042)
							(end 0.3048 -0.2032)
						)
					)
					(width 0)
					(fill yes)
				)
			)
		)
	)
	(footprint ""
		(layer "B.Cu")
		(at 92.310966 -50.644806 -90)
		(property "Reference" "SR629"
			(at 0 0 90)
			(layer "B.SilkS")
			(hide yes)
			(effects
				(font
					(size 1.27 1.27)
				)
				(justify mirror)
			)
		)
		(property "Value" "2K2R2F-GP"
			(at -0.064008 -3.993896 270)
			(unlocked yes)
			(layer "B.Fab")
			(hide yes)
			(effects
				(font
					(size 1.016 1.016)
					(thickness 0.1524)
				)
				(justify mirror)
			)
		)
		(property "Device Type" "R402H16"
			(at -0.064008 -5.517896 270)
			(unlocked yes)
			(layer "B.Fab")
			(hide yes)
			(effects
				(font
					(size 1.016 1.016)
					(thickness 0.1524)
				)
				(justify mirror)
			)
		)
		(duplicate_pad_numbers_are_jumpers no)
		(fp_line
			(start -0.508 -0.9398)
			(end 0.508 -0.9398)
			(stroke
				(width 0.1524)
				(type default)
			)
			(layer "B.SilkS")
		)
		(fp_line
			(start 0.508 -0.9398)
			(end 0.508 0.9398)
			(stroke
				(width 0.1524)
				(type default)
			)
			(layer "B.SilkS")
		)
		(fp_rect
			(start 0.508 0.9398)
			(end -0.508 -0.9398)
			(stroke
				(width 0)
				(type default)
			)
			(fill no)
			(layer "B.CrtYd")
		)
		(fp_rect
			(start 0.508 0.9398)
			(end -0.508 -0.9398)
			(stroke
				(width 0)
				(type default)
			)
			(fill no)
			(layer "B.Fab")
		)
		(pad "1" smd custom
			(at 0 -0.4445 90)
			(size 0.1397 0.1397)
			(layers "B.Cu" "B.Mask" "B.Paste")
			(net "P1V8_C")
			(options
				(clearance outline)
				(anchor circle)
			)
			(primitives
				(gr_poly
					(pts
						(arc
							(start -0.1778 0.2794)
							(mid -0.249642 0.249642)
							(end -0.2794 0.1778)
						)
						(arc
							(start -0.2794 -0.1778)
							(mid -0.249642 -0.249642)
							(end -0.1778 -0.2794)
						)
						(arc
							(start 0.1778 -0.2794)
							(mid 0.249642 -0.249642)
							(end 0.2794 -0.1778)
						)
						(arc
							(start 0.2794 0.1778)
							(mid 0.249642 0.249642)
							(end 0.1778 0.2794)
						)
					)
					(width 0)
					(fill yes)
				)
			)
		)
		(pad "2" smd custom
			(at 0 0.4445 90)
			(size 0.1397 0.1397)
			(layers "B.Cu" "B.Mask" "B.Paste")
			(net "SIO_LOAD_0")
			(options
				(clearance outline)
				(anchor circle)
			)
			(primitives
				(gr_poly
					(pts
						(arc
							(start -0.1778 0.2794)
							(mid -0.249642 0.249642)
							(end -0.2794 0.1778)
						)
						(arc
							(start -0.2794 -0.1778)
							(mid -0.249642 -0.249642)
							(end -0.1778 -0.2794)
						)
						(arc
							(start 0.1778 -0.2794)
							(mid 0.249642 -0.249642)
							(end 0.2794 -0.1778)
						)
						(arc
							(start 0.2794 0.1778)
							(mid 0.249642 0.249642)
							(end 0.1778 0.2794)
						)
					)
					(width 0)
					(fill yes)
				)
			)
		)
	)
	(footprint ""
		(layer "B.Cu")
		(at 274.193 -184.785 90)
		(property "Reference" "R362"
			(at 0 0 90)
			(layer "B.SilkS")
			(hide yes)
			(effects
				(font
					(size 1.27 1.27)
				)
				(justify mirror)
			)
		)
		(property "Value" "3K3R2F-2-GP"
			(at -0.064008 -3.993896 90)
			(unlocked yes)
			(layer "B.Fab")
			(hide yes)
			(effects
				(font
					(size 1.016 1.016)
					(thickness 0.1524)
				)
				(justify mirror)
			)
		)
		(property "Device Type" "R402H16"
			(at -0.064008 -5.517896 90)
			(unlocked yes)
			(layer "B.Fab")
			(hide yes)
			(effects
				(font
					(size 1.016 1.016)
					(thickness 0.1524)
				)
				(justify mirror)
			)
		)
		(duplicate_pad_numbers_are_jumpers no)
		(fp_line
			(start 0.508 -0.9398)
			(end 0.508 0.9398)
			(stroke
				(width 0.1524)
				(type default)
			)
			(layer "B.SilkS")
		)
		(fp_line
			(start -0.508 -0.9398)
			(end 0.508 -0.9398)
			(stroke
				(width 0.1524)
				(type default)
			)
			(layer "B.SilkS")
		)
		(fp_rect
			(start 0.508 0.9398)
			(end -0.508 -0.9398)
			(stroke
				(width 0)
				(type default)
			)
			(fill no)
			(layer "B.CrtYd")
		)
		(fp_rect
			(start 0.508 0.9398)
			(end -0.508 -0.9398)
			(stroke
				(width 0)
				(type default)
			)
			(fill no)
			(layer "B.Fab")
		)
		(pad "1" smd custom
			(at 0 -0.4445 270)
			(size 0.1397 0.1397)
			(layers "B.Cu" "B.Mask" "B.Paste")
			(net "P3V3_STBY")
			(options
				(clearance outline)
				(anchor circle)
			)
			(primitives
				(gr_poly
					(pts
						(arc
							(start -0.1778 0.2794)
							(mid -0.249642 0.249642)
							(end -0.2794 0.1778)
						)
						(arc
							(start -0.2794 -0.1778)
							(mid -0.249642 -0.249642)
							(end -0.1778 -0.2794)
						)
						(arc
							(start 0.1778 -0.2794)
							(mid 0.249642 -0.249642)
							(end 0.2794 -0.1778)
						)
						(arc
							(start 0.2794 0.1778)
							(mid 0.249642 0.249642)
							(end 0.1778 0.2794)
						)
					)
					(width 0)
					(fill yes)
				)
			)
		)
		(pad "2" smd custom
			(at 0 0.4445 270)
			(size 0.1397 0.1397)
			(layers "B.Cu" "B.Mask" "B.Paste")
			(net "ROMD5")
			(options
				(clearance outline)
				(anchor circle)
			)
			(primitives
				(gr_poly
					(pts
						(arc
							(start -0.1778 0.2794)
							(mid -0.249642 0.249642)
							(end -0.2794 0.1778)
						)
						(arc
							(start -0.2794 -0.1778)
							(mid -0.249642 -0.249642)
							(end -0.1778 -0.2794)
						)
						(arc
							(start 0.1778 -0.2794)
							(mid 0.249642 -0.249642)
							(end 0.2794 -0.1778)
						)
						(arc
							(start 0.2794 0.1778)
							(mid 0.249642 0.249642)
							(end 0.1778 0.2794)
						)
					)
					(width 0)
					(fill yes)
				)
			)
		)
	)
	(footprint ""
		(layer "B.Cu")
		(at 198.710296 -87.388192 180)
		(property "Reference" "SC1133"
			(at 0 0 0)
			(layer "B.SilkS")
			(hide yes)
			(effects
				(font
					(size 1.27 1.27)
				)
				(justify mirror)
			)
		)
		(property "Value" "SC1U6D3V1MX-GP"
			(at -1.9177 2.0193 180)
			(unlocked yes)
			(layer "B.Fab")
			(hide yes)
			(effects
				(font
					(size 1.016 1.016)
					(thickness 0.1524)
				)
				(justify mirror)
			)
		)
		(property "Device Type" "C0201H14"
			(at -1.9177 0.4953 180)
			(unlocked yes)
			(layer "B.Fab")
			(hide yes)
			(effects
				(font
					(size 1.016 1.016)
					(thickness 0.1524)
				)
				(justify mirror)
			)
		)
		(duplicate_pad_numbers_are_jumpers no)
		(fp_rect
			(start 0.1524 0.3048)
			(end -0.1524 -0.3048)
			(stroke
				(width 0)
				(type default)
			)
			(fill no)
			(layer "B.CrtYd")
		)
		(fp_poly
			(pts
				(xy 0.2794 0.6477) (xy 0.2794 -0.6477) (xy -0.2794 -0.6477) (xy -0.2794 -0.1905) (xy -0.1524 -0.1905)
				(xy -0.1524 -0.3048) (xy 0.1524 -0.3048) (xy 0.1524 0.3048) (xy -0.1524 0.3048) (xy -0.1524 -0.1778)
				(xy -0.2794 -0.1778) (xy -0.2794 0.6477)
			)
			(stroke
				(width 0)
				(type default)
			)
			(fill no)
			(layer "B.CrtYd")
		)
		(fp_rect
			(start 0.2794 0.6477)
			(end -0.2794 -0.6477)
			(stroke
				(width 0)
				(type default)
			)
			(fill no)
			(layer "B.Fab")
		)
		(pad "1" smd custom
			(at 0 -0.2794)
			(size 0.0762 0.0762)
			(layers "B.Cu" "B.Mask" "B.Paste")
			(net "GB_VDDH2")
			(options
				(clearance outline)
				(anchor circle)
			)
			(primitives
				(gr_poly
					(pts
						(arc
							(start 0.1524 0.127)
							(mid 0.137521 0.162921)
							(end 0.1016 0.1778)
						)
						(arc
							(start -0.1016 0.1778)
							(mid -0.137521 0.162921)
							(end -0.1524 0.127)
						)
						(arc
							(start -0.1524 -0.127)
							(mid -0.137521 -0.162921)
							(end -0.1016 -0.1778)
						)
						(arc
							(start 0.1016 -0.1778)
							(mid 0.137521 -0.162921)
							(end 0.1524 -0.127)
						)
					)
					(width 0)
					(fill yes)
				)
			)
		)
		(pad "2" smd custom
			(at 0 0.2794)
			(size 0.0762 0.0762)
			(layers "B.Cu" "B.Mask" "B.Paste")
			(net "GND")
			(options
				(clearance outline)
				(anchor circle)
			)
			(primitives
				(gr_poly
					(pts
						(arc
							(start 0.1524 0.127)
							(mid 0.137521 0.162921)
							(end 0.1016 0.1778)
						)
						(arc
							(start -0.1016 0.1778)
							(mid -0.137521 0.162921)
							(end -0.1524 0.127)
						)
						(arc
							(start -0.1524 -0.127)
							(mid -0.137521 -0.162921)
							(end -0.1016 -0.1778)
						)
						(arc
							(start 0.1016 -0.1778)
							(mid 0.137521 -0.162921)
							(end 0.1524 -0.127)
						)
					)
					(width 0)
					(fill yes)
				)
			)
		)
	)
	(footprint ""
		(layer "B.Cu")
		(at 107.982004 -56.165496)
		(property "Reference" "STP153"
			(at 0 0 0)
			(layer "B.SilkS")
			(hide yes)
			(effects
				(font
					(size 1.27 1.27)
				)
				(justify mirror)
			)
		)
		(property "Value" "TPAD28"
			(at -0.0127 -1.8034 0)
			(unlocked yes)
			(layer "B.Fab")
			(hide yes)
			(effects
				(font
					(size 1.016 1.016)
					(thickness 0.1524)
				)
				(justify mirror)
			)
		)
		(property "Device Type" "TPAD28"
			(at -0.0127 -3.3274 0)
			(unlocked yes)
			(layer "B.Fab")
			(hide yes)
			(effects
				(font
					(size 1.016 1.016)
					(thickness 0.1524)
				)
				(justify mirror)
			)
		)
		(duplicate_pad_numbers_are_jumpers no)
		(fp_poly
			(pts
				(arc
					(start 0.3556 0)
					(mid -0.3556 0)
					(end 0.3556 0)
				)
			)
			(stroke
				(width 0)
				(type default)
			)
			(fill no)
			(layer "B.CrtYd")
		)
		(fp_poly
			(pts
				(arc
					(start 0.6096 0)
					(mid -0.6096 0)
					(end 0.6096 0)
				)
			)
			(stroke
				(width 0)
				(type default)
			)
			(fill no)
			(layer "B.Fab")
		)
		(pad "1" smd circle
			(at 0 0 180)
			(size 0.7112 0.7112)
			(layers "B.Cu" "B.Mask" "B.Paste")
			(net "XM_CLE")
		)
	)
	(footprint ""
		(layer "B.Cu")
		(at 99.45116 -31.623)
		(property "Reference" "SC869"
			(at 0 0 0)
			(layer "B.SilkS")
			(hide yes)
			(effects
				(font
					(size 1.27 1.27)
				)
				(justify mirror)
			)
		)
		(property "Value" "SCD22U6D3V1MX-1-GP"
			(at 2.8321 -1.7399 0)
			(unlocked yes)
			(layer "B.Fab")
			(hide yes)
			(effects
				(font
					(size 1.016 1.016)
					(thickness 0.1524)
				)
				(justify mirror)
			)
		)
		(property "Device Type" "C0201H13"
			(at 2.8321 -3.2639 0)
			(unlocked yes)
			(layer "B.Fab")
			(hide yes)
			(effects
				(font
					(size 1.016 1.016)
					(thickness 0.1524)
				)
				(justify mirror)
			)
		)
		(duplicate_pad_numbers_are_jumpers no)
		(fp_rect
			(start 0.2794 0.6477)
			(end -0.2794 -0.6477)
			(stroke
				(width 0)
				(type default)
			)
			(fill no)
			(layer "B.CrtYd")
		)
		(fp_rect
			(start 0.2794 0.6477)
			(end -0.2794 -0.6477)
			(stroke
				(width 0)
				(type default)
			)
			(fill no)
			(layer "B.Fab")
		)
		(pad "1" smd custom
			(at 0 -0.2794 180)
			(size 0.0762 0.0762)
			(layers "B.Cu" "B.Mask" "B.Paste")
			(net "PCIE_SAS_C_CPU_RX_P4")
			(options
				(clearance outline)
				(anchor circle)
			)
			(primitives
				(gr_poly
					(pts
						(arc
							(start 0.1524 0.127)
							(mid 0.137521 0.162921)
							(end 0.1016 0.1778)
						)
						(arc
							(start -0.1016 0.1778)
							(mid -0.137521 0.162921)
							(end -0.1524 0.127)
						)
						(arc
							(start -0.1524 -0.127)
							(mid -0.137521 -0.162921)
							(end -0.1016 -0.1778)
						)
						(arc
							(start 0.1016 -0.1778)
							(mid 0.137521 -0.162921)
							(end 0.1524 -0.127)
						)
					)
					(width 0)
					(fill yes)
				)
			)
		)
		(pad "2" smd custom
			(at 0 0.2794 180)
			(size 0.0762 0.0762)
			(layers "B.Cu" "B.Mask" "B.Paste")
			(net "PCIE_SAS_CPU_RX_P4")
			(options
				(clearance outline)
				(anchor circle)
			)
			(primitives
				(gr_poly
					(pts
						(arc
							(start 0.1524 0.127)
							(mid 0.137521 0.162921)
							(end 0.1016 0.1778)
						)
						(arc
							(start -0.1016 0.1778)
							(mid -0.137521 0.162921)
							(end -0.1524 0.127)
						)
						(arc
							(start -0.1524 -0.127)
							(mid -0.137521 -0.162921)
							(end -0.1016 -0.1778)
						)
						(arc
							(start 0.1016 -0.1778)
							(mid 0.137521 -0.162921)
							(end 0.1524 -0.127)
						)
					)
					(width 0)
					(fill yes)
				)
			)
		)
	)
	(footprint ""
		(layer "B.Cu")
		(at 351.6122 -71.8058)
		(property "Reference" "R342"
			(at 0 0 0)
			(layer "B.SilkS")
			(hide yes)
			(effects
				(font
					(size 1.27 1.27)
				)
				(justify mirror)
			)
		)
		(property "Value" "3K3R2F-2-GP"
			(at -0.064008 -3.993896 0)
			(unlocked yes)
			(layer "B.Fab")
			(hide yes)
			(effects
				(font
					(size 1.016 1.016)
					(thickness 0.1524)
				)
				(justify mirror)
			)
		)
		(property "Device Type" "R402H16"
			(at -0.064008 -5.517896 0)
			(unlocked yes)
			(layer "B.Fab")
			(hide yes)
			(effects
				(font
					(size 1.016 1.016)
					(thickness 0.1524)
				)
				(justify mirror)
			)
		)
		(duplicate_pad_numbers_are_jumpers no)
		(fp_line
			(start -0.508 -0.9398)
			(end 0.508 -0.9398)
			(stroke
				(width 0.1524)
				(type default)
			)
			(layer "B.SilkS")
		)
		(fp_line
			(start 0.508 -0.9398)
			(end 0.508 0.9398)
			(stroke
				(width 0.1524)
				(type default)
			)
			(layer "B.SilkS")
		)
		(fp_rect
			(start 0.508 0.9398)
			(end -0.508 -0.9398)
			(stroke
				(width 0)
				(type default)
			)
			(fill no)
			(layer "B.CrtYd")
		)
		(fp_rect
			(start 0.508 0.9398)
			(end -0.508 -0.9398)
			(stroke
				(width 0)
				(type default)
			)
			(fill no)
			(layer "B.Fab")
		)
		(pad "1" smd custom
			(at 0 -0.4445 180)
			(size 0.1397 0.1397)
			(layers "B.Cu" "B.Mask" "B.Paste")
			(net "P3V3_STBY")
			(options
				(clearance outline)
				(anchor circle)
			)
			(primitives
				(gr_poly
					(pts
						(arc
							(start -0.1778 0.2794)
							(mid -0.249642 0.249642)
							(end -0.2794 0.1778)
						)
						(arc
							(start -0.2794 -0.1778)
							(mid -0.249642 -0.249642)
							(end -0.1778 -0.2794)
						)
						(arc
							(start 0.1778 -0.2794)
							(mid 0.249642 -0.249642)
							(end 0.2794 -0.1778)
						)
						(arc
							(start 0.2794 0.1778)
							(mid 0.249642 0.249642)
							(end 0.1778 0.2794)
						)
					)
					(width 0)
					(fill yes)
				)
			)
		)
		(pad "2" smd custom
			(at 0 0.4445 180)
			(size 0.1397 0.1397)
			(layers "B.Cu" "B.Mask" "B.Paste")
			(net "ROMD0_R")
			(options
				(clearance outline)
				(anchor circle)
			)
			(primitives
				(gr_poly
					(pts
						(arc
							(start -0.1778 0.2794)
							(mid -0.249642 0.249642)
							(end -0.2794 0.1778)
						)
						(arc
							(start -0.2794 -0.1778)
							(mid -0.249642 -0.249642)
							(end -0.1778 -0.2794)
						)
						(arc
							(start 0.1778 -0.2794)
							(mid 0.249642 -0.249642)
							(end 0.2794 -0.1778)
						)
						(arc
							(start 0.2794 0.1778)
							(mid 0.249642 0.249642)
							(end 0.1778 0.2794)
						)
					)
					(width 0)
					(fill yes)
				)
			)
		)
	)
	(footprint ""
		(layer "B.Cu")
		(at 105.918 -239.395)
		(property "Reference" "SR947"
			(at 0 0 0)
			(layer "B.SilkS")
			(hide yes)
			(effects
				(font
					(size 1.27 1.27)
				)
				(justify mirror)
			)
		)
		(property "Value" "4K7R2F-GP"
			(at -0.064008 -3.993896 0)
			(unlocked yes)
			(layer "B.Fab")
			(hide yes)
			(effects
				(font
					(size 1.016 1.016)
					(thickness 0.1524)
				)
				(justify mirror)
			)
		)
		(property "Device Type" "R402H16"
			(at -0.064008 -5.517896 0)
			(unlocked yes)
			(layer "B.Fab")
			(hide yes)
			(effects
				(font
					(size 1.016 1.016)
					(thickness 0.1524)
				)
				(justify mirror)
			)
		)
		(duplicate_pad_numbers_are_jumpers no)
		(fp_line
			(start -0.508 -0.9398)
			(end 0.508 -0.9398)
			(stroke
				(width 0.1524)
				(type default)
			)
			(layer "B.SilkS")
		)
		(fp_line
			(start 0.508 -0.9398)
			(end 0.508 0.9398)
			(stroke
				(width 0.1524)
				(type default)
			)
			(layer "B.SilkS")
		)
		(fp_rect
			(start 0.508 0.9398)
			(end -0.508 -0.9398)
			(stroke
				(width 0)
				(type default)
			)
			(fill no)
			(layer "B.CrtYd")
		)
		(fp_rect
			(start 0.508 0.9398)
			(end -0.508 -0.9398)
			(stroke
				(width 0)
				(type default)
			)
			(fill no)
			(layer "B.Fab")
		)
		(pad "1" smd custom
			(at 0 -0.4445 180)
			(size 0.1397 0.1397)
			(layers "B.Cu" "B.Mask" "B.Paste")
			(net "SAS_FAULT_LED6")
			(options
				(clearance outline)
				(anchor circle)
			)
			(primitives
				(gr_poly
					(pts
						(arc
							(start -0.1778 0.2794)
							(mid -0.249642 0.249642)
							(end -0.2794 0.1778)
						)
						(arc
							(start -0.2794 -0.1778)
							(mid -0.249642 -0.249642)
							(end -0.1778 -0.2794)
						)
						(arc
							(start 0.1778 -0.2794)
							(mid 0.249642 -0.249642)
							(end 0.2794 -0.1778)
						)
						(arc
							(start 0.2794 0.1778)
							(mid 0.249642 0.249642)
							(end 0.1778 0.2794)
						)
					)
					(width 0)
					(fill yes)
				)
			)
		)
		(pad "2" smd custom
			(at 0 0.4445 180)
			(size 0.1397 0.1397)
			(layers "B.Cu" "B.Mask" "B.Paste")
			(net "P3V3_STBY")
			(options
				(clearance outline)
				(anchor circle)
			)
			(primitives
				(gr_poly
					(pts
						(arc
							(start -0.1778 0.2794)
							(mid -0.249642 0.249642)
							(end -0.2794 0.1778)
						)
						(arc
							(start -0.2794 -0.1778)
							(mid -0.249642 -0.249642)
							(end -0.1778 -0.2794)
						)
						(arc
							(start 0.1778 -0.2794)
							(mid 0.249642 -0.249642)
							(end 0.2794 -0.1778)
						)
						(arc
							(start 0.2794 0.1778)
							(mid 0.249642 0.249642)
							(end 0.1778 0.2794)
						)
					)
					(width 0)
					(fill yes)
				)
			)
		)
	)
	(footprint ""
		(layer "B.Cu")
		(at 24.461216 -170.10888 90)
		(property "Reference" "SC1114"
			(at 0 0 90)
			(layer "B.SilkS")
			(hide yes)
			(effects
				(font
					(size 1.27 1.27)
				)
				(justify mirror)
			)
		)
		(property "Value" "SCD1U16V2KX-3GP"
			(at -1.1811 -2.7051 90)
			(unlocked yes)
			(layer "B.Fab")
			(hide yes)
			(effects
				(font
					(size 1.016 1.016)
					(thickness 0.1524)
				)
				(justify mirror)
			)
		)
		(property "Device Type" "C402H22"
			(at -1.1811 -4.2291 90)
			(unlocked yes)
			(layer "B.Fab")
			(hide yes)
			(effects
				(font
					(size 1.016 1.016)
					(thickness 0.1524)
				)
				(justify mirror)
			)
		)
		(duplicate_pad_numbers_are_jumpers no)
		(fp_rect
			(start 0.4318 0.9525)
			(end -0.4318 -0.9525)
			(stroke
				(width 0)
				(type default)
			)
			(fill no)
			(layer "B.CrtYd")
		)
		(fp_rect
			(start 0.4318 0.9525)
			(end -0.4318 -0.9525)
			(stroke
				(width 0)
				(type default)
			)
			(fill no)
			(layer "B.Fab")
		)
		(pad "1" smd custom
			(at 0 -0.4445 270)
			(size 0.1524 0.1524)
			(layers "B.Cu" "B.Mask" "B.Paste")
			(net "P1V8_E")
			(options
				(clearance outline)
				(anchor circle)
			)
			(primitives
				(gr_poly
					(pts
						(arc
							(start 0.3048 0.2032)
							(mid 0.275042 0.275042)
							(end 0.2032 0.3048)
						)
						(arc
							(start -0.2032 0.3048)
							(mid -0.275042 0.275042)
							(end -0.3048 0.2032)
						)
						(arc
							(start -0.3048 -0.2032)
							(mid -0.275042 -0.275042)
							(end -0.2032 -0.3048)
						)
						(arc
							(start 0.2032 -0.3048)
							(mid 0.275042 -0.275042)
							(end 0.3048 -0.2032)
						)
					)
					(width 0)
					(fill yes)
				)
			)
		)
		(pad "2" smd custom
			(at 0 0.4445 270)
			(size 0.1524 0.1524)
			(layers "B.Cu" "B.Mask" "B.Paste")
			(net "GND")
			(options
				(clearance outline)
				(anchor circle)
			)
			(primitives
				(gr_poly
					(pts
						(arc
							(start 0.3048 0.2032)
							(mid 0.275042 0.275042)
							(end 0.2032 0.3048)
						)
						(arc
							(start -0.2032 0.3048)
							(mid -0.275042 0.275042)
							(end -0.3048 0.2032)
						)
						(arc
							(start -0.3048 -0.2032)
							(mid -0.275042 -0.275042)
							(end -0.2032 -0.3048)
						)
						(arc
							(start 0.2032 -0.3048)
							(mid 0.275042 -0.275042)
							(end 0.3048 -0.2032)
						)
					)
					(width 0)
					(fill yes)
				)
			)
		)
	)
	(footprint ""
		(layer "B.Cu")
		(at 92.818966 -55.1815 180)
		(property "Reference" "SC1009"
			(at 0 0 0)
			(layer "B.SilkS")
			(hide yes)
			(effects
				(font
					(size 1.27 1.27)
				)
				(justify mirror)
			)
		)
		(property "Value" "SC1KP50V2KX-1GP"
			(at -1.1811 -2.7051 180)
			(unlocked yes)
			(layer "B.Fab")
			(hide yes)
			(effects
				(font
					(size 1.016 1.016)
					(thickness 0.1524)
				)
				(justify mirror)
			)
		)
		(property "Device Type" "C402H22"
			(at -1.1811 -4.2291 180)
			(unlocked yes)
			(layer "B.Fab")
			(hide yes)
			(effects
				(font
					(size 1.016 1.016)
					(thickness 0.1524)
				)
				(justify mirror)
			)
		)
		(duplicate_pad_numbers_are_jumpers no)
		(fp_rect
			(start 0.4318 0.9525)
			(end -0.4318 -0.9525)
			(stroke
				(width 0)
				(type default)
			)
			(fill no)
			(layer "B.CrtYd")
		)
		(fp_rect
			(start 0.4318 0.9525)
			(end -0.4318 -0.9525)
			(stroke
				(width 0)
				(type default)
			)
			(fill no)
			(layer "B.Fab")
		)
		(pad "1" smd custom
			(at 0 -0.4445)
			(size 0.1524 0.1524)
			(layers "B.Cu" "B.Mask" "B.Paste")
			(net "P1V8_C")
			(options
				(clearance outline)
				(anchor circle)
			)
			(primitives
				(gr_poly
					(pts
						(arc
							(start 0.3048 0.2032)
							(mid 0.275042 0.275042)
							(end 0.2032 0.3048)
						)
						(arc
							(start -0.2032 0.3048)
							(mid -0.275042 0.275042)
							(end -0.3048 0.2032)
						)
						(arc
							(start -0.3048 -0.2032)
							(mid -0.275042 -0.275042)
							(end -0.2032 -0.3048)
						)
						(arc
							(start 0.2032 -0.3048)
							(mid 0.275042 -0.275042)
							(end 0.3048 -0.2032)
						)
					)
					(width 0)
					(fill yes)
				)
			)
		)
		(pad "2" smd custom
			(at 0 0.4445)
			(size 0.1524 0.1524)
			(layers "B.Cu" "B.Mask" "B.Paste")
			(net "GND")
			(options
				(clearance outline)
				(anchor circle)
			)
			(primitives
				(gr_poly
					(pts
						(arc
							(start 0.3048 0.2032)
							(mid 0.275042 0.275042)
							(end 0.2032 0.3048)
						)
						(arc
							(start -0.2032 0.3048)
							(mid -0.275042 0.275042)
							(end -0.3048 0.2032)
						)
						(arc
							(start -0.3048 -0.2032)
							(mid -0.275042 -0.275042)
							(end -0.2032 -0.3048)
						)
						(arc
							(start 0.2032 -0.3048)
							(mid 0.275042 -0.275042)
							(end 0.3048 -0.2032)
						)
					)
					(width 0)
					(fill yes)
				)
			)
		)
	)
	(footprint ""
		(layer "B.Cu")
		(at 88.91016 -50.419)
		(property "Reference" "STP14"
			(at 0 0 0)
			(layer "B.SilkS")
			(hide yes)
			(effects
				(font
					(size 1.27 1.27)
				)
				(justify mirror)
			)
		)
		(property "Value" "TPAD28"
			(at -0.0127 -1.8034 0)
			(unlocked yes)
			(layer "B.Fab")
			(hide yes)
			(effects
				(font
					(size 1.016 1.016)
					(thickness 0.1524)
				)
				(justify mirror)
			)
		)
		(property "Device Type" "TPAD28"
			(at -0.0127 -3.3274 0)
			(unlocked yes)
			(layer "B.Fab")
			(hide yes)
			(effects
				(font
					(size 1.016 1.016)
					(thickness 0.1524)
				)
				(justify mirror)
			)
		)
		(duplicate_pad_numbers_are_jumpers no)
		(fp_poly
			(pts
				(arc
					(start 0.3556 0)
					(mid -0.3556 0)
					(end 0.3556 0)
				)
			)
			(stroke
				(width 0)
				(type default)
			)
			(fill no)
			(layer "B.CrtYd")
		)
		(fp_poly
			(pts
				(arc
					(start 0.6096 0)
					(mid -0.6096 0)
					(end 0.6096 0)
				)
			)
			(stroke
				(width 0)
				(type default)
			)
			(fill no)
			(layer "B.Fab")
		)
		(pad "1" smd circle
			(at 0 0 180)
			(size 0.7112 0.7112)
			(layers "B.Cu" "B.Mask" "B.Paste")
			(net "SIO_DIN_1")
		)
	)
	(footprint ""
		(layer "B.Cu")
		(at 188.949584 -104.299766)
		(property "Reference" ""
			(at 0 0 0)
			(layer "B.SilkS")
			(hide yes)
			(effects
				(font
					(size 1.27 1.27)
				)
				(justify mirror)
			)
		)
		(property "Value" "*"
			(at 5.5753 -0.4572 0)
			(unlocked yes)
			(layer "B.Fab")
			(hide yes)
			(effects
				(font
					(size 1.016 1.016)
					(thickness 0.1524)
				)
				(justify mirror)
			)
		)
		(duplicate_pad_numbers_are_jumpers no)
		(fp_poly
			(pts
				(arc
					(start 4.3053 0)
					(mid -4.3053 0)
					(end 4.3053 0)
				)
			)
			(stroke
				(width 0)
				(type default)
			)
			(fill no)
			(layer "B.CrtYd")
		)
		(fp_poly
			(pts
				(arc
					(start 4.3053 0)
					(mid -4.3053 0)
					(end 4.3053 0)
				)
			)
			(stroke
				(width 0)
				(type default)
			)
			(fill no)
			(layer "B.Fab")
		)
		(pad "1" smd custom
			(at 2.95275 0 180)
			(size 2.000013 2.000013)
			(layers "B.Cu" "B.Mask" "B.Paste")
			(net "Net_51")
			(options
				(clearance outline)
				(anchor circle)
			)
			(primitives
				(gr_poly
					(pts
						(arc
							(start 4.0005 -0.00254)
							(mid -4.000501 0)
							(end 4.0005 0.00254)
						)
						(arc
							(start 1.905 0.00254)
							(mid -1.905002 0)
							(end 1.905 -0.00254)
						)
					)
					(width 0)
					(fill yes)
				)
			)
		)
	)
	(footprint ""
		(layer "B.Cu")
		(at 97.898966 -56.261 180)
		(property "Reference" "SC971"
			(at 0 0 0)
			(layer "B.SilkS")
			(hide yes)
			(effects
				(font
					(size 1.27 1.27)
				)
				(justify mirror)
			)
		)
		(property "Value" "SC1U10V2KX-4-GP"
			(at -1.1811 -2.7051 180)
			(unlocked yes)
			(layer "B.Fab")
			(hide yes)
			(effects
				(font
					(size 1.016 1.016)
					(thickness 0.1524)
				)
				(justify mirror)
			)
		)
		(property "Device Type" "C402H22"
			(at -1.1811 -4.2291 180)
			(unlocked yes)
			(layer "B.Fab")
			(hide yes)
			(effects
				(font
					(size 1.016 1.016)
					(thickness 0.1524)
				)
				(justify mirror)
			)
		)
		(duplicate_pad_numbers_are_jumpers no)
		(fp_rect
			(start 0.4318 0.9525)
			(end -0.4318 -0.9525)
			(stroke
				(width 0)
				(type default)
			)
			(fill no)
			(layer "B.CrtYd")
		)
		(fp_rect
			(start 0.4318 0.9525)
			(end -0.4318 -0.9525)
			(stroke
				(width 0)
				(type default)
			)
			(fill no)
			(layer "B.Fab")
		)
		(pad "1" smd custom
			(at 0 -0.4445)
			(size 0.1524 0.1524)
			(layers "B.Cu" "B.Mask" "B.Paste")
			(net "P1V8_C")
			(options
				(clearance outline)
				(anchor circle)
			)
			(primitives
				(gr_poly
					(pts
						(arc
							(start 0.3048 0.2032)
							(mid 0.275042 0.275042)
							(end 0.2032 0.3048)
						)
						(arc
							(start -0.2032 0.3048)
							(mid -0.275042 0.275042)
							(end -0.3048 0.2032)
						)
						(arc
							(start -0.3048 -0.2032)
							(mid -0.275042 -0.275042)
							(end -0.2032 -0.3048)
						)
						(arc
							(start 0.2032 -0.3048)
							(mid 0.275042 -0.275042)
							(end 0.3048 -0.2032)
						)
					)
					(width 0)
					(fill yes)
				)
			)
		)
		(pad "2" smd custom
			(at 0 0.4445)
			(size 0.1524 0.1524)
			(layers "B.Cu" "B.Mask" "B.Paste")
			(net "GND")
			(options
				(clearance outline)
				(anchor circle)
			)
			(primitives
				(gr_poly
					(pts
						(arc
							(start 0.3048 0.2032)
							(mid 0.275042 0.275042)
							(end 0.2032 0.3048)
						)
						(arc
							(start -0.2032 0.3048)
							(mid -0.275042 0.275042)
							(end -0.3048 0.2032)
						)
						(arc
							(start -0.3048 -0.2032)
							(mid -0.275042 -0.275042)
							(end -0.2032 -0.3048)
						)
						(arc
							(start 0.2032 -0.3048)
							(mid 0.275042 -0.275042)
							(end 0.3048 -0.2032)
						)
					)
					(width 0)
					(fill yes)
				)
			)
		)
	)
	(footprint ""
		(layer "B.Cu")
		(at 90.81516 -50.673)
		(property "Reference" "STP7"
			(at 0 0 0)
			(layer "B.SilkS")
			(hide yes)
			(effects
				(font
					(size 1.27 1.27)
				)
				(justify mirror)
			)
		)
		(property "Value" "TPAD28"
			(at -0.0127 -1.8034 0)
			(unlocked yes)
			(layer "B.Fab")
			(hide yes)
			(effects
				(font
					(size 1.016 1.016)
					(thickness 0.1524)
				)
				(justify mirror)
			)
		)
		(property "Device Type" "TPAD28"
			(at -0.0127 -3.3274 0)
			(unlocked yes)
			(layer "B.Fab")
			(hide yes)
			(effects
				(font
					(size 1.016 1.016)
					(thickness 0.1524)
				)
				(justify mirror)
			)
		)
		(duplicate_pad_numbers_are_jumpers no)
		(fp_poly
			(pts
				(arc
					(start 0.3556 0)
					(mid -0.3556 0)
					(end 0.3556 0)
				)
			)
			(stroke
				(width 0)
				(type default)
			)
			(fill no)
			(layer "B.CrtYd")
		)
		(fp_poly
			(pts
				(arc
					(start 0.6096 0)
					(mid -0.6096 0)
					(end 0.6096 0)
				)
			)
			(stroke
				(width 0)
				(type default)
			)
			(fill no)
			(layer "B.Fab")
		)
		(pad "1" smd circle
			(at 0 0 180)
			(size 0.7112 0.7112)
			(layers "B.Cu" "B.Mask" "B.Paste")
			(net "SIO_DOUT_0")
		)
	)
	(footprint ""
		(layer "B.Cu")
		(at 103.740966 -55.8038)
		(property "Reference" "STP61"
			(at 0 0 0)
			(layer "B.SilkS")
			(hide yes)
			(effects
				(font
					(size 1.27 1.27)
				)
				(justify mirror)
			)
		)
		(property "Value" "TPAD28"
			(at -0.0127 -1.8034 0)
			(unlocked yes)
			(layer "B.Fab")
			(hide yes)
			(effects
				(font
					(size 1.016 1.016)
					(thickness 0.1524)
				)
				(justify mirror)
			)
		)
		(property "Device Type" "TPAD28"
			(at -0.0127 -3.3274 0)
			(unlocked yes)
			(layer "B.Fab")
			(hide yes)
			(effects
				(font
					(size 1.016 1.016)
					(thickness 0.1524)
				)
				(justify mirror)
			)
		)
		(duplicate_pad_numbers_are_jumpers no)
		(fp_poly
			(pts
				(arc
					(start 0.3556 0)
					(mid -0.3556 0)
					(end 0.3556 0)
				)
			)
			(stroke
				(width 0)
				(type default)
			)
			(fill no)
			(layer "B.CrtYd")
		)
		(fp_poly
			(pts
				(arc
					(start 0.6096 0)
					(mid -0.6096 0)
					(end 0.6096 0)
				)
			)
			(stroke
				(width 0)
				(type default)
			)
			(fill no)
			(layer "B.Fab")
		)
		(pad "1" smd circle
			(at 0 0 180)
			(size 0.7112 0.7112)
			(layers "B.Cu" "B.Mask" "B.Paste")
			(net "IOC_TDO")
		)
	)
	(footprint ""
		(layer "B.Cu")
		(at 140.34897 -87.249 180)
		(property "Reference" "R175"
			(at 0 0 0)
			(layer "B.SilkS")
			(hide yes)
			(effects
				(font
					(size 1.27 1.27)
				)
				(justify mirror)
			)
		)
		(property "Value" "4K7R2F-GP"
			(at -0.064008 -3.993896 180)
			(unlocked yes)
			(layer "B.Fab")
			(hide yes)
			(effects
				(font
					(size 1.016 1.016)
					(thickness 0.1524)
				)
				(justify mirror)
			)
		)
		(property "Device Type" "R402H16"
			(at -0.064008 -5.517896 180)
			(unlocked yes)
			(layer "B.Fab")
			(hide yes)
			(effects
				(font
					(size 1.016 1.016)
					(thickness 0.1524)
				)
				(justify mirror)
			)
		)
		(duplicate_pad_numbers_are_jumpers no)
		(fp_line
			(start 0.508 -0.9398)
			(end 0.508 0.9398)
			(stroke
				(width 0.1524)
				(type default)
			)
			(layer "B.SilkS")
		)
		(fp_line
			(start -0.508 -0.9398)
			(end 0.508 -0.9398)
			(stroke
				(width 0.1524)
				(type default)
			)
			(layer "B.SilkS")
		)
		(fp_rect
			(start 0.508 0.9398)
			(end -0.508 -0.9398)
			(stroke
				(width 0)
				(type default)
			)
			(fill no)
			(layer "B.CrtYd")
		)
		(fp_rect
			(start 0.508 0.9398)
			(end -0.508 -0.9398)
			(stroke
				(width 0)
				(type default)
			)
			(fill no)
			(layer "B.Fab")
		)
		(pad "1" smd custom
			(at 0 -0.4445)
			(size 0.1397 0.1397)
			(layers "B.Cu" "B.Mask" "B.Paste")
			(net "TEMP_3_A1")
			(options
				(clearance outline)
				(anchor circle)
			)
			(primitives
				(gr_poly
					(pts
						(arc
							(start -0.1778 0.2794)
							(mid -0.249642 0.249642)
							(end -0.2794 0.1778)
						)
						(arc
							(start -0.2794 -0.1778)
							(mid -0.249642 -0.249642)
							(end -0.1778 -0.2794)
						)
						(arc
							(start 0.1778 -0.2794)
							(mid 0.249642 -0.249642)
							(end 0.2794 -0.1778)
						)
						(arc
							(start 0.2794 0.1778)
							(mid 0.249642 0.249642)
							(end 0.1778 0.2794)
						)
					)
					(width 0)
					(fill yes)
				)
			)
		)
		(pad "2" smd custom
			(at 0 0.4445)
			(size 0.1397 0.1397)
			(layers "B.Cu" "B.Mask" "B.Paste")
			(net "GND")
			(options
				(clearance outline)
				(anchor circle)
			)
			(primitives
				(gr_poly
					(pts
						(arc
							(start -0.1778 0.2794)
							(mid -0.249642 0.249642)
							(end -0.2794 0.1778)
						)
						(arc
							(start -0.2794 -0.1778)
							(mid -0.249642 -0.249642)
							(end -0.1778 -0.2794)
						)
						(arc
							(start 0.1778 -0.2794)
							(mid 0.249642 -0.249642)
							(end 0.2794 -0.1778)
						)
						(arc
							(start 0.2794 0.1778)
							(mid 0.249642 0.249642)
							(end 0.1778 0.2794)
						)
					)
					(width 0)
					(fill yes)
				)
			)
		)
	)
	(footprint ""
		(layer "B.Cu")
		(at 113.850166 -33.782)
		(property "Reference" "STP47"
			(at 0 0 0)
			(layer "B.SilkS")
			(hide yes)
			(effects
				(font
					(size 1.27 1.27)
				)
				(justify mirror)
			)
		)
		(property "Value" "TPAD28"
			(at -0.0127 -1.8034 0)
			(unlocked yes)
			(layer "B.Fab")
			(hide yes)
			(effects
				(font
					(size 1.016 1.016)
					(thickness 0.1524)
				)
				(justify mirror)
			)
		)
		(property "Device Type" "TPAD28"
			(at -0.0127 -3.3274 0)
			(unlocked yes)
			(layer "B.Fab")
			(hide yes)
			(effects
				(font
					(size 1.016 1.016)
					(thickness 0.1524)
				)
				(justify mirror)
			)
		)
		(duplicate_pad_numbers_are_jumpers no)
		(fp_poly
			(pts
				(arc
					(start 0.3556 0)
					(mid -0.3556 0)
					(end 0.3556 0)
				)
			)
			(stroke
				(width 0)
				(type default)
			)
			(fill no)
			(layer "B.CrtYd")
		)
		(fp_poly
			(pts
				(arc
					(start 0.6096 0)
					(mid -0.6096 0)
					(end 0.6096 0)
				)
			)
			(stroke
				(width 0)
				(type default)
			)
			(fill no)
			(layer "B.Fab")
		)
		(pad "1" smd circle
			(at 0 0 180)
			(size 0.7112 0.7112)
			(layers "B.Cu" "B.Mask" "B.Paste")
			(net "IOC_GPIO_10")
		)
	)
	(footprint ""
		(layer "B.Cu")
		(at 101.35997 -112.395 180)
		(property "Reference" "SC1224"
			(at 0 0 0)
			(layer "B.SilkS")
			(hide yes)
			(effects
				(font
					(size 1.27 1.27)
				)
				(justify mirror)
			)
		)
		(property "Value" "SCD1U6D3V1KX-GP"
			(at 2.8321 -1.7399 180)
			(unlocked yes)
			(layer "B.Fab")
			(hide yes)
			(effects
				(font
					(size 1.016 1.016)
					(thickness 0.1524)
				)
				(justify mirror)
			)
		)
		(property "Device Type" "C0201H13"
			(at 2.8321 -3.2639 180)
			(unlocked yes)
			(layer "B.Fab")
			(hide yes)
			(effects
				(font
					(size 1.016 1.016)
					(thickness 0.1524)
				)
				(justify mirror)
			)
		)
		(duplicate_pad_numbers_are_jumpers no)
		(fp_rect
			(start 0.2794 0.6477)
			(end -0.2794 -0.6477)
			(stroke
				(width 0)
				(type default)
			)
			(fill no)
			(layer "B.CrtYd")
		)
		(fp_rect
			(start 0.2794 0.6477)
			(end -0.2794 -0.6477)
			(stroke
				(width 0)
				(type default)
			)
			(fill no)
			(layer "B.Fab")
		)
		(pad "1" smd custom
			(at 0 -0.2794)
			(size 0.0762 0.0762)
			(layers "B.Cu" "B.Mask" "B.Paste")
			(net "P1V8_E")
			(options
				(clearance outline)
				(anchor circle)
			)
			(primitives
				(gr_poly
					(pts
						(arc
							(start 0.1524 0.127)
							(mid 0.137521 0.162921)
							(end 0.1016 0.1778)
						)
						(arc
							(start -0.1016 0.1778)
							(mid -0.137521 0.162921)
							(end -0.1524 0.127)
						)
						(arc
							(start -0.1524 -0.127)
							(mid -0.137521 -0.162921)
							(end -0.1016 -0.1778)
						)
						(arc
							(start 0.1016 -0.1778)
							(mid 0.137521 -0.162921)
							(end 0.1524 -0.127)
						)
					)
					(width 0)
					(fill yes)
				)
			)
		)
		(pad "2" smd custom
			(at 0 0.2794)
			(size 0.0762 0.0762)
			(layers "B.Cu" "B.Mask" "B.Paste")
			(net "GND")
			(options
				(clearance outline)
				(anchor circle)
			)
			(primitives
				(gr_poly
					(pts
						(arc
							(start 0.1524 0.127)
							(mid 0.137521 0.162921)
							(end 0.1016 0.1778)
						)
						(arc
							(start -0.1016 0.1778)
							(mid -0.137521 0.162921)
							(end -0.1524 0.127)
						)
						(arc
							(start -0.1524 -0.127)
							(mid -0.137521 -0.162921)
							(end -0.1016 -0.1778)
						)
						(arc
							(start 0.1016 -0.1778)
							(mid 0.137521 -0.162921)
							(end 0.1524 -0.127)
						)
					)
					(width 0)
					(fill yes)
				)
			)
		)
	)
	(footprint ""
		(layer "B.Cu")
		(at 274.193 -177.673 90)
		(property "Reference" "R340"
			(at 0 0 90)
			(layer "B.SilkS")
			(hide yes)
			(effects
				(font
					(size 1.27 1.27)
				)
				(justify mirror)
			)
		)
		(property "Value" "3K3R2F-2-GP"
			(at -0.064008 -3.993896 90)
			(unlocked yes)
			(layer "B.Fab")
			(hide yes)
			(effects
				(font
					(size 1.016 1.016)
					(thickness 0.1524)
				)
				(justify mirror)
			)
		)
		(property "Device Type" "R402H16"
			(at -0.064008 -5.517896 90)
			(unlocked yes)
			(layer "B.Fab")
			(hide yes)
			(effects
				(font
					(size 1.016 1.016)
					(thickness 0.1524)
				)
				(justify mirror)
			)
		)
		(duplicate_pad_numbers_are_jumpers no)
		(fp_line
			(start 0.508 -0.9398)
			(end 0.508 0.9398)
			(stroke
				(width 0.1524)
				(type default)
			)
			(layer "B.SilkS")
		)
		(fp_line
			(start -0.508 -0.9398)
			(end 0.508 -0.9398)
			(stroke
				(width 0.1524)
				(type default)
			)
			(layer "B.SilkS")
		)
		(fp_rect
			(start 0.508 0.9398)
			(end -0.508 -0.9398)
			(stroke
				(width 0)
				(type default)
			)
			(fill no)
			(layer "B.CrtYd")
		)
		(fp_rect
			(start 0.508 0.9398)
			(end -0.508 -0.9398)
			(stroke
				(width 0)
				(type default)
			)
			(fill no)
			(layer "B.Fab")
		)
		(pad "1" smd custom
			(at 0 -0.4445 270)
			(size 0.1397 0.1397)
			(layers "B.Cu" "B.Mask" "B.Paste")
			(net "P3V3_STBY")
			(options
				(clearance outline)
				(anchor circle)
			)
			(primitives
				(gr_poly
					(pts
						(arc
							(start -0.1778 0.2794)
							(mid -0.249642 0.249642)
							(end -0.2794 0.1778)
						)
						(arc
							(start -0.2794 -0.1778)
							(mid -0.249642 -0.249642)
							(end -0.1778 -0.2794)
						)
						(arc
							(start 0.1778 -0.2794)
							(mid 0.249642 -0.249642)
							(end 0.2794 -0.1778)
						)
						(arc
							(start 0.2794 0.1778)
							(mid 0.249642 0.249642)
							(end 0.1778 0.2794)
						)
					)
					(width 0)
					(fill yes)
				)
			)
		)
		(pad "2" smd custom
			(at 0 0.4445 270)
			(size 0.1397 0.1397)
			(layers "B.Cu" "B.Mask" "B.Paste")
			(net "ROMA8")
			(options
				(clearance outline)
				(anchor circle)
			)
			(primitives
				(gr_poly
					(pts
						(arc
							(start -0.1778 0.2794)
							(mid -0.249642 0.249642)
							(end -0.2794 0.1778)
						)
						(arc
							(start -0.2794 -0.1778)
							(mid -0.249642 -0.249642)
							(end -0.1778 -0.2794)
						)
						(arc
							(start 0.1778 -0.2794)
							(mid 0.249642 -0.249642)
							(end 0.2794 -0.1778)
						)
						(arc
							(start 0.2794 0.1778)
							(mid 0.249642 0.249642)
							(end 0.1778 0.2794)
						)
					)
					(width 0)
					(fill yes)
				)
			)
		)
	)
	(footprint ""
		(layer "B.Cu")
		(at 276.098 -162.56 -90)
		(property "Reference" "R329"
			(at 0 0 90)
			(layer "B.SilkS")
			(hide yes)
			(effects
				(font
					(size 1.27 1.27)
				)
				(justify mirror)
			)
		)
		(property "Value" "0R2J-2-GP"
			(at -0.064008 -3.993896 270)
			(unlocked yes)
			(layer "B.Fab")
			(hide yes)
			(effects
				(font
					(size 1.016 1.016)
					(thickness 0.1524)
				)
				(justify mirror)
			)
		)
		(property "Device Type" "R402H16"
			(at -0.064008 -5.517896 270)
			(unlocked yes)
			(layer "B.Fab")
			(hide yes)
			(effects
				(font
					(size 1.016 1.016)
					(thickness 0.1524)
				)
				(justify mirror)
			)
		)
		(duplicate_pad_numbers_are_jumpers no)
		(fp_line
			(start -0.508 -0.9398)
			(end 0.508 -0.9398)
			(stroke
				(width 0.1524)
				(type default)
			)
			(layer "B.SilkS")
		)
		(fp_line
			(start 0.508 -0.9398)
			(end 0.508 0.9398)
			(stroke
				(width 0.1524)
				(type default)
			)
			(layer "B.SilkS")
		)
		(fp_rect
			(start 0.508 0.9398)
			(end -0.508 -0.9398)
			(stroke
				(width 0)
				(type default)
			)
			(fill no)
			(layer "B.CrtYd")
		)
		(fp_rect
			(start 0.508 0.9398)
			(end -0.508 -0.9398)
			(stroke
				(width 0)
				(type default)
			)
			(fill no)
			(layer "B.Fab")
		)
		(pad "1" smd custom
			(at 0 -0.4445 90)
			(size 0.1397 0.1397)
			(layers "B.Cu" "B.Mask" "B.Paste")
			(net "PMU_PLTRST_N")
			(options
				(clearance outline)
				(anchor circle)
			)
			(primitives
				(gr_poly
					(pts
						(arc
							(start -0.1778 0.2794)
							(mid -0.249642 0.249642)
							(end -0.2794 0.1778)
						)
						(arc
							(start -0.2794 -0.1778)
							(mid -0.249642 -0.249642)
							(end -0.1778 -0.2794)
						)
						(arc
							(start 0.1778 -0.2794)
							(mid 0.249642 -0.249642)
							(end 0.2794 -0.1778)
						)
						(arc
							(start 0.2794 0.1778)
							(mid 0.249642 0.249642)
							(end 0.1778 0.2794)
						)
					)
					(width 0)
					(fill yes)
				)
			)
		)
		(pad "2" smd custom
			(at 0 0.4445 90)
			(size 0.1397 0.1397)
			(layers "B.Cu" "B.Mask" "B.Paste")
			(net "LPCRST0_N")
			(options
				(clearance outline)
				(anchor circle)
			)
			(primitives
				(gr_poly
					(pts
						(arc
							(start -0.1778 0.2794)
							(mid -0.249642 0.249642)
							(end -0.2794 0.1778)
						)
						(arc
							(start -0.2794 -0.1778)
							(mid -0.249642 -0.249642)
							(end -0.1778 -0.2794)
						)
						(arc
							(start 0.1778 -0.2794)
							(mid 0.249642 -0.249642)
							(end 0.2794 -0.1778)
						)
						(arc
							(start 0.2794 0.1778)
							(mid 0.249642 0.249642)
							(end 0.1778 0.2794)
						)
					)
					(width 0)
					(fill yes)
				)
			)
		)
	)
	(footprint ""
		(layer "B.Cu")
		(at 119.742966 -32.512 180)
		(property "Reference" "SC1001"
			(at 0 0 0)
			(layer "B.SilkS")
			(hide yes)
			(effects
				(font
					(size 1.27 1.27)
				)
				(justify mirror)
			)
		)
		(property "Value" "SCD1U16V2KX-3GP"
			(at -1.1811 -2.7051 180)
			(unlocked yes)
			(layer "B.Fab")
			(hide yes)
			(effects
				(font
					(size 1.016 1.016)
					(thickness 0.1524)
				)
				(justify mirror)
			)
		)
		(property "Device Type" "C402H22"
			(at -1.1811 -4.2291 180)
			(unlocked yes)
			(layer "B.Fab")
			(hide yes)
			(effects
				(font
					(size 1.016 1.016)
					(thickness 0.1524)
				)
				(justify mirror)
			)
		)
		(duplicate_pad_numbers_are_jumpers no)
		(fp_rect
			(start 0.4318 0.9525)
			(end -0.4318 -0.9525)
			(stroke
				(width 0)
				(type default)
			)
			(fill no)
			(layer "B.CrtYd")
		)
		(fp_rect
			(start 0.4318 0.9525)
			(end -0.4318 -0.9525)
			(stroke
				(width 0)
				(type default)
			)
			(fill no)
			(layer "B.Fab")
		)
		(pad "1" smd custom
			(at 0 -0.4445)
			(size 0.1524 0.1524)
			(layers "B.Cu" "B.Mask" "B.Paste")
			(net "P1V8_C")
			(options
				(clearance outline)
				(anchor circle)
			)
			(primitives
				(gr_poly
					(pts
						(arc
							(start 0.3048 0.2032)
							(mid 0.275042 0.275042)
							(end 0.2032 0.3048)
						)
						(arc
							(start -0.2032 0.3048)
							(mid -0.275042 0.275042)
							(end -0.3048 0.2032)
						)
						(arc
							(start -0.3048 -0.2032)
							(mid -0.275042 -0.275042)
							(end -0.2032 -0.3048)
						)
						(arc
							(start 0.2032 -0.3048)
							(mid 0.275042 -0.275042)
							(end 0.3048 -0.2032)
						)
					)
					(width 0)
					(fill yes)
				)
			)
		)
		(pad "2" smd custom
			(at 0 0.4445)
			(size 0.1524 0.1524)
			(layers "B.Cu" "B.Mask" "B.Paste")
			(net "GND")
			(options
				(clearance outline)
				(anchor circle)
			)
			(primitives
				(gr_poly
					(pts
						(arc
							(start 0.3048 0.2032)
							(mid 0.275042 0.275042)
							(end 0.2032 0.3048)
						)
						(arc
							(start -0.2032 0.3048)
							(mid -0.275042 0.275042)
							(end -0.3048 0.2032)
						)
						(arc
							(start -0.3048 -0.2032)
							(mid -0.275042 -0.275042)
							(end -0.2032 -0.3048)
						)
						(arc
							(start 0.2032 -0.3048)
							(mid 0.275042 -0.275042)
							(end 0.3048 -0.2032)
						)
					)
					(width 0)
					(fill yes)
				)
			)
		)
	)
	(footprint ""
		(layer "B.Cu")
		(at 293.1922 -204.343 180)
		(property "Reference" "C171"
			(at 0 0 0)
			(layer "B.SilkS")
			(hide yes)
			(effects
				(font
					(size 1.27 1.27)
				)
				(justify mirror)
			)
		)
		(property "Value" "SCD1U16V2KX-3GP"
			(at -1.1811 -2.7051 180)
			(unlocked yes)
			(layer "B.Fab")
			(hide yes)
			(effects
				(font
					(size 1.016 1.016)
					(thickness 0.1524)
				)
				(justify mirror)
			)
		)
		(property "Device Type" "C402H22"
			(at -1.1811 -4.2291 180)
			(unlocked yes)
			(layer "B.Fab")
			(hide yes)
			(effects
				(font
					(size 1.016 1.016)
					(thickness 0.1524)
				)
				(justify mirror)
			)
		)
		(duplicate_pad_numbers_are_jumpers no)
		(fp_rect
			(start 0.4318 0.9525)
			(end -0.4318 -0.9525)
			(stroke
				(width 0)
				(type default)
			)
			(fill no)
			(layer "B.CrtYd")
		)
		(fp_rect
			(start 0.4318 0.9525)
			(end -0.4318 -0.9525)
			(stroke
				(width 0)
				(type default)
			)
			(fill no)
			(layer "B.Fab")
		)
		(pad "1" smd custom
			(at 0 -0.4445)
			(size 0.1524 0.1524)
			(layers "B.Cu" "B.Mask" "B.Paste")
			(net "P1V53_STBY")
			(options
				(clearance outline)
				(anchor circle)
			)
			(primitives
				(gr_poly
					(pts
						(arc
							(start 0.3048 0.2032)
							(mid 0.275042 0.275042)
							(end 0.2032 0.3048)
						)
						(arc
							(start -0.2032 0.3048)
							(mid -0.275042 0.275042)
							(end -0.3048 0.2032)
						)
						(arc
							(start -0.3048 -0.2032)
							(mid -0.275042 -0.275042)
							(end -0.2032 -0.3048)
						)
						(arc
							(start 0.2032 -0.3048)
							(mid 0.275042 -0.275042)
							(end 0.3048 -0.2032)
						)
					)
					(width 0)
					(fill yes)
				)
			)
		)
		(pad "2" smd custom
			(at 0 0.4445)
			(size 0.1524 0.1524)
			(layers "B.Cu" "B.Mask" "B.Paste")
			(net "GND")
			(options
				(clearance outline)
				(anchor circle)
			)
			(primitives
				(gr_poly
					(pts
						(arc
							(start 0.3048 0.2032)
							(mid 0.275042 0.275042)
							(end 0.2032 0.3048)
						)
						(arc
							(start -0.2032 0.3048)
							(mid -0.275042 0.275042)
							(end -0.3048 0.2032)
						)
						(arc
							(start -0.3048 -0.2032)
							(mid -0.275042 -0.275042)
							(end -0.2032 -0.3048)
						)
						(arc
							(start 0.2032 -0.3048)
							(mid 0.275042 -0.275042)
							(end 0.3048 -0.2032)
						)
					)
					(width 0)
					(fill yes)
				)
			)
		)
	)
	(footprint ""
		(layer "B.Cu")
		(at 325.374 -175.006)
		(property "Reference" "R5764"
			(at 0 0 0)
			(layer "B.SilkS")
			(hide yes)
			(effects
				(font
					(size 1.27 1.27)
				)
				(justify mirror)
			)
		)
		(property "Value" "5K6R2F-2-GP"
			(at -0.064008 -3.993896 0)
			(unlocked yes)
			(layer "B.Fab")
			(hide yes)
			(effects
				(font
					(size 1.016 1.016)
					(thickness 0.1524)
				)
				(justify mirror)
			)
		)
		(property "Device Type" "R402H16"
			(at -0.064008 -5.517896 0)
			(unlocked yes)
			(layer "B.Fab")
			(hide yes)
			(effects
				(font
					(size 1.016 1.016)
					(thickness 0.1524)
				)
				(justify mirror)
			)
		)
		(duplicate_pad_numbers_are_jumpers no)
		(fp_line
			(start -0.508 -0.9398)
			(end 0.508 -0.9398)
			(stroke
				(width 0.1524)
				(type default)
			)
			(layer "B.SilkS")
		)
		(fp_line
			(start 0.508 -0.9398)
			(end 0.508 0.9398)
			(stroke
				(width 0.1524)
				(type default)
			)
			(layer "B.SilkS")
		)
		(fp_rect
			(start 0.508 0.9398)
			(end -0.508 -0.9398)
			(stroke
				(width 0)
				(type default)
			)
			(fill no)
			(layer "B.CrtYd")
		)
		(fp_rect
			(start 0.508 0.9398)
			(end -0.508 -0.9398)
			(stroke
				(width 0)
				(type default)
			)
			(fill no)
			(layer "B.Fab")
		)
		(pad "1" smd custom
			(at 0 -0.4445 180)
			(size 0.1397 0.1397)
			(layers "B.Cu" "B.Mask" "B.Paste")
			(net "P12V")
			(options
				(clearance outline)
				(anchor circle)
			)
			(primitives
				(gr_poly
					(pts
						(arc
							(start -0.1778 0.2794)
							(mid -0.249642 0.249642)
							(end -0.2794 0.1778)
						)
						(arc
							(start -0.2794 -0.1778)
							(mid -0.249642 -0.249642)
							(end -0.1778 -0.2794)
						)
						(arc
							(start 0.1778 -0.2794)
							(mid 0.249642 -0.249642)
							(end 0.2794 -0.1778)
						)
						(arc
							(start 0.2794 0.1778)
							(mid 0.249642 0.249642)
							(end 0.1778 0.2794)
						)
					)
					(width 0)
					(fill yes)
				)
			)
		)
		(pad "2" smd custom
			(at 0 0.4445 180)
			(size 0.1397 0.1397)
			(layers "B.Cu" "B.Mask" "B.Paste")
			(net "ADC_12V")
			(options
				(clearance outline)
				(anchor circle)
			)
			(primitives
				(gr_poly
					(pts
						(arc
							(start -0.1778 0.2794)
							(mid -0.249642 0.249642)
							(end -0.2794 0.1778)
						)
						(arc
							(start -0.2794 -0.1778)
							(mid -0.249642 -0.249642)
							(end -0.1778 -0.2794)
						)
						(arc
							(start 0.1778 -0.2794)
							(mid 0.249642 -0.249642)
							(end 0.2794 -0.1778)
						)
						(arc
							(start 0.2794 0.1778)
							(mid 0.249642 0.249642)
							(end 0.1778 0.2794)
						)
					)
					(width 0)
					(fill yes)
				)
			)
		)
	)
	(footprint ""
		(layer "B.Cu")
		(at 108.020612 -213.868 -90)
		(property "Reference" "SR906"
			(at 0 0 90)
			(layer "B.SilkS")
			(hide yes)
			(effects
				(font
					(size 1.27 1.27)
				)
				(justify mirror)
			)
		)
		(property "Value" "4K7R2F-GP"
			(at -0.064008 -3.993896 270)
			(unlocked yes)
			(layer "B.Fab")
			(hide yes)
			(effects
				(font
					(size 1.016 1.016)
					(thickness 0.1524)
				)
				(justify mirror)
			)
		)
		(property "Device Type" "R402H16"
			(at -0.064008 -5.517896 270)
			(unlocked yes)
			(layer "B.Fab")
			(hide yes)
			(effects
				(font
					(size 1.016 1.016)
					(thickness 0.1524)
				)
				(justify mirror)
			)
		)
		(duplicate_pad_numbers_are_jumpers no)
		(fp_line
			(start -0.508 -0.9398)
			(end 0.508 -0.9398)
			(stroke
				(width 0.1524)
				(type default)
			)
			(layer "B.SilkS")
		)
		(fp_line
			(start 0.508 -0.9398)
			(end 0.508 0.9398)
			(stroke
				(width 0.1524)
				(type default)
			)
			(layer "B.SilkS")
		)
		(fp_rect
			(start 0.508 0.9398)
			(end -0.508 -0.9398)
			(stroke
				(width 0)
				(type default)
			)
			(fill no)
			(layer "B.CrtYd")
		)
		(fp_rect
			(start 0.508 0.9398)
			(end -0.508 -0.9398)
			(stroke
				(width 0)
				(type default)
			)
			(fill no)
			(layer "B.Fab")
		)
		(pad "1" smd custom
			(at 0 -0.4445 90)
			(size 0.1397 0.1397)
			(layers "B.Cu" "B.Mask" "B.Paste")
			(net "REDV_D1_B")
			(options
				(clearance outline)
				(anchor circle)
			)
			(primitives
				(gr_poly
					(pts
						(arc
							(start -0.1778 0.2794)
							(mid -0.249642 0.249642)
							(end -0.2794 0.1778)
						)
						(arc
							(start -0.2794 -0.1778)
							(mid -0.249642 -0.249642)
							(end -0.1778 -0.2794)
						)
						(arc
							(start 0.1778 -0.2794)
							(mid 0.249642 -0.249642)
							(end 0.2794 -0.1778)
						)
						(arc
							(start 0.2794 0.1778)
							(mid 0.249642 0.249642)
							(end 0.1778 0.2794)
						)
					)
					(width 0)
					(fill yes)
				)
			)
		)
		(pad "2" smd custom
			(at 0 0.4445 90)
			(size 0.1397 0.1397)
			(layers "B.Cu" "B.Mask" "B.Paste")
			(net "GND")
			(options
				(clearance outline)
				(anchor circle)
			)
			(primitives
				(gr_poly
					(pts
						(arc
							(start -0.1778 0.2794)
							(mid -0.249642 0.249642)
							(end -0.2794 0.1778)
						)
						(arc
							(start -0.2794 -0.1778)
							(mid -0.249642 -0.249642)
							(end -0.1778 -0.2794)
						)
						(arc
							(start 0.1778 -0.2794)
							(mid 0.249642 -0.249642)
							(end 0.2794 -0.1778)
						)
						(arc
							(start 0.2794 0.1778)
							(mid 0.249642 0.249642)
							(end 0.1778 0.2794)
						)
					)
					(width 0)
					(fill yes)
				)
			)
		)
	)
	(footprint ""
		(layer "B.Cu")
		(at 323.401944 -174.975012 180)
		(property "Reference" "C8084"
			(at 0 0 0)
			(layer "B.SilkS")
			(hide yes)
			(effects
				(font
					(size 1.27 1.27)
				)
				(justify mirror)
			)
		)
		(property "Value" "SCD1U25V2KX-2-GP"
			(at -1.1811 -2.7051 180)
			(unlocked yes)
			(layer "B.Fab")
			(hide yes)
			(effects
				(font
					(size 1.016 1.016)
					(thickness 0.1524)
				)
				(justify mirror)
			)
		)
		(property "Device Type" "C402H22"
			(at -1.1811 -4.2291 180)
			(unlocked yes)
			(layer "B.Fab")
			(hide yes)
			(effects
				(font
					(size 1.016 1.016)
					(thickness 0.1524)
				)
				(justify mirror)
			)
		)
		(duplicate_pad_numbers_are_jumpers no)
		(fp_rect
			(start 0.4318 0.9525)
			(end -0.4318 -0.9525)
			(stroke
				(width 0)
				(type default)
			)
			(fill no)
			(layer "B.CrtYd")
		)
		(fp_rect
			(start 0.4318 0.9525)
			(end -0.4318 -0.9525)
			(stroke
				(width 0)
				(type default)
			)
			(fill no)
			(layer "B.Fab")
		)
		(pad "1" smd custom
			(at 0 -0.4445)
			(size 0.1524 0.1524)
			(layers "B.Cu" "B.Mask" "B.Paste")
			(net "ADC_12V")
			(options
				(clearance outline)
				(anchor circle)
			)
			(primitives
				(gr_poly
					(pts
						(arc
							(start 0.3048 0.2032)
							(mid 0.275042 0.275042)
							(end 0.2032 0.3048)
						)
						(arc
							(start -0.2032 0.3048)
							(mid -0.275042 0.275042)
							(end -0.3048 0.2032)
						)
						(arc
							(start -0.3048 -0.2032)
							(mid -0.275042 -0.275042)
							(end -0.2032 -0.3048)
						)
						(arc
							(start 0.2032 -0.3048)
							(mid 0.275042 -0.275042)
							(end 0.3048 -0.2032)
						)
					)
					(width 0)
					(fill yes)
				)
			)
		)
		(pad "2" smd custom
			(at 0 0.4445)
			(size 0.1524 0.1524)
			(layers "B.Cu" "B.Mask" "B.Paste")
			(net "GND")
			(options
				(clearance outline)
				(anchor circle)
			)
			(primitives
				(gr_poly
					(pts
						(arc
							(start 0.3048 0.2032)
							(mid 0.275042 0.275042)
							(end 0.2032 0.3048)
						)
						(arc
							(start -0.2032 0.3048)
							(mid -0.275042 0.275042)
							(end -0.3048 0.2032)
						)
						(arc
							(start -0.3048 -0.2032)
							(mid -0.275042 -0.275042)
							(end -0.2032 -0.3048)
						)
						(arc
							(start 0.2032 -0.3048)
							(mid 0.275042 -0.275042)
							(end 0.3048 -0.2032)
						)
					)
					(width 0)
					(fill yes)
				)
			)
		)
	)
	(footprint ""
		(layer "B.Cu")
		(at 114.281966 -43.561 -90)
		(property "Reference" "SR587"
			(at 0 0 90)
			(layer "B.SilkS")
			(hide yes)
			(effects
				(font
					(size 1.27 1.27)
				)
				(justify mirror)
			)
		)
		(property "Value" "10KR2F-2-GP"
			(at -0.064008 -3.993896 270)
			(unlocked yes)
			(layer "B.Fab")
			(hide yes)
			(effects
				(font
					(size 1.016 1.016)
					(thickness 0.1524)
				)
				(justify mirror)
			)
		)
		(property "Device Type" "R402H16"
			(at -0.064008 -5.517896 270)
			(unlocked yes)
			(layer "B.Fab")
			(hide yes)
			(effects
				(font
					(size 1.016 1.016)
					(thickness 0.1524)
				)
				(justify mirror)
			)
		)
		(duplicate_pad_numbers_are_jumpers no)
		(fp_line
			(start -0.508 -0.9398)
			(end 0.508 -0.9398)
			(stroke
				(width 0.1524)
				(type default)
			)
			(layer "B.SilkS")
		)
		(fp_line
			(start 0.508 -0.9398)
			(end 0.508 0.9398)
			(stroke
				(width 0.1524)
				(type default)
			)
			(layer "B.SilkS")
		)
		(fp_rect
			(start 0.508 0.9398)
			(end -0.508 -0.9398)
			(stroke
				(width 0)
				(type default)
			)
			(fill no)
			(layer "B.CrtYd")
		)
		(fp_rect
			(start 0.508 0.9398)
			(end -0.508 -0.9398)
			(stroke
				(width 0)
				(type default)
			)
			(fill no)
			(layer "B.Fab")
		)
		(pad "1" smd custom
			(at 0 -0.4445 90)
			(size 0.1397 0.1397)
			(layers "B.Cu" "B.Mask" "B.Paste")
			(net "GND")
			(options
				(clearance outline)
				(anchor circle)
			)
			(primitives
				(gr_poly
					(pts
						(arc
							(start -0.1778 0.2794)
							(mid -0.249642 0.249642)
							(end -0.2794 0.1778)
						)
						(arc
							(start -0.2794 -0.1778)
							(mid -0.249642 -0.249642)
							(end -0.1778 -0.2794)
						)
						(arc
							(start 0.1778 -0.2794)
							(mid 0.249642 -0.249642)
							(end 0.2794 -0.1778)
						)
						(arc
							(start 0.2794 0.1778)
							(mid 0.249642 0.249642)
							(end 0.1778 0.2794)
						)
					)
					(width 0)
					(fill yes)
				)
			)
		)
		(pad "2" smd custom
			(at 0 0.4445 90)
			(size 0.1397 0.1397)
			(layers "B.Cu" "B.Mask" "B.Paste")
			(net "IOC_CLK_SEL1")
			(options
				(clearance outline)
				(anchor circle)
			)
			(primitives
				(gr_poly
					(pts
						(arc
							(start -0.1778 0.2794)
							(mid -0.249642 0.249642)
							(end -0.2794 0.1778)
						)
						(arc
							(start -0.2794 -0.1778)
							(mid -0.249642 -0.249642)
							(end -0.1778 -0.2794)
						)
						(arc
							(start 0.1778 -0.2794)
							(mid 0.249642 -0.249642)
							(end 0.2794 -0.1778)
						)
						(arc
							(start 0.2794 0.1778)
							(mid 0.249642 0.249642)
							(end 0.1778 0.2794)
						)
					)
					(width 0)
					(fill yes)
				)
			)
		)
	)
	(footprint ""
		(layer "B.Cu")
		(at 126.600966 -33.401)
		(property "Reference" "SC932"
			(at 0 0 0)
			(layer "B.SilkS")
			(hide yes)
			(effects
				(font
					(size 1.27 1.27)
				)
				(justify mirror)
			)
		)
		(property "Value" "SC10U6D3V5KX-4GP"
			(at 0.0762 -6.1214 0)
			(unlocked yes)
			(layer "B.Fab")
			(hide yes)
			(effects
				(font
					(size 1.016 1.016)
					(thickness 0.1524)
				)
				(justify mirror)
			)
		)
		(property "Device Type" "C805H58"
			(at 0.0762 -8.1534 0)
			(unlocked yes)
			(layer "B.Fab")
			(hide yes)
			(effects
				(font
					(size 1.016 1.016)
					(thickness 0.1524)
				)
				(justify mirror)
			)
		)
		(duplicate_pad_numbers_are_jumpers no)
		(fp_line
			(start -0.635 0)
			(end 0.635 0)
			(stroke
				(width 0.508)
				(type default)
			)
			(layer "B.SilkS")
		)
		(fp_rect
			(start 0.9652 1.778)
			(end -0.9652 -1.778)
			(stroke
				(width 0)
				(type default)
			)
			(fill no)
			(layer "B.CrtYd")
		)
		(fp_poly
			(pts
				(xy 0.9652 -1.778) (xy -0.9652 -1.778) (xy -0.9652 1.778) (xy 0.9652 1.778)
			)
			(stroke
				(width 0)
				(type default)
			)
			(fill no)
			(layer "B.Fab")
		)
		(pad "1" smd rect
			(at 0 -0.9652 180)
			(size 1.397 1.143)
			(layers "B.Cu" "B.Mask" "B.Paste")
			(net "PLL_VDD")
		)
		(pad "2" smd rect
			(at 0 0.9652 180)
			(size 1.397 1.143)
			(layers "B.Cu" "B.Mask" "B.Paste")
			(net "GND")
		)
	)
	(footprint ""
		(layer "B.Cu")
		(at 109.352842 -82.621882 180)
		(property "Reference" "SR769"
			(at 0 0 0)
			(layer "B.SilkS")
			(hide yes)
			(effects
				(font
					(size 1.27 1.27)
				)
				(justify mirror)
			)
		)
		(property "Value" "4K75R2F-1-GP"
			(at -0.064008 -3.993896 180)
			(unlocked yes)
			(layer "B.Fab")
			(hide yes)
			(effects
				(font
					(size 1.016 1.016)
					(thickness 0.1524)
				)
				(justify mirror)
			)
		)
		(property "Device Type" "R402H16"
			(at -0.064008 -5.517896 180)
			(unlocked yes)
			(layer "B.Fab")
			(hide yes)
			(effects
				(font
					(size 1.016 1.016)
					(thickness 0.1524)
				)
				(justify mirror)
			)
		)
		(duplicate_pad_numbers_are_jumpers no)
		(fp_line
			(start 0.508 -0.9398)
			(end 0.508 0.9398)
			(stroke
				(width 0.1524)
				(type default)
			)
			(layer "B.SilkS")
		)
		(fp_line
			(start -0.508 -0.9398)
			(end 0.508 -0.9398)
			(stroke
				(width 0.1524)
				(type default)
			)
			(layer "B.SilkS")
		)
		(fp_rect
			(start 0.508 0.9398)
			(end -0.508 -0.9398)
			(stroke
				(width 0)
				(type default)
			)
			(fill no)
			(layer "B.CrtYd")
		)
		(fp_rect
			(start 0.508 0.9398)
			(end -0.508 -0.9398)
			(stroke
				(width 0)
				(type default)
			)
			(fill no)
			(layer "B.Fab")
		)
		(pad "1" smd custom
			(at 0 -0.4445)
			(size 0.1397 0.1397)
			(layers "B.Cu" "B.Mask" "B.Paste")
			(net "GND")
			(options
				(clearance outline)
				(anchor circle)
			)
			(primitives
				(gr_poly
					(pts
						(arc
							(start -0.1778 0.2794)
							(mid -0.249642 0.249642)
							(end -0.2794 0.1778)
						)
						(arc
							(start -0.2794 -0.1778)
							(mid -0.249642 -0.249642)
							(end -0.1778 -0.2794)
						)
						(arc
							(start 0.1778 -0.2794)
							(mid 0.249642 -0.249642)
							(end 0.2794 -0.1778)
						)
						(arc
							(start 0.2794 0.1778)
							(mid 0.249642 0.249642)
							(end 0.1778 0.2794)
						)
					)
					(width 0)
					(fill yes)
				)
			)
		)
		(pad "2" smd custom
			(at 0 0.4445)
			(size 0.1397 0.1397)
			(layers "B.Cu" "B.Mask" "B.Paste")
			(net "EXP_ADC_IN0")
			(options
				(clearance outline)
				(anchor circle)
			)
			(primitives
				(gr_poly
					(pts
						(arc
							(start -0.1778 0.2794)
							(mid -0.249642 0.249642)
							(end -0.2794 0.1778)
						)
						(arc
							(start -0.2794 -0.1778)
							(mid -0.249642 -0.249642)
							(end -0.1778 -0.2794)
						)
						(arc
							(start 0.1778 -0.2794)
							(mid 0.249642 -0.249642)
							(end 0.2794 -0.1778)
						)
						(arc
							(start 0.2794 0.1778)
							(mid 0.249642 0.249642)
							(end 0.1778 0.2794)
						)
					)
					(width 0)
					(fill yes)
				)
			)
		)
	)
	(footprint ""
		(layer "B.Cu")
		(at 320.167 -162.433 180)
		(property "Reference" "R439"
			(at 0 0 0)
			(layer "B.SilkS")
			(hide yes)
			(effects
				(font
					(size 1.27 1.27)
				)
				(justify mirror)
			)
		)
		(property "Value" "10KR2F-2-GP"
			(at -0.064008 -3.993896 180)
			(unlocked yes)
			(layer "B.Fab")
			(hide yes)
			(effects
				(font
					(size 1.016 1.016)
					(thickness 0.1524)
				)
				(justify mirror)
			)
		)
		(property "Device Type" "R402H16"
			(at -0.064008 -5.517896 180)
			(unlocked yes)
			(layer "B.Fab")
			(hide yes)
			(effects
				(font
					(size 1.016 1.016)
					(thickness 0.1524)
				)
				(justify mirror)
			)
		)
		(duplicate_pad_numbers_are_jumpers no)
		(fp_line
			(start 0.508 -0.9398)
			(end 0.508 0.9398)
			(stroke
				(width 0.1524)
				(type default)
			)
			(layer "B.SilkS")
		)
		(fp_line
			(start -0.508 -0.9398)
			(end 0.508 -0.9398)
			(stroke
				(width 0.1524)
				(type default)
			)
			(layer "B.SilkS")
		)
		(fp_rect
			(start 0.508 0.9398)
			(end -0.508 -0.9398)
			(stroke
				(width 0)
				(type default)
			)
			(fill no)
			(layer "B.CrtYd")
		)
		(fp_rect
			(start 0.508 0.9398)
			(end -0.508 -0.9398)
			(stroke
				(width 0)
				(type default)
			)
			(fill no)
			(layer "B.Fab")
		)
		(pad "1" smd custom
			(at 0 -0.4445)
			(size 0.1397 0.1397)
			(layers "B.Cu" "B.Mask" "B.Paste")
			(net "P3V3_STBY")
			(options
				(clearance outline)
				(anchor circle)
			)
			(primitives
				(gr_poly
					(pts
						(arc
							(start -0.1778 0.2794)
							(mid -0.249642 0.249642)
							(end -0.2794 0.1778)
						)
						(arc
							(start -0.2794 -0.1778)
							(mid -0.249642 -0.249642)
							(end -0.1778 -0.2794)
						)
						(arc
							(start 0.1778 -0.2794)
							(mid 0.249642 -0.249642)
							(end 0.2794 -0.1778)
						)
						(arc
							(start 0.2794 0.1778)
							(mid 0.249642 0.249642)
							(end 0.1778 0.2794)
						)
					)
					(width 0)
					(fill yes)
				)
			)
		)
		(pad "2" smd custom
			(at 0 0.4445)
			(size 0.1397 0.1397)
			(layers "B.Cu" "B.Mask" "B.Paste")
			(net "NIC_SMBUS_SCL")
			(options
				(clearance outline)
				(anchor circle)
			)
			(primitives
				(gr_poly
					(pts
						(arc
							(start -0.1778 0.2794)
							(mid -0.249642 0.249642)
							(end -0.2794 0.1778)
						)
						(arc
							(start -0.2794 -0.1778)
							(mid -0.249642 -0.249642)
							(end -0.1778 -0.2794)
						)
						(arc
							(start 0.1778 -0.2794)
							(mid 0.249642 -0.249642)
							(end 0.2794 -0.1778)
						)
						(arc
							(start 0.2794 0.1778)
							(mid 0.249642 0.249642)
							(end 0.1778 0.2794)
						)
					)
					(width 0)
					(fill yes)
				)
			)
		)
	)
	(footprint ""
		(layer "B.Cu")
		(at 124.441966 -37.973 -90)
		(property "Reference" "SQ1"
			(at 0 0 90)
			(layer "B.SilkS")
			(hide yes)
			(effects
				(font
					(size 1.27 1.27)
				)
				(justify mirror)
			)
		)
		(property "Value" "AO3400A-GP"
			(at -0.0254 -12.3444 270)
			(unlocked yes)
			(layer "B.Fab")
			(hide yes)
			(effects
				(font
					(size 1.016 1.016)
					(thickness 0.1524)
				)
				(justify mirror)
			)
		)
		(property "Device Type" "SOT23DGS2D8H50"
			(at -0.0254 -14.2494 270)
			(unlocked yes)
			(layer "B.Fab")
			(hide yes)
			(effects
				(font
					(size 1.016 1.016)
					(thickness 0.1524)
				)
				(justify mirror)
			)
		)
		(duplicate_pad_numbers_are_jumpers no)
		(fp_line
			(start -1.7018 0.254)
			(end 1.7018 0.254)
			(stroke
				(width 0.1524)
				(type default)
			)
			(layer "B.SilkS")
		)
		(fp_line
			(start 1.7018 0.254)
			(end 1.7018 -0.254)
			(stroke
				(width 0.1524)
				(type default)
			)
			(layer "B.SilkS")
		)
		(fp_line
			(start -1.7018 -0.254)
			(end -1.7018 0.254)
			(stroke
				(width 0.1524)
				(type default)
			)
			(layer "B.SilkS")
		)
		(fp_line
			(start 1.7018 -0.254)
			(end -1.7018 -0.254)
			(stroke
				(width 0.1524)
				(type default)
			)
			(layer "B.SilkS")
		)
		(fp_rect
			(start 1.778 1.9812)
			(end -1.778 -1.9812)
			(stroke
				(width 0)
				(type default)
			)
			(fill no)
			(layer "B.CrtYd")
		)
		(fp_poly
			(pts
				(xy 1.778 -1.9812) (xy -1.778 -1.9812) (xy -1.778 1.9812) (xy 1.778 1.9812)
			)
			(stroke
				(width 0)
				(type default)
			)
			(fill no)
			(layer "B.Fab")
		)
		(pad "D" smd custom
			(at 0 -1.1176 90)
			(size 0.254 0.254)
			(layers "B.Cu" "B.Mask" "B.Paste")
			(net "SYS_HB_LED_D")
			(options
				(clearance outline)
				(anchor circle)
			)
			(primitives
				(gr_poly
					(pts
						(arc
							(start -0.508 0.4064)
							(mid -0.448484 0.550084)
							(end -0.3048 0.6096)
						)
						(arc
							(start 0.3048 0.6096)
							(mid 0.448484 0.550084)
							(end 0.508 0.4064)
						)
						(arc
							(start 0.508 -0.4064)
							(mid 0.448484 -0.550084)
							(end 0.3048 -0.6096)
						)
						(arc
							(start -0.3048 -0.6096)
							(mid -0.448484 -0.550084)
							(end -0.508 -0.4064)
						)
					)
					(width 0)
					(fill yes)
				)
			)
		)
		(pad "G" smd custom
			(at 1.016 1.1176 90)
			(size 0.254 0.254)
			(layers "B.Cu" "B.Mask" "B.Paste")
			(net "SYS_HB_LED")
			(options
				(clearance outline)
				(anchor circle)
			)
			(primitives
				(gr_poly
					(pts
						(arc
							(start -0.508 0.4064)
							(mid -0.448484 0.550084)
							(end -0.3048 0.6096)
						)
						(arc
							(start 0.3048 0.6096)
							(mid 0.448484 0.550084)
							(end 0.508 0.4064)
						)
						(arc
							(start 0.508 -0.4064)
							(mid 0.448484 -0.550084)
							(end 0.3048 -0.6096)
						)
						(arc
							(start -0.3048 -0.6096)
							(mid -0.448484 -0.550084)
							(end -0.508 -0.4064)
						)
					)
					(width 0)
					(fill yes)
				)
			)
		)
		(pad "S" smd custom
			(at -1.016 1.1176 90)
			(size 0.254 0.254)
			(layers "B.Cu" "B.Mask" "B.Paste")
			(net "GND")
			(options
				(clearance outline)
				(anchor circle)
			)
			(primitives
				(gr_poly
					(pts
						(arc
							(start -0.508 0.4064)
							(mid -0.448484 0.550084)
							(end -0.3048 0.6096)
						)
						(arc
							(start 0.3048 0.6096)
							(mid 0.448484 0.550084)
							(end 0.508 0.4064)
						)
						(arc
							(start 0.508 -0.4064)
							(mid 0.448484 -0.550084)
							(end 0.3048 -0.6096)
						)
						(arc
							(start -0.3048 -0.6096)
							(mid -0.448484 -0.550084)
							(end -0.508 -0.4064)
						)
					)
					(width 0)
					(fill yes)
				)
			)
		)
	)
	(footprint ""
		(layer "B.Cu")
		(at 340.110318 -135.385048 90)
		(property "Reference" "R559"
			(at 0 0 90)
			(layer "B.SilkS")
			(hide yes)
			(effects
				(font
					(size 1.27 1.27)
				)
				(justify mirror)
			)
		)
		(property "Value" "0R3J-0-U-GP"
			(at 0.0254 -2.5146 90)
			(unlocked yes)
			(layer "B.Fab")
			(hide yes)
			(effects
				(font
					(size 1.016 1.016)
					(thickness 0.1524)
				)
				(justify mirror)
			)
		)
		(property "Device Type" "R603H22"
			(at 0.0254 -4.0386 90)
			(unlocked yes)
			(layer "B.Fab")
			(hide yes)
			(effects
				(font
					(size 1.016 1.016)
					(thickness 0.1524)
				)
				(justify mirror)
			)
		)
		(duplicate_pad_numbers_are_jumpers no)
		(fp_line
			(start 0.4826 0)
			(end 0.2032 0)
			(stroke
				(width 0.2032)
				(type default)
			)
			(layer "B.SilkS")
		)
		(fp_line
			(start -0.2032 0)
			(end -0.4826 0)
			(stroke
				(width 0.2032)
				(type default)
			)
			(layer "B.SilkS")
		)
		(fp_rect
			(start 0.5842 1.3335)
			(end -0.5842 -1.3335)
			(stroke
				(width 0)
				(type default)
			)
			(fill no)
			(layer "B.CrtYd")
		)
		(fp_rect
			(start 0.5842 1.3335)
			(end -0.5842 -1.3335)
			(stroke
				(width 0)
				(type default)
			)
			(fill no)
			(layer "B.Fab")
		)
		(pad "1" smd custom
			(at 0 -0.762 270)
			(size 0.2159 0.2159)
			(layers "B.Cu" "B.Mask" "B.Paste")
			(net "USB_P0_DN")
			(options
				(clearance outline)
				(anchor circle)
			)
			(primitives
				(gr_poly
					(pts
						(arc
							(start -0.3302 0.4318)
							(mid -0.402042 0.402042)
							(end -0.4318 0.3302)
						)
						(arc
							(start -0.4318 -0.3302)
							(mid -0.402042 -0.402042)
							(end -0.3302 -0.4318)
						)
						(arc
							(start 0.3302 -0.4318)
							(mid 0.402042 -0.402042)
							(end 0.4318 -0.3302)
						)
						(arc
							(start 0.4318 0.3302)
							(mid 0.402042 0.402042)
							(end 0.3302 0.4318)
						)
					)
					(width 0)
					(fill yes)
				)
			)
		)
		(pad "2" smd custom
			(at 0 0.762 270)
			(size 0.2159 0.2159)
			(layers "B.Cu" "B.Mask" "B.Paste")
			(net "USB_DN_R")
			(options
				(clearance outline)
				(anchor circle)
			)
			(primitives
				(gr_poly
					(pts
						(arc
							(start -0.3302 0.4318)
							(mid -0.402042 0.402042)
							(end -0.4318 0.3302)
						)
						(arc
							(start -0.4318 -0.3302)
							(mid -0.402042 -0.402042)
							(end -0.3302 -0.4318)
						)
						(arc
							(start 0.3302 -0.4318)
							(mid 0.402042 -0.402042)
							(end 0.4318 -0.3302)
						)
						(arc
							(start 0.4318 0.3302)
							(mid 0.402042 0.402042)
							(end 0.3302 0.4318)
						)
					)
					(width 0)
					(fill yes)
				)
			)
		)
	)
	(footprint ""
		(layer "B.Cu")
		(at 121.925842 -107.894882 180)
		(property "Reference" "SC1177"
			(at 0 0 0)
			(layer "B.SilkS")
			(hide yes)
			(effects
				(font
					(size 1.27 1.27)
				)
				(justify mirror)
			)
		)
		(property "Value" "SC22U6D3V5MX-2GP"
			(at 0.0762 -6.1214 180)
			(unlocked yes)
			(layer "B.Fab")
			(hide yes)
			(effects
				(font
					(size 1.016 1.016)
					(thickness 0.1524)
				)
				(justify mirror)
			)
		)
		(property "Device Type" "C805H58"
			(at 0.0762 -8.1534 180)
			(unlocked yes)
			(layer "B.Fab")
			(hide yes)
			(effects
				(font
					(size 1.016 1.016)
					(thickness 0.1524)
				)
				(justify mirror)
			)
		)
		(duplicate_pad_numbers_are_jumpers no)
		(fp_line
			(start -0.635 0)
			(end 0.635 0)
			(stroke
				(width 0.508)
				(type default)
			)
			(layer "B.SilkS")
		)
		(fp_rect
			(start 0.9652 1.778)
			(end -0.9652 -1.778)
			(stroke
				(width 0)
				(type default)
			)
			(fill no)
			(layer "B.CrtYd")
		)
		(fp_poly
			(pts
				(xy 0.9652 -1.778) (xy -0.9652 -1.778) (xy -0.9652 1.778) (xy 0.9652 1.778)
			)
			(stroke
				(width 0)
				(type default)
			)
			(fill no)
			(layer "B.Fab")
		)
		(pad "1" smd rect
			(at 0 -0.9652)
			(size 1.397 1.143)
			(layers "B.Cu" "B.Mask" "B.Paste")
			(net "GB_VDDA")
		)
		(pad "2" smd rect
			(at 0 0.9652)
			(size 1.397 1.143)
			(layers "B.Cu" "B.Mask" "B.Paste")
			(net "GND")
		)
	)
	(footprint ""
		(layer "B.Cu")
		(at 82.804 -21.209 180)
		(property "Reference" "PR186"
			(at 0 0 0)
			(layer "B.SilkS")
			(hide yes)
			(effects
				(font
					(size 1.27 1.27)
				)
				(justify mirror)
			)
		)
		(property "Value" "10KR2F-2-GP"
			(at -0.064008 -3.993896 180)
			(unlocked yes)
			(layer "B.Fab")
			(hide yes)
			(effects
				(font
					(size 1.016 1.016)
					(thickness 0.1524)
				)
				(justify mirror)
			)
		)
		(property "Device Type" "R402H16"
			(at -0.064008 -5.517896 180)
			(unlocked yes)
			(layer "B.Fab")
			(hide yes)
			(effects
				(font
					(size 1.016 1.016)
					(thickness 0.1524)
				)
				(justify mirror)
			)
		)
		(duplicate_pad_numbers_are_jumpers no)
		(fp_line
			(start 0.508 -0.9398)
			(end 0.508 0.9398)
			(stroke
				(width 0.1524)
				(type default)
			)
			(layer "B.SilkS")
		)
		(fp_line
			(start -0.508 -0.9398)
			(end 0.508 -0.9398)
			(stroke
				(width 0.1524)
				(type default)
			)
			(layer "B.SilkS")
		)
		(fp_rect
			(start 0.508 0.9398)
			(end -0.508 -0.9398)
			(stroke
				(width 0)
				(type default)
			)
			(fill no)
			(layer "B.CrtYd")
		)
		(fp_rect
			(start 0.508 0.9398)
			(end -0.508 -0.9398)
			(stroke
				(width 0)
				(type default)
			)
			(fill no)
			(layer "B.Fab")
		)
		(pad "1" smd custom
			(at 0 -0.4445)
			(size 0.1397 0.1397)
			(layers "B.Cu" "B.Mask" "B.Paste")
			(net "AGND_P0V9_C")
			(options
				(clearance outline)
				(anchor circle)
			)
			(primitives
				(gr_poly
					(pts
						(arc
							(start -0.1778 0.2794)
							(mid -0.249642 0.249642)
							(end -0.2794 0.1778)
						)
						(arc
							(start -0.2794 -0.1778)
							(mid -0.249642 -0.249642)
							(end -0.1778 -0.2794)
						)
						(arc
							(start 0.1778 -0.2794)
							(mid 0.249642 -0.249642)
							(end 0.2794 -0.1778)
						)
						(arc
							(start 0.2794 0.1778)
							(mid 0.249642 0.249642)
							(end 0.1778 0.2794)
						)
					)
					(width 0)
					(fill yes)
				)
			)
		)
		(pad "2" smd custom
			(at 0 0.4445)
			(size 0.1397 0.1397)
			(layers "B.Cu" "B.Mask" "B.Paste")
			(net "VT235_BIAS")
			(options
				(clearance outline)
				(anchor circle)
			)
			(primitives
				(gr_poly
					(pts
						(arc
							(start -0.1778 0.2794)
							(mid -0.249642 0.249642)
							(end -0.2794 0.1778)
						)
						(arc
							(start -0.2794 -0.1778)
							(mid -0.249642 -0.249642)
							(end -0.1778 -0.2794)
						)
						(arc
							(start 0.1778 -0.2794)
							(mid 0.249642 -0.249642)
							(end 0.2794 -0.1778)
						)
						(arc
							(start 0.2794 0.1778)
							(mid 0.249642 0.249642)
							(end 0.1778 0.2794)
						)
					)
					(width 0)
					(fill yes)
				)
			)
		)
	)
	(footprint ""
		(layer "B.Cu")
		(at 121.419874 -48.333914 -90)
		(property "Reference" "SR618"
			(at 0 0 90)
			(layer "B.SilkS")
			(hide yes)
			(effects
				(font
					(size 1.27 1.27)
				)
				(justify mirror)
			)
		)
		(property "Value" "2K2R2F-GP"
			(at -0.064008 -3.993896 270)
			(unlocked yes)
			(layer "B.Fab")
			(hide yes)
			(effects
				(font
					(size 1.016 1.016)
					(thickness 0.1524)
				)
				(justify mirror)
			)
		)
		(property "Device Type" "R402H16"
			(at -0.064008 -5.517896 270)
			(unlocked yes)
			(layer "B.Fab")
			(hide yes)
			(effects
				(font
					(size 1.016 1.016)
					(thickness 0.1524)
				)
				(justify mirror)
			)
		)
		(duplicate_pad_numbers_are_jumpers no)
		(fp_line
			(start -0.508 -0.9398)
			(end 0.508 -0.9398)
			(stroke
				(width 0.1524)
				(type default)
			)
			(layer "B.SilkS")
		)
		(fp_line
			(start 0.508 -0.9398)
			(end 0.508 0.9398)
			(stroke
				(width 0.1524)
				(type default)
			)
			(layer "B.SilkS")
		)
		(fp_rect
			(start 0.508 0.9398)
			(end -0.508 -0.9398)
			(stroke
				(width 0)
				(type default)
			)
			(fill no)
			(layer "B.CrtYd")
		)
		(fp_rect
			(start 0.508 0.9398)
			(end -0.508 -0.9398)
			(stroke
				(width 0)
				(type default)
			)
			(fill no)
			(layer "B.Fab")
		)
		(pad "1" smd custom
			(at 0 -0.4445 90)
			(size 0.1397 0.1397)
			(layers "B.Cu" "B.Mask" "B.Paste")
			(net "P1V8_C")
			(options
				(clearance outline)
				(anchor circle)
			)
			(primitives
				(gr_poly
					(pts
						(arc
							(start -0.1778 0.2794)
							(mid -0.249642 0.249642)
							(end -0.2794 0.1778)
						)
						(arc
							(start -0.2794 -0.1778)
							(mid -0.249642 -0.249642)
							(end -0.1778 -0.2794)
						)
						(arc
							(start 0.1778 -0.2794)
							(mid 0.249642 -0.249642)
							(end 0.2794 -0.1778)
						)
						(arc
							(start 0.2794 0.1778)
							(mid 0.249642 0.249642)
							(end 0.1778 0.2794)
						)
					)
					(width 0)
					(fill yes)
				)
			)
		)
		(pad "2" smd custom
			(at 0 0.4445 90)
			(size 0.1397 0.1397)
			(layers "B.Cu" "B.Mask" "B.Paste")
			(net "IOC_SCL_1")
			(options
				(clearance outline)
				(anchor circle)
			)
			(primitives
				(gr_poly
					(pts
						(arc
							(start -0.1778 0.2794)
							(mid -0.249642 0.249642)
							(end -0.2794 0.1778)
						)
						(arc
							(start -0.2794 -0.1778)
							(mid -0.249642 -0.249642)
							(end -0.1778 -0.2794)
						)
						(arc
							(start 0.1778 -0.2794)
							(mid 0.249642 -0.249642)
							(end 0.2794 -0.1778)
						)
						(arc
							(start 0.2794 0.1778)
							(mid 0.249642 0.249642)
							(end 0.1778 0.2794)
						)
					)
					(width 0)
					(fill yes)
				)
			)
		)
	)
	(footprint ""
		(layer "B.Cu")
		(at 105.41 -57.15 90)
		(property "Reference" "SR705"
			(at 0 0 90)
			(layer "B.SilkS")
			(hide yes)
			(effects
				(font
					(size 1.27 1.27)
				)
				(justify mirror)
			)
		)
		(property "Value" "10KR2F-2-GP"
			(at -0.064008 -3.993896 90)
			(unlocked yes)
			(layer "B.Fab")
			(hide yes)
			(effects
				(font
					(size 1.016 1.016)
					(thickness 0.1524)
				)
				(justify mirror)
			)
		)
		(property "Device Type" "R402H16"
			(at -0.064008 -5.517896 90)
			(unlocked yes)
			(layer "B.Fab")
			(hide yes)
			(effects
				(font
					(size 1.016 1.016)
					(thickness 0.1524)
				)
				(justify mirror)
			)
		)
		(duplicate_pad_numbers_are_jumpers no)
		(fp_line
			(start 0.508 -0.9398)
			(end 0.508 0.9398)
			(stroke
				(width 0.1524)
				(type default)
			)
			(layer "B.SilkS")
		)
		(fp_line
			(start -0.508 -0.9398)
			(end 0.508 -0.9398)
			(stroke
				(width 0.1524)
				(type default)
			)
			(layer "B.SilkS")
		)
		(fp_rect
			(start 0.508 0.9398)
			(end -0.508 -0.9398)
			(stroke
				(width 0)
				(type default)
			)
			(fill no)
			(layer "B.CrtYd")
		)
		(fp_rect
			(start 0.508 0.9398)
			(end -0.508 -0.9398)
			(stroke
				(width 0)
				(type default)
			)
			(fill no)
			(layer "B.Fab")
		)
		(pad "1" smd custom
			(at 0 -0.4445 270)
			(size 0.1397 0.1397)
			(layers "B.Cu" "B.Mask" "B.Paste")
			(net "P1V8_C")
			(options
				(clearance outline)
				(anchor circle)
			)
			(primitives
				(gr_poly
					(pts
						(arc
							(start -0.1778 0.2794)
							(mid -0.249642 0.249642)
							(end -0.2794 0.1778)
						)
						(arc
							(start -0.2794 -0.1778)
							(mid -0.249642 -0.249642)
							(end -0.1778 -0.2794)
						)
						(arc
							(start 0.1778 -0.2794)
							(mid 0.249642 -0.249642)
							(end 0.2794 -0.1778)
						)
						(arc
							(start 0.2794 0.1778)
							(mid 0.249642 0.249642)
							(end 0.1778 0.2794)
						)
					)
					(width 0)
					(fill yes)
				)
			)
		)
		(pad "2" smd custom
			(at 0 0.4445 270)
			(size 0.1397 0.1397)
			(layers "B.Cu" "B.Mask" "B.Paste")
			(net "XM_NAND_CS_N")
			(options
				(clearance outline)
				(anchor circle)
			)
			(primitives
				(gr_poly
					(pts
						(arc
							(start -0.1778 0.2794)
							(mid -0.249642 0.249642)
							(end -0.2794 0.1778)
						)
						(arc
							(start -0.2794 -0.1778)
							(mid -0.249642 -0.249642)
							(end -0.1778 -0.2794)
						)
						(arc
							(start 0.1778 -0.2794)
							(mid 0.249642 -0.249642)
							(end 0.2794 -0.1778)
						)
						(arc
							(start 0.2794 0.1778)
							(mid 0.249642 0.249642)
							(end 0.1778 0.2794)
						)
					)
					(width 0)
					(fill yes)
				)
			)
		)
	)
	(footprint ""
		(layer "B.Cu")
		(at 108.839 -61.214 -90)
		(property "Reference" "PR182"
			(at 0 0 90)
			(layer "B.SilkS")
			(hide yes)
			(effects
				(font
					(size 1.27 1.27)
				)
				(justify mirror)
			)
		)
		(property "Value" "221R2F-2-GP"
			(at -0.064008 -3.993896 270)
			(unlocked yes)
			(layer "B.Fab")
			(hide yes)
			(effects
				(font
					(size 1.016 1.016)
					(thickness 0.1524)
				)
				(justify mirror)
			)
		)
		(property "Device Type" "R402H16"
			(at -0.064008 -5.517896 270)
			(unlocked yes)
			(layer "B.Fab")
			(hide yes)
			(effects
				(font
					(size 1.016 1.016)
					(thickness 0.1524)
				)
				(justify mirror)
			)
		)
		(duplicate_pad_numbers_are_jumpers no)
		(fp_line
			(start -0.508 -0.9398)
			(end 0.508 -0.9398)
			(stroke
				(width 0.1524)
				(type default)
			)
			(layer "B.SilkS")
		)
		(fp_line
			(start 0.508 -0.9398)
			(end 0.508 0.9398)
			(stroke
				(width 0.1524)
				(type default)
			)
			(layer "B.SilkS")
		)
		(fp_rect
			(start 0.508 0.9398)
			(end -0.508 -0.9398)
			(stroke
				(width 0)
				(type default)
			)
			(fill no)
			(layer "B.CrtYd")
		)
		(fp_rect
			(start 0.508 0.9398)
			(end -0.508 -0.9398)
			(stroke
				(width 0)
				(type default)
			)
			(fill no)
			(layer "B.Fab")
		)
		(pad "1" smd custom
			(at 0 -0.4445 90)
			(size 0.1397 0.1397)
			(layers "B.Cu" "B.Mask" "B.Paste")
			(net "VT235_VFB")
			(options
				(clearance outline)
				(anchor circle)
			)
			(primitives
				(gr_poly
					(pts
						(arc
							(start -0.1778 0.2794)
							(mid -0.249642 0.249642)
							(end -0.2794 0.1778)
						)
						(arc
							(start -0.2794 -0.1778)
							(mid -0.249642 -0.249642)
							(end -0.1778 -0.2794)
						)
						(arc
							(start 0.1778 -0.2794)
							(mid 0.249642 -0.249642)
							(end 0.2794 -0.1778)
						)
						(arc
							(start 0.2794 0.1778)
							(mid 0.249642 0.249642)
							(end 0.1778 0.2794)
						)
					)
					(width 0)
					(fill yes)
				)
			)
		)
		(pad "2" smd custom
			(at 0 0.4445 90)
			(size 0.1397 0.1397)
			(layers "B.Cu" "B.Mask" "B.Paste")
			(net "P0V955_C")
			(options
				(clearance outline)
				(anchor circle)
			)
			(primitives
				(gr_poly
					(pts
						(arc
							(start -0.1778 0.2794)
							(mid -0.249642 0.249642)
							(end -0.2794 0.1778)
						)
						(arc
							(start -0.2794 -0.1778)
							(mid -0.249642 -0.249642)
							(end -0.1778 -0.2794)
						)
						(arc
							(start 0.1778 -0.2794)
							(mid 0.249642 -0.249642)
							(end 0.2794 -0.1778)
						)
						(arc
							(start 0.2794 0.1778)
							(mid 0.249642 0.249642)
							(end 0.1778 0.2794)
						)
					)
					(width 0)
					(fill yes)
				)
			)
		)
	)
	(footprint ""
		(layer "B.Cu")
		(at 102.389686 -55.31612 180)
		(property "Reference" "SC1012"
			(at 0 0 0)
			(layer "B.SilkS")
			(hide yes)
			(effects
				(font
					(size 1.27 1.27)
				)
				(justify mirror)
			)
		)
		(property "Value" "SC1KP50V2KX-1GP"
			(at -1.1811 -2.7051 180)
			(unlocked yes)
			(layer "B.Fab")
			(hide yes)
			(effects
				(font
					(size 1.016 1.016)
					(thickness 0.1524)
				)
				(justify mirror)
			)
		)
		(property "Device Type" "C402H22"
			(at -1.1811 -4.2291 180)
			(unlocked yes)
			(layer "B.Fab")
			(hide yes)
			(effects
				(font
					(size 1.016 1.016)
					(thickness 0.1524)
				)
				(justify mirror)
			)
		)
		(duplicate_pad_numbers_are_jumpers no)
		(fp_rect
			(start 0.4318 0.9525)
			(end -0.4318 -0.9525)
			(stroke
				(width 0)
				(type default)
			)
			(fill no)
			(layer "B.CrtYd")
		)
		(fp_rect
			(start 0.4318 0.9525)
			(end -0.4318 -0.9525)
			(stroke
				(width 0)
				(type default)
			)
			(fill no)
			(layer "B.Fab")
		)
		(pad "1" smd custom
			(at 0 -0.4445)
			(size 0.1524 0.1524)
			(layers "B.Cu" "B.Mask" "B.Paste")
			(net "P1V8_C")
			(options
				(clearance outline)
				(anchor circle)
			)
			(primitives
				(gr_poly
					(pts
						(arc
							(start 0.3048 0.2032)
							(mid 0.275042 0.275042)
							(end 0.2032 0.3048)
						)
						(arc
							(start -0.2032 0.3048)
							(mid -0.275042 0.275042)
							(end -0.3048 0.2032)
						)
						(arc
							(start -0.3048 -0.2032)
							(mid -0.275042 -0.275042)
							(end -0.2032 -0.3048)
						)
						(arc
							(start 0.2032 -0.3048)
							(mid 0.275042 -0.275042)
							(end 0.3048 -0.2032)
						)
					)
					(width 0)
					(fill yes)
				)
			)
		)
		(pad "2" smd custom
			(at 0 0.4445)
			(size 0.1524 0.1524)
			(layers "B.Cu" "B.Mask" "B.Paste")
			(net "GND")
			(options
				(clearance outline)
				(anchor circle)
			)
			(primitives
				(gr_poly
					(pts
						(arc
							(start 0.3048 0.2032)
							(mid 0.275042 0.275042)
							(end 0.2032 0.3048)
						)
						(arc
							(start -0.2032 0.3048)
							(mid -0.275042 0.275042)
							(end -0.3048 0.2032)
						)
						(arc
							(start -0.3048 -0.2032)
							(mid -0.275042 -0.275042)
							(end -0.2032 -0.3048)
						)
						(arc
							(start 0.2032 -0.3048)
							(mid 0.275042 -0.275042)
							(end 0.3048 -0.2032)
						)
					)
					(width 0)
					(fill yes)
				)
			)
		)
	)
	(footprint ""
		(layer "B.Cu")
		(at 77.089 -22.352 90)
		(property "Reference" "SQ18"
			(at 0 0 90)
			(layer "B.SilkS")
			(hide yes)
			(effects
				(font
					(size 1.27 1.27)
				)
				(justify mirror)
			)
		)
		(property "Value" "2N7002A-7-GP"
			(at -0.127 -8.9662 90)
			(unlocked yes)
			(layer "B.Fab")
			(hide yes)
			(effects
				(font
					(size 1.016 1.016)
					(thickness 0.1524)
				)
				(justify mirror)
			)
		)
		(property "Device Type" "SOT23DGS2D4H48"
			(at -0.127 -10.4902 90)
			(unlocked yes)
			(layer "B.Fab")
			(hide yes)
			(effects
				(font
					(size 1.016 1.016)
					(thickness 0.1524)
				)
				(justify mirror)
			)
		)
		(duplicate_pad_numbers_are_jumpers no)
		(fp_line
			(start 1.651 -1.778)
			(end 1.651 1.778)
			(stroke
				(width 0.1524)
				(type default)
			)
			(layer "B.SilkS")
		)
		(fp_line
			(start -1.651 -1.778)
			(end 1.651 -1.778)
			(stroke
				(width 0.1524)
				(type default)
			)
			(layer "B.SilkS")
		)
		(fp_line
			(start 1.651 1.778)
			(end -1.651 1.778)
			(stroke
				(width 0.1524)
				(type default)
			)
			(layer "B.SilkS")
		)
		(fp_line
			(start -1.651 1.778)
			(end -1.651 -1.778)
			(stroke
				(width 0.1524)
				(type default)
			)
			(layer "B.SilkS")
		)
		(fp_poly
			(pts
				(xy 1.778 1.8796) (xy 1.778 -1.8796) (xy -1.778 -1.8796) (xy -1.778 1.8796)
			)
			(stroke
				(width 0)
				(type default)
			)
			(fill no)
			(layer "B.CrtYd")
		)
		(fp_poly
			(pts
				(xy 1.778 1.8796) (xy 1.778 -1.8796) (xy -1.778 -1.8796) (xy -1.778 1.8796)
			)
			(stroke
				(width 0)
				(type default)
			)
			(fill no)
			(layer "B.Fab")
		)
		(pad "D" smd custom
			(at 0 -0.9525 270)
			(size 0.1905 0.1905)
			(layers "B.Cu" "B.Mask" "B.Paste")
			(net "P3V3_STBY_R9")
			(options
				(clearance outline)
				(anchor circle)
			)
			(primitives
				(gr_poly
					(pts
						(arc
							(start -0.1778 -0.5715)
							(mid -0.321484 -0.511984)
							(end -0.381 -0.3683)
						)
						(arc
							(start -0.381 0.3683)
							(mid -0.321484 0.511984)
							(end -0.1778 0.5715)
						)
						(arc
							(start 0.1778 0.5715)
							(mid 0.321484 0.511984)
							(end 0.381 0.3683)
						)
						(arc
							(start 0.381 -0.3683)
							(mid 0.321484 -0.511984)
							(end 0.1778 -0.5715)
						)
					)
					(width 0)
					(fill yes)
				)
			)
		)
		(pad "G" smd custom
			(at 0.98425 0.9525 270)
			(size 0.1905 0.1905)
			(layers "B.Cu" "B.Mask" "B.Paste")
			(net "PG_STAT_P0V955_C")
			(options
				(clearance outline)
				(anchor circle)
			)
			(primitives
				(gr_poly
					(pts
						(arc
							(start -0.1778 -0.5715)
							(mid -0.321484 -0.511984)
							(end -0.381 -0.3683)
						)
						(arc
							(start -0.381 0.3683)
							(mid -0.321484 0.511984)
							(end -0.1778 0.5715)
						)
						(arc
							(start 0.1778 0.5715)
							(mid 0.321484 0.511984)
							(end 0.381 0.3683)
						)
						(arc
							(start 0.381 -0.3683)
							(mid 0.321484 -0.511984)
							(end 0.1778 -0.5715)
						)
					)
					(width 0)
					(fill yes)
				)
			)
		)
		(pad "S" smd custom
			(at -0.98425 0.9525 270)
			(size 0.1905 0.1905)
			(layers "B.Cu" "B.Mask" "B.Paste")
			(net "GND")
			(options
				(clearance outline)
				(anchor circle)
			)
			(primitives
				(gr_poly
					(pts
						(arc
							(start -0.1778 -0.5715)
							(mid -0.321484 -0.511984)
							(end -0.381 -0.3683)
						)
						(arc
							(start -0.381 0.3683)
							(mid -0.321484 0.511984)
							(end -0.1778 0.5715)
						)
						(arc
							(start 0.1778 0.5715)
							(mid 0.321484 0.511984)
							(end 0.381 0.3683)
						)
						(arc
							(start 0.381 -0.3683)
							(mid 0.321484 -0.511984)
							(end 0.1778 -0.5715)
						)
					)
					(width 0)
					(fill yes)
				)
			)
		)
	)
	(footprint ""
		(layer "B.Cu")
		(at 256.159 -17.907 -90)
		(property "Reference" "C239"
			(at 0 0 90)
			(layer "B.SilkS")
			(hide yes)
			(effects
				(font
					(size 1.27 1.27)
				)
				(justify mirror)
			)
		)
		(property "Value" "SC1KP50V2KX-1GP"
			(at -1.1811 -2.7051 270)
			(unlocked yes)
			(layer "B.Fab")
			(hide yes)
			(effects
				(font
					(size 1.016 1.016)
					(thickness 0.1524)
				)
				(justify mirror)
			)
		)
		(property "Device Type" "C402H22"
			(at -1.1811 -4.2291 270)
			(unlocked yes)
			(layer "B.Fab")
			(hide yes)
			(effects
				(font
					(size 1.016 1.016)
					(thickness 0.1524)
				)
				(justify mirror)
			)
		)
		(duplicate_pad_numbers_are_jumpers no)
		(fp_rect
			(start 0.4318 0.9525)
			(end -0.4318 -0.9525)
			(stroke
				(width 0)
				(type default)
			)
			(fill no)
			(layer "B.CrtYd")
		)
		(fp_rect
			(start 0.4318 0.9525)
			(end -0.4318 -0.9525)
			(stroke
				(width 0)
				(type default)
			)
			(fill no)
			(layer "B.Fab")
		)
		(pad "1" smd custom
			(at 0 -0.4445 90)
			(size 0.1524 0.1524)
			(layers "B.Cu" "B.Mask" "B.Paste")
			(net "USB_OCS_N1")
			(options
				(clearance outline)
				(anchor circle)
			)
			(primitives
				(gr_poly
					(pts
						(arc
							(start 0.3048 0.2032)
							(mid 0.275042 0.275042)
							(end 0.2032 0.3048)
						)
						(arc
							(start -0.2032 0.3048)
							(mid -0.275042 0.275042)
							(end -0.3048 0.2032)
						)
						(arc
							(start -0.3048 -0.2032)
							(mid -0.275042 -0.275042)
							(end -0.2032 -0.3048)
						)
						(arc
							(start 0.2032 -0.3048)
							(mid 0.275042 -0.275042)
							(end 0.3048 -0.2032)
						)
					)
					(width 0)
					(fill yes)
				)
			)
		)
		(pad "2" smd custom
			(at 0 0.4445 90)
			(size 0.1524 0.1524)
			(layers "B.Cu" "B.Mask" "B.Paste")
			(net "GND")
			(options
				(clearance outline)
				(anchor circle)
			)
			(primitives
				(gr_poly
					(pts
						(arc
							(start 0.3048 0.2032)
							(mid 0.275042 0.275042)
							(end 0.2032 0.3048)
						)
						(arc
							(start -0.2032 0.3048)
							(mid -0.275042 0.275042)
							(end -0.3048 0.2032)
						)
						(arc
							(start -0.3048 -0.2032)
							(mid -0.275042 -0.275042)
							(end -0.2032 -0.3048)
						)
						(arc
							(start 0.2032 -0.3048)
							(mid 0.275042 -0.275042)
							(end 0.3048 -0.2032)
						)
					)
					(width 0)
					(fill yes)
				)
			)
		)
	)
	(footprint ""
		(layer "B.Cu")
		(at 294.7162 -203.962 180)
		(property "Reference" "C173"
			(at 0 0 0)
			(layer "B.SilkS")
			(hide yes)
			(effects
				(font
					(size 1.27 1.27)
				)
				(justify mirror)
			)
		)
		(property "Value" "SCD1U16V2KX-3GP"
			(at -1.1811 -2.7051 180)
			(unlocked yes)
			(layer "B.Fab")
			(hide yes)
			(effects
				(font
					(size 1.016 1.016)
					(thickness 0.1524)
				)
				(justify mirror)
			)
		)
		(property "Device Type" "C402H22"
			(at -1.1811 -4.2291 180)
			(unlocked yes)
			(layer "B.Fab")
			(hide yes)
			(effects
				(font
					(size 1.016 1.016)
					(thickness 0.1524)
				)
				(justify mirror)
			)
		)
		(duplicate_pad_numbers_are_jumpers no)
		(fp_rect
			(start 0.4318 0.9525)
			(end -0.4318 -0.9525)
			(stroke
				(width 0)
				(type default)
			)
			(fill no)
			(layer "B.CrtYd")
		)
		(fp_rect
			(start 0.4318 0.9525)
			(end -0.4318 -0.9525)
			(stroke
				(width 0)
				(type default)
			)
			(fill no)
			(layer "B.Fab")
		)
		(pad "1" smd custom
			(at 0 -0.4445)
			(size 0.1524 0.1524)
			(layers "B.Cu" "B.Mask" "B.Paste")
			(net "P1V53_STBY")
			(options
				(clearance outline)
				(anchor circle)
			)
			(primitives
				(gr_poly
					(pts
						(arc
							(start 0.3048 0.2032)
							(mid 0.275042 0.275042)
							(end 0.2032 0.3048)
						)
						(arc
							(start -0.2032 0.3048)
							(mid -0.275042 0.275042)
							(end -0.3048 0.2032)
						)
						(arc
							(start -0.3048 -0.2032)
							(mid -0.275042 -0.275042)
							(end -0.2032 -0.3048)
						)
						(arc
							(start 0.2032 -0.3048)
							(mid 0.275042 -0.275042)
							(end 0.3048 -0.2032)
						)
					)
					(width 0)
					(fill yes)
				)
			)
		)
		(pad "2" smd custom
			(at 0 0.4445)
			(size 0.1524 0.1524)
			(layers "B.Cu" "B.Mask" "B.Paste")
			(net "GND")
			(options
				(clearance outline)
				(anchor circle)
			)
			(primitives
				(gr_poly
					(pts
						(arc
							(start 0.3048 0.2032)
							(mid 0.275042 0.275042)
							(end 0.2032 0.3048)
						)
						(arc
							(start -0.2032 0.3048)
							(mid -0.275042 0.275042)
							(end -0.3048 0.2032)
						)
						(arc
							(start -0.3048 -0.2032)
							(mid -0.275042 -0.275042)
							(end -0.2032 -0.3048)
						)
						(arc
							(start 0.2032 -0.3048)
							(mid 0.275042 -0.275042)
							(end 0.3048 -0.2032)
						)
					)
					(width 0)
					(fill yes)
				)
			)
		)
	)
	(footprint ""
		(layer "B.Cu")
		(at 338.713318 -135.385048 90)
		(property "Reference" "R557"
			(at 0 0 90)
			(layer "B.SilkS")
			(hide yes)
			(effects
				(font
					(size 1.27 1.27)
				)
				(justify mirror)
			)
		)
		(property "Value" "0R3J-0-U-GP"
			(at 0.0254 -2.5146 90)
			(unlocked yes)
			(layer "B.Fab")
			(hide yes)
			(effects
				(font
					(size 1.016 1.016)
					(thickness 0.1524)
				)
				(justify mirror)
			)
		)
		(property "Device Type" "R603H22"
			(at 0.0254 -4.0386 90)
			(unlocked yes)
			(layer "B.Fab")
			(hide yes)
			(effects
				(font
					(size 1.016 1.016)
					(thickness 0.1524)
				)
				(justify mirror)
			)
		)
		(duplicate_pad_numbers_are_jumpers no)
		(fp_line
			(start 0.4826 0)
			(end 0.2032 0)
			(stroke
				(width 0.2032)
				(type default)
			)
			(layer "B.SilkS")
		)
		(fp_line
			(start -0.2032 0)
			(end -0.4826 0)
			(stroke
				(width 0.2032)
				(type default)
			)
			(layer "B.SilkS")
		)
		(fp_rect
			(start 0.5842 1.3335)
			(end -0.5842 -1.3335)
			(stroke
				(width 0)
				(type default)
			)
			(fill no)
			(layer "B.CrtYd")
		)
		(fp_rect
			(start 0.5842 1.3335)
			(end -0.5842 -1.3335)
			(stroke
				(width 0)
				(type default)
			)
			(fill no)
			(layer "B.Fab")
		)
		(pad "1" smd custom
			(at 0 -0.762 270)
			(size 0.2159 0.2159)
			(layers "B.Cu" "B.Mask" "B.Paste")
			(net "USB_P0_DN_R")
			(options
				(clearance outline)
				(anchor circle)
			)
			(primitives
				(gr_poly
					(pts
						(arc
							(start -0.3302 0.4318)
							(mid -0.402042 0.402042)
							(end -0.4318 0.3302)
						)
						(arc
							(start -0.4318 -0.3302)
							(mid -0.402042 -0.402042)
							(end -0.3302 -0.4318)
						)
						(arc
							(start 0.3302 -0.4318)
							(mid 0.402042 -0.402042)
							(end 0.4318 -0.3302)
						)
						(arc
							(start 0.4318 0.3302)
							(mid 0.402042 0.402042)
							(end 0.3302 0.4318)
						)
					)
					(width 0)
					(fill yes)
				)
			)
		)
		(pad "2" smd custom
			(at 0 0.762 270)
			(size 0.2159 0.2159)
			(layers "B.Cu" "B.Mask" "B.Paste")
			(net "USB_P0_DN")
			(options
				(clearance outline)
				(anchor circle)
			)
			(primitives
				(gr_poly
					(pts
						(arc
							(start -0.3302 0.4318)
							(mid -0.402042 0.402042)
							(end -0.4318 0.3302)
						)
						(arc
							(start -0.4318 -0.3302)
							(mid -0.402042 -0.402042)
							(end -0.3302 -0.4318)
						)
						(arc
							(start 0.3302 -0.4318)
							(mid 0.402042 -0.402042)
							(end 0.4318 -0.3302)
						)
						(arc
							(start 0.4318 0.3302)
							(mid 0.402042 0.402042)
							(end 0.3302 0.4318)
						)
					)
					(width 0)
					(fill yes)
				)
			)
		)
	)
	(footprint ""
		(layer "B.Cu")
		(at 127.90297 -101.727 90)
		(property "Reference" "SC1183"
			(at 0 0 90)
			(layer "B.SilkS")
			(hide yes)
			(effects
				(font
					(size 1.27 1.27)
				)
				(justify mirror)
			)
		)
		(property "Value" "SC22U6D3V5MX-2GP"
			(at 0.0762 -6.1214 90)
			(unlocked yes)
			(layer "B.Fab")
			(hide yes)
			(effects
				(font
					(size 1.016 1.016)
					(thickness 0.1524)
				)
				(justify mirror)
			)
		)
		(property "Device Type" "C805H58"
			(at 0.0762 -8.1534 90)
			(unlocked yes)
			(layer "B.Fab")
			(hide yes)
			(effects
				(font
					(size 1.016 1.016)
					(thickness 0.1524)
				)
				(justify mirror)
			)
		)
		(duplicate_pad_numbers_are_jumpers no)
		(fp_line
			(start -0.635 0)
			(end 0.635 0)
			(stroke
				(width 0.508)
				(type default)
			)
			(layer "B.SilkS")
		)
		(fp_rect
			(start 0.9652 1.778)
			(end -0.9652 -1.778)
			(stroke
				(width 0)
				(type default)
			)
			(fill no)
			(layer "B.CrtYd")
		)
		(fp_poly
			(pts
				(xy 0.9652 -1.778) (xy -0.9652 -1.778) (xy -0.9652 1.778) (xy 0.9652 1.778)
			)
			(stroke
				(width 0)
				(type default)
			)
			(fill no)
			(layer "B.Fab")
		)
		(pad "1" smd rect
			(at 0 -0.9652 270)
			(size 1.397 1.143)
			(layers "B.Cu" "B.Mask" "B.Paste")
			(net "GB_VDDA")
		)
		(pad "2" smd rect
			(at 0 0.9652 270)
			(size 1.397 1.143)
			(layers "B.Cu" "B.Mask" "B.Paste")
			(net "GND")
		)
	)
	(footprint ""
		(layer "B.Cu")
		(at 34.494216 -232.33888)
		(property "Reference" "R511"
			(at 0 0 0)
			(layer "B.SilkS")
			(hide yes)
			(effects
				(font
					(size 1.27 1.27)
				)
				(justify mirror)
			)
		)
		(property "Value" "0R2J-2-GP"
			(at -0.064008 -3.993896 0)
			(unlocked yes)
			(layer "B.Fab")
			(hide yes)
			(effects
				(font
					(size 1.016 1.016)
					(thickness 0.1524)
				)
				(justify mirror)
			)
		)
		(property "Device Type" "R402H16"
			(at -0.064008 -5.517896 0)
			(unlocked yes)
			(layer "B.Fab")
			(hide yes)
			(effects
				(font
					(size 1.016 1.016)
					(thickness 0.1524)
				)
				(justify mirror)
			)
		)
		(duplicate_pad_numbers_are_jumpers no)
		(fp_line
			(start -0.508 -0.9398)
			(end 0.508 -0.9398)
			(stroke
				(width 0.1524)
				(type default)
			)
			(layer "B.SilkS")
		)
		(fp_line
			(start 0.508 -0.9398)
			(end 0.508 0.9398)
			(stroke
				(width 0.1524)
				(type default)
			)
			(layer "B.SilkS")
		)
		(fp_rect
			(start 0.508 0.9398)
			(end -0.508 -0.9398)
			(stroke
				(width 0)
				(type default)
			)
			(fill no)
			(layer "B.CrtYd")
		)
		(fp_rect
			(start 0.508 0.9398)
			(end -0.508 -0.9398)
			(stroke
				(width 0)
				(type default)
			)
			(fill no)
			(layer "B.Fab")
		)
		(pad "1" smd custom
			(at 0 -0.4445 180)
			(size 0.1397 0.1397)
			(layers "B.Cu" "B.Mask" "B.Paste")
			(net "SAS_HDD_PWR9_PCIE")
			(options
				(clearance outline)
				(anchor circle)
			)
			(primitives
				(gr_poly
					(pts
						(arc
							(start -0.1778 0.2794)
							(mid -0.249642 0.249642)
							(end -0.2794 0.1778)
						)
						(arc
							(start -0.2794 -0.1778)
							(mid -0.249642 -0.249642)
							(end -0.1778 -0.2794)
						)
						(arc
							(start 0.1778 -0.2794)
							(mid 0.249642 -0.249642)
							(end 0.2794 -0.1778)
						)
						(arc
							(start 0.2794 0.1778)
							(mid 0.249642 0.249642)
							(end 0.1778 0.2794)
						)
					)
					(width 0)
					(fill yes)
				)
			)
		)
		(pad "2" smd custom
			(at 0 0.4445 180)
			(size 0.1397 0.1397)
			(layers "B.Cu" "B.Mask" "B.Paste")
			(net "SAS_HDD_PWR9")
			(options
				(clearance outline)
				(anchor circle)
			)
			(primitives
				(gr_poly
					(pts
						(arc
							(start -0.1778 0.2794)
							(mid -0.249642 0.249642)
							(end -0.2794 0.1778)
						)
						(arc
							(start -0.2794 -0.1778)
							(mid -0.249642 -0.249642)
							(end -0.1778 -0.2794)
						)
						(arc
							(start 0.1778 -0.2794)
							(mid 0.249642 -0.249642)
							(end 0.2794 -0.1778)
						)
						(arc
							(start 0.2794 0.1778)
							(mid 0.249642 0.249642)
							(end 0.1778 0.2794)
						)
					)
					(width 0)
					(fill yes)
				)
			)
		)
	)
	(footprint ""
		(layer "B.Cu")
		(at 297.2308 -172.5422 90)
		(property "Reference" "R335"
			(at 0 0 90)
			(layer "B.SilkS")
			(hide yes)
			(effects
				(font
					(size 1.27 1.27)
				)
				(justify mirror)
			)
		)
		(property "Value" "10KR2F-2-GP"
			(at -0.064008 -3.993896 90)
			(unlocked yes)
			(layer "B.Fab")
			(hide yes)
			(effects
				(font
					(size 1.016 1.016)
					(thickness 0.1524)
				)
				(justify mirror)
			)
		)
		(property "Device Type" "R402H16"
			(at -0.064008 -5.517896 90)
			(unlocked yes)
			(layer "B.Fab")
			(hide yes)
			(effects
				(font
					(size 1.016 1.016)
					(thickness 0.1524)
				)
				(justify mirror)
			)
		)
		(duplicate_pad_numbers_are_jumpers no)
		(fp_line
			(start 0.508 -0.9398)
			(end 0.508 0.9398)
			(stroke
				(width 0.1524)
				(type default)
			)
			(layer "B.SilkS")
		)
		(fp_line
			(start -0.508 -0.9398)
			(end 0.508 -0.9398)
			(stroke
				(width 0.1524)
				(type default)
			)
			(layer "B.SilkS")
		)
		(fp_rect
			(start 0.508 0.9398)
			(end -0.508 -0.9398)
			(stroke
				(width 0)
				(type default)
			)
			(fill no)
			(layer "B.CrtYd")
		)
		(fp_rect
			(start 0.508 0.9398)
			(end -0.508 -0.9398)
			(stroke
				(width 0)
				(type default)
			)
			(fill no)
			(layer "B.Fab")
		)
		(pad "1" smd custom
			(at 0 -0.4445 270)
			(size 0.1397 0.1397)
			(layers "B.Cu" "B.Mask" "B.Paste")
			(net "GND")
			(options
				(clearance outline)
				(anchor circle)
			)
			(primitives
				(gr_poly
					(pts
						(arc
							(start -0.1778 0.2794)
							(mid -0.249642 0.249642)
							(end -0.2794 0.1778)
						)
						(arc
							(start -0.2794 -0.1778)
							(mid -0.249642 -0.249642)
							(end -0.1778 -0.2794)
						)
						(arc
							(start 0.1778 -0.2794)
							(mid 0.249642 -0.249642)
							(end 0.2794 -0.1778)
						)
						(arc
							(start 0.2794 0.1778)
							(mid 0.249642 0.249642)
							(end 0.1778 0.2794)
						)
					)
					(width 0)
					(fill yes)
				)
			)
		)
		(pad "2" smd custom
			(at 0 0.4445 270)
			(size 0.1397 0.1397)
			(layers "B.Cu" "B.Mask" "B.Paste")
			(net "BMC0_JTAG_RTCK")
			(options
				(clearance outline)
				(anchor circle)
			)
			(primitives
				(gr_poly
					(pts
						(arc
							(start -0.1778 0.2794)
							(mid -0.249642 0.249642)
							(end -0.2794 0.1778)
						)
						(arc
							(start -0.2794 -0.1778)
							(mid -0.249642 -0.249642)
							(end -0.1778 -0.2794)
						)
						(arc
							(start 0.1778 -0.2794)
							(mid 0.249642 -0.249642)
							(end 0.2794 -0.1778)
						)
						(arc
							(start 0.2794 0.1778)
							(mid 0.249642 0.249642)
							(end 0.1778 0.2794)
						)
					)
					(width 0)
					(fill yes)
				)
			)
		)
	)
	(footprint ""
		(layer "B.Cu")
		(at 94.87916 -31.623)
		(property "Reference" "SC863"
			(at 0 0 0)
			(layer "B.SilkS")
			(hide yes)
			(effects
				(font
					(size 1.27 1.27)
				)
				(justify mirror)
			)
		)
		(property "Value" "SCD22U6D3V1MX-1-GP"
			(at 2.8321 -1.7399 0)
			(unlocked yes)
			(layer "B.Fab")
			(hide yes)
			(effects
				(font
					(size 1.016 1.016)
					(thickness 0.1524)
				)
				(justify mirror)
			)
		)
		(property "Device Type" "C0201H13"
			(at 2.8321 -3.2639 0)
			(unlocked yes)
			(layer "B.Fab")
			(hide yes)
			(effects
				(font
					(size 1.016 1.016)
					(thickness 0.1524)
				)
				(justify mirror)
			)
		)
		(duplicate_pad_numbers_are_jumpers no)
		(fp_rect
			(start 0.2794 0.6477)
			(end -0.2794 -0.6477)
			(stroke
				(width 0)
				(type default)
			)
			(fill no)
			(layer "B.CrtYd")
		)
		(fp_rect
			(start 0.2794 0.6477)
			(end -0.2794 -0.6477)
			(stroke
				(width 0)
				(type default)
			)
			(fill no)
			(layer "B.Fab")
		)
		(pad "1" smd custom
			(at 0 -0.2794 180)
			(size 0.0762 0.0762)
			(layers "B.Cu" "B.Mask" "B.Paste")
			(net "PCIE_SAS_C_CPU_RX_P1")
			(options
				(clearance outline)
				(anchor circle)
			)
			(primitives
				(gr_poly
					(pts
						(arc
							(start 0.1524 0.127)
							(mid 0.137521 0.162921)
							(end 0.1016 0.1778)
						)
						(arc
							(start -0.1016 0.1778)
							(mid -0.137521 0.162921)
							(end -0.1524 0.127)
						)
						(arc
							(start -0.1524 -0.127)
							(mid -0.137521 -0.162921)
							(end -0.1016 -0.1778)
						)
						(arc
							(start 0.1016 -0.1778)
							(mid 0.137521 -0.162921)
							(end 0.1524 -0.127)
						)
					)
					(width 0)
					(fill yes)
				)
			)
		)
		(pad "2" smd custom
			(at 0 0.2794 180)
			(size 0.0762 0.0762)
			(layers "B.Cu" "B.Mask" "B.Paste")
			(net "PCIE_SAS_CPU_RX_P1")
			(options
				(clearance outline)
				(anchor circle)
			)
			(primitives
				(gr_poly
					(pts
						(arc
							(start 0.1524 0.127)
							(mid 0.137521 0.162921)
							(end 0.1016 0.1778)
						)
						(arc
							(start -0.1016 0.1778)
							(mid -0.137521 0.162921)
							(end -0.1524 0.127)
						)
						(arc
							(start -0.1524 -0.127)
							(mid -0.137521 -0.162921)
							(end -0.1016 -0.1778)
						)
						(arc
							(start 0.1016 -0.1778)
							(mid 0.137521 -0.162921)
							(end 0.1524 -0.127)
						)
					)
					(width 0)
					(fill yes)
				)
			)
		)
	)
	(footprint ""
		(layer "B.Cu")
		(at 299.339 -164.084)
		(property "Reference" "R538"
			(at 0 0 0)
			(layer "B.SilkS")
			(hide yes)
			(effects
				(font
					(size 1.27 1.27)
				)
				(justify mirror)
			)
		)
		(property "Value" "0R2J-2-GP"
			(at -0.064008 -3.993896 0)
			(unlocked yes)
			(layer "B.Fab")
			(hide yes)
			(effects
				(font
					(size 1.016 1.016)
					(thickness 0.1524)
				)
				(justify mirror)
			)
		)
		(property "Device Type" "R402H16"
			(at -0.064008 -5.517896 0)
			(unlocked yes)
			(layer "B.Fab")
			(hide yes)
			(effects
				(font
					(size 1.016 1.016)
					(thickness 0.1524)
				)
				(justify mirror)
			)
		)
		(duplicate_pad_numbers_are_jumpers no)
		(fp_line
			(start -0.508 -0.9398)
			(end 0.508 -0.9398)
			(stroke
				(width 0.1524)
				(type default)
			)
			(layer "B.SilkS")
		)
		(fp_line
			(start 0.508 -0.9398)
			(end 0.508 0.9398)
			(stroke
				(width 0.1524)
				(type default)
			)
			(layer "B.SilkS")
		)
		(fp_rect
			(start 0.508 0.9398)
			(end -0.508 -0.9398)
			(stroke
				(width 0)
				(type default)
			)
			(fill no)
			(layer "B.CrtYd")
		)
		(fp_rect
			(start 0.508 0.9398)
			(end -0.508 -0.9398)
			(stroke
				(width 0)
				(type default)
			)
			(fill no)
			(layer "B.Fab")
		)
		(pad "1" smd custom
			(at 0 -0.4445 180)
			(size 0.1397 0.1397)
			(layers "B.Cu" "B.Mask" "B.Paste")
			(net "EXP_ID_BMC")
			(options
				(clearance outline)
				(anchor circle)
			)
			(primitives
				(gr_poly
					(pts
						(arc
							(start -0.1778 0.2794)
							(mid -0.249642 0.249642)
							(end -0.2794 0.1778)
						)
						(arc
							(start -0.2794 -0.1778)
							(mid -0.249642 -0.249642)
							(end -0.1778 -0.2794)
						)
						(arc
							(start 0.1778 -0.2794)
							(mid 0.249642 -0.249642)
							(end 0.2794 -0.1778)
						)
						(arc
							(start 0.2794 0.1778)
							(mid 0.249642 0.249642)
							(end 0.1778 0.2794)
						)
					)
					(width 0)
					(fill yes)
				)
			)
		)
		(pad "2" smd custom
			(at 0 0.4445 180)
			(size 0.1397 0.1397)
			(layers "B.Cu" "B.Mask" "B.Paste")
			(net "EXP_ID")
			(options
				(clearance outline)
				(anchor circle)
			)
			(primitives
				(gr_poly
					(pts
						(arc
							(start -0.1778 0.2794)
							(mid -0.249642 0.249642)
							(end -0.2794 0.1778)
						)
						(arc
							(start -0.2794 -0.1778)
							(mid -0.249642 -0.249642)
							(end -0.1778 -0.2794)
						)
						(arc
							(start 0.1778 -0.2794)
							(mid 0.249642 -0.249642)
							(end 0.2794 -0.1778)
						)
						(arc
							(start 0.2794 0.1778)
							(mid 0.249642 0.249642)
							(end 0.1778 0.2794)
						)
					)
					(width 0)
					(fill yes)
				)
			)
		)
	)
	(footprint ""
		(layer "B.Cu")
		(at 108.020612 -215.011 -90)
		(property "Reference" "SR900"
			(at 0 0 90)
			(layer "B.SilkS")
			(hide yes)
			(effects
				(font
					(size 1.27 1.27)
				)
				(justify mirror)
			)
		)
		(property "Value" "4K7R2F-GP"
			(at -0.064008 -3.993896 270)
			(unlocked yes)
			(layer "B.Fab")
			(hide yes)
			(effects
				(font
					(size 1.016 1.016)
					(thickness 0.1524)
				)
				(justify mirror)
			)
		)
		(property "Device Type" "R402H16"
			(at -0.064008 -5.517896 270)
			(unlocked yes)
			(layer "B.Fab")
			(hide yes)
			(effects
				(font
					(size 1.016 1.016)
					(thickness 0.1524)
				)
				(justify mirror)
			)
		)
		(duplicate_pad_numbers_are_jumpers no)
		(fp_line
			(start -0.508 -0.9398)
			(end 0.508 -0.9398)
			(stroke
				(width 0.1524)
				(type default)
			)
			(layer "B.SilkS")
		)
		(fp_line
			(start 0.508 -0.9398)
			(end 0.508 0.9398)
			(stroke
				(width 0.1524)
				(type default)
			)
			(layer "B.SilkS")
		)
		(fp_rect
			(start 0.508 0.9398)
			(end -0.508 -0.9398)
			(stroke
				(width 0)
				(type default)
			)
			(fill no)
			(layer "B.CrtYd")
		)
		(fp_rect
			(start 0.508 0.9398)
			(end -0.508 -0.9398)
			(stroke
				(width 0)
				(type default)
			)
			(fill no)
			(layer "B.Fab")
		)
		(pad "1" smd custom
			(at 0 -0.4445 90)
			(size 0.1397 0.1397)
			(layers "B.Cu" "B.Mask" "B.Paste")
			(net "REDV_I2C_A0")
			(options
				(clearance outline)
				(anchor circle)
			)
			(primitives
				(gr_poly
					(pts
						(arc
							(start -0.1778 0.2794)
							(mid -0.249642 0.249642)
							(end -0.2794 0.1778)
						)
						(arc
							(start -0.2794 -0.1778)
							(mid -0.249642 -0.249642)
							(end -0.1778 -0.2794)
						)
						(arc
							(start 0.1778 -0.2794)
							(mid 0.249642 -0.249642)
							(end 0.2794 -0.1778)
						)
						(arc
							(start 0.2794 0.1778)
							(mid 0.249642 0.249642)
							(end 0.1778 0.2794)
						)
					)
					(width 0)
					(fill yes)
				)
			)
		)
		(pad "2" smd custom
			(at 0 0.4445 90)
			(size 0.1397 0.1397)
			(layers "B.Cu" "B.Mask" "B.Paste")
			(net "GND")
			(options
				(clearance outline)
				(anchor circle)
			)
			(primitives
				(gr_poly
					(pts
						(arc
							(start -0.1778 0.2794)
							(mid -0.249642 0.249642)
							(end -0.2794 0.1778)
						)
						(arc
							(start -0.2794 -0.1778)
							(mid -0.249642 -0.249642)
							(end -0.1778 -0.2794)
						)
						(arc
							(start 0.1778 -0.2794)
							(mid 0.249642 -0.249642)
							(end 0.2794 -0.1778)
						)
						(arc
							(start 0.2794 0.1778)
							(mid 0.249642 0.249642)
							(end 0.1778 0.2794)
						)
					)
					(width 0)
					(fill yes)
				)
			)
		)
	)
	(footprint ""
		(layer "B.Cu")
		(at 112.30737 -92.1258 90)
		(property "Reference" "SC1253"
			(at 0 0 90)
			(layer "B.SilkS")
			(hide yes)
			(effects
				(font
					(size 1.27 1.27)
				)
				(justify mirror)
			)
		)
		(property "Value" "SCD1U6D3V1KX-GP"
			(at 2.8321 -1.7399 90)
			(unlocked yes)
			(layer "B.Fab")
			(hide yes)
			(effects
				(font
					(size 1.016 1.016)
					(thickness 0.1524)
				)
				(justify mirror)
			)
		)
		(property "Device Type" "C0201H13"
			(at 2.8321 -3.2639 90)
			(unlocked yes)
			(layer "B.Fab")
			(hide yes)
			(effects
				(font
					(size 1.016 1.016)
					(thickness 0.1524)
				)
				(justify mirror)
			)
		)
		(duplicate_pad_numbers_are_jumpers no)
		(fp_rect
			(start 0.2794 0.6477)
			(end -0.2794 -0.6477)
			(stroke
				(width 0)
				(type default)
			)
			(fill no)
			(layer "B.CrtYd")
		)
		(fp_rect
			(start 0.2794 0.6477)
			(end -0.2794 -0.6477)
			(stroke
				(width 0)
				(type default)
			)
			(fill no)
			(layer "B.Fab")
		)
		(pad "1" smd custom
			(at 0 -0.2794 270)
			(size 0.0762 0.0762)
			(layers "B.Cu" "B.Mask" "B.Paste")
			(net "P0V9_E")
			(options
				(clearance outline)
				(anchor circle)
			)
			(primitives
				(gr_poly
					(pts
						(arc
							(start 0.1524 0.127)
							(mid 0.137521 0.162921)
							(end 0.1016 0.1778)
						)
						(arc
							(start -0.1016 0.1778)
							(mid -0.137521 0.162921)
							(end -0.1524 0.127)
						)
						(arc
							(start -0.1524 -0.127)
							(mid -0.137521 -0.162921)
							(end -0.1016 -0.1778)
						)
						(arc
							(start 0.1016 -0.1778)
							(mid 0.137521 -0.162921)
							(end 0.1524 -0.127)
						)
					)
					(width 0)
					(fill yes)
				)
			)
		)
		(pad "2" smd custom
			(at 0 0.2794 270)
			(size 0.0762 0.0762)
			(layers "B.Cu" "B.Mask" "B.Paste")
			(net "GND")
			(options
				(clearance outline)
				(anchor circle)
			)
			(primitives
				(gr_poly
					(pts
						(arc
							(start 0.1524 0.127)
							(mid 0.137521 0.162921)
							(end 0.1016 0.1778)
						)
						(arc
							(start -0.1016 0.1778)
							(mid -0.137521 0.162921)
							(end -0.1524 0.127)
						)
						(arc
							(start -0.1524 -0.127)
							(mid -0.137521 -0.162921)
							(end -0.1016 -0.1778)
						)
						(arc
							(start 0.1016 -0.1778)
							(mid 0.137521 -0.162921)
							(end 0.1524 -0.127)
						)
					)
					(width 0)
					(fill yes)
				)
			)
		)
	)
	(footprint ""
		(layer "B.Cu")
		(at 274.193 -183.769 90)
		(property "Reference" "R350"
			(at 0 0 90)
			(layer "B.SilkS")
			(hide yes)
			(effects
				(font
					(size 1.27 1.27)
				)
				(justify mirror)
			)
		)
		(property "Value" "3K3R2F-2-GP"
			(at -0.064008 -3.993896 90)
			(unlocked yes)
			(layer "B.Fab")
			(hide yes)
			(effects
				(font
					(size 1.016 1.016)
					(thickness 0.1524)
				)
				(justify mirror)
			)
		)
		(property "Device Type" "R402H16"
			(at -0.064008 -5.517896 90)
			(unlocked yes)
			(layer "B.Fab")
			(hide yes)
			(effects
				(font
					(size 1.016 1.016)
					(thickness 0.1524)
				)
				(justify mirror)
			)
		)
		(duplicate_pad_numbers_are_jumpers no)
		(fp_line
			(start 0.508 -0.9398)
			(end 0.508 0.9398)
			(stroke
				(width 0.1524)
				(type default)
			)
			(layer "B.SilkS")
		)
		(fp_line
			(start -0.508 -0.9398)
			(end 0.508 -0.9398)
			(stroke
				(width 0.1524)
				(type default)
			)
			(layer "B.SilkS")
		)
		(fp_rect
			(start 0.508 0.9398)
			(end -0.508 -0.9398)
			(stroke
				(width 0)
				(type default)
			)
			(fill no)
			(layer "B.CrtYd")
		)
		(fp_rect
			(start 0.508 0.9398)
			(end -0.508 -0.9398)
			(stroke
				(width 0)
				(type default)
			)
			(fill no)
			(layer "B.Fab")
		)
		(pad "1" smd custom
			(at 0 -0.4445 270)
			(size 0.1397 0.1397)
			(layers "B.Cu" "B.Mask" "B.Paste")
			(net "P3V3_STBY")
			(options
				(clearance outline)
				(anchor circle)
			)
			(primitives
				(gr_poly
					(pts
						(arc
							(start -0.1778 0.2794)
							(mid -0.249642 0.249642)
							(end -0.2794 0.1778)
						)
						(arc
							(start -0.2794 -0.1778)
							(mid -0.249642 -0.249642)
							(end -0.1778 -0.2794)
						)
						(arc
							(start 0.1778 -0.2794)
							(mid 0.249642 -0.249642)
							(end 0.2794 -0.1778)
						)
						(arc
							(start 0.2794 0.1778)
							(mid 0.249642 0.249642)
							(end 0.1778 0.2794)
						)
					)
					(width 0)
					(fill yes)
				)
			)
		)
		(pad "2" smd custom
			(at 0 0.4445 270)
			(size 0.1397 0.1397)
			(layers "B.Cu" "B.Mask" "B.Paste")
			(net "ROMD2")
			(options
				(clearance outline)
				(anchor circle)
			)
			(primitives
				(gr_poly
					(pts
						(arc
							(start -0.1778 0.2794)
							(mid -0.249642 0.249642)
							(end -0.2794 0.1778)
						)
						(arc
							(start -0.2794 -0.1778)
							(mid -0.249642 -0.249642)
							(end -0.1778 -0.2794)
						)
						(arc
							(start 0.1778 -0.2794)
							(mid 0.249642 -0.249642)
							(end 0.2794 -0.1778)
						)
						(arc
							(start 0.2794 0.1778)
							(mid 0.249642 0.249642)
							(end 0.1778 0.2794)
						)
					)
					(width 0)
					(fill yes)
				)
			)
		)
	)
	(footprint ""
		(layer "B.Cu")
		(at 86.11616 -50.165 90)
		(property "Reference" "SR632"
			(at 0 0 90)
			(layer "B.SilkS")
			(hide yes)
			(effects
				(font
					(size 1.27 1.27)
				)
				(justify mirror)
			)
		)
		(property "Value" "2K2R2F-GP"
			(at -0.064008 -3.993896 90)
			(unlocked yes)
			(layer "B.Fab")
			(hide yes)
			(effects
				(font
					(size 1.016 1.016)
					(thickness 0.1524)
				)
				(justify mirror)
			)
		)
		(property "Device Type" "R402H16"
			(at -0.064008 -5.517896 90)
			(unlocked yes)
			(layer "B.Fab")
			(hide yes)
			(effects
				(font
					(size 1.016 1.016)
					(thickness 0.1524)
				)
				(justify mirror)
			)
		)
		(duplicate_pad_numbers_are_jumpers no)
		(fp_line
			(start 0.508 -0.9398)
			(end 0.508 0.9398)
			(stroke
				(width 0.1524)
				(type default)
			)
			(layer "B.SilkS")
		)
		(fp_line
			(start -0.508 -0.9398)
			(end 0.508 -0.9398)
			(stroke
				(width 0.1524)
				(type default)
			)
			(layer "B.SilkS")
		)
		(fp_rect
			(start 0.508 0.9398)
			(end -0.508 -0.9398)
			(stroke
				(width 0)
				(type default)
			)
			(fill no)
			(layer "B.CrtYd")
		)
		(fp_rect
			(start 0.508 0.9398)
			(end -0.508 -0.9398)
			(stroke
				(width 0)
				(type default)
			)
			(fill no)
			(layer "B.Fab")
		)
		(pad "1" smd custom
			(at 0 -0.4445 270)
			(size 0.1397 0.1397)
			(layers "B.Cu" "B.Mask" "B.Paste")
			(net "P1V8_C")
			(options
				(clearance outline)
				(anchor circle)
			)
			(primitives
				(gr_poly
					(pts
						(arc
							(start -0.1778 0.2794)
							(mid -0.249642 0.249642)
							(end -0.2794 0.1778)
						)
						(arc
							(start -0.2794 -0.1778)
							(mid -0.249642 -0.249642)
							(end -0.1778 -0.2794)
						)
						(arc
							(start 0.1778 -0.2794)
							(mid 0.249642 -0.249642)
							(end 0.2794 -0.1778)
						)
						(arc
							(start 0.2794 0.1778)
							(mid 0.249642 0.249642)
							(end 0.1778 0.2794)
						)
					)
					(width 0)
					(fill yes)
				)
			)
		)
		(pad "2" smd custom
			(at 0 0.4445 270)
			(size 0.1397 0.1397)
			(layers "B.Cu" "B.Mask" "B.Paste")
			(net "SIO_DOUT_1")
			(options
				(clearance outline)
				(anchor circle)
			)
			(primitives
				(gr_poly
					(pts
						(arc
							(start -0.1778 0.2794)
							(mid -0.249642 0.249642)
							(end -0.2794 0.1778)
						)
						(arc
							(start -0.2794 -0.1778)
							(mid -0.249642 -0.249642)
							(end -0.1778 -0.2794)
						)
						(arc
							(start 0.1778 -0.2794)
							(mid 0.249642 -0.249642)
							(end 0.2794 -0.1778)
						)
						(arc
							(start 0.2794 0.1778)
							(mid 0.249642 0.249642)
							(end 0.1778 0.2794)
						)
					)
					(width 0)
					(fill yes)
				)
			)
		)
	)
	(footprint ""
		(layer "B.Cu")
		(at 169.672 -113.284 90)
		(property "Reference" "PC185"
			(at 0 0 90)
			(layer "B.SilkS")
			(hide yes)
			(effects
				(font
					(size 1.27 1.27)
				)
				(justify mirror)
			)
		)
		(property "Value" "SCD1U50V3KX-GP"
			(at 0 -2.8194 90)
			(unlocked yes)
			(layer "B.Fab")
			(hide yes)
			(effects
				(font
					(size 1.016 1.016)
					(thickness 0.1524)
				)
				(justify mirror)
			)
		)
		(property "Device Type" "C603H36"
			(at 0 -4.3434 90)
			(unlocked yes)
			(layer "B.Fab")
			(hide yes)
			(effects
				(font
					(size 1.016 1.016)
					(thickness 0.1524)
				)
				(justify mirror)
			)
		)
		(duplicate_pad_numbers_are_jumpers no)
		(fp_line
			(start -0.508 0)
			(end 0.508 0)
			(stroke
				(width 0.2032)
				(type default)
			)
			(layer "B.SilkS")
		)
		(fp_rect
			(start 0.5842 1.3335)
			(end -0.5842 -1.3335)
			(stroke
				(width 0)
				(type default)
			)
			(fill no)
			(layer "B.CrtYd")
		)
		(fp_rect
			(start 0.5842 1.3335)
			(end -0.5842 -1.3335)
			(stroke
				(width 0)
				(type default)
			)
			(fill no)
			(layer "B.Fab")
		)
		(pad "1" smd custom
			(at 0 -0.762 270)
			(size 0.2159 0.2159)
			(layers "B.Cu" "B.Mask" "B.Paste")
			(net "P0V9_E_VBST")
			(options
				(clearance outline)
				(anchor circle)
			)
			(primitives
				(gr_poly
					(pts
						(arc
							(start -0.3302 0.4318)
							(mid -0.402042 0.402042)
							(end -0.4318 0.3302)
						)
						(arc
							(start -0.4318 -0.3302)
							(mid -0.402042 -0.402042)
							(end -0.3302 -0.4318)
						)
						(arc
							(start 0.3302 -0.4318)
							(mid 0.402042 -0.402042)
							(end 0.4318 -0.3302)
						)
						(arc
							(start 0.4318 0.3302)
							(mid 0.402042 0.402042)
							(end 0.3302 0.4318)
						)
					)
					(width 0)
					(fill yes)
				)
			)
		)
		(pad "2" smd custom
			(at 0 0.762 270)
			(size 0.2159 0.2159)
			(layers "B.Cu" "B.Mask" "B.Paste")
			(net "P0V9_E_VBST_RC")
			(options
				(clearance outline)
				(anchor circle)
			)
			(primitives
				(gr_poly
					(pts
						(arc
							(start -0.3302 0.4318)
							(mid -0.402042 0.402042)
							(end -0.4318 0.3302)
						)
						(arc
							(start -0.4318 -0.3302)
							(mid -0.402042 -0.402042)
							(end -0.3302 -0.4318)
						)
						(arc
							(start 0.3302 -0.4318)
							(mid 0.402042 -0.402042)
							(end 0.4318 -0.3302)
						)
						(arc
							(start 0.4318 0.3302)
							(mid 0.402042 0.402042)
							(end 0.3302 0.4318)
						)
					)
					(width 0)
					(fill yes)
				)
			)
		)
	)
	(footprint ""
		(layer "B.Cu")
		(at 88.41232 -45.6692 -90)
		(property "Reference" "SR605"
			(at 0 0 90)
			(layer "B.SilkS")
			(hide yes)
			(effects
				(font
					(size 1.27 1.27)
				)
				(justify mirror)
			)
		)
		(property "Value" "10KR2F-2-GP"
			(at -0.064008 -3.993896 270)
			(unlocked yes)
			(layer "B.Fab")
			(hide yes)
			(effects
				(font
					(size 1.016 1.016)
					(thickness 0.1524)
				)
				(justify mirror)
			)
		)
		(property "Device Type" "R402H16"
			(at -0.064008 -5.517896 270)
			(unlocked yes)
			(layer "B.Fab")
			(hide yes)
			(effects
				(font
					(size 1.016 1.016)
					(thickness 0.1524)
				)
				(justify mirror)
			)
		)
		(duplicate_pad_numbers_are_jumpers no)
		(fp_line
			(start -0.508 -0.9398)
			(end 0.508 -0.9398)
			(stroke
				(width 0.1524)
				(type default)
			)
			(layer "B.SilkS")
		)
		(fp_line
			(start 0.508 -0.9398)
			(end 0.508 0.9398)
			(stroke
				(width 0.1524)
				(type default)
			)
			(layer "B.SilkS")
		)
		(fp_rect
			(start 0.508 0.9398)
			(end -0.508 -0.9398)
			(stroke
				(width 0)
				(type default)
			)
			(fill no)
			(layer "B.CrtYd")
		)
		(fp_rect
			(start 0.508 0.9398)
			(end -0.508 -0.9398)
			(stroke
				(width 0)
				(type default)
			)
			(fill no)
			(layer "B.Fab")
		)
		(pad "1" smd custom
			(at 0 -0.4445 90)
			(size 0.1397 0.1397)
			(layers "B.Cu" "B.Mask" "B.Paste")
			(net "IOC_SIO_BLINK")
			(options
				(clearance outline)
				(anchor circle)
			)
			(primitives
				(gr_poly
					(pts
						(arc
							(start -0.1778 0.2794)
							(mid -0.249642 0.249642)
							(end -0.2794 0.1778)
						)
						(arc
							(start -0.2794 -0.1778)
							(mid -0.249642 -0.249642)
							(end -0.1778 -0.2794)
						)
						(arc
							(start 0.1778 -0.2794)
							(mid 0.249642 -0.249642)
							(end 0.2794 -0.1778)
						)
						(arc
							(start 0.2794 0.1778)
							(mid 0.249642 0.249642)
							(end 0.1778 0.2794)
						)
					)
					(width 0)
					(fill yes)
				)
			)
		)
		(pad "2" smd custom
			(at 0 0.4445 90)
			(size 0.1397 0.1397)
			(layers "B.Cu" "B.Mask" "B.Paste")
			(net "GND")
			(options
				(clearance outline)
				(anchor circle)
			)
			(primitives
				(gr_poly
					(pts
						(arc
							(start -0.1778 0.2794)
							(mid -0.249642 0.249642)
							(end -0.2794 0.1778)
						)
						(arc
							(start -0.2794 -0.1778)
							(mid -0.249642 -0.249642)
							(end -0.1778 -0.2794)
						)
						(arc
							(start 0.1778 -0.2794)
							(mid 0.249642 -0.249642)
							(end 0.2794 -0.1778)
						)
						(arc
							(start 0.2794 0.1778)
							(mid 0.249642 0.249642)
							(end 0.1778 0.2794)
						)
					)
					(width 0)
					(fill yes)
				)
			)
		)
	)
	(footprint ""
		(layer "B.Cu")
		(at 130.283966 -38.354 -90)
		(property "Reference" "SR651"
			(at 0 0 90)
			(layer "B.SilkS")
			(hide yes)
			(effects
				(font
					(size 1.27 1.27)
				)
				(justify mirror)
			)
		)
		(property "Value" "150R2F-1-GP"
			(at -0.064008 -3.993896 270)
			(unlocked yes)
			(layer "B.Fab")
			(hide yes)
			(effects
				(font
					(size 1.016 1.016)
					(thickness 0.1524)
				)
				(justify mirror)
			)
		)
		(property "Device Type" "R402H16"
			(at -0.064008 -5.517896 270)
			(unlocked yes)
			(layer "B.Fab")
			(hide yes)
			(effects
				(font
					(size 1.016 1.016)
					(thickness 0.1524)
				)
				(justify mirror)
			)
		)
		(duplicate_pad_numbers_are_jumpers no)
		(fp_line
			(start -0.508 -0.9398)
			(end 0.508 -0.9398)
			(stroke
				(width 0.1524)
				(type default)
			)
			(layer "B.SilkS")
		)
		(fp_line
			(start 0.508 -0.9398)
			(end 0.508 0.9398)
			(stroke
				(width 0.1524)
				(type default)
			)
			(layer "B.SilkS")
		)
		(fp_rect
			(start 0.508 0.9398)
			(end -0.508 -0.9398)
			(stroke
				(width 0)
				(type default)
			)
			(fill no)
			(layer "B.CrtYd")
		)
		(fp_rect
			(start 0.508 0.9398)
			(end -0.508 -0.9398)
			(stroke
				(width 0)
				(type default)
			)
			(fill no)
			(layer "B.Fab")
		)
		(pad "1" smd custom
			(at 0 -0.4445 90)
			(size 0.1397 0.1397)
			(layers "B.Cu" "B.Mask" "B.Paste")
			(net "P3V3")
			(options
				(clearance outline)
				(anchor circle)
			)
			(primitives
				(gr_poly
					(pts
						(arc
							(start -0.1778 0.2794)
							(mid -0.249642 0.249642)
							(end -0.2794 0.1778)
						)
						(arc
							(start -0.2794 -0.1778)
							(mid -0.249642 -0.249642)
							(end -0.1778 -0.2794)
						)
						(arc
							(start 0.1778 -0.2794)
							(mid 0.249642 -0.249642)
							(end 0.2794 -0.1778)
						)
						(arc
							(start 0.2794 0.1778)
							(mid 0.249642 0.249642)
							(end 0.1778 0.2794)
						)
					)
					(width 0)
					(fill yes)
				)
			)
		)
		(pad "2" smd custom
			(at 0 0.4445 90)
			(size 0.1397 0.1397)
			(layers "B.Cu" "B.Mask" "B.Paste")
			(net "SYS_HB_LED_R")
			(options
				(clearance outline)
				(anchor circle)
			)
			(primitives
				(gr_poly
					(pts
						(arc
							(start -0.1778 0.2794)
							(mid -0.249642 0.249642)
							(end -0.2794 0.1778)
						)
						(arc
							(start -0.2794 -0.1778)
							(mid -0.249642 -0.249642)
							(end -0.1778 -0.2794)
						)
						(arc
							(start 0.1778 -0.2794)
							(mid 0.249642 -0.249642)
							(end 0.2794 -0.1778)
						)
						(arc
							(start 0.2794 0.1778)
							(mid 0.249642 0.249642)
							(end 0.1778 0.2794)
						)
					)
					(width 0)
					(fill yes)
				)
			)
		)
	)
	(footprint ""
		(layer "B.Cu")
		(at 113.044986 -32.46882)
		(property "Reference" "STP93"
			(at 0 0 0)
			(layer "B.SilkS")
			(hide yes)
			(effects
				(font
					(size 1.27 1.27)
				)
				(justify mirror)
			)
		)
		(property "Value" "TPAD28"
			(at -0.0127 -1.8034 0)
			(unlocked yes)
			(layer "B.Fab")
			(hide yes)
			(effects
				(font
					(size 1.016 1.016)
					(thickness 0.1524)
				)
				(justify mirror)
			)
		)
		(property "Device Type" "TPAD28"
			(at -0.0127 -3.3274 0)
			(unlocked yes)
			(layer "B.Fab")
			(hide yes)
			(effects
				(font
					(size 1.016 1.016)
					(thickness 0.1524)
				)
				(justify mirror)
			)
		)
		(duplicate_pad_numbers_are_jumpers no)
		(fp_poly
			(pts
				(arc
					(start 0.3556 0)
					(mid -0.3556 0)
					(end 0.3556 0)
				)
			)
			(stroke
				(width 0)
				(type default)
			)
			(fill no)
			(layer "B.CrtYd")
		)
		(fp_poly
			(pts
				(arc
					(start 0.6096 0)
					(mid -0.6096 0)
					(end 0.6096 0)
				)
			)
			(stroke
				(width 0)
				(type default)
			)
			(fill no)
			(layer "B.Fab")
		)
		(pad "1" smd circle
			(at 0 0 180)
			(size 0.7112 0.7112)
			(layers "B.Cu" "B.Mask" "B.Paste")
			(net "IOC_GPIO_9")
		)
	)
	(footprint ""
		(layer "B.Cu")
		(at 114.281966 -46.863 -90)
		(property "Reference" "SR622"
			(at 0 0 90)
			(layer "B.SilkS")
			(hide yes)
			(effects
				(font
					(size 1.27 1.27)
				)
				(justify mirror)
			)
		)
		(property "Value" "2K2R2F-GP"
			(at -0.064008 -3.993896 270)
			(unlocked yes)
			(layer "B.Fab")
			(hide yes)
			(effects
				(font
					(size 1.016 1.016)
					(thickness 0.1524)
				)
				(justify mirror)
			)
		)
		(property "Device Type" "R402H16"
			(at -0.064008 -5.517896 270)
			(unlocked yes)
			(layer "B.Fab")
			(hide yes)
			(effects
				(font
					(size 1.016 1.016)
					(thickness 0.1524)
				)
				(justify mirror)
			)
		)
		(duplicate_pad_numbers_are_jumpers no)
		(fp_line
			(start -0.508 -0.9398)
			(end 0.508 -0.9398)
			(stroke
				(width 0.1524)
				(type default)
			)
			(layer "B.SilkS")
		)
		(fp_line
			(start 0.508 -0.9398)
			(end 0.508 0.9398)
			(stroke
				(width 0.1524)
				(type default)
			)
			(layer "B.SilkS")
		)
		(fp_rect
			(start 0.508 0.9398)
			(end -0.508 -0.9398)
			(stroke
				(width 0)
				(type default)
			)
			(fill no)
			(layer "B.CrtYd")
		)
		(fp_rect
			(start 0.508 0.9398)
			(end -0.508 -0.9398)
			(stroke
				(width 0)
				(type default)
			)
			(fill no)
			(layer "B.Fab")
		)
		(pad "1" smd custom
			(at 0 -0.4445 90)
			(size 0.1397 0.1397)
			(layers "B.Cu" "B.Mask" "B.Paste")
			(net "P1V8_C")
			(options
				(clearance outline)
				(anchor circle)
			)
			(primitives
				(gr_poly
					(pts
						(arc
							(start -0.1778 0.2794)
							(mid -0.249642 0.249642)
							(end -0.2794 0.1778)
						)
						(arc
							(start -0.2794 -0.1778)
							(mid -0.249642 -0.249642)
							(end -0.1778 -0.2794)
						)
						(arc
							(start 0.1778 -0.2794)
							(mid 0.249642 -0.249642)
							(end 0.2794 -0.1778)
						)
						(arc
							(start 0.2794 0.1778)
							(mid 0.249642 0.249642)
							(end 0.1778 0.2794)
						)
					)
					(width 0)
					(fill yes)
				)
			)
		)
		(pad "2" smd custom
			(at 0 0.4445 90)
			(size 0.1397 0.1397)
			(layers "B.Cu" "B.Mask" "B.Paste")
			(net "IOC_SCL_3")
			(options
				(clearance outline)
				(anchor circle)
			)
			(primitives
				(gr_poly
					(pts
						(arc
							(start -0.1778 0.2794)
							(mid -0.249642 0.249642)
							(end -0.2794 0.1778)
						)
						(arc
							(start -0.2794 -0.1778)
							(mid -0.249642 -0.249642)
							(end -0.1778 -0.2794)
						)
						(arc
							(start 0.1778 -0.2794)
							(mid 0.249642 -0.249642)
							(end 0.2794 -0.1778)
						)
						(arc
							(start 0.2794 0.1778)
							(mid 0.249642 0.249642)
							(end 0.1778 0.2794)
						)
					)
					(width 0)
					(fill yes)
				)
			)
		)
	)
	(footprint ""
		(layer "B.Cu")
		(at 119.0244 -34.7218)
		(property "Reference" "STP142"
			(at 0 0 0)
			(layer "B.SilkS")
			(hide yes)
			(effects
				(font
					(size 1.27 1.27)
				)
				(justify mirror)
			)
		)
		(property "Value" "TPAD28"
			(at -0.0127 -1.8034 0)
			(unlocked yes)
			(layer "B.Fab")
			(hide yes)
			(effects
				(font
					(size 1.016 1.016)
					(thickness 0.1524)
				)
				(justify mirror)
			)
		)
		(property "Device Type" "TPAD28"
			(at -0.0127 -3.3274 0)
			(unlocked yes)
			(layer "B.Fab")
			(hide yes)
			(effects
				(font
					(size 1.016 1.016)
					(thickness 0.1524)
				)
				(justify mirror)
			)
		)
		(duplicate_pad_numbers_are_jumpers no)
		(fp_poly
			(pts
				(arc
					(start 0.3556 0)
					(mid -0.3556 0)
					(end 0.3556 0)
				)
			)
			(stroke
				(width 0)
				(type default)
			)
			(fill no)
			(layer "B.CrtYd")
		)
		(fp_poly
			(pts
				(arc
					(start 0.6096 0)
					(mid -0.6096 0)
					(end 0.6096 0)
				)
			)
			(stroke
				(width 0)
				(type default)
			)
			(fill no)
			(layer "B.Fab")
		)
		(pad "1" smd circle
			(at 0 0 180)
			(size 0.7112 0.7112)
			(layers "B.Cu" "B.Mask" "B.Paste")
			(net "IOC_GPIO_23")
		)
	)
	(footprint ""
		(layer "B.Cu")
		(at 98.806 -48.26 -90)
		(property "Reference" "SC1044"
			(at 0 0 90)
			(layer "B.SilkS")
			(hide yes)
			(effects
				(font
					(size 1.27 1.27)
				)
				(justify mirror)
			)
		)
		(property "Value" "SCD1U16V2KX-3GP"
			(at -1.1811 -2.7051 270)
			(unlocked yes)
			(layer "B.Fab")
			(hide yes)
			(effects
				(font
					(size 1.016 1.016)
					(thickness 0.1524)
				)
				(justify mirror)
			)
		)
		(property "Device Type" "C402H22"
			(at -1.1811 -4.2291 270)
			(unlocked yes)
			(layer "B.Fab")
			(hide yes)
			(effects
				(font
					(size 1.016 1.016)
					(thickness 0.1524)
				)
				(justify mirror)
			)
		)
		(duplicate_pad_numbers_are_jumpers no)
		(fp_rect
			(start 0.4318 0.9525)
			(end -0.4318 -0.9525)
			(stroke
				(width 0)
				(type default)
			)
			(fill no)
			(layer "B.CrtYd")
		)
		(fp_rect
			(start 0.4318 0.9525)
			(end -0.4318 -0.9525)
			(stroke
				(width 0)
				(type default)
			)
			(fill no)
			(layer "B.Fab")
		)
		(pad "1" smd custom
			(at 0 -0.4445 90)
			(size 0.1524 0.1524)
			(layers "B.Cu" "B.Mask" "B.Paste")
			(net "P0V955_C")
			(options
				(clearance outline)
				(anchor circle)
			)
			(primitives
				(gr_poly
					(pts
						(arc
							(start 0.3048 0.2032)
							(mid 0.275042 0.275042)
							(end 0.2032 0.3048)
						)
						(arc
							(start -0.2032 0.3048)
							(mid -0.275042 0.275042)
							(end -0.3048 0.2032)
						)
						(arc
							(start -0.3048 -0.2032)
							(mid -0.275042 -0.275042)
							(end -0.2032 -0.3048)
						)
						(arc
							(start 0.2032 -0.3048)
							(mid 0.275042 -0.275042)
							(end 0.3048 -0.2032)
						)
					)
					(width 0)
					(fill yes)
				)
			)
		)
		(pad "2" smd custom
			(at 0 0.4445 90)
			(size 0.1524 0.1524)
			(layers "B.Cu" "B.Mask" "B.Paste")
			(net "GND")
			(options
				(clearance outline)
				(anchor circle)
			)
			(primitives
				(gr_poly
					(pts
						(arc
							(start 0.3048 0.2032)
							(mid 0.275042 0.275042)
							(end 0.2032 0.3048)
						)
						(arc
							(start -0.2032 0.3048)
							(mid -0.275042 0.275042)
							(end -0.3048 0.2032)
						)
						(arc
							(start -0.3048 -0.2032)
							(mid -0.275042 -0.275042)
							(end -0.2032 -0.3048)
						)
						(arc
							(start 0.2032 -0.3048)
							(mid 0.275042 -0.275042)
							(end 0.3048 -0.2032)
						)
					)
					(width 0)
					(fill yes)
				)
			)
		)
	)
	(footprint ""
		(layer "B.Cu")
		(at 114.281966 -44.577 90)
		(property "Reference" "SR584"
			(at 0 0 90)
			(layer "B.SilkS")
			(hide yes)
			(effects
				(font
					(size 1.27 1.27)
				)
				(justify mirror)
			)
		)
		(property "Value" "10KR2F-2-GP"
			(at -0.064008 -3.993896 90)
			(unlocked yes)
			(layer "B.Fab")
			(hide yes)
			(effects
				(font
					(size 1.016 1.016)
					(thickness 0.1524)
				)
				(justify mirror)
			)
		)
		(property "Device Type" "R402H16"
			(at -0.064008 -5.517896 90)
			(unlocked yes)
			(layer "B.Fab")
			(hide yes)
			(effects
				(font
					(size 1.016 1.016)
					(thickness 0.1524)
				)
				(justify mirror)
			)
		)
		(duplicate_pad_numbers_are_jumpers no)
		(fp_line
			(start 0.508 -0.9398)
			(end 0.508 0.9398)
			(stroke
				(width 0.1524)
				(type default)
			)
			(layer "B.SilkS")
		)
		(fp_line
			(start -0.508 -0.9398)
			(end 0.508 -0.9398)
			(stroke
				(width 0.1524)
				(type default)
			)
			(layer "B.SilkS")
		)
		(fp_rect
			(start 0.508 0.9398)
			(end -0.508 -0.9398)
			(stroke
				(width 0)
				(type default)
			)
			(fill no)
			(layer "B.CrtYd")
		)
		(fp_rect
			(start 0.508 0.9398)
			(end -0.508 -0.9398)
			(stroke
				(width 0)
				(type default)
			)
			(fill no)
			(layer "B.Fab")
		)
		(pad "1" smd custom
			(at 0 -0.4445 270)
			(size 0.1397 0.1397)
			(layers "B.Cu" "B.Mask" "B.Paste")
			(net "IOC_CLK_SEL1")
			(options
				(clearance outline)
				(anchor circle)
			)
			(primitives
				(gr_poly
					(pts
						(arc
							(start -0.1778 0.2794)
							(mid -0.249642 0.249642)
							(end -0.2794 0.1778)
						)
						(arc
							(start -0.2794 -0.1778)
							(mid -0.249642 -0.249642)
							(end -0.1778 -0.2794)
						)
						(arc
							(start 0.1778 -0.2794)
							(mid 0.249642 -0.249642)
							(end 0.2794 -0.1778)
						)
						(arc
							(start 0.2794 0.1778)
							(mid 0.249642 0.249642)
							(end 0.1778 0.2794)
						)
					)
					(width 0)
					(fill yes)
				)
			)
		)
		(pad "2" smd custom
			(at 0 0.4445 270)
			(size 0.1397 0.1397)
			(layers "B.Cu" "B.Mask" "B.Paste")
			(net "P1V8_C")
			(options
				(clearance outline)
				(anchor circle)
			)
			(primitives
				(gr_poly
					(pts
						(arc
							(start -0.1778 0.2794)
							(mid -0.249642 0.249642)
							(end -0.2794 0.1778)
						)
						(arc
							(start -0.2794 -0.1778)
							(mid -0.249642 -0.249642)
							(end -0.1778 -0.2794)
						)
						(arc
							(start 0.1778 -0.2794)
							(mid 0.249642 -0.249642)
							(end 0.2794 -0.1778)
						)
						(arc
							(start 0.2794 0.1778)
							(mid 0.249642 0.249642)
							(end 0.1778 0.2794)
						)
					)
					(width 0)
					(fill yes)
				)
			)
		)
	)
	(footprint ""
		(layer "B.Cu")
		(at 109.86897 -84.709)
		(property "Reference" "STP101"
			(at 0 0 0)
			(layer "B.SilkS")
			(hide yes)
			(effects
				(font
					(size 1.27 1.27)
				)
				(justify mirror)
			)
		)
		(property "Value" "TPAD28"
			(at -0.0127 -1.8034 0)
			(unlocked yes)
			(layer "B.Fab")
			(hide yes)
			(effects
				(font
					(size 1.016 1.016)
					(thickness 0.1524)
				)
				(justify mirror)
			)
		)
		(property "Device Type" "TPAD28"
			(at -0.0127 -3.3274 0)
			(unlocked yes)
			(layer "B.Fab")
			(hide yes)
			(effects
				(font
					(size 1.016 1.016)
					(thickness 0.1524)
				)
				(justify mirror)
			)
		)
		(duplicate_pad_numbers_are_jumpers no)
		(fp_poly
			(pts
				(arc
					(start 0.3556 0)
					(mid -0.3556 0)
					(end 0.3556 0)
				)
			)
			(stroke
				(width 0)
				(type default)
			)
			(fill no)
			(layer "B.CrtYd")
		)
		(fp_poly
			(pts
				(arc
					(start 0.6096 0)
					(mid -0.6096 0)
					(end 0.6096 0)
				)
			)
			(stroke
				(width 0)
				(type default)
			)
			(fill no)
			(layer "B.Fab")
		)
		(pad "1" smd circle
			(at 0 0 180)
			(size 0.7112 0.7112)
			(layers "B.Cu" "B.Mask" "B.Paste")
			(net "TESTIBIAS")
		)
	)
	(footprint ""
		(layer "B.Cu")
		(at 172.339 -103.759)
		(property "Reference" "PR155"
			(at 0 0 0)
			(layer "B.SilkS")
			(hide yes)
			(effects
				(font
					(size 1.27 1.27)
				)
				(justify mirror)
			)
		)
		(property "Value" "2K21R2F-GP"
			(at -0.064008 -3.993896 0)
			(unlocked yes)
			(layer "B.Fab")
			(hide yes)
			(effects
				(font
					(size 1.016 1.016)
					(thickness 0.1524)
				)
				(justify mirror)
			)
		)
		(property "Device Type" "R402H16"
			(at -0.064008 -5.517896 0)
			(unlocked yes)
			(layer "B.Fab")
			(hide yes)
			(effects
				(font
					(size 1.016 1.016)
					(thickness 0.1524)
				)
				(justify mirror)
			)
		)
		(duplicate_pad_numbers_are_jumpers no)
		(fp_line
			(start -0.508 -0.9398)
			(end 0.508 -0.9398)
			(stroke
				(width 0.1524)
				(type default)
			)
			(layer "B.SilkS")
		)
		(fp_line
			(start 0.508 -0.9398)
			(end 0.508 0.9398)
			(stroke
				(width 0.1524)
				(type default)
			)
			(layer "B.SilkS")
		)
		(fp_rect
			(start 0.508 0.9398)
			(end -0.508 -0.9398)
			(stroke
				(width 0)
				(type default)
			)
			(fill no)
			(layer "B.CrtYd")
		)
		(fp_rect
			(start 0.508 0.9398)
			(end -0.508 -0.9398)
			(stroke
				(width 0)
				(type default)
			)
			(fill no)
			(layer "B.Fab")
		)
		(pad "1" smd custom
			(at 0 -0.4445 180)
			(size 0.1397 0.1397)
			(layers "B.Cu" "B.Mask" "B.Paste")
			(net "P0V9_E_LX")
			(options
				(clearance outline)
				(anchor circle)
			)
			(primitives
				(gr_poly
					(pts
						(arc
							(start -0.1778 0.2794)
							(mid -0.249642 0.249642)
							(end -0.2794 0.1778)
						)
						(arc
							(start -0.2794 -0.1778)
							(mid -0.249642 -0.249642)
							(end -0.1778 -0.2794)
						)
						(arc
							(start 0.1778 -0.2794)
							(mid 0.249642 -0.249642)
							(end 0.2794 -0.1778)
						)
						(arc
							(start 0.2794 0.1778)
							(mid 0.249642 0.249642)
							(end 0.1778 0.2794)
						)
					)
					(width 0)
					(fill yes)
				)
			)
		)
		(pad "2" smd custom
			(at 0 0.4445 180)
			(size 0.1397 0.1397)
			(layers "B.Cu" "B.Mask" "B.Paste")
			(net "P0V9_E_SW_R")
			(options
				(clearance outline)
				(anchor circle)
			)
			(primitives
				(gr_poly
					(pts
						(arc
							(start -0.1778 0.2794)
							(mid -0.249642 0.249642)
							(end -0.2794 0.1778)
						)
						(arc
							(start -0.2794 -0.1778)
							(mid -0.249642 -0.249642)
							(end -0.1778 -0.2794)
						)
						(arc
							(start 0.1778 -0.2794)
							(mid 0.249642 -0.249642)
							(end 0.2794 -0.1778)
						)
						(arc
							(start 0.2794 0.1778)
							(mid 0.249642 0.249642)
							(end 0.1778 0.2794)
						)
					)
					(width 0)
					(fill yes)
				)
			)
		)
	)
	(footprint ""
		(layer "B.Cu")
		(at 108.020612 -211.582 -90)
		(property "Reference" "SR907"
			(at 0 0 90)
			(layer "B.SilkS")
			(hide yes)
			(effects
				(font
					(size 1.27 1.27)
				)
				(justify mirror)
			)
		)
		(property "Value" "4K7R2F-GP"
			(at -0.064008 -3.993896 270)
			(unlocked yes)
			(layer "B.Fab")
			(hide yes)
			(effects
				(font
					(size 1.016 1.016)
					(thickness 0.1524)
				)
				(justify mirror)
			)
		)
		(property "Device Type" "R402H16"
			(at -0.064008 -5.517896 270)
			(unlocked yes)
			(layer "B.Fab")
			(hide yes)
			(effects
				(font
					(size 1.016 1.016)
					(thickness 0.1524)
				)
				(justify mirror)
			)
		)
		(duplicate_pad_numbers_are_jumpers no)
		(fp_line
			(start -0.508 -0.9398)
			(end 0.508 -0.9398)
			(stroke
				(width 0.1524)
				(type default)
			)
			(layer "B.SilkS")
		)
		(fp_line
			(start 0.508 -0.9398)
			(end 0.508 0.9398)
			(stroke
				(width 0.1524)
				(type default)
			)
			(layer "B.SilkS")
		)
		(fp_rect
			(start 0.508 0.9398)
			(end -0.508 -0.9398)
			(stroke
				(width 0)
				(type default)
			)
			(fill no)
			(layer "B.CrtYd")
		)
		(fp_rect
			(start 0.508 0.9398)
			(end -0.508 -0.9398)
			(stroke
				(width 0)
				(type default)
			)
			(fill no)
			(layer "B.Fab")
		)
		(pad "1" smd custom
			(at 0 -0.4445 90)
			(size 0.1397 0.1397)
			(layers "B.Cu" "B.Mask" "B.Paste")
			(net "REDV_D2_B")
			(options
				(clearance outline)
				(anchor circle)
			)
			(primitives
				(gr_poly
					(pts
						(arc
							(start -0.1778 0.2794)
							(mid -0.249642 0.249642)
							(end -0.2794 0.1778)
						)
						(arc
							(start -0.2794 -0.1778)
							(mid -0.249642 -0.249642)
							(end -0.1778 -0.2794)
						)
						(arc
							(start 0.1778 -0.2794)
							(mid 0.249642 -0.249642)
							(end 0.2794 -0.1778)
						)
						(arc
							(start 0.2794 0.1778)
							(mid 0.249642 0.249642)
							(end 0.1778 0.2794)
						)
					)
					(width 0)
					(fill yes)
				)
			)
		)
		(pad "2" smd custom
			(at 0 0.4445 90)
			(size 0.1397 0.1397)
			(layers "B.Cu" "B.Mask" "B.Paste")
			(net "GND")
			(options
				(clearance outline)
				(anchor circle)
			)
			(primitives
				(gr_poly
					(pts
						(arc
							(start -0.1778 0.2794)
							(mid -0.249642 0.249642)
							(end -0.2794 0.1778)
						)
						(arc
							(start -0.2794 -0.1778)
							(mid -0.249642 -0.249642)
							(end -0.1778 -0.2794)
						)
						(arc
							(start 0.1778 -0.2794)
							(mid 0.249642 -0.249642)
							(end 0.2794 -0.1778)
						)
						(arc
							(start 0.2794 0.1778)
							(mid 0.249642 0.249642)
							(end 0.1778 0.2794)
						)
					)
					(width 0)
					(fill yes)
				)
			)
		)
	)
	(footprint ""
		(layer "B.Cu")
		(at 290.4744 -173.9392 90)
		(property "Reference" "C209"
			(at 0 0 90)
			(layer "B.SilkS")
			(hide yes)
			(effects
				(font
					(size 1.27 1.27)
				)
				(justify mirror)
			)
		)
		(property "Value" "SC220P50V2KX-3GP"
			(at -1.1811 -2.7051 90)
			(unlocked yes)
			(layer "B.Fab")
			(hide yes)
			(effects
				(font
					(size 1.016 1.016)
					(thickness 0.1524)
				)
				(justify mirror)
			)
		)
		(property "Device Type" "C402H22"
			(at -1.1811 -4.2291 90)
			(unlocked yes)
			(layer "B.Fab")
			(hide yes)
			(effects
				(font
					(size 1.016 1.016)
					(thickness 0.1524)
				)
				(justify mirror)
			)
		)
		(duplicate_pad_numbers_are_jumpers no)
		(fp_rect
			(start 0.4318 0.9525)
			(end -0.4318 -0.9525)
			(stroke
				(width 0)
				(type default)
			)
			(fill no)
			(layer "B.CrtYd")
		)
		(fp_rect
			(start 0.4318 0.9525)
			(end -0.4318 -0.9525)
			(stroke
				(width 0)
				(type default)
			)
			(fill no)
			(layer "B.Fab")
		)
		(pad "1" smd custom
			(at 0 -0.4445 270)
			(size 0.1524 0.1524)
			(layers "B.Cu" "B.Mask" "B.Paste")
			(net "P3V3_STBY")
			(options
				(clearance outline)
				(anchor circle)
			)
			(primitives
				(gr_poly
					(pts
						(arc
							(start 0.3048 0.2032)
							(mid 0.275042 0.275042)
							(end 0.2032 0.3048)
						)
						(arc
							(start -0.2032 0.3048)
							(mid -0.275042 0.275042)
							(end -0.3048 0.2032)
						)
						(arc
							(start -0.3048 -0.2032)
							(mid -0.275042 -0.275042)
							(end -0.2032 -0.3048)
						)
						(arc
							(start 0.2032 -0.3048)
							(mid 0.275042 -0.275042)
							(end 0.3048 -0.2032)
						)
					)
					(width 0)
					(fill yes)
				)
			)
		)
		(pad "2" smd custom
			(at 0 0.4445 270)
			(size 0.1524 0.1524)
			(layers "B.Cu" "B.Mask" "B.Paste")
			(net "GND")
			(options
				(clearance outline)
				(anchor circle)
			)
			(primitives
				(gr_poly
					(pts
						(arc
							(start 0.3048 0.2032)
							(mid 0.275042 0.275042)
							(end 0.2032 0.3048)
						)
						(arc
							(start -0.2032 0.3048)
							(mid -0.275042 0.275042)
							(end -0.3048 0.2032)
						)
						(arc
							(start -0.3048 -0.2032)
							(mid -0.275042 -0.275042)
							(end -0.2032 -0.3048)
						)
						(arc
							(start 0.2032 -0.3048)
							(mid 0.275042 -0.275042)
							(end 0.3048 -0.2032)
						)
					)
					(width 0)
					(fill yes)
				)
			)
		)
	)
	(footprint ""
		(layer "B.Cu")
		(at 107.169966 -43.307 90)
		(property "Reference" "SC1026"
			(at 0 0 90)
			(layer "B.SilkS")
			(hide yes)
			(effects
				(font
					(size 1.27 1.27)
				)
				(justify mirror)
			)
		)
		(property "Value" "SC1U10V2KX-4-GP"
			(at -1.1811 -2.7051 90)
			(unlocked yes)
			(layer "B.Fab")
			(hide yes)
			(effects
				(font
					(size 1.016 1.016)
					(thickness 0.1524)
				)
				(justify mirror)
			)
		)
		(property "Device Type" "C402H22"
			(at -1.1811 -4.2291 90)
			(unlocked yes)
			(layer "B.Fab")
			(hide yes)
			(effects
				(font
					(size 1.016 1.016)
					(thickness 0.1524)
				)
				(justify mirror)
			)
		)
		(duplicate_pad_numbers_are_jumpers no)
		(fp_rect
			(start 0.4318 0.9525)
			(end -0.4318 -0.9525)
			(stroke
				(width 0)
				(type default)
			)
			(fill no)
			(layer "B.CrtYd")
		)
		(fp_rect
			(start 0.4318 0.9525)
			(end -0.4318 -0.9525)
			(stroke
				(width 0)
				(type default)
			)
			(fill no)
			(layer "B.Fab")
		)
		(pad "1" smd custom
			(at 0 -0.4445 270)
			(size 0.1524 0.1524)
			(layers "B.Cu" "B.Mask" "B.Paste")
			(net "P0V955_C")
			(options
				(clearance outline)
				(anchor circle)
			)
			(primitives
				(gr_poly
					(pts
						(arc
							(start 0.3048 0.2032)
							(mid 0.275042 0.275042)
							(end 0.2032 0.3048)
						)
						(arc
							(start -0.2032 0.3048)
							(mid -0.275042 0.275042)
							(end -0.3048 0.2032)
						)
						(arc
							(start -0.3048 -0.2032)
							(mid -0.275042 -0.275042)
							(end -0.2032 -0.3048)
						)
						(arc
							(start 0.2032 -0.3048)
							(mid 0.275042 -0.275042)
							(end 0.3048 -0.2032)
						)
					)
					(width 0)
					(fill yes)
				)
			)
		)
		(pad "2" smd custom
			(at 0 0.4445 270)
			(size 0.1524 0.1524)
			(layers "B.Cu" "B.Mask" "B.Paste")
			(net "GND")
			(options
				(clearance outline)
				(anchor circle)
			)
			(primitives
				(gr_poly
					(pts
						(arc
							(start 0.3048 0.2032)
							(mid 0.275042 0.275042)
							(end 0.2032 0.3048)
						)
						(arc
							(start -0.2032 0.3048)
							(mid -0.275042 0.275042)
							(end -0.3048 0.2032)
						)
						(arc
							(start -0.3048 -0.2032)
							(mid -0.275042 -0.275042)
							(end -0.2032 -0.3048)
						)
						(arc
							(start 0.2032 -0.3048)
							(mid 0.275042 -0.275042)
							(end 0.3048 -0.2032)
						)
					)
					(width 0)
					(fill yes)
				)
			)
		)
	)
	(footprint ""
		(layer "B.Cu")
		(at 29.414216 -232.33888)
		(property "Reference" "R506"
			(at 0 0 0)
			(layer "B.SilkS")
			(hide yes)
			(effects
				(font
					(size 1.27 1.27)
				)
				(justify mirror)
			)
		)
		(property "Value" "0R2J-2-GP"
			(at -0.064008 -3.993896 0)
			(unlocked yes)
			(layer "B.Fab")
			(hide yes)
			(effects
				(font
					(size 1.016 1.016)
					(thickness 0.1524)
				)
				(justify mirror)
			)
		)
		(property "Device Type" "R402H16"
			(at -0.064008 -5.517896 0)
			(unlocked yes)
			(layer "B.Fab")
			(hide yes)
			(effects
				(font
					(size 1.016 1.016)
					(thickness 0.1524)
				)
				(justify mirror)
			)
		)
		(duplicate_pad_numbers_are_jumpers no)
		(fp_line
			(start -0.508 -0.9398)
			(end 0.508 -0.9398)
			(stroke
				(width 0.1524)
				(type default)
			)
			(layer "B.SilkS")
		)
		(fp_line
			(start 0.508 -0.9398)
			(end 0.508 0.9398)
			(stroke
				(width 0.1524)
				(type default)
			)
			(layer "B.SilkS")
		)
		(fp_rect
			(start 0.508 0.9398)
			(end -0.508 -0.9398)
			(stroke
				(width 0)
				(type default)
			)
			(fill no)
			(layer "B.CrtYd")
		)
		(fp_rect
			(start 0.508 0.9398)
			(end -0.508 -0.9398)
			(stroke
				(width 0)
				(type default)
			)
			(fill no)
			(layer "B.Fab")
		)
		(pad "1" smd custom
			(at 0 -0.4445 180)
			(size 0.1397 0.1397)
			(layers "B.Cu" "B.Mask" "B.Paste")
			(net "SAS_HDD_PWR4_PCIE")
			(options
				(clearance outline)
				(anchor circle)
			)
			(primitives
				(gr_poly
					(pts
						(arc
							(start -0.1778 0.2794)
							(mid -0.249642 0.249642)
							(end -0.2794 0.1778)
						)
						(arc
							(start -0.2794 -0.1778)
							(mid -0.249642 -0.249642)
							(end -0.1778 -0.2794)
						)
						(arc
							(start 0.1778 -0.2794)
							(mid 0.249642 -0.249642)
							(end 0.2794 -0.1778)
						)
						(arc
							(start 0.2794 0.1778)
							(mid 0.249642 0.249642)
							(end 0.1778 0.2794)
						)
					)
					(width 0)
					(fill yes)
				)
			)
		)
		(pad "2" smd custom
			(at 0 0.4445 180)
			(size 0.1397 0.1397)
			(layers "B.Cu" "B.Mask" "B.Paste")
			(net "SAS_HDD_PWR4")
			(options
				(clearance outline)
				(anchor circle)
			)
			(primitives
				(gr_poly
					(pts
						(arc
							(start -0.1778 0.2794)
							(mid -0.249642 0.249642)
							(end -0.2794 0.1778)
						)
						(arc
							(start -0.2794 -0.1778)
							(mid -0.249642 -0.249642)
							(end -0.1778 -0.2794)
						)
						(arc
							(start 0.1778 -0.2794)
							(mid 0.249642 -0.249642)
							(end 0.2794 -0.1778)
						)
						(arc
							(start 0.2794 0.1778)
							(mid 0.249642 0.249642)
							(end 0.1778 0.2794)
						)
					)
					(width 0)
					(fill yes)
				)
			)
		)
	)
	(footprint ""
		(layer "B.Cu")
		(at 108.458 -79.883 -90)
		(property "Reference" "SR773"
			(at 0 0 90)
			(layer "B.SilkS")
			(hide yes)
			(effects
				(font
					(size 1.27 1.27)
				)
				(justify mirror)
			)
		)
		(property "Value" "4K75R2F-1-GP"
			(at -0.064008 -3.993896 270)
			(unlocked yes)
			(layer "B.Fab")
			(hide yes)
			(effects
				(font
					(size 1.016 1.016)
					(thickness 0.1524)
				)
				(justify mirror)
			)
		)
		(property "Device Type" "R402H16"
			(at -0.064008 -5.517896 270)
			(unlocked yes)
			(layer "B.Fab")
			(hide yes)
			(effects
				(font
					(size 1.016 1.016)
					(thickness 0.1524)
				)
				(justify mirror)
			)
		)
		(duplicate_pad_numbers_are_jumpers no)
		(fp_line
			(start -0.508 -0.9398)
			(end 0.508 -0.9398)
			(stroke
				(width 0.1524)
				(type default)
			)
			(layer "B.SilkS")
		)
		(fp_line
			(start 0.508 -0.9398)
			(end 0.508 0.9398)
			(stroke
				(width 0.1524)
				(type default)
			)
			(layer "B.SilkS")
		)
		(fp_rect
			(start 0.508 0.9398)
			(end -0.508 -0.9398)
			(stroke
				(width 0)
				(type default)
			)
			(fill no)
			(layer "B.CrtYd")
		)
		(fp_rect
			(start 0.508 0.9398)
			(end -0.508 -0.9398)
			(stroke
				(width 0)
				(type default)
			)
			(fill no)
			(layer "B.Fab")
		)
		(pad "1" smd custom
			(at 0 -0.4445 90)
			(size 0.1397 0.1397)
			(layers "B.Cu" "B.Mask" "B.Paste")
			(net "P1V8_E")
			(options
				(clearance outline)
				(anchor circle)
			)
			(primitives
				(gr_poly
					(pts
						(arc
							(start -0.1778 0.2794)
							(mid -0.249642 0.249642)
							(end -0.2794 0.1778)
						)
						(arc
							(start -0.2794 -0.1778)
							(mid -0.249642 -0.249642)
							(end -0.1778 -0.2794)
						)
						(arc
							(start 0.1778 -0.2794)
							(mid 0.249642 -0.249642)
							(end 0.2794 -0.1778)
						)
						(arc
							(start 0.2794 0.1778)
							(mid 0.249642 0.249642)
							(end 0.1778 0.2794)
						)
					)
					(width 0)
					(fill yes)
				)
			)
		)
		(pad "2" smd custom
			(at 0 0.4445 90)
			(size 0.1397 0.1397)
			(layers "B.Cu" "B.Mask" "B.Paste")
			(net "SXP_ACTIVE_2")
			(options
				(clearance outline)
				(anchor circle)
			)
			(primitives
				(gr_poly
					(pts
						(arc
							(start -0.1778 0.2794)
							(mid -0.249642 0.249642)
							(end -0.2794 0.1778)
						)
						(arc
							(start -0.2794 -0.1778)
							(mid -0.249642 -0.249642)
							(end -0.1778 -0.2794)
						)
						(arc
							(start 0.1778 -0.2794)
							(mid 0.249642 -0.249642)
							(end 0.2794 -0.1778)
						)
						(arc
							(start 0.2794 0.1778)
							(mid 0.249642 0.249642)
							(end 0.1778 0.2794)
						)
					)
					(width 0)
					(fill yes)
				)
			)
		)
	)
	(footprint ""
		(layer "B.Cu")
		(at 101.454966 -46.609 -90)
		(property "Reference" "SC1034"
			(at 0 0 90)
			(layer "B.SilkS")
			(hide yes)
			(effects
				(font
					(size 1.27 1.27)
				)
				(justify mirror)
			)
		)
		(property "Value" "SC1KP50V2KX-1GP"
			(at -1.1811 -2.7051 270)
			(unlocked yes)
			(layer "B.Fab")
			(hide yes)
			(effects
				(font
					(size 1.016 1.016)
					(thickness 0.1524)
				)
				(justify mirror)
			)
		)
		(property "Device Type" "C402H22"
			(at -1.1811 -4.2291 270)
			(unlocked yes)
			(layer "B.Fab")
			(hide yes)
			(effects
				(font
					(size 1.016 1.016)
					(thickness 0.1524)
				)
				(justify mirror)
			)
		)
		(duplicate_pad_numbers_are_jumpers no)
		(fp_rect
			(start 0.4318 0.9525)
			(end -0.4318 -0.9525)
			(stroke
				(width 0)
				(type default)
			)
			(fill no)
			(layer "B.CrtYd")
		)
		(fp_rect
			(start 0.4318 0.9525)
			(end -0.4318 -0.9525)
			(stroke
				(width 0)
				(type default)
			)
			(fill no)
			(layer "B.Fab")
		)
		(pad "1" smd custom
			(at 0 -0.4445 90)
			(size 0.1524 0.1524)
			(layers "B.Cu" "B.Mask" "B.Paste")
			(net "P0V955_C")
			(options
				(clearance outline)
				(anchor circle)
			)
			(primitives
				(gr_poly
					(pts
						(arc
							(start 0.3048 0.2032)
							(mid 0.275042 0.275042)
							(end 0.2032 0.3048)
						)
						(arc
							(start -0.2032 0.3048)
							(mid -0.275042 0.275042)
							(end -0.3048 0.2032)
						)
						(arc
							(start -0.3048 -0.2032)
							(mid -0.275042 -0.275042)
							(end -0.2032 -0.3048)
						)
						(arc
							(start 0.2032 -0.3048)
							(mid 0.275042 -0.275042)
							(end 0.3048 -0.2032)
						)
					)
					(width 0)
					(fill yes)
				)
			)
		)
		(pad "2" smd custom
			(at 0 0.4445 90)
			(size 0.1524 0.1524)
			(layers "B.Cu" "B.Mask" "B.Paste")
			(net "GND")
			(options
				(clearance outline)
				(anchor circle)
			)
			(primitives
				(gr_poly
					(pts
						(arc
							(start 0.3048 0.2032)
							(mid 0.275042 0.275042)
							(end 0.2032 0.3048)
						)
						(arc
							(start -0.2032 0.3048)
							(mid -0.275042 0.275042)
							(end -0.3048 0.2032)
						)
						(arc
							(start -0.3048 -0.2032)
							(mid -0.275042 -0.275042)
							(end -0.2032 -0.3048)
						)
						(arc
							(start 0.2032 -0.3048)
							(mid 0.275042 -0.275042)
							(end 0.3048 -0.2032)
						)
					)
					(width 0)
					(fill yes)
				)
			)
		)
	)
	(footprint ""
		(layer "B.Cu")
		(at 105.137966 -33.655 180)
		(property "Reference" "SC951"
			(at 0 0 0)
			(layer "B.SilkS")
			(hide yes)
			(effects
				(font
					(size 1.27 1.27)
				)
				(justify mirror)
			)
		)
		(property "Value" "SCD1U6D3V1KX-GP"
			(at 2.8321 -1.7399 180)
			(unlocked yes)
			(layer "B.Fab")
			(hide yes)
			(effects
				(font
					(size 1.016 1.016)
					(thickness 0.1524)
				)
				(justify mirror)
			)
		)
		(property "Device Type" "C0201H13"
			(at 2.8321 -3.2639 180)
			(unlocked yes)
			(layer "B.Fab")
			(hide yes)
			(effects
				(font
					(size 1.016 1.016)
					(thickness 0.1524)
				)
				(justify mirror)
			)
		)
		(duplicate_pad_numbers_are_jumpers no)
		(fp_rect
			(start 0.2794 0.6477)
			(end -0.2794 -0.6477)
			(stroke
				(width 0)
				(type default)
			)
			(fill no)
			(layer "B.CrtYd")
		)
		(fp_rect
			(start 0.2794 0.6477)
			(end -0.2794 -0.6477)
			(stroke
				(width 0)
				(type default)
			)
			(fill no)
			(layer "B.Fab")
		)
		(pad "1" smd custom
			(at 0 -0.2794)
			(size 0.0762 0.0762)
			(layers "B.Cu" "B.Mask" "B.Paste")
			(net "PCE_AVDD")
			(options
				(clearance outline)
				(anchor circle)
			)
			(primitives
				(gr_poly
					(pts
						(arc
							(start 0.1524 0.127)
							(mid 0.137521 0.162921)
							(end 0.1016 0.1778)
						)
						(arc
							(start -0.1016 0.1778)
							(mid -0.137521 0.162921)
							(end -0.1524 0.127)
						)
						(arc
							(start -0.1524 -0.127)
							(mid -0.137521 -0.162921)
							(end -0.1016 -0.1778)
						)
						(arc
							(start 0.1016 -0.1778)
							(mid 0.137521 -0.162921)
							(end 0.1524 -0.127)
						)
					)
					(width 0)
					(fill yes)
				)
			)
		)
		(pad "2" smd custom
			(at 0 0.2794)
			(size 0.0762 0.0762)
			(layers "B.Cu" "B.Mask" "B.Paste")
			(net "GND")
			(options
				(clearance outline)
				(anchor circle)
			)
			(primitives
				(gr_poly
					(pts
						(arc
							(start 0.1524 0.127)
							(mid 0.137521 0.162921)
							(end 0.1016 0.1778)
						)
						(arc
							(start -0.1016 0.1778)
							(mid -0.137521 0.162921)
							(end -0.1524 0.127)
						)
						(arc
							(start -0.1524 -0.127)
							(mid -0.137521 -0.162921)
							(end -0.1016 -0.1778)
						)
						(arc
							(start 0.1016 -0.1778)
							(mid 0.137521 -0.162921)
							(end 0.1524 -0.127)
						)
					)
					(width 0)
					(fill yes)
				)
			)
		)
	)
	(footprint ""
		(layer "B.Cu")
		(at 111.38916 -30.226)
		(property "Reference" "STP78"
			(at 0 0 0)
			(layer "B.SilkS")
			(hide yes)
			(effects
				(font
					(size 1.27 1.27)
				)
				(justify mirror)
			)
		)
		(property "Value" "TPAD28"
			(at -0.0127 -1.8034 0)
			(unlocked yes)
			(layer "B.Fab")
			(hide yes)
			(effects
				(font
					(size 1.016 1.016)
					(thickness 0.1524)
				)
				(justify mirror)
			)
		)
		(property "Device Type" "TPAD28"
			(at -0.0127 -3.3274 0)
			(unlocked yes)
			(layer "B.Fab")
			(hide yes)
			(effects
				(font
					(size 1.016 1.016)
					(thickness 0.1524)
				)
				(justify mirror)
			)
		)
		(duplicate_pad_numbers_are_jumpers no)
		(fp_poly
			(pts
				(arc
					(start 0.3556 0)
					(mid -0.3556 0)
					(end 0.3556 0)
				)
			)
			(stroke
				(width 0)
				(type default)
			)
			(fill no)
			(layer "B.CrtYd")
		)
		(fp_poly
			(pts
				(arc
					(start 0.6096 0)
					(mid -0.6096 0)
					(end 0.6096 0)
				)
			)
			(stroke
				(width 0)
				(type default)
			)
			(fill no)
			(layer "B.Fab")
		)
		(pad "1" smd circle
			(at 0 0 180)
			(size 0.7112 0.7112)
			(layers "B.Cu" "B.Mask" "B.Paste")
			(net "IOC_GPIO_1")
		)
	)
	(footprint ""
		(layer "B.Cu")
		(at 121.29897 -87.503 -90)
		(property "Reference" "SC1181"
			(at 0 0 90)
			(layer "B.SilkS")
			(hide yes)
			(effects
				(font
					(size 1.27 1.27)
				)
				(justify mirror)
			)
		)
		(property "Value" "SCD1U6D3V1KX-GP"
			(at 2.8321 -1.7399 270)
			(unlocked yes)
			(layer "B.Fab")
			(hide yes)
			(effects
				(font
					(size 1.016 1.016)
					(thickness 0.1524)
				)
				(justify mirror)
			)
		)
		(property "Device Type" "C0201H13"
			(at 2.8321 -3.2639 270)
			(unlocked yes)
			(layer "B.Fab")
			(hide yes)
			(effects
				(font
					(size 1.016 1.016)
					(thickness 0.1524)
				)
				(justify mirror)
			)
		)
		(duplicate_pad_numbers_are_jumpers no)
		(fp_rect
			(start 0.2794 0.6477)
			(end -0.2794 -0.6477)
			(stroke
				(width 0)
				(type default)
			)
			(fill no)
			(layer "B.CrtYd")
		)
		(fp_rect
			(start 0.2794 0.6477)
			(end -0.2794 -0.6477)
			(stroke
				(width 0)
				(type default)
			)
			(fill no)
			(layer "B.Fab")
		)
		(pad "1" smd custom
			(at 0 -0.2794 90)
			(size 0.0762 0.0762)
			(layers "B.Cu" "B.Mask" "B.Paste")
			(net "GB_VDDA")
			(options
				(clearance outline)
				(anchor circle)
			)
			(primitives
				(gr_poly
					(pts
						(arc
							(start 0.1524 0.127)
							(mid 0.137521 0.162921)
							(end 0.1016 0.1778)
						)
						(arc
							(start -0.1016 0.1778)
							(mid -0.137521 0.162921)
							(end -0.1524 0.127)
						)
						(arc
							(start -0.1524 -0.127)
							(mid -0.137521 -0.162921)
							(end -0.1016 -0.1778)
						)
						(arc
							(start 0.1016 -0.1778)
							(mid 0.137521 -0.162921)
							(end 0.1524 -0.127)
						)
					)
					(width 0)
					(fill yes)
				)
			)
		)
		(pad "2" smd custom
			(at 0 0.2794 90)
			(size 0.0762 0.0762)
			(layers "B.Cu" "B.Mask" "B.Paste")
			(net "GND")
			(options
				(clearance outline)
				(anchor circle)
			)
			(primitives
				(gr_poly
					(pts
						(arc
							(start 0.1524 0.127)
							(mid 0.137521 0.162921)
							(end 0.1016 0.1778)
						)
						(arc
							(start -0.1016 0.1778)
							(mid -0.137521 0.162921)
							(end -0.1524 0.127)
						)
						(arc
							(start -0.1524 -0.127)
							(mid -0.137521 -0.162921)
							(end -0.1016 -0.1778)
						)
						(arc
							(start 0.1016 -0.1778)
							(mid 0.137521 -0.162921)
							(end 0.1524 -0.127)
						)
					)
					(width 0)
					(fill yes)
				)
			)
		)
	)
	(footprint ""
		(layer "B.Cu")
		(at 340.995 -100.203 90)
		(property "Reference" "PC14"
			(at 0 0 90)
			(layer "B.SilkS")
			(hide yes)
			(effects
				(font
					(size 1.27 1.27)
				)
				(justify mirror)
			)
		)
		(property "Value" "SCD1U50V3KX-GP"
			(at 0 -2.8194 90)
			(unlocked yes)
			(layer "B.Fab")
			(hide yes)
			(effects
				(font
					(size 1.016 1.016)
					(thickness 0.1524)
				)
				(justify mirror)
			)
		)
		(property "Device Type" "C603H36"
			(at 0 -4.3434 90)
			(unlocked yes)
			(layer "B.Fab")
			(hide yes)
			(effects
				(font
					(size 1.016 1.016)
					(thickness 0.1524)
				)
				(justify mirror)
			)
		)
		(duplicate_pad_numbers_are_jumpers no)
		(fp_line
			(start -0.508 0)
			(end 0.508 0)
			(stroke
				(width 0.2032)
				(type default)
			)
			(layer "B.SilkS")
		)
		(fp_rect
			(start 0.5842 1.3335)
			(end -0.5842 -1.3335)
			(stroke
				(width 0)
				(type default)
			)
			(fill no)
			(layer "B.CrtYd")
		)
		(fp_rect
			(start 0.5842 1.3335)
			(end -0.5842 -1.3335)
			(stroke
				(width 0)
				(type default)
			)
			(fill no)
			(layer "B.Fab")
		)
		(pad "1" smd custom
			(at 0 -0.762 270)
			(size 0.2159 0.2159)
			(layers "B.Cu" "B.Mask" "B.Paste")
			(net "P5V_STBY_VFB_R")
			(options
				(clearance outline)
				(anchor circle)
			)
			(primitives
				(gr_poly
					(pts
						(arc
							(start -0.3302 0.4318)
							(mid -0.402042 0.402042)
							(end -0.4318 0.3302)
						)
						(arc
							(start -0.4318 -0.3302)
							(mid -0.402042 -0.402042)
							(end -0.3302 -0.4318)
						)
						(arc
							(start 0.3302 -0.4318)
							(mid 0.402042 -0.402042)
							(end 0.4318 -0.3302)
						)
						(arc
							(start 0.4318 0.3302)
							(mid 0.402042 0.402042)
							(end 0.3302 0.4318)
						)
					)
					(width 0)
					(fill yes)
				)
			)
		)
		(pad "2" smd custom
			(at 0 0.762 270)
			(size 0.2159 0.2159)
			(layers "B.Cu" "B.Mask" "B.Paste")
			(net "P5V_STBY")
			(options
				(clearance outline)
				(anchor circle)
			)
			(primitives
				(gr_poly
					(pts
						(arc
							(start -0.3302 0.4318)
							(mid -0.402042 0.402042)
							(end -0.4318 0.3302)
						)
						(arc
							(start -0.4318 -0.3302)
							(mid -0.402042 -0.402042)
							(end -0.3302 -0.4318)
						)
						(arc
							(start 0.3302 -0.4318)
							(mid 0.402042 -0.402042)
							(end 0.4318 -0.3302)
						)
						(arc
							(start 0.4318 0.3302)
							(mid 0.402042 0.402042)
							(end 0.3302 0.4318)
						)
					)
					(width 0)
					(fill yes)
				)
			)
		)
	)
	(footprint ""
		(layer "B.Cu")
		(at 110.954566 -38.53434 -90)
		(property "Reference" "SC986"
			(at 0 0 90)
			(layer "B.SilkS")
			(hide yes)
			(effects
				(font
					(size 1.27 1.27)
				)
				(justify mirror)
			)
		)
		(property "Value" "SCD1U16V2KX-3GP"
			(at -1.1811 -2.7051 270)
			(unlocked yes)
			(layer "B.Fab")
			(hide yes)
			(effects
				(font
					(size 1.016 1.016)
					(thickness 0.1524)
				)
				(justify mirror)
			)
		)
		(property "Device Type" "C402H22"
			(at -1.1811 -4.2291 270)
			(unlocked yes)
			(layer "B.Fab")
			(hide yes)
			(effects
				(font
					(size 1.016 1.016)
					(thickness 0.1524)
				)
				(justify mirror)
			)
		)
		(duplicate_pad_numbers_are_jumpers no)
		(fp_rect
			(start 0.4318 0.9525)
			(end -0.4318 -0.9525)
			(stroke
				(width 0)
				(type default)
			)
			(fill no)
			(layer "B.CrtYd")
		)
		(fp_rect
			(start 0.4318 0.9525)
			(end -0.4318 -0.9525)
			(stroke
				(width 0)
				(type default)
			)
			(fill no)
			(layer "B.Fab")
		)
		(pad "1" smd custom
			(at 0 -0.4445 90)
			(size 0.1524 0.1524)
			(layers "B.Cu" "B.Mask" "B.Paste")
			(net "P1V8_C")
			(options
				(clearance outline)
				(anchor circle)
			)
			(primitives
				(gr_poly
					(pts
						(arc
							(start 0.3048 0.2032)
							(mid 0.275042 0.275042)
							(end 0.2032 0.3048)
						)
						(arc
							(start -0.2032 0.3048)
							(mid -0.275042 0.275042)
							(end -0.3048 0.2032)
						)
						(arc
							(start -0.3048 -0.2032)
							(mid -0.275042 -0.275042)
							(end -0.2032 -0.3048)
						)
						(arc
							(start 0.2032 -0.3048)
							(mid 0.275042 -0.275042)
							(end 0.3048 -0.2032)
						)
					)
					(width 0)
					(fill yes)
				)
			)
		)
		(pad "2" smd custom
			(at 0 0.4445 90)
			(size 0.1524 0.1524)
			(layers "B.Cu" "B.Mask" "B.Paste")
			(net "GND")
			(options
				(clearance outline)
				(anchor circle)
			)
			(primitives
				(gr_poly
					(pts
						(arc
							(start 0.3048 0.2032)
							(mid 0.275042 0.275042)
							(end 0.2032 0.3048)
						)
						(arc
							(start -0.2032 0.3048)
							(mid -0.275042 0.275042)
							(end -0.3048 0.2032)
						)
						(arc
							(start -0.3048 -0.2032)
							(mid -0.275042 -0.275042)
							(end -0.2032 -0.3048)
						)
						(arc
							(start 0.2032 -0.3048)
							(mid 0.275042 -0.275042)
							(end 0.3048 -0.2032)
						)
					)
					(width 0)
					(fill yes)
				)
			)
		)
	)
	(footprint ""
		(layer "B.Cu")
		(at 158.42996 -107.239054 90)
		(property "Reference" "SC1243"
			(at 0 0 90)
			(layer "B.SilkS")
			(hide yes)
			(effects
				(font
					(size 1.27 1.27)
				)
				(justify mirror)
			)
		)
		(property "Value" "SCD1U6D3V1KX-GP"
			(at 2.8321 -1.7399 90)
			(unlocked yes)
			(layer "B.Fab")
			(hide yes)
			(effects
				(font
					(size 1.016 1.016)
					(thickness 0.1524)
				)
				(justify mirror)
			)
		)
		(property "Device Type" "C0201H13"
			(at 2.8321 -3.2639 90)
			(unlocked yes)
			(layer "B.Fab")
			(hide yes)
			(effects
				(font
					(size 1.016 1.016)
					(thickness 0.1524)
				)
				(justify mirror)
			)
		)
		(duplicate_pad_numbers_are_jumpers no)
		(fp_rect
			(start 0.2794 0.6477)
			(end -0.2794 -0.6477)
			(stroke
				(width 0)
				(type default)
			)
			(fill no)
			(layer "B.CrtYd")
		)
		(fp_rect
			(start 0.2794 0.6477)
			(end -0.2794 -0.6477)
			(stroke
				(width 0)
				(type default)
			)
			(fill no)
			(layer "B.Fab")
		)
		(pad "1" smd custom
			(at 0 -0.2794 270)
			(size 0.0762 0.0762)
			(layers "B.Cu" "B.Mask" "B.Paste")
			(net "P0V9_E")
			(options
				(clearance outline)
				(anchor circle)
			)
			(primitives
				(gr_poly
					(pts
						(arc
							(start 0.1524 0.127)
							(mid 0.137521 0.162921)
							(end 0.1016 0.1778)
						)
						(arc
							(start -0.1016 0.1778)
							(mid -0.137521 0.162921)
							(end -0.1524 0.127)
						)
						(arc
							(start -0.1524 -0.127)
							(mid -0.137521 -0.162921)
							(end -0.1016 -0.1778)
						)
						(arc
							(start 0.1016 -0.1778)
							(mid 0.137521 -0.162921)
							(end 0.1524 -0.127)
						)
					)
					(width 0)
					(fill yes)
				)
			)
		)
		(pad "2" smd custom
			(at 0 0.2794 270)
			(size 0.0762 0.0762)
			(layers "B.Cu" "B.Mask" "B.Paste")
			(net "GND")
			(options
				(clearance outline)
				(anchor circle)
			)
			(primitives
				(gr_poly
					(pts
						(arc
							(start 0.1524 0.127)
							(mid 0.137521 0.162921)
							(end 0.1016 0.1778)
						)
						(arc
							(start -0.1016 0.1778)
							(mid -0.137521 0.162921)
							(end -0.1524 0.127)
						)
						(arc
							(start -0.1524 -0.127)
							(mid -0.137521 -0.162921)
							(end -0.1016 -0.1778)
						)
						(arc
							(start 0.1016 -0.1778)
							(mid 0.137521 -0.162921)
							(end 0.1524 -0.127)
						)
					)
					(width 0)
					(fill yes)
				)
			)
		)
	)
	(footprint ""
		(layer "B.Cu")
		(at 99.7966 -98.552)
		(property "Reference" "STP164"
			(at 0 0 0)
			(layer "B.SilkS")
			(hide yes)
			(effects
				(font
					(size 1.27 1.27)
				)
				(justify mirror)
			)
		)
		(property "Value" "TPAD28"
			(at -0.0127 -1.8034 0)
			(unlocked yes)
			(layer "B.Fab")
			(hide yes)
			(effects
				(font
					(size 1.016 1.016)
					(thickness 0.1524)
				)
				(justify mirror)
			)
		)
		(property "Device Type" "TPAD28"
			(at -0.0127 -3.3274 0)
			(unlocked yes)
			(layer "B.Fab")
			(hide yes)
			(effects
				(font
					(size 1.016 1.016)
					(thickness 0.1524)
				)
				(justify mirror)
			)
		)
		(duplicate_pad_numbers_are_jumpers no)
		(fp_poly
			(pts
				(arc
					(start 0.3556 0)
					(mid -0.3556 0)
					(end 0.3556 0)
				)
			)
			(stroke
				(width 0)
				(type default)
			)
			(fill no)
			(layer "B.CrtYd")
		)
		(fp_poly
			(pts
				(arc
					(start 0.6096 0)
					(mid -0.6096 0)
					(end 0.6096 0)
				)
			)
			(stroke
				(width 0)
				(type default)
			)
			(fill no)
			(layer "B.Fab")
		)
		(pad "1" smd circle
			(at 0 0 180)
			(size 0.7112 0.7112)
			(layers "B.Cu" "B.Mask" "B.Paste")
			(net "EXP_XM_ADDR_0")
		)
	)
	(footprint ""
		(layer "B.Cu")
		(at 124.530612 -220.345 90)
		(property "Reference" "SC1288"
			(at 0 0 90)
			(layer "B.SilkS")
			(hide yes)
			(effects
				(font
					(size 1.27 1.27)
				)
				(justify mirror)
			)
		)
		(property "Value" "SC10U6D3V5KX-4GP"
			(at 0.0762 -6.1214 90)
			(unlocked yes)
			(layer "B.Fab")
			(hide yes)
			(effects
				(font
					(size 1.016 1.016)
					(thickness 0.1524)
				)
				(justify mirror)
			)
		)
		(property "Device Type" "C805H58"
			(at 0.0762 -8.1534 90)
			(unlocked yes)
			(layer "B.Fab")
			(hide yes)
			(effects
				(font
					(size 1.016 1.016)
					(thickness 0.1524)
				)
				(justify mirror)
			)
		)
		(duplicate_pad_numbers_are_jumpers no)
		(fp_line
			(start -0.635 0)
			(end 0.635 0)
			(stroke
				(width 0.508)
				(type default)
			)
			(layer "B.SilkS")
		)
		(fp_rect
			(start 0.9652 1.778)
			(end -0.9652 -1.778)
			(stroke
				(width 0)
				(type default)
			)
			(fill no)
			(layer "B.CrtYd")
		)
		(fp_poly
			(pts
				(xy 0.9652 -1.778) (xy -0.9652 -1.778) (xy -0.9652 1.778) (xy 0.9652 1.778)
			)
			(stroke
				(width 0)
				(type default)
			)
			(fill no)
			(layer "B.Fab")
		)
		(pad "1" smd rect
			(at 0 -0.9652 270)
			(size 1.397 1.143)
			(layers "B.Cu" "B.Mask" "B.Paste")
			(net "1.2V_REDV")
		)
		(pad "2" smd rect
			(at 0 0.9652 270)
			(size 1.397 1.143)
			(layers "B.Cu" "B.Mask" "B.Paste")
			(net "GND")
		)
	)
	(footprint ""
		(layer "B.Cu")
		(at 124.799852 -64.799972)
		(property "Reference" ""
			(at 0 0 0)
			(layer "B.SilkS")
			(hide yes)
			(effects
				(font
					(size 1.27 1.27)
				)
				(justify mirror)
			)
		)
		(property "Value" "*"
			(at 5.5753 -0.4572 0)
			(unlocked yes)
			(layer "B.Fab")
			(hide yes)
			(effects
				(font
					(size 1.016 1.016)
					(thickness 0.1524)
				)
				(justify mirror)
			)
		)
		(duplicate_pad_numbers_are_jumpers no)
		(fp_poly
			(pts
				(arc
					(start 4.3053 0)
					(mid -4.3053 0)
					(end 4.3053 0)
				)
			)
			(stroke
				(width 0)
				(type default)
			)
			(fill no)
			(layer "B.CrtYd")
		)
		(fp_poly
			(pts
				(arc
					(start 4.3053 0)
					(mid -4.3053 0)
					(end 4.3053 0)
				)
			)
			(stroke
				(width 0)
				(type default)
			)
			(fill no)
			(layer "B.Fab")
		)
		(pad "1" smd custom
			(at 2.95275 0 180)
			(size 2.000013 2.000013)
			(layers "B.Cu" "B.Mask" "B.Paste")
			(net "Net_48")
			(options
				(clearance outline)
				(anchor circle)
			)
			(primitives
				(gr_poly
					(pts
						(arc
							(start 4.0005 -0.00254)
							(mid -4.000501 0)
							(end 4.0005 0.00254)
						)
						(arc
							(start 1.905 0.00254)
							(mid -1.905002 0)
							(end 1.905 -0.00254)
						)
					)
					(width 0)
					(fill yes)
				)
			)
		)
	)
	(footprint ""
		(layer "B.Cu")
		(at 297.18 -180.54066)
		(property "Reference" "TP116"
			(at 0 0 0)
			(layer "B.SilkS")
			(hide yes)
			(effects
				(font
					(size 1.27 1.27)
				)
				(justify mirror)
			)
		)
		(property "Value" "TPAD28"
			(at -0.0127 -1.8034 0)
			(unlocked yes)
			(layer "B.Fab")
			(hide yes)
			(effects
				(font
					(size 1.016 1.016)
					(thickness 0.1524)
				)
				(justify mirror)
			)
		)
		(property "Device Type" "TPAD28"
			(at -0.0127 -3.3274 0)
			(unlocked yes)
			(layer "B.Fab")
			(hide yes)
			(effects
				(font
					(size 1.016 1.016)
					(thickness 0.1524)
				)
				(justify mirror)
			)
		)
		(duplicate_pad_numbers_are_jumpers no)
		(fp_poly
			(pts
				(arc
					(start 0.3556 0)
					(mid -0.3556 0)
					(end 0.3556 0)
				)
			)
			(stroke
				(width 0)
				(type default)
			)
			(fill no)
			(layer "B.CrtYd")
		)
		(fp_poly
			(pts
				(arc
					(start 0.6096 0)
					(mid -0.6096 0)
					(end 0.6096 0)
				)
			)
			(stroke
				(width 0)
				(type default)
			)
			(fill no)
			(layer "B.Fab")
		)
		(pad "1" smd circle
			(at 0 0 180)
			(size 0.7112 0.7112)
			(layers "B.Cu" "B.Mask" "B.Paste")
			(net "TP_BMC_GPIOM7")
		)
	)
	(footprint ""
		(layer "B.Cu")
		(at 95.504 -3.429)
		(property "Reference" "PC194"
			(at 0 0 0)
			(layer "B.SilkS")
			(hide yes)
			(effects
				(font
					(size 1.27 1.27)
				)
				(justify mirror)
			)
		)
		(property "Value" "SC6800P50V3KX-GP"
			(at 0 -2.8194 0)
			(unlocked yes)
			(layer "B.Fab")
			(hide yes)
			(effects
				(font
					(size 1.016 1.016)
					(thickness 0.1524)
				)
				(justify mirror)
			)
		)
		(property "Device Type" "C603"
			(at 0 -4.3434 0)
			(unlocked yes)
			(layer "B.Fab")
			(hide yes)
			(effects
				(font
					(size 1.016 1.016)
					(thickness 0.1524)
				)
				(justify mirror)
			)
		)
		(duplicate_pad_numbers_are_jumpers no)
		(fp_line
			(start -0.508 0)
			(end 0.508 0)
			(stroke
				(width 0.2032)
				(type default)
			)
			(layer "B.SilkS")
		)
		(fp_rect
			(start 0.5842 1.3335)
			(end -0.5842 -1.3335)
			(stroke
				(width 0)
				(type default)
			)
			(fill no)
			(layer "B.CrtYd")
		)
		(fp_rect
			(start 0.5842 1.3335)
			(end -0.5842 -1.3335)
			(stroke
				(width 0)
				(type default)
			)
			(fill no)
			(layer "B.Fab")
		)
		(pad "1" smd custom
			(at 0 -0.762 180)
			(size 0.2159 0.2159)
			(layers "B.Cu" "B.Mask" "B.Paste")
			(net "P0V955_C")
			(options
				(clearance outline)
				(anchor circle)
			)
			(primitives
				(gr_poly
					(pts
						(arc
							(start -0.3302 0.4318)
							(mid -0.402042 0.402042)
							(end -0.4318 0.3302)
						)
						(arc
							(start -0.4318 -0.3302)
							(mid -0.402042 -0.402042)
							(end -0.3302 -0.4318)
						)
						(arc
							(start 0.3302 -0.4318)
							(mid 0.402042 -0.402042)
							(end 0.4318 -0.3302)
						)
						(arc
							(start 0.4318 0.3302)
							(mid 0.402042 0.402042)
							(end 0.3302 0.4318)
						)
					)
					(width 0)
					(fill yes)
				)
			)
		)
		(pad "2" smd custom
			(at 0 0.762 180)
			(size 0.2159 0.2159)
			(layers "B.Cu" "B.Mask" "B.Paste")
			(net "GND")
			(options
				(clearance outline)
				(anchor circle)
			)
			(primitives
				(gr_poly
					(pts
						(arc
							(start -0.3302 0.4318)
							(mid -0.402042 0.402042)
							(end -0.4318 0.3302)
						)
						(arc
							(start -0.4318 -0.3302)
							(mid -0.402042 -0.402042)
							(end -0.3302 -0.4318)
						)
						(arc
							(start 0.3302 -0.4318)
							(mid 0.402042 -0.402042)
							(end 0.4318 -0.3302)
						)
						(arc
							(start 0.4318 0.3302)
							(mid 0.402042 0.402042)
							(end 0.3302 0.4318)
						)
					)
					(width 0)
					(fill yes)
				)
			)
		)
	)
	(footprint ""
		(layer "B.Cu")
		(at 263.525 -36.957 -90)
		(property "Reference" "PR45"
			(at 0 0 90)
			(layer "B.SilkS")
			(hide yes)
			(effects
				(font
					(size 1.27 1.27)
				)
				(justify mirror)
			)
		)
		(property "Value" "10KR2F-2-GP"
			(at -0.064008 -3.993896 270)
			(unlocked yes)
			(layer "B.Fab")
			(hide yes)
			(effects
				(font
					(size 1.016 1.016)
					(thickness 0.1524)
				)
				(justify mirror)
			)
		)
		(property "Device Type" "R402H16"
			(at -0.064008 -5.517896 270)
			(unlocked yes)
			(layer "B.Fab")
			(hide yes)
			(effects
				(font
					(size 1.016 1.016)
					(thickness 0.1524)
				)
				(justify mirror)
			)
		)
		(duplicate_pad_numbers_are_jumpers no)
		(fp_line
			(start -0.508 -0.9398)
			(end 0.508 -0.9398)
			(stroke
				(width 0.1524)
				(type default)
			)
			(layer "B.SilkS")
		)
		(fp_line
			(start 0.508 -0.9398)
			(end 0.508 0.9398)
			(stroke
				(width 0.1524)
				(type default)
			)
			(layer "B.SilkS")
		)
		(fp_rect
			(start 0.508 0.9398)
			(end -0.508 -0.9398)
			(stroke
				(width 0)
				(type default)
			)
			(fill no)
			(layer "B.CrtYd")
		)
		(fp_rect
			(start 0.508 0.9398)
			(end -0.508 -0.9398)
			(stroke
				(width 0)
				(type default)
			)
			(fill no)
			(layer "B.Fab")
		)
		(pad "1" smd custom
			(at 0 -0.4445 90)
			(size 0.1397 0.1397)
			(layers "B.Cu" "B.Mask" "B.Paste")
			(net "P1V8_STBY_PG")
			(options
				(clearance outline)
				(anchor circle)
			)
			(primitives
				(gr_poly
					(pts
						(arc
							(start -0.1778 0.2794)
							(mid -0.249642 0.249642)
							(end -0.2794 0.1778)
						)
						(arc
							(start -0.2794 -0.1778)
							(mid -0.249642 -0.249642)
							(end -0.1778 -0.2794)
						)
						(arc
							(start 0.1778 -0.2794)
							(mid 0.249642 -0.249642)
							(end 0.2794 -0.1778)
						)
						(arc
							(start 0.2794 0.1778)
							(mid 0.249642 0.249642)
							(end 0.1778 0.2794)
						)
					)
					(width 0)
					(fill yes)
				)
			)
		)
		(pad "2" smd custom
			(at 0 0.4445 90)
			(size 0.1397 0.1397)
			(layers "B.Cu" "B.Mask" "B.Paste")
			(net "P1V8_STBY_VREG")
			(options
				(clearance outline)
				(anchor circle)
			)
			(primitives
				(gr_poly
					(pts
						(arc
							(start -0.1778 0.2794)
							(mid -0.249642 0.249642)
							(end -0.2794 0.1778)
						)
						(arc
							(start -0.2794 -0.1778)
							(mid -0.249642 -0.249642)
							(end -0.1778 -0.2794)
						)
						(arc
							(start 0.1778 -0.2794)
							(mid 0.249642 -0.249642)
							(end 0.2794 -0.1778)
						)
						(arc
							(start 0.2794 0.1778)
							(mid 0.249642 0.249642)
							(end 0.1778 0.2794)
						)
					)
					(width 0)
					(fill yes)
				)
			)
		)
	)
	(footprint ""
		(layer "B.Cu")
		(at 99.20097 -112.014 -90)
		(property "Reference" "SC1202"
			(at 0 0 90)
			(layer "B.SilkS")
			(hide yes)
			(effects
				(font
					(size 1.27 1.27)
				)
				(justify mirror)
			)
		)
		(property "Value" "SC10U6D3V5KX-4GP"
			(at 0.0762 -6.1214 270)
			(unlocked yes)
			(layer "B.Fab")
			(hide yes)
			(effects
				(font
					(size 1.016 1.016)
					(thickness 0.1524)
				)
				(justify mirror)
			)
		)
		(property "Device Type" "C805H58"
			(at 0.0762 -8.1534 270)
			(unlocked yes)
			(layer "B.Fab")
			(hide yes)
			(effects
				(font
					(size 1.016 1.016)
					(thickness 0.1524)
				)
				(justify mirror)
			)
		)
		(duplicate_pad_numbers_are_jumpers no)
		(fp_line
			(start -0.635 0)
			(end 0.635 0)
			(stroke
				(width 0.508)
				(type default)
			)
			(layer "B.SilkS")
		)
		(fp_rect
			(start 0.9652 1.778)
			(end -0.9652 -1.778)
			(stroke
				(width 0)
				(type default)
			)
			(fill no)
			(layer "B.CrtYd")
		)
		(fp_poly
			(pts
				(xy 0.9652 -1.778) (xy -0.9652 -1.778) (xy -0.9652 1.778) (xy 0.9652 1.778)
			)
			(stroke
				(width 0)
				(type default)
			)
			(fill no)
			(layer "B.Fab")
		)
		(pad "1" smd rect
			(at 0 -0.9652 90)
			(size 1.397 1.143)
			(layers "B.Cu" "B.Mask" "B.Paste")
			(net "P1V8_E")
		)
		(pad "2" smd rect
			(at 0 0.9652 90)
			(size 1.397 1.143)
			(layers "B.Cu" "B.Mask" "B.Paste")
			(net "GND")
		)
	)
	(footprint ""
		(layer "B.Cu")
		(at 301.55642 -178.3715)
		(property "Reference" "TP159"
			(at 0 0 0)
			(layer "B.SilkS")
			(hide yes)
			(effects
				(font
					(size 1.27 1.27)
				)
				(justify mirror)
			)
		)
		(property "Value" "TPAD28"
			(at -0.0127 -1.8034 0)
			(unlocked yes)
			(layer "B.Fab")
			(hide yes)
			(effects
				(font
					(size 1.016 1.016)
					(thickness 0.1524)
				)
				(justify mirror)
			)
		)
		(property "Device Type" "TPAD28"
			(at -0.0127 -3.3274 0)
			(unlocked yes)
			(layer "B.Fab")
			(hide yes)
			(effects
				(font
					(size 1.016 1.016)
					(thickness 0.1524)
				)
				(justify mirror)
			)
		)
		(duplicate_pad_numbers_are_jumpers no)
		(fp_poly
			(pts
				(arc
					(start 0.3556 0)
					(mid -0.3556 0)
					(end 0.3556 0)
				)
			)
			(stroke
				(width 0)
				(type default)
			)
			(fill no)
			(layer "B.CrtYd")
		)
		(fp_poly
			(pts
				(arc
					(start 0.6096 0)
					(mid -0.6096 0)
					(end 0.6096 0)
				)
			)
			(stroke
				(width 0)
				(type default)
			)
			(fill no)
			(layer "B.Fab")
		)
		(pad "1" smd circle
			(at 0 0 180)
			(size 0.7112 0.7112)
			(layers "B.Cu" "B.Mask" "B.Paste")
			(net "TP_BMC_GPIOJ4")
		)
	)
	(footprint ""
		(layer "B.Cu")
		(at 92.310966 -37.084 -90)
		(property "Reference" "SC961"
			(at 0 0 90)
			(layer "B.SilkS")
			(hide yes)
			(effects
				(font
					(size 1.27 1.27)
				)
				(justify mirror)
			)
		)
		(property "Value" "SCD1U6D3V1KX-GP"
			(at 2.8321 -1.7399 270)
			(unlocked yes)
			(layer "B.Fab")
			(hide yes)
			(effects
				(font
					(size 1.016 1.016)
					(thickness 0.1524)
				)
				(justify mirror)
			)
		)
		(property "Device Type" "C0201H13"
			(at 2.8321 -3.2639 270)
			(unlocked yes)
			(layer "B.Fab")
			(hide yes)
			(effects
				(font
					(size 1.016 1.016)
					(thickness 0.1524)
				)
				(justify mirror)
			)
		)
		(duplicate_pad_numbers_are_jumpers no)
		(fp_rect
			(start 0.2794 0.6477)
			(end -0.2794 -0.6477)
			(stroke
				(width 0)
				(type default)
			)
			(fill no)
			(layer "B.CrtYd")
		)
		(fp_rect
			(start 0.2794 0.6477)
			(end -0.2794 -0.6477)
			(stroke
				(width 0)
				(type default)
			)
			(fill no)
			(layer "B.Fab")
		)
		(pad "1" smd custom
			(at 0 -0.2794 90)
			(size 0.0762 0.0762)
			(layers "B.Cu" "B.Mask" "B.Paste")
			(net "SAS0_AVDD")
			(options
				(clearance outline)
				(anchor circle)
			)
			(primitives
				(gr_poly
					(pts
						(arc
							(start 0.1524 0.127)
							(mid 0.137521 0.162921)
							(end 0.1016 0.1778)
						)
						(arc
							(start -0.1016 0.1778)
							(mid -0.137521 0.162921)
							(end -0.1524 0.127)
						)
						(arc
							(start -0.1524 -0.127)
							(mid -0.137521 -0.162921)
							(end -0.1016 -0.1778)
						)
						(arc
							(start 0.1016 -0.1778)
							(mid 0.137521 -0.162921)
							(end 0.1524 -0.127)
						)
					)
					(width 0)
					(fill yes)
				)
			)
		)
		(pad "2" smd custom
			(at 0 0.2794 90)
			(size 0.0762 0.0762)
			(layers "B.Cu" "B.Mask" "B.Paste")
			(net "GND")
			(options
				(clearance outline)
				(anchor circle)
			)
			(primitives
				(gr_poly
					(pts
						(arc
							(start 0.1524 0.127)
							(mid 0.137521 0.162921)
							(end 0.1016 0.1778)
						)
						(arc
							(start -0.1016 0.1778)
							(mid -0.137521 0.162921)
							(end -0.1524 0.127)
						)
						(arc
							(start -0.1524 -0.127)
							(mid -0.137521 -0.162921)
							(end -0.1016 -0.1778)
						)
						(arc
							(start 0.1016 -0.1778)
							(mid 0.137521 -0.162921)
							(end 0.1524 -0.127)
						)
					)
					(width 0)
					(fill yes)
				)
			)
		)
	)
	(footprint ""
		(layer "B.Cu")
		(at 296.672 -179.324)
		(property "Reference" "TP104"
			(at 0 0 0)
			(layer "B.SilkS")
			(hide yes)
			(effects
				(font
					(size 1.27 1.27)
				)
				(justify mirror)
			)
		)
		(property "Value" "TPAD28"
			(at -0.0127 -1.8034 0)
			(unlocked yes)
			(layer "B.Fab")
			(hide yes)
			(effects
				(font
					(size 1.016 1.016)
					(thickness 0.1524)
				)
				(justify mirror)
			)
		)
		(property "Device Type" "TPAD28"
			(at -0.0127 -3.3274 0)
			(unlocked yes)
			(layer "B.Fab")
			(hide yes)
			(effects
				(font
					(size 1.016 1.016)
					(thickness 0.1524)
				)
				(justify mirror)
			)
		)
		(duplicate_pad_numbers_are_jumpers no)
		(fp_poly
			(pts
				(arc
					(start 0.3556 0)
					(mid -0.3556 0)
					(end 0.3556 0)
				)
			)
			(stroke
				(width 0)
				(type default)
			)
			(fill no)
			(layer "B.CrtYd")
		)
		(fp_poly
			(pts
				(arc
					(start 0.6096 0)
					(mid -0.6096 0)
					(end 0.6096 0)
				)
			)
			(stroke
				(width 0)
				(type default)
			)
			(fill no)
			(layer "B.Fab")
		)
		(pad "1" smd circle
			(at 0 0 180)
			(size 0.7112 0.7112)
			(layers "B.Cu" "B.Mask" "B.Paste")
			(net "TP_BMC_GPIOL7")
		)
	)
	(footprint ""
		(layer "B.Cu")
		(at 140.95857 -93.9546)
		(property "Reference" "R5314"
			(at 0 0 0)
			(layer "B.SilkS")
			(hide yes)
			(effects
				(font
					(size 1.27 1.27)
				)
				(justify mirror)
			)
		)
		(property "Value" "0R2J-2-GP"
			(at -0.064008 -3.993896 0)
			(unlocked yes)
			(layer "B.Fab")
			(hide yes)
			(effects
				(font
					(size 1.016 1.016)
					(thickness 0.1524)
				)
				(justify mirror)
			)
		)
		(property "Device Type" "R402H16"
			(at -0.064008 -5.517896 0)
			(unlocked yes)
			(layer "B.Fab")
			(hide yes)
			(effects
				(font
					(size 1.016 1.016)
					(thickness 0.1524)
				)
				(justify mirror)
			)
		)
		(duplicate_pad_numbers_are_jumpers no)
		(fp_line
			(start -0.508 -0.9398)
			(end 0.508 -0.9398)
			(stroke
				(width 0.1524)
				(type default)
			)
			(layer "B.SilkS")
		)
		(fp_line
			(start 0.508 -0.9398)
			(end 0.508 0.9398)
			(stroke
				(width 0.1524)
				(type default)
			)
			(layer "B.SilkS")
		)
		(fp_rect
			(start 0.508 0.9398)
			(end -0.508 -0.9398)
			(stroke
				(width 0)
				(type default)
			)
			(fill no)
			(layer "B.CrtYd")
		)
		(fp_rect
			(start 0.508 0.9398)
			(end -0.508 -0.9398)
			(stroke
				(width 0)
				(type default)
			)
			(fill no)
			(layer "B.Fab")
		)
		(pad "1" smd custom
			(at 0 -0.4445 180)
			(size 0.1397 0.1397)
			(layers "B.Cu" "B.Mask" "B.Paste")
			(net "BMC_I2C_SCL_10")
			(options
				(clearance outline)
				(anchor circle)
			)
			(primitives
				(gr_poly
					(pts
						(arc
							(start -0.1778 0.2794)
							(mid -0.249642 0.249642)
							(end -0.2794 0.1778)
						)
						(arc
							(start -0.2794 -0.1778)
							(mid -0.249642 -0.249642)
							(end -0.1778 -0.2794)
						)
						(arc
							(start 0.1778 -0.2794)
							(mid 0.249642 -0.249642)
							(end 0.2794 -0.1778)
						)
						(arc
							(start 0.2794 0.1778)
							(mid 0.249642 0.249642)
							(end 0.1778 0.2794)
						)
					)
					(width 0)
					(fill yes)
				)
			)
		)
		(pad "2" smd custom
			(at 0 0.4445 180)
			(size 0.1397 0.1397)
			(layers "B.Cu" "B.Mask" "B.Paste")
			(net "TEMP_3_SCL")
			(options
				(clearance outline)
				(anchor circle)
			)
			(primitives
				(gr_poly
					(pts
						(arc
							(start -0.1778 0.2794)
							(mid -0.249642 0.249642)
							(end -0.2794 0.1778)
						)
						(arc
							(start -0.2794 -0.1778)
							(mid -0.249642 -0.249642)
							(end -0.1778 -0.2794)
						)
						(arc
							(start 0.1778 -0.2794)
							(mid 0.249642 -0.249642)
							(end 0.2794 -0.1778)
						)
						(arc
							(start 0.2794 0.1778)
							(mid 0.249642 0.249642)
							(end 0.1778 0.2794)
						)
					)
					(width 0)
					(fill yes)
				)
			)
		)
	)
	(footprint ""
		(layer "B.Cu")
		(at 110.725966 -48.1965 -90)
		(property "Reference" "SC991"
			(at 0 0 90)
			(layer "B.SilkS")
			(hide yes)
			(effects
				(font
					(size 1.27 1.27)
				)
				(justify mirror)
			)
		)
		(property "Value" "SCD1U16V2KX-3GP"
			(at -1.1811 -2.7051 270)
			(unlocked yes)
			(layer "B.Fab")
			(hide yes)
			(effects
				(font
					(size 1.016 1.016)
					(thickness 0.1524)
				)
				(justify mirror)
			)
		)
		(property "Device Type" "C402H22"
			(at -1.1811 -4.2291 270)
			(unlocked yes)
			(layer "B.Fab")
			(hide yes)
			(effects
				(font
					(size 1.016 1.016)
					(thickness 0.1524)
				)
				(justify mirror)
			)
		)
		(duplicate_pad_numbers_are_jumpers no)
		(fp_rect
			(start 0.4318 0.9525)
			(end -0.4318 -0.9525)
			(stroke
				(width 0)
				(type default)
			)
			(fill no)
			(layer "B.CrtYd")
		)
		(fp_rect
			(start 0.4318 0.9525)
			(end -0.4318 -0.9525)
			(stroke
				(width 0)
				(type default)
			)
			(fill no)
			(layer "B.Fab")
		)
		(pad "1" smd custom
			(at 0 -0.4445 90)
			(size 0.1524 0.1524)
			(layers "B.Cu" "B.Mask" "B.Paste")
			(net "P1V8_C")
			(options
				(clearance outline)
				(anchor circle)
			)
			(primitives
				(gr_poly
					(pts
						(arc
							(start 0.3048 0.2032)
							(mid 0.275042 0.275042)
							(end 0.2032 0.3048)
						)
						(arc
							(start -0.2032 0.3048)
							(mid -0.275042 0.275042)
							(end -0.3048 0.2032)
						)
						(arc
							(start -0.3048 -0.2032)
							(mid -0.275042 -0.275042)
							(end -0.2032 -0.3048)
						)
						(arc
							(start 0.2032 -0.3048)
							(mid 0.275042 -0.275042)
							(end 0.3048 -0.2032)
						)
					)
					(width 0)
					(fill yes)
				)
			)
		)
		(pad "2" smd custom
			(at 0 0.4445 90)
			(size 0.1524 0.1524)
			(layers "B.Cu" "B.Mask" "B.Paste")
			(net "GND")
			(options
				(clearance outline)
				(anchor circle)
			)
			(primitives
				(gr_poly
					(pts
						(arc
							(start 0.3048 0.2032)
							(mid 0.275042 0.275042)
							(end 0.2032 0.3048)
						)
						(arc
							(start -0.2032 0.3048)
							(mid -0.275042 0.275042)
							(end -0.3048 0.2032)
						)
						(arc
							(start -0.3048 -0.2032)
							(mid -0.275042 -0.275042)
							(end -0.2032 -0.3048)
						)
						(arc
							(start 0.2032 -0.3048)
							(mid 0.275042 -0.275042)
							(end 0.3048 -0.2032)
						)
					)
					(width 0)
					(fill yes)
				)
			)
		)
	)
	(footprint ""
		(layer "B.Cu")
		(at 138.221212 -245.491)
		(property "Reference" "R148"
			(at 0 0 0)
			(layer "B.SilkS")
			(hide yes)
			(effects
				(font
					(size 1.27 1.27)
				)
				(justify mirror)
			)
		)
		(property "Value" "0R2J-2-GP"
			(at -0.064008 -3.993896 0)
			(unlocked yes)
			(layer "B.Fab")
			(hide yes)
			(effects
				(font
					(size 1.016 1.016)
					(thickness 0.1524)
				)
				(justify mirror)
			)
		)
		(property "Device Type" "R402H16"
			(at -0.064008 -5.517896 0)
			(unlocked yes)
			(layer "B.Fab")
			(hide yes)
			(effects
				(font
					(size 1.016 1.016)
					(thickness 0.1524)
				)
				(justify mirror)
			)
		)
		(duplicate_pad_numbers_are_jumpers no)
		(fp_line
			(start -0.508 -0.9398)
			(end 0.508 -0.9398)
			(stroke
				(width 0.1524)
				(type default)
			)
			(layer "B.SilkS")
		)
		(fp_line
			(start 0.508 -0.9398)
			(end 0.508 0.9398)
			(stroke
				(width 0.1524)
				(type default)
			)
			(layer "B.SilkS")
		)
		(fp_rect
			(start 0.508 0.9398)
			(end -0.508 -0.9398)
			(stroke
				(width 0)
				(type default)
			)
			(fill no)
			(layer "B.CrtYd")
		)
		(fp_rect
			(start 0.508 0.9398)
			(end -0.508 -0.9398)
			(stroke
				(width 0)
				(type default)
			)
			(fill no)
			(layer "B.Fab")
		)
		(pad "1" smd custom
			(at 0 -0.4445 180)
			(size 0.1397 0.1397)
			(layers "B.Cu" "B.Mask" "B.Paste")
			(net "TRAY_ID")
			(options
				(clearance outline)
				(anchor circle)
			)
			(primitives
				(gr_poly
					(pts
						(arc
							(start -0.1778 0.2794)
							(mid -0.249642 0.249642)
							(end -0.2794 0.1778)
						)
						(arc
							(start -0.2794 -0.1778)
							(mid -0.249642 -0.249642)
							(end -0.1778 -0.2794)
						)
						(arc
							(start 0.1778 -0.2794)
							(mid 0.249642 -0.249642)
							(end 0.2794 -0.1778)
						)
						(arc
							(start 0.2794 0.1778)
							(mid 0.249642 0.249642)
							(end 0.1778 0.2794)
						)
					)
					(width 0)
					(fill yes)
				)
			)
		)
		(pad "2" smd custom
			(at 0 0.4445 180)
			(size 0.1397 0.1397)
			(layers "B.Cu" "B.Mask" "B.Paste")
			(net "EXP_TRAY_ID")
			(options
				(clearance outline)
				(anchor circle)
			)
			(primitives
				(gr_poly
					(pts
						(arc
							(start -0.1778 0.2794)
							(mid -0.249642 0.249642)
							(end -0.2794 0.1778)
						)
						(arc
							(start -0.2794 -0.1778)
							(mid -0.249642 -0.249642)
							(end -0.1778 -0.2794)
						)
						(arc
							(start 0.1778 -0.2794)
							(mid 0.249642 -0.249642)
							(end 0.2794 -0.1778)
						)
						(arc
							(start 0.2794 0.1778)
							(mid 0.249642 0.249642)
							(end 0.1778 0.2794)
						)
					)
					(width 0)
					(fill yes)
				)
			)
		)
	)
	(footprint ""
		(layer "B.Cu")
		(at 11.938 -220.599 90)
		(property "Reference" "SR316"
			(at 0 0 90)
			(layer "B.SilkS")
			(hide yes)
			(effects
				(font
					(size 1.27 1.27)
				)
				(justify mirror)
			)
		)
		(property "Value" "0R2J-2-GP"
			(at -0.064008 -3.993896 90)
			(unlocked yes)
			(layer "B.Fab")
			(hide yes)
			(effects
				(font
					(size 1.016 1.016)
					(thickness 0.1524)
				)
				(justify mirror)
			)
		)
		(property "Device Type" "R402H16"
			(at -0.064008 -5.517896 90)
			(unlocked yes)
			(layer "B.Fab")
			(hide yes)
			(effects
				(font
					(size 1.016 1.016)
					(thickness 0.1524)
				)
				(justify mirror)
			)
		)
		(duplicate_pad_numbers_are_jumpers no)
		(fp_line
			(start 0.508 -0.9398)
			(end 0.508 0.9398)
			(stroke
				(width 0.1524)
				(type default)
			)
			(layer "B.SilkS")
		)
		(fp_line
			(start -0.508 -0.9398)
			(end 0.508 -0.9398)
			(stroke
				(width 0.1524)
				(type default)
			)
			(layer "B.SilkS")
		)
		(fp_rect
			(start 0.508 0.9398)
			(end -0.508 -0.9398)
			(stroke
				(width 0)
				(type default)
			)
			(fill no)
			(layer "B.CrtYd")
		)
		(fp_rect
			(start 0.508 0.9398)
			(end -0.508 -0.9398)
			(stroke
				(width 0)
				(type default)
			)
			(fill no)
			(layer "B.Fab")
		)
		(pad "1" smd custom
			(at 0 -0.4445 270)
			(size 0.1397 0.1397)
			(layers "B.Cu" "B.Mask" "B.Paste")
			(net "EXP_SDA_0")
			(options
				(clearance outline)
				(anchor circle)
			)
			(primitives
				(gr_poly
					(pts
						(arc
							(start -0.1778 0.2794)
							(mid -0.249642 0.249642)
							(end -0.2794 0.1778)
						)
						(arc
							(start -0.2794 -0.1778)
							(mid -0.249642 -0.249642)
							(end -0.1778 -0.2794)
						)
						(arc
							(start 0.1778 -0.2794)
							(mid 0.249642 -0.249642)
							(end 0.2794 -0.1778)
						)
						(arc
							(start 0.2794 0.1778)
							(mid 0.249642 0.249642)
							(end 0.1778 0.2794)
						)
					)
					(width 0)
					(fill yes)
				)
			)
		)
		(pad "2" smd custom
			(at 0 0.4445 270)
			(size 0.1397 0.1397)
			(layers "B.Cu" "B.Mask" "B.Paste")
			(net "BMC_IOEXP_SDA_10")
			(options
				(clearance outline)
				(anchor circle)
			)
			(primitives
				(gr_poly
					(pts
						(arc
							(start -0.1778 0.2794)
							(mid -0.249642 0.249642)
							(end -0.2794 0.1778)
						)
						(arc
							(start -0.2794 -0.1778)
							(mid -0.249642 -0.249642)
							(end -0.1778 -0.2794)
						)
						(arc
							(start 0.1778 -0.2794)
							(mid 0.249642 -0.249642)
							(end 0.2794 -0.1778)
						)
						(arc
							(start 0.2794 0.1778)
							(mid 0.249642 0.249642)
							(end 0.1778 0.2794)
						)
					)
					(width 0)
					(fill yes)
				)
			)
		)
	)
	(footprint ""
		(layer "B.Cu")
		(at 122.56897 -96.393 180)
		(property "Reference" "SC1187"
			(at 0 0 0)
			(layer "B.SilkS")
			(hide yes)
			(effects
				(font
					(size 1.27 1.27)
				)
				(justify mirror)
			)
		)
		(property "Value" "SCD1U6D3V1KX-GP"
			(at 2.8321 -1.7399 180)
			(unlocked yes)
			(layer "B.Fab")
			(hide yes)
			(effects
				(font
					(size 1.016 1.016)
					(thickness 0.1524)
				)
				(justify mirror)
			)
		)
		(property "Device Type" "C0201H13"
			(at 2.8321 -3.2639 180)
			(unlocked yes)
			(layer "B.Fab")
			(hide yes)
			(effects
				(font
					(size 1.016 1.016)
					(thickness 0.1524)
				)
				(justify mirror)
			)
		)
		(duplicate_pad_numbers_are_jumpers no)
		(fp_rect
			(start 0.2794 0.6477)
			(end -0.2794 -0.6477)
			(stroke
				(width 0)
				(type default)
			)
			(fill no)
			(layer "B.CrtYd")
		)
		(fp_rect
			(start 0.2794 0.6477)
			(end -0.2794 -0.6477)
			(stroke
				(width 0)
				(type default)
			)
			(fill no)
			(layer "B.Fab")
		)
		(pad "1" smd custom
			(at 0 -0.2794)
			(size 0.0762 0.0762)
			(layers "B.Cu" "B.Mask" "B.Paste")
			(net "GB_VDDA")
			(options
				(clearance outline)
				(anchor circle)
			)
			(primitives
				(gr_poly
					(pts
						(arc
							(start 0.1524 0.127)
							(mid 0.137521 0.162921)
							(end 0.1016 0.1778)
						)
						(arc
							(start -0.1016 0.1778)
							(mid -0.137521 0.162921)
							(end -0.1524 0.127)
						)
						(arc
							(start -0.1524 -0.127)
							(mid -0.137521 -0.162921)
							(end -0.1016 -0.1778)
						)
						(arc
							(start 0.1016 -0.1778)
							(mid 0.137521 -0.162921)
							(end 0.1524 -0.127)
						)
					)
					(width 0)
					(fill yes)
				)
			)
		)
		(pad "2" smd custom
			(at 0 0.2794)
			(size 0.0762 0.0762)
			(layers "B.Cu" "B.Mask" "B.Paste")
			(net "GND")
			(options
				(clearance outline)
				(anchor circle)
			)
			(primitives
				(gr_poly
					(pts
						(arc
							(start 0.1524 0.127)
							(mid 0.137521 0.162921)
							(end 0.1016 0.1778)
						)
						(arc
							(start -0.1016 0.1778)
							(mid -0.137521 0.162921)
							(end -0.1524 0.127)
						)
						(arc
							(start -0.1524 -0.127)
							(mid -0.137521 -0.162921)
							(end -0.1016 -0.1778)
						)
						(arc
							(start 0.1016 -0.1778)
							(mid 0.137521 -0.162921)
							(end 0.1524 -0.127)
						)
					)
					(width 0)
					(fill yes)
				)
			)
		)
	)
	(footprint ""
		(layer "B.Cu")
		(at 109.544612 -221.996)
		(property "Reference" "SR896"
			(at 0 0 0)
			(layer "B.SilkS")
			(hide yes)
			(effects
				(font
					(size 1.27 1.27)
				)
				(justify mirror)
			)
		)
		(property "Value" "0R2J-2-GP"
			(at -0.064008 -3.993896 0)
			(unlocked yes)
			(layer "B.Fab")
			(hide yes)
			(effects
				(font
					(size 1.016 1.016)
					(thickness 0.1524)
				)
				(justify mirror)
			)
		)
		(property "Device Type" "R402H16"
			(at -0.064008 -5.517896 0)
			(unlocked yes)
			(layer "B.Fab")
			(hide yes)
			(effects
				(font
					(size 1.016 1.016)
					(thickness 0.1524)
				)
				(justify mirror)
			)
		)
		(duplicate_pad_numbers_are_jumpers no)
		(fp_line
			(start -0.508 -0.9398)
			(end 0.508 -0.9398)
			(stroke
				(width 0.1524)
				(type default)
			)
			(layer "B.SilkS")
		)
		(fp_line
			(start 0.508 -0.9398)
			(end 0.508 0.9398)
			(stroke
				(width 0.1524)
				(type default)
			)
			(layer "B.SilkS")
		)
		(fp_rect
			(start 0.508 0.9398)
			(end -0.508 -0.9398)
			(stroke
				(width 0)
				(type default)
			)
			(fill no)
			(layer "B.CrtYd")
		)
		(fp_rect
			(start 0.508 0.9398)
			(end -0.508 -0.9398)
			(stroke
				(width 0)
				(type default)
			)
			(fill no)
			(layer "B.Fab")
		)
		(pad "1" smd custom
			(at 0 -0.4445 180)
			(size 0.1397 0.1397)
			(layers "B.Cu" "B.Mask" "B.Paste")
			(net "SAS_GF_EXP_RX_DN8")
			(options
				(clearance outline)
				(anchor circle)
			)
			(primitives
				(gr_poly
					(pts
						(arc
							(start -0.1778 0.2794)
							(mid -0.249642 0.249642)
							(end -0.2794 0.1778)
						)
						(arc
							(start -0.2794 -0.1778)
							(mid -0.249642 -0.249642)
							(end -0.1778 -0.2794)
						)
						(arc
							(start 0.1778 -0.2794)
							(mid 0.249642 -0.249642)
							(end 0.2794 -0.1778)
						)
						(arc
							(start 0.2794 0.1778)
							(mid 0.249642 0.249642)
							(end 0.1778 0.2794)
						)
					)
					(width 0)
					(fill yes)
				)
			)
		)
		(pad "2" smd custom
			(at 0 0.4445 180)
			(size 0.1397 0.1397)
			(layers "B.Cu" "B.Mask" "B.Paste")
			(net "SAS_HDD_CONN_SER_RX8_N")
			(options
				(clearance outline)
				(anchor circle)
			)
			(primitives
				(gr_poly
					(pts
						(arc
							(start -0.1778 0.2794)
							(mid -0.249642 0.249642)
							(end -0.2794 0.1778)
						)
						(arc
							(start -0.2794 -0.1778)
							(mid -0.249642 -0.249642)
							(end -0.1778 -0.2794)
						)
						(arc
							(start 0.1778 -0.2794)
							(mid 0.249642 -0.249642)
							(end 0.2794 -0.1778)
						)
						(arc
							(start 0.2794 0.1778)
							(mid 0.249642 0.249642)
							(end 0.1778 0.2794)
						)
					)
					(width 0)
					(fill yes)
				)
			)
		)
	)
	(footprint ""
		(layer "B.Cu")
		(at 81.153 -18.796 180)
		(property "Reference" "PC212"
			(at 0 0 0)
			(layer "B.SilkS")
			(hide yes)
			(effects
				(font
					(size 1.27 1.27)
				)
				(justify mirror)
			)
		)
		(property "Value" "SC1U25V3KX-GP"
			(at 0 -2.8194 180)
			(unlocked yes)
			(layer "B.Fab")
			(hide yes)
			(effects
				(font
					(size 1.016 1.016)
					(thickness 0.1524)
				)
				(justify mirror)
			)
		)
		(property "Device Type" "C603H36"
			(at 0 -4.3434 180)
			(unlocked yes)
			(layer "B.Fab")
			(hide yes)
			(effects
				(font
					(size 1.016 1.016)
					(thickness 0.1524)
				)
				(justify mirror)
			)
		)
		(duplicate_pad_numbers_are_jumpers no)
		(fp_line
			(start -0.508 0)
			(end 0.508 0)
			(stroke
				(width 0.2032)
				(type default)
			)
			(layer "B.SilkS")
		)
		(fp_rect
			(start 0.5842 1.3335)
			(end -0.5842 -1.3335)
			(stroke
				(width 0)
				(type default)
			)
			(fill no)
			(layer "B.CrtYd")
		)
		(fp_rect
			(start 0.5842 1.3335)
			(end -0.5842 -1.3335)
			(stroke
				(width 0)
				(type default)
			)
			(fill no)
			(layer "B.Fab")
		)
		(pad "1" smd custom
			(at 0 -0.762)
			(size 0.2159 0.2159)
			(layers "B.Cu" "B.Mask" "B.Paste")
			(net "VT235_AVDD")
			(options
				(clearance outline)
				(anchor circle)
			)
			(primitives
				(gr_poly
					(pts
						(arc
							(start -0.3302 0.4318)
							(mid -0.402042 0.402042)
							(end -0.4318 0.3302)
						)
						(arc
							(start -0.4318 -0.3302)
							(mid -0.402042 -0.402042)
							(end -0.3302 -0.4318)
						)
						(arc
							(start 0.3302 -0.4318)
							(mid 0.402042 -0.402042)
							(end 0.4318 -0.3302)
						)
						(arc
							(start 0.4318 0.3302)
							(mid 0.402042 0.402042)
							(end 0.3302 0.4318)
						)
					)
					(width 0)
					(fill yes)
				)
			)
		)
		(pad "2" smd custom
			(at 0 0.762)
			(size 0.2159 0.2159)
			(layers "B.Cu" "B.Mask" "B.Paste")
			(net "AGND_P0V9_C")
			(options
				(clearance outline)
				(anchor circle)
			)
			(primitives
				(gr_poly
					(pts
						(arc
							(start -0.3302 0.4318)
							(mid -0.402042 0.402042)
							(end -0.4318 0.3302)
						)
						(arc
							(start -0.4318 -0.3302)
							(mid -0.402042 -0.402042)
							(end -0.3302 -0.4318)
						)
						(arc
							(start 0.3302 -0.4318)
							(mid 0.402042 -0.402042)
							(end 0.4318 -0.3302)
						)
						(arc
							(start 0.4318 0.3302)
							(mid 0.402042 0.402042)
							(end 0.3302 0.4318)
						)
					)
					(width 0)
					(fill yes)
				)
			)
		)
	)
	(footprint ""
		(layer "B.Cu")
		(at 101.854 -239.395)
		(property "Reference" "SR845"
			(at 0 0 0)
			(layer "B.SilkS")
			(hide yes)
			(effects
				(font
					(size 1.27 1.27)
				)
				(justify mirror)
			)
		)
		(property "Value" "4K7R2F-GP"
			(at -0.064008 -3.993896 0)
			(unlocked yes)
			(layer "B.Fab")
			(hide yes)
			(effects
				(font
					(size 1.016 1.016)
					(thickness 0.1524)
				)
				(justify mirror)
			)
		)
		(property "Device Type" "R402H16"
			(at -0.064008 -5.517896 0)
			(unlocked yes)
			(layer "B.Fab")
			(hide yes)
			(effects
				(font
					(size 1.016 1.016)
					(thickness 0.1524)
				)
				(justify mirror)
			)
		)
		(duplicate_pad_numbers_are_jumpers no)
		(fp_line
			(start -0.508 -0.9398)
			(end 0.508 -0.9398)
			(stroke
				(width 0.1524)
				(type default)
			)
			(layer "B.SilkS")
		)
		(fp_line
			(start 0.508 -0.9398)
			(end 0.508 0.9398)
			(stroke
				(width 0.1524)
				(type default)
			)
			(layer "B.SilkS")
		)
		(fp_rect
			(start 0.508 0.9398)
			(end -0.508 -0.9398)
			(stroke
				(width 0)
				(type default)
			)
			(fill no)
			(layer "B.CrtYd")
		)
		(fp_rect
			(start 0.508 0.9398)
			(end -0.508 -0.9398)
			(stroke
				(width 0)
				(type default)
			)
			(fill no)
			(layer "B.Fab")
		)
		(pad "1" smd custom
			(at 0 -0.4445 180)
			(size 0.1397 0.1397)
			(layers "B.Cu" "B.Mask" "B.Paste")
			(net "SAS_FAULT_LED2")
			(options
				(clearance outline)
				(anchor circle)
			)
			(primitives
				(gr_poly
					(pts
						(arc
							(start -0.1778 0.2794)
							(mid -0.249642 0.249642)
							(end -0.2794 0.1778)
						)
						(arc
							(start -0.2794 -0.1778)
							(mid -0.249642 -0.249642)
							(end -0.1778 -0.2794)
						)
						(arc
							(start 0.1778 -0.2794)
							(mid 0.249642 -0.249642)
							(end 0.2794 -0.1778)
						)
						(arc
							(start 0.2794 0.1778)
							(mid 0.249642 0.249642)
							(end 0.1778 0.2794)
						)
					)
					(width 0)
					(fill yes)
				)
			)
		)
		(pad "2" smd custom
			(at 0 0.4445 180)
			(size 0.1397 0.1397)
			(layers "B.Cu" "B.Mask" "B.Paste")
			(net "P3V3_STBY")
			(options
				(clearance outline)
				(anchor circle)
			)
			(primitives
				(gr_poly
					(pts
						(arc
							(start -0.1778 0.2794)
							(mid -0.249642 0.249642)
							(end -0.2794 0.1778)
						)
						(arc
							(start -0.2794 -0.1778)
							(mid -0.249642 -0.249642)
							(end -0.1778 -0.2794)
						)
						(arc
							(start 0.1778 -0.2794)
							(mid 0.249642 -0.249642)
							(end 0.2794 -0.1778)
						)
						(arc
							(start 0.2794 0.1778)
							(mid 0.249642 0.249642)
							(end 0.1778 0.2794)
						)
					)
					(width 0)
					(fill yes)
				)
			)
		)
	)
	(footprint ""
		(layer "B.Cu")
		(at 114.82197 -86.868 -90)
		(property "Reference" "SC1234"
			(at 0 0 90)
			(layer "B.SilkS")
			(hide yes)
			(effects
				(font
					(size 1.27 1.27)
				)
				(justify mirror)
			)
		)
		(property "Value" "SCD1U6D3V1KX-GP"
			(at 2.8321 -1.7399 270)
			(unlocked yes)
			(layer "B.Fab")
			(hide yes)
			(effects
				(font
					(size 1.016 1.016)
					(thickness 0.1524)
				)
				(justify mirror)
			)
		)
		(property "Device Type" "C0201H13"
			(at 2.8321 -3.2639 270)
			(unlocked yes)
			(layer "B.Fab")
			(hide yes)
			(effects
				(font
					(size 1.016 1.016)
					(thickness 0.1524)
				)
				(justify mirror)
			)
		)
		(duplicate_pad_numbers_are_jumpers no)
		(fp_rect
			(start 0.2794 0.6477)
			(end -0.2794 -0.6477)
			(stroke
				(width 0)
				(type default)
			)
			(fill no)
			(layer "B.CrtYd")
		)
		(fp_rect
			(start 0.2794 0.6477)
			(end -0.2794 -0.6477)
			(stroke
				(width 0)
				(type default)
			)
			(fill no)
			(layer "B.Fab")
		)
		(pad "1" smd custom
			(at 0 -0.2794 90)
			(size 0.0762 0.0762)
			(layers "B.Cu" "B.Mask" "B.Paste")
			(net "P1V8_E")
			(options
				(clearance outline)
				(anchor circle)
			)
			(primitives
				(gr_poly
					(pts
						(arc
							(start 0.1524 0.127)
							(mid 0.137521 0.162921)
							(end 0.1016 0.1778)
						)
						(arc
							(start -0.1016 0.1778)
							(mid -0.137521 0.162921)
							(end -0.1524 0.127)
						)
						(arc
							(start -0.1524 -0.127)
							(mid -0.137521 -0.162921)
							(end -0.1016 -0.1778)
						)
						(arc
							(start 0.1016 -0.1778)
							(mid 0.137521 -0.162921)
							(end 0.1524 -0.127)
						)
					)
					(width 0)
					(fill yes)
				)
			)
		)
		(pad "2" smd custom
			(at 0 0.2794 90)
			(size 0.0762 0.0762)
			(layers "B.Cu" "B.Mask" "B.Paste")
			(net "GND")
			(options
				(clearance outline)
				(anchor circle)
			)
			(primitives
				(gr_poly
					(pts
						(arc
							(start 0.1524 0.127)
							(mid 0.137521 0.162921)
							(end 0.1016 0.1778)
						)
						(arc
							(start -0.1016 0.1778)
							(mid -0.137521 0.162921)
							(end -0.1524 0.127)
						)
						(arc
							(start -0.1524 -0.127)
							(mid -0.137521 -0.162921)
							(end -0.1016 -0.1778)
						)
						(arc
							(start 0.1016 -0.1778)
							(mid 0.137521 -0.162921)
							(end 0.1524 -0.127)
						)
					)
					(width 0)
					(fill yes)
				)
			)
		)
	)
	(footprint ""
		(layer "B.Cu")
		(at 110.30077 -88.6206 90)
		(property "Reference" "SC1225"
			(at 0 0 90)
			(layer "B.SilkS")
			(hide yes)
			(effects
				(font
					(size 1.27 1.27)
				)
				(justify mirror)
			)
		)
		(property "Value" "SCD1U6D3V1KX-GP"
			(at 2.8321 -1.7399 90)
			(unlocked yes)
			(layer "B.Fab")
			(hide yes)
			(effects
				(font
					(size 1.016 1.016)
					(thickness 0.1524)
				)
				(justify mirror)
			)
		)
		(property "Device Type" "C0201H13"
			(at 2.8321 -3.2639 90)
			(unlocked yes)
			(layer "B.Fab")
			(hide yes)
			(effects
				(font
					(size 1.016 1.016)
					(thickness 0.1524)
				)
				(justify mirror)
			)
		)
		(duplicate_pad_numbers_are_jumpers no)
		(fp_rect
			(start 0.2794 0.6477)
			(end -0.2794 -0.6477)
			(stroke
				(width 0)
				(type default)
			)
			(fill no)
			(layer "B.CrtYd")
		)
		(fp_rect
			(start 0.2794 0.6477)
			(end -0.2794 -0.6477)
			(stroke
				(width 0)
				(type default)
			)
			(fill no)
			(layer "B.Fab")
		)
		(pad "1" smd custom
			(at 0 -0.2794 270)
			(size 0.0762 0.0762)
			(layers "B.Cu" "B.Mask" "B.Paste")
			(net "P1V8_E")
			(options
				(clearance outline)
				(anchor circle)
			)
			(primitives
				(gr_poly
					(pts
						(arc
							(start 0.1524 0.127)
							(mid 0.137521 0.162921)
							(end 0.1016 0.1778)
						)
						(arc
							(start -0.1016 0.1778)
							(mid -0.137521 0.162921)
							(end -0.1524 0.127)
						)
						(arc
							(start -0.1524 -0.127)
							(mid -0.137521 -0.162921)
							(end -0.1016 -0.1778)
						)
						(arc
							(start 0.1016 -0.1778)
							(mid 0.137521 -0.162921)
							(end 0.1524 -0.127)
						)
					)
					(width 0)
					(fill yes)
				)
			)
		)
		(pad "2" smd custom
			(at 0 0.2794 270)
			(size 0.0762 0.0762)
			(layers "B.Cu" "B.Mask" "B.Paste")
			(net "GND")
			(options
				(clearance outline)
				(anchor circle)
			)
			(primitives
				(gr_poly
					(pts
						(arc
							(start 0.1524 0.127)
							(mid 0.137521 0.162921)
							(end 0.1016 0.1778)
						)
						(arc
							(start -0.1016 0.1778)
							(mid -0.137521 0.162921)
							(end -0.1524 0.127)
						)
						(arc
							(start -0.1524 -0.127)
							(mid -0.137521 -0.162921)
							(end -0.1016 -0.1778)
						)
						(arc
							(start 0.1016 -0.1778)
							(mid 0.137521 -0.162921)
							(end 0.1524 -0.127)
						)
					)
					(width 0)
					(fill yes)
				)
			)
		)
	)
	(footprint ""
		(layer "B.Cu")
		(at 328.295 -105.41)
		(property "Reference" "PR26"
			(at 0 0 0)
			(layer "B.SilkS")
			(hide yes)
			(effects
				(font
					(size 1.27 1.27)
				)
				(justify mirror)
			)
		)
		(property "Value" "3K9R2F-GP"
			(at -0.064008 -3.993896 0)
			(unlocked yes)
			(layer "B.Fab")
			(hide yes)
			(effects
				(font
					(size 1.016 1.016)
					(thickness 0.1524)
				)
				(justify mirror)
			)
		)
		(property "Device Type" "R402H16"
			(at -0.064008 -5.517896 0)
			(unlocked yes)
			(layer "B.Fab")
			(hide yes)
			(effects
				(font
					(size 1.016 1.016)
					(thickness 0.1524)
				)
				(justify mirror)
			)
		)
		(duplicate_pad_numbers_are_jumpers no)
		(fp_line
			(start -0.508 -0.9398)
			(end 0.508 -0.9398)
			(stroke
				(width 0.1524)
				(type default)
			)
			(layer "B.SilkS")
		)
		(fp_line
			(start 0.508 -0.9398)
			(end 0.508 0.9398)
			(stroke
				(width 0.1524)
				(type default)
			)
			(layer "B.SilkS")
		)
		(fp_rect
			(start 0.508 0.9398)
			(end -0.508 -0.9398)
			(stroke
				(width 0)
				(type default)
			)
			(fill no)
			(layer "B.CrtYd")
		)
		(fp_rect
			(start 0.508 0.9398)
			(end -0.508 -0.9398)
			(stroke
				(width 0)
				(type default)
			)
			(fill no)
			(layer "B.Fab")
		)
		(pad "1" smd custom
			(at 0 -0.4445 180)
			(size 0.1397 0.1397)
			(layers "B.Cu" "B.Mask" "B.Paste")
			(net "P3V3_STBY_LL")
			(options
				(clearance outline)
				(anchor circle)
			)
			(primitives
				(gr_poly
					(pts
						(arc
							(start -0.1778 0.2794)
							(mid -0.249642 0.249642)
							(end -0.2794 0.1778)
						)
						(arc
							(start -0.2794 -0.1778)
							(mid -0.249642 -0.249642)
							(end -0.1778 -0.2794)
						)
						(arc
							(start 0.1778 -0.2794)
							(mid 0.249642 -0.249642)
							(end 0.2794 -0.1778)
						)
						(arc
							(start 0.2794 0.1778)
							(mid 0.249642 0.249642)
							(end 0.1778 0.2794)
						)
					)
					(width 0)
					(fill yes)
				)
			)
		)
		(pad "2" smd custom
			(at 0 0.4445 180)
			(size 0.1397 0.1397)
			(layers "B.Cu" "B.Mask" "B.Paste")
			(net "P3V3_STBY_LL_R")
			(options
				(clearance outline)
				(anchor circle)
			)
			(primitives
				(gr_poly
					(pts
						(arc
							(start -0.1778 0.2794)
							(mid -0.249642 0.249642)
							(end -0.2794 0.1778)
						)
						(arc
							(start -0.2794 -0.1778)
							(mid -0.249642 -0.249642)
							(end -0.1778 -0.2794)
						)
						(arc
							(start 0.1778 -0.2794)
							(mid 0.249642 -0.249642)
							(end 0.2794 -0.1778)
						)
						(arc
							(start 0.2794 0.1778)
							(mid 0.249642 0.249642)
							(end 0.1778 0.2794)
						)
					)
					(width 0)
					(fill yes)
				)
			)
		)
	)
	(footprint ""
		(layer "B.Cu")
		(at 274.193 -162.56 -90)
		(property "Reference" "R327"
			(at 0 0 90)
			(layer "B.SilkS")
			(hide yes)
			(effects
				(font
					(size 1.27 1.27)
				)
				(justify mirror)
			)
		)
		(property "Value" "100KR2F-L1-GP"
			(at -0.064008 -3.993896 270)
			(unlocked yes)
			(layer "B.Fab")
			(hide yes)
			(effects
				(font
					(size 1.016 1.016)
					(thickness 0.1524)
				)
				(justify mirror)
			)
		)
		(property "Device Type" "R402H16"
			(at -0.064008 -5.517896 270)
			(unlocked yes)
			(layer "B.Fab")
			(hide yes)
			(effects
				(font
					(size 1.016 1.016)
					(thickness 0.1524)
				)
				(justify mirror)
			)
		)
		(duplicate_pad_numbers_are_jumpers no)
		(fp_line
			(start -0.508 -0.9398)
			(end 0.508 -0.9398)
			(stroke
				(width 0.1524)
				(type default)
			)
			(layer "B.SilkS")
		)
		(fp_line
			(start 0.508 -0.9398)
			(end 0.508 0.9398)
			(stroke
				(width 0.1524)
				(type default)
			)
			(layer "B.SilkS")
		)
		(fp_rect
			(start 0.508 0.9398)
			(end -0.508 -0.9398)
			(stroke
				(width 0)
				(type default)
			)
			(fill no)
			(layer "B.CrtYd")
		)
		(fp_rect
			(start 0.508 0.9398)
			(end -0.508 -0.9398)
			(stroke
				(width 0)
				(type default)
			)
			(fill no)
			(layer "B.Fab")
		)
		(pad "1" smd custom
			(at 0 -0.4445 90)
			(size 0.1397 0.1397)
			(layers "B.Cu" "B.Mask" "B.Paste")
			(net "LPCRST0_N")
			(options
				(clearance outline)
				(anchor circle)
			)
			(primitives
				(gr_poly
					(pts
						(arc
							(start -0.1778 0.2794)
							(mid -0.249642 0.249642)
							(end -0.2794 0.1778)
						)
						(arc
							(start -0.2794 -0.1778)
							(mid -0.249642 -0.249642)
							(end -0.1778 -0.2794)
						)
						(arc
							(start 0.1778 -0.2794)
							(mid 0.249642 -0.249642)
							(end 0.2794 -0.1778)
						)
						(arc
							(start 0.2794 0.1778)
							(mid 0.249642 0.249642)
							(end 0.1778 0.2794)
						)
					)
					(width 0)
					(fill yes)
				)
			)
		)
		(pad "2" smd custom
			(at 0 0.4445 90)
			(size 0.1397 0.1397)
			(layers "B.Cu" "B.Mask" "B.Paste")
			(net "GND")
			(options
				(clearance outline)
				(anchor circle)
			)
			(primitives
				(gr_poly
					(pts
						(arc
							(start -0.1778 0.2794)
							(mid -0.249642 0.249642)
							(end -0.2794 0.1778)
						)
						(arc
							(start -0.2794 -0.1778)
							(mid -0.249642 -0.249642)
							(end -0.1778 -0.2794)
						)
						(arc
							(start 0.1778 -0.2794)
							(mid 0.249642 -0.249642)
							(end 0.2794 -0.1778)
						)
						(arc
							(start 0.2794 0.1778)
							(mid 0.249642 0.249642)
							(end 0.1778 0.2794)
						)
					)
					(width 0)
					(fill yes)
				)
			)
		)
	)
	(footprint ""
		(layer "B.Cu")
		(at 109.555534 -59.15152)
		(property "Reference" "STP151"
			(at 0 0 0)
			(layer "B.SilkS")
			(hide yes)
			(effects
				(font
					(size 1.27 1.27)
				)
				(justify mirror)
			)
		)
		(property "Value" "TPAD28"
			(at -0.0127 -1.8034 0)
			(unlocked yes)
			(layer "B.Fab")
			(hide yes)
			(effects
				(font
					(size 1.016 1.016)
					(thickness 0.1524)
				)
				(justify mirror)
			)
		)
		(property "Device Type" "TPAD28"
			(at -0.0127 -3.3274 0)
			(unlocked yes)
			(layer "B.Fab")
			(hide yes)
			(effects
				(font
					(size 1.016 1.016)
					(thickness 0.1524)
				)
				(justify mirror)
			)
		)
		(duplicate_pad_numbers_are_jumpers no)
		(fp_poly
			(pts
				(arc
					(start 0.3556 0)
					(mid -0.3556 0)
					(end 0.3556 0)
				)
			)
			(stroke
				(width 0)
				(type default)
			)
			(fill no)
			(layer "B.CrtYd")
		)
		(fp_poly
			(pts
				(arc
					(start 0.6096 0)
					(mid -0.6096 0)
					(end 0.6096 0)
				)
			)
			(stroke
				(width 0)
				(type default)
			)
			(fill no)
			(layer "B.Fab")
		)
		(pad "1" smd circle
			(at 0 0 180)
			(size 0.7112 0.7112)
			(layers "B.Cu" "B.Mask" "B.Paste")
			(net "XM_ADDR_0")
		)
	)
	(footprint ""
		(layer "B.Cu")
		(at 97.92716 -31.623)
		(property "Reference" "SC1296"
			(at 0 0 0)
			(layer "B.SilkS")
			(hide yes)
			(effects
				(font
					(size 1.27 1.27)
				)
				(justify mirror)
			)
		)
		(property "Value" "SCD22U6D3V1MX-1-GP"
			(at 2.8321 -1.7399 0)
			(unlocked yes)
			(layer "B.Fab")
			(hide yes)
			(effects
				(font
					(size 1.016 1.016)
					(thickness 0.1524)
				)
				(justify mirror)
			)
		)
		(property "Device Type" "C0201H13"
			(at 2.8321 -3.2639 0)
			(unlocked yes)
			(layer "B.Fab")
			(hide yes)
			(effects
				(font
					(size 1.016 1.016)
					(thickness 0.1524)
				)
				(justify mirror)
			)
		)
		(duplicate_pad_numbers_are_jumpers no)
		(fp_rect
			(start 0.2794 0.6477)
			(end -0.2794 -0.6477)
			(stroke
				(width 0)
				(type default)
			)
			(fill no)
			(layer "B.CrtYd")
		)
		(fp_rect
			(start 0.2794 0.6477)
			(end -0.2794 -0.6477)
			(stroke
				(width 0)
				(type default)
			)
			(fill no)
			(layer "B.Fab")
		)
		(pad "1" smd custom
			(at 0 -0.2794 180)
			(size 0.0762 0.0762)
			(layers "B.Cu" "B.Mask" "B.Paste")
			(net "PCIE_SAS_C_CPU_RX_P3")
			(options
				(clearance outline)
				(anchor circle)
			)
			(primitives
				(gr_poly
					(pts
						(arc
							(start 0.1524 0.127)
							(mid 0.137521 0.162921)
							(end 0.1016 0.1778)
						)
						(arc
							(start -0.1016 0.1778)
							(mid -0.137521 0.162921)
							(end -0.1524 0.127)
						)
						(arc
							(start -0.1524 -0.127)
							(mid -0.137521 -0.162921)
							(end -0.1016 -0.1778)
						)
						(arc
							(start 0.1016 -0.1778)
							(mid 0.137521 -0.162921)
							(end 0.1524 -0.127)
						)
					)
					(width 0)
					(fill yes)
				)
			)
		)
		(pad "2" smd custom
			(at 0 0.2794 180)
			(size 0.0762 0.0762)
			(layers "B.Cu" "B.Mask" "B.Paste")
			(net "PCIE_SAS_CPU_RX_P3")
			(options
				(clearance outline)
				(anchor circle)
			)
			(primitives
				(gr_poly
					(pts
						(arc
							(start 0.1524 0.127)
							(mid 0.137521 0.162921)
							(end 0.1016 0.1778)
						)
						(arc
							(start -0.1016 0.1778)
							(mid -0.137521 0.162921)
							(end -0.1524 0.127)
						)
						(arc
							(start -0.1524 -0.127)
							(mid -0.137521 -0.162921)
							(end -0.1016 -0.1778)
						)
						(arc
							(start 0.1016 -0.1778)
							(mid 0.137521 -0.162921)
							(end 0.1524 -0.127)
						)
					)
					(width 0)
					(fill yes)
				)
			)
		)
	)
	(footprint ""
		(layer "B.Cu")
		(at 127.01397 -99.822 90)
		(property "Reference" "SC1167"
			(at 0 0 90)
			(layer "B.SilkS")
			(hide yes)
			(effects
				(font
					(size 1.27 1.27)
				)
				(justify mirror)
			)
		)
		(property "Value" "SCD1U6D3V1KX-GP"
			(at 2.8321 -1.7399 90)
			(unlocked yes)
			(layer "B.Fab")
			(hide yes)
			(effects
				(font
					(size 1.016 1.016)
					(thickness 0.1524)
				)
				(justify mirror)
			)
		)
		(property "Device Type" "C0201H13"
			(at 2.8321 -3.2639 90)
			(unlocked yes)
			(layer "B.Fab")
			(hide yes)
			(effects
				(font
					(size 1.016 1.016)
					(thickness 0.1524)
				)
				(justify mirror)
			)
		)
		(duplicate_pad_numbers_are_jumpers no)
		(fp_rect
			(start 0.2794 0.6477)
			(end -0.2794 -0.6477)
			(stroke
				(width 0)
				(type default)
			)
			(fill no)
			(layer "B.CrtYd")
		)
		(fp_rect
			(start 0.2794 0.6477)
			(end -0.2794 -0.6477)
			(stroke
				(width 0)
				(type default)
			)
			(fill no)
			(layer "B.Fab")
		)
		(pad "1" smd custom
			(at 0 -0.2794 270)
			(size 0.0762 0.0762)
			(layers "B.Cu" "B.Mask" "B.Paste")
			(net "GB_VDDA")
			(options
				(clearance outline)
				(anchor circle)
			)
			(primitives
				(gr_poly
					(pts
						(arc
							(start 0.1524 0.127)
							(mid 0.137521 0.162921)
							(end 0.1016 0.1778)
						)
						(arc
							(start -0.1016 0.1778)
							(mid -0.137521 0.162921)
							(end -0.1524 0.127)
						)
						(arc
							(start -0.1524 -0.127)
							(mid -0.137521 -0.162921)
							(end -0.1016 -0.1778)
						)
						(arc
							(start 0.1016 -0.1778)
							(mid 0.137521 -0.162921)
							(end 0.1524 -0.127)
						)
					)
					(width 0)
					(fill yes)
				)
			)
		)
		(pad "2" smd custom
			(at 0 0.2794 270)
			(size 0.0762 0.0762)
			(layers "B.Cu" "B.Mask" "B.Paste")
			(net "GND")
			(options
				(clearance outline)
				(anchor circle)
			)
			(primitives
				(gr_poly
					(pts
						(arc
							(start 0.1524 0.127)
							(mid 0.137521 0.162921)
							(end 0.1016 0.1778)
						)
						(arc
							(start -0.1016 0.1778)
							(mid -0.137521 0.162921)
							(end -0.1524 0.127)
						)
						(arc
							(start -0.1524 -0.127)
							(mid -0.137521 -0.162921)
							(end -0.1016 -0.1778)
						)
						(arc
							(start 0.1016 -0.1778)
							(mid 0.137521 -0.162921)
							(end 0.1524 -0.127)
						)
					)
					(width 0)
					(fill yes)
				)
			)
		)
	)
	(footprint ""
		(layer "B.Cu")
		(at 108.18876 -38.9382 180)
		(property "Reference" "SR686"
			(at 0 0 0)
			(layer "B.SilkS")
			(hide yes)
			(effects
				(font
					(size 1.27 1.27)
				)
				(justify mirror)
			)
		)
		(property "Value" "10KR2F-2-GP"
			(at -0.064008 -3.993896 180)
			(unlocked yes)
			(layer "B.Fab")
			(hide yes)
			(effects
				(font
					(size 1.016 1.016)
					(thickness 0.1524)
				)
				(justify mirror)
			)
		)
		(property "Device Type" "R402H16"
			(at -0.064008 -5.517896 180)
			(unlocked yes)
			(layer "B.Fab")
			(hide yes)
			(effects
				(font
					(size 1.016 1.016)
					(thickness 0.1524)
				)
				(justify mirror)
			)
		)
		(duplicate_pad_numbers_are_jumpers no)
		(fp_line
			(start 0.508 -0.9398)
			(end 0.508 0.9398)
			(stroke
				(width 0.1524)
				(type default)
			)
			(layer "B.SilkS")
		)
		(fp_line
			(start -0.508 -0.9398)
			(end 0.508 -0.9398)
			(stroke
				(width 0.1524)
				(type default)
			)
			(layer "B.SilkS")
		)
		(fp_rect
			(start 0.508 0.9398)
			(end -0.508 -0.9398)
			(stroke
				(width 0)
				(type default)
			)
			(fill no)
			(layer "B.CrtYd")
		)
		(fp_rect
			(start 0.508 0.9398)
			(end -0.508 -0.9398)
			(stroke
				(width 0)
				(type default)
			)
			(fill no)
			(layer "B.Fab")
		)
		(pad "1" smd custom
			(at 0 -0.4445)
			(size 0.1397 0.1397)
			(layers "B.Cu" "B.Mask" "B.Paste")
			(net "SYS_DBMODE0")
			(options
				(clearance outline)
				(anchor circle)
			)
			(primitives
				(gr_poly
					(pts
						(arc
							(start -0.1778 0.2794)
							(mid -0.249642 0.249642)
							(end -0.2794 0.1778)
						)
						(arc
							(start -0.2794 -0.1778)
							(mid -0.249642 -0.249642)
							(end -0.1778 -0.2794)
						)
						(arc
							(start 0.1778 -0.2794)
							(mid 0.249642 -0.249642)
							(end 0.2794 -0.1778)
						)
						(arc
							(start 0.2794 0.1778)
							(mid 0.249642 0.249642)
							(end 0.1778 0.2794)
						)
					)
					(width 0)
					(fill yes)
				)
			)
		)
		(pad "2" smd custom
			(at 0 0.4445)
			(size 0.1397 0.1397)
			(layers "B.Cu" "B.Mask" "B.Paste")
			(net "GND")
			(options
				(clearance outline)
				(anchor circle)
			)
			(primitives
				(gr_poly
					(pts
						(arc
							(start -0.1778 0.2794)
							(mid -0.249642 0.249642)
							(end -0.2794 0.1778)
						)
						(arc
							(start -0.2794 -0.1778)
							(mid -0.249642 -0.249642)
							(end -0.1778 -0.2794)
						)
						(arc
							(start 0.1778 -0.2794)
							(mid 0.249642 -0.249642)
							(end 0.2794 -0.1778)
						)
						(arc
							(start 0.2794 0.1778)
							(mid 0.249642 0.249642)
							(end 0.1778 0.2794)
						)
					)
					(width 0)
					(fill yes)
				)
			)
		)
	)
	(footprint ""
		(layer "B.Cu")
		(at 318.008 -177.673 -90)
		(property "Reference" "R316"
			(at 0 0 90)
			(layer "B.SilkS")
			(hide yes)
			(effects
				(font
					(size 1.27 1.27)
				)
				(justify mirror)
			)
		)
		(property "Value" "0R2J-2-GP"
			(at -0.064008 -3.993896 270)
			(unlocked yes)
			(layer "B.Fab")
			(hide yes)
			(effects
				(font
					(size 1.016 1.016)
					(thickness 0.1524)
				)
				(justify mirror)
			)
		)
		(property "Device Type" "R402H16"
			(at -0.064008 -5.517896 270)
			(unlocked yes)
			(layer "B.Fab")
			(hide yes)
			(effects
				(font
					(size 1.016 1.016)
					(thickness 0.1524)
				)
				(justify mirror)
			)
		)
		(duplicate_pad_numbers_are_jumpers no)
		(fp_line
			(start -0.508 -0.9398)
			(end 0.508 -0.9398)
			(stroke
				(width 0.1524)
				(type default)
			)
			(layer "B.SilkS")
		)
		(fp_line
			(start 0.508 -0.9398)
			(end 0.508 0.9398)
			(stroke
				(width 0.1524)
				(type default)
			)
			(layer "B.SilkS")
		)
		(fp_rect
			(start 0.508 0.9398)
			(end -0.508 -0.9398)
			(stroke
				(width 0)
				(type default)
			)
			(fill no)
			(layer "B.CrtYd")
		)
		(fp_rect
			(start 0.508 0.9398)
			(end -0.508 -0.9398)
			(stroke
				(width 0)
				(type default)
			)
			(fill no)
			(layer "B.Fab")
		)
		(pad "1" smd custom
			(at 0 -0.4445 90)
			(size 0.1397 0.1397)
			(layers "B.Cu" "B.Mask" "B.Paste")
			(net "ADC_P5V_STBY")
			(options
				(clearance outline)
				(anchor circle)
			)
			(primitives
				(gr_poly
					(pts
						(arc
							(start -0.1778 0.2794)
							(mid -0.249642 0.249642)
							(end -0.2794 0.1778)
						)
						(arc
							(start -0.2794 -0.1778)
							(mid -0.249642 -0.249642)
							(end -0.1778 -0.2794)
						)
						(arc
							(start 0.1778 -0.2794)
							(mid 0.249642 -0.249642)
							(end 0.2794 -0.1778)
						)
						(arc
							(start 0.2794 0.1778)
							(mid 0.249642 0.249642)
							(end 0.1778 0.2794)
						)
					)
					(width 0)
					(fill yes)
				)
			)
		)
		(pad "2" smd custom
			(at 0 0.4445 90)
			(size 0.1397 0.1397)
			(layers "B.Cu" "B.Mask" "B.Paste")
			(net "ADC_P5V_STBY_BMC")
			(options
				(clearance outline)
				(anchor circle)
			)
			(primitives
				(gr_poly
					(pts
						(arc
							(start -0.1778 0.2794)
							(mid -0.249642 0.249642)
							(end -0.2794 0.1778)
						)
						(arc
							(start -0.2794 -0.1778)
							(mid -0.249642 -0.249642)
							(end -0.1778 -0.2794)
						)
						(arc
							(start 0.1778 -0.2794)
							(mid 0.249642 -0.249642)
							(end 0.2794 -0.1778)
						)
						(arc
							(start 0.2794 0.1778)
							(mid 0.249642 0.249642)
							(end 0.1778 0.2794)
						)
					)
					(width 0)
					(fill yes)
				)
			)
		)
	)
	(footprint ""
		(layer "B.Cu")
		(at 135.382 -37.719 90)
		(property "Reference" "SR660"
			(at 0 0 90)
			(layer "B.SilkS")
			(hide yes)
			(effects
				(font
					(size 1.27 1.27)
				)
				(justify mirror)
			)
		)
		(property "Value" "4K7R2F-GP"
			(at -0.064008 -3.993896 90)
			(unlocked yes)
			(layer "B.Fab")
			(hide yes)
			(effects
				(font
					(size 1.016 1.016)
					(thickness 0.1524)
				)
				(justify mirror)
			)
		)
		(property "Device Type" "R402H16"
			(at -0.064008 -5.517896 90)
			(unlocked yes)
			(layer "B.Fab")
			(hide yes)
			(effects
				(font
					(size 1.016 1.016)
					(thickness 0.1524)
				)
				(justify mirror)
			)
		)
		(duplicate_pad_numbers_are_jumpers no)
		(fp_line
			(start 0.508 -0.9398)
			(end 0.508 0.9398)
			(stroke
				(width 0.1524)
				(type default)
			)
			(layer "B.SilkS")
		)
		(fp_line
			(start -0.508 -0.9398)
			(end 0.508 -0.9398)
			(stroke
				(width 0.1524)
				(type default)
			)
			(layer "B.SilkS")
		)
		(fp_rect
			(start 0.508 0.9398)
			(end -0.508 -0.9398)
			(stroke
				(width 0)
				(type default)
			)
			(fill no)
			(layer "B.CrtYd")
		)
		(fp_rect
			(start 0.508 0.9398)
			(end -0.508 -0.9398)
			(stroke
				(width 0)
				(type default)
			)
			(fill no)
			(layer "B.Fab")
		)
		(pad "1" smd custom
			(at 0 -0.4445 270)
			(size 0.1397 0.1397)
			(layers "B.Cu" "B.Mask" "B.Paste")
			(net "PMU_PLTRST_R_N")
			(options
				(clearance outline)
				(anchor circle)
			)
			(primitives
				(gr_poly
					(pts
						(arc
							(start -0.1778 0.2794)
							(mid -0.249642 0.249642)
							(end -0.2794 0.1778)
						)
						(arc
							(start -0.2794 -0.1778)
							(mid -0.249642 -0.249642)
							(end -0.1778 -0.2794)
						)
						(arc
							(start 0.1778 -0.2794)
							(mid 0.249642 -0.249642)
							(end 0.2794 -0.1778)
						)
						(arc
							(start 0.2794 0.1778)
							(mid 0.249642 0.249642)
							(end 0.1778 0.2794)
						)
					)
					(width 0)
					(fill yes)
				)
			)
		)
		(pad "2" smd custom
			(at 0 0.4445 270)
			(size 0.1397 0.1397)
			(layers "B.Cu" "B.Mask" "B.Paste")
			(net "PMU_PLTRST_N")
			(options
				(clearance outline)
				(anchor circle)
			)
			(primitives
				(gr_poly
					(pts
						(arc
							(start -0.1778 0.2794)
							(mid -0.249642 0.249642)
							(end -0.2794 0.1778)
						)
						(arc
							(start -0.2794 -0.1778)
							(mid -0.249642 -0.249642)
							(end -0.1778 -0.2794)
						)
						(arc
							(start 0.1778 -0.2794)
							(mid 0.249642 -0.249642)
							(end 0.2794 -0.1778)
						)
						(arc
							(start 0.2794 0.1778)
							(mid 0.249642 0.249642)
							(end 0.1778 0.2794)
						)
					)
					(width 0)
					(fill yes)
				)
			)
		)
	)
	(footprint ""
		(layer "B.Cu")
		(at 87.76716 -51.308)
		(property "Reference" "STP12"
			(at 0 0 0)
			(layer "B.SilkS")
			(hide yes)
			(effects
				(font
					(size 1.27 1.27)
				)
				(justify mirror)
			)
		)
		(property "Value" "TPAD28"
			(at -0.0127 -1.8034 0)
			(unlocked yes)
			(layer "B.Fab")
			(hide yes)
			(effects
				(font
					(size 1.016 1.016)
					(thickness 0.1524)
				)
				(justify mirror)
			)
		)
		(property "Device Type" "TPAD28"
			(at -0.0127 -3.3274 0)
			(unlocked yes)
			(layer "B.Fab")
			(hide yes)
			(effects
				(font
					(size 1.016 1.016)
					(thickness 0.1524)
				)
				(justify mirror)
			)
		)
		(duplicate_pad_numbers_are_jumpers no)
		(fp_poly
			(pts
				(arc
					(start 0.3556 0)
					(mid -0.3556 0)
					(end 0.3556 0)
				)
			)
			(stroke
				(width 0)
				(type default)
			)
			(fill no)
			(layer "B.CrtYd")
		)
		(fp_poly
			(pts
				(arc
					(start 0.6096 0)
					(mid -0.6096 0)
					(end 0.6096 0)
				)
			)
			(stroke
				(width 0)
				(type default)
			)
			(fill no)
			(layer "B.Fab")
		)
		(pad "1" smd circle
			(at 0 0 180)
			(size 0.7112 0.7112)
			(layers "B.Cu" "B.Mask" "B.Paste")
			(net "SIO_CLK_1")
		)
	)
	(footprint ""
		(layer "B.Cu")
		(at 113.626646 -38.07968)
		(property "Reference" "STP10"
			(at 0 0 0)
			(layer "B.SilkS")
			(hide yes)
			(effects
				(font
					(size 1.27 1.27)
				)
				(justify mirror)
			)
		)
		(property "Value" "TPAD28"
			(at -0.0127 -1.8034 0)
			(unlocked yes)
			(layer "B.Fab")
			(hide yes)
			(effects
				(font
					(size 1.016 1.016)
					(thickness 0.1524)
				)
				(justify mirror)
			)
		)
		(property "Device Type" "TPAD28"
			(at -0.0127 -3.3274 0)
			(unlocked yes)
			(layer "B.Fab")
			(hide yes)
			(effects
				(font
					(size 1.016 1.016)
					(thickness 0.1524)
				)
				(justify mirror)
			)
		)
		(duplicate_pad_numbers_are_jumpers no)
		(fp_poly
			(pts
				(arc
					(start 0.3556 0)
					(mid -0.3556 0)
					(end 0.3556 0)
				)
			)
			(stroke
				(width 0)
				(type default)
			)
			(fill no)
			(layer "B.CrtYd")
		)
		(fp_poly
			(pts
				(arc
					(start 0.6096 0)
					(mid -0.6096 0)
					(end 0.6096 0)
				)
			)
			(stroke
				(width 0)
				(type default)
			)
			(fill no)
			(layer "B.Fab")
		)
		(pad "1" smd circle
			(at 0 0 180)
			(size 0.7112 0.7112)
			(layers "B.Cu" "B.Mask" "B.Paste")
			(net "IOC_GPIO_29")
		)
	)
	(footprint ""
		(layer "B.Cu")
		(at 109.99216 -30.226)
		(property "Reference" "STP51"
			(at 0 0 0)
			(layer "B.SilkS")
			(hide yes)
			(effects
				(font
					(size 1.27 1.27)
				)
				(justify mirror)
			)
		)
		(property "Value" "TPAD28"
			(at -0.0127 -1.8034 0)
			(unlocked yes)
			(layer "B.Fab")
			(hide yes)
			(effects
				(font
					(size 1.016 1.016)
					(thickness 0.1524)
				)
				(justify mirror)
			)
		)
		(property "Device Type" "TPAD28"
			(at -0.0127 -3.3274 0)
			(unlocked yes)
			(layer "B.Fab")
			(hide yes)
			(effects
				(font
					(size 1.016 1.016)
					(thickness 0.1524)
				)
				(justify mirror)
			)
		)
		(duplicate_pad_numbers_are_jumpers no)
		(fp_poly
			(pts
				(arc
					(start 0.3556 0)
					(mid -0.3556 0)
					(end 0.3556 0)
				)
			)
			(stroke
				(width 0)
				(type default)
			)
			(fill no)
			(layer "B.CrtYd")
		)
		(fp_poly
			(pts
				(arc
					(start 0.6096 0)
					(mid -0.6096 0)
					(end 0.6096 0)
				)
			)
			(stroke
				(width 0)
				(type default)
			)
			(fill no)
			(layer "B.Fab")
		)
		(pad "1" smd circle
			(at 0 0 180)
			(size 0.7112 0.7112)
			(layers "B.Cu" "B.Mask" "B.Paste")
			(net "SPARE1")
		)
	)
	(footprint ""
		(layer "B.Cu")
		(at 299.77334 -182.4101)
		(property "Reference" "TP111"
			(at 0 0 0)
			(layer "B.SilkS")
			(hide yes)
			(effects
				(font
					(size 1.27 1.27)
				)
				(justify mirror)
			)
		)
		(property "Value" "TPAD28"
			(at -0.0127 -1.8034 0)
			(unlocked yes)
			(layer "B.Fab")
			(hide yes)
			(effects
				(font
					(size 1.016 1.016)
					(thickness 0.1524)
				)
				(justify mirror)
			)
		)
		(property "Device Type" "TPAD28"
			(at -0.0127 -3.3274 0)
			(unlocked yes)
			(layer "B.Fab")
			(hide yes)
			(effects
				(font
					(size 1.016 1.016)
					(thickness 0.1524)
				)
				(justify mirror)
			)
		)
		(duplicate_pad_numbers_are_jumpers no)
		(fp_poly
			(pts
				(arc
					(start 0.3556 0)
					(mid -0.3556 0)
					(end 0.3556 0)
				)
			)
			(stroke
				(width 0)
				(type default)
			)
			(fill no)
			(layer "B.CrtYd")
		)
		(fp_poly
			(pts
				(arc
					(start 0.6096 0)
					(mid -0.6096 0)
					(end 0.6096 0)
				)
			)
			(stroke
				(width 0)
				(type default)
			)
			(fill no)
			(layer "B.Fab")
		)
		(pad "1" smd circle
			(at 0 0 180)
			(size 0.7112 0.7112)
			(layers "B.Cu" "B.Mask" "B.Paste")
			(net "TP_BMC_GPIOM3")
		)
	)
	(footprint ""
		(layer "B.Cu")
		(at 115.894612 -205.867)
		(property "Reference" "SR890"
			(at 0 0 0)
			(layer "B.SilkS")
			(hide yes)
			(effects
				(font
					(size 1.27 1.27)
				)
				(justify mirror)
			)
		)
		(property "Value" "0R2J-2-GP"
			(at -0.064008 -3.993896 0)
			(unlocked yes)
			(layer "B.Fab")
			(hide yes)
			(effects
				(font
					(size 1.016 1.016)
					(thickness 0.1524)
				)
				(justify mirror)
			)
		)
		(property "Device Type" "R402H16"
			(at -0.064008 -5.517896 0)
			(unlocked yes)
			(layer "B.Fab")
			(hide yes)
			(effects
				(font
					(size 1.016 1.016)
					(thickness 0.1524)
				)
				(justify mirror)
			)
		)
		(duplicate_pad_numbers_are_jumpers no)
		(fp_line
			(start -0.508 -0.9398)
			(end 0.508 -0.9398)
			(stroke
				(width 0.1524)
				(type default)
			)
			(layer "B.SilkS")
		)
		(fp_line
			(start 0.508 -0.9398)
			(end 0.508 0.9398)
			(stroke
				(width 0.1524)
				(type default)
			)
			(layer "B.SilkS")
		)
		(fp_rect
			(start 0.508 0.9398)
			(end -0.508 -0.9398)
			(stroke
				(width 0)
				(type default)
			)
			(fill no)
			(layer "B.CrtYd")
		)
		(fp_rect
			(start 0.508 0.9398)
			(end -0.508 -0.9398)
			(stroke
				(width 0)
				(type default)
			)
			(fill no)
			(layer "B.Fab")
		)
		(pad "1" smd custom
			(at 0 -0.4445 180)
			(size 0.1397 0.1397)
			(layers "B.Cu" "B.Mask" "B.Paste")
			(net "SAS_HDD_REDV_SER_RX7_N")
			(options
				(clearance outline)
				(anchor circle)
			)
			(primitives
				(gr_poly
					(pts
						(arc
							(start -0.1778 0.2794)
							(mid -0.249642 0.249642)
							(end -0.2794 0.1778)
						)
						(arc
							(start -0.2794 -0.1778)
							(mid -0.249642 -0.249642)
							(end -0.1778 -0.2794)
						)
						(arc
							(start 0.1778 -0.2794)
							(mid 0.249642 -0.249642)
							(end 0.2794 -0.1778)
						)
						(arc
							(start 0.2794 0.1778)
							(mid 0.249642 0.249642)
							(end 0.1778 0.2794)
						)
					)
					(width 0)
					(fill yes)
				)
			)
		)
		(pad "2" smd custom
			(at 0 0.4445 180)
			(size 0.1397 0.1397)
			(layers "B.Cu" "B.Mask" "B.Paste")
			(net "SAS_HDD_CONN_RX7_N")
			(options
				(clearance outline)
				(anchor circle)
			)
			(primitives
				(gr_poly
					(pts
						(arc
							(start -0.1778 0.2794)
							(mid -0.249642 0.249642)
							(end -0.2794 0.1778)
						)
						(arc
							(start -0.2794 -0.1778)
							(mid -0.249642 -0.249642)
							(end -0.1778 -0.2794)
						)
						(arc
							(start 0.1778 -0.2794)
							(mid 0.249642 -0.249642)
							(end 0.2794 -0.1778)
						)
						(arc
							(start 0.2794 0.1778)
							(mid 0.249642 0.249642)
							(end 0.1778 0.2794)
						)
					)
					(width 0)
					(fill yes)
				)
			)
		)
	)
	(footprint ""
		(layer "B.Cu")
		(at 100.083366 -50.2666 180)
		(property "Reference" "SC1031"
			(at 0 0 0)
			(layer "B.SilkS")
			(hide yes)
			(effects
				(font
					(size 1.27 1.27)
				)
				(justify mirror)
			)
		)
		(property "Value" "SC1KP50V2KX-1GP"
			(at -1.1811 -2.7051 180)
			(unlocked yes)
			(layer "B.Fab")
			(hide yes)
			(effects
				(font
					(size 1.016 1.016)
					(thickness 0.1524)
				)
				(justify mirror)
			)
		)
		(property "Device Type" "C402H22"
			(at -1.1811 -4.2291 180)
			(unlocked yes)
			(layer "B.Fab")
			(hide yes)
			(effects
				(font
					(size 1.016 1.016)
					(thickness 0.1524)
				)
				(justify mirror)
			)
		)
		(duplicate_pad_numbers_are_jumpers no)
		(fp_rect
			(start 0.4318 0.9525)
			(end -0.4318 -0.9525)
			(stroke
				(width 0)
				(type default)
			)
			(fill no)
			(layer "B.CrtYd")
		)
		(fp_rect
			(start 0.4318 0.9525)
			(end -0.4318 -0.9525)
			(stroke
				(width 0)
				(type default)
			)
			(fill no)
			(layer "B.Fab")
		)
		(pad "1" smd custom
			(at 0 -0.4445)
			(size 0.1524 0.1524)
			(layers "B.Cu" "B.Mask" "B.Paste")
			(net "P0V955_C")
			(options
				(clearance outline)
				(anchor circle)
			)
			(primitives
				(gr_poly
					(pts
						(arc
							(start 0.3048 0.2032)
							(mid 0.275042 0.275042)
							(end 0.2032 0.3048)
						)
						(arc
							(start -0.2032 0.3048)
							(mid -0.275042 0.275042)
							(end -0.3048 0.2032)
						)
						(arc
							(start -0.3048 -0.2032)
							(mid -0.275042 -0.275042)
							(end -0.2032 -0.3048)
						)
						(arc
							(start 0.2032 -0.3048)
							(mid 0.275042 -0.275042)
							(end 0.3048 -0.2032)
						)
					)
					(width 0)
					(fill yes)
				)
			)
		)
		(pad "2" smd custom
			(at 0 0.4445)
			(size 0.1524 0.1524)
			(layers "B.Cu" "B.Mask" "B.Paste")
			(net "GND")
			(options
				(clearance outline)
				(anchor circle)
			)
			(primitives
				(gr_poly
					(pts
						(arc
							(start 0.3048 0.2032)
							(mid 0.275042 0.275042)
							(end 0.2032 0.3048)
						)
						(arc
							(start -0.2032 0.3048)
							(mid -0.275042 0.275042)
							(end -0.3048 0.2032)
						)
						(arc
							(start -0.3048 -0.2032)
							(mid -0.275042 -0.275042)
							(end -0.2032 -0.3048)
						)
						(arc
							(start 0.2032 -0.3048)
							(mid 0.275042 -0.275042)
							(end 0.3048 -0.2032)
						)
					)
					(width 0)
					(fill yes)
				)
			)
		)
	)
	(footprint ""
		(layer "B.Cu")
		(at 120.38457 -92.6846 90)
		(property "Reference" "SC1143"
			(at 0 0 90)
			(layer "B.SilkS")
			(hide yes)
			(effects
				(font
					(size 1.27 1.27)
				)
				(justify mirror)
			)
		)
		(property "Value" "SCD1U6D3V1KX-GP"
			(at 2.8321 -1.7399 90)
			(unlocked yes)
			(layer "B.Fab")
			(hide yes)
			(effects
				(font
					(size 1.016 1.016)
					(thickness 0.1524)
				)
				(justify mirror)
			)
		)
		(property "Device Type" "C0201H13"
			(at 2.8321 -3.2639 90)
			(unlocked yes)
			(layer "B.Fab")
			(hide yes)
			(effects
				(font
					(size 1.016 1.016)
					(thickness 0.1524)
				)
				(justify mirror)
			)
		)
		(duplicate_pad_numbers_are_jumpers no)
		(fp_rect
			(start 0.2794 0.6477)
			(end -0.2794 -0.6477)
			(stroke
				(width 0)
				(type default)
			)
			(fill no)
			(layer "B.CrtYd")
		)
		(fp_rect
			(start 0.2794 0.6477)
			(end -0.2794 -0.6477)
			(stroke
				(width 0)
				(type default)
			)
			(fill no)
			(layer "B.Fab")
		)
		(pad "1" smd custom
			(at 0 -0.2794 270)
			(size 0.0762 0.0762)
			(layers "B.Cu" "B.Mask" "B.Paste")
			(net "GB_VDDH2")
			(options
				(clearance outline)
				(anchor circle)
			)
			(primitives
				(gr_poly
					(pts
						(arc
							(start 0.1524 0.127)
							(mid 0.137521 0.162921)
							(end 0.1016 0.1778)
						)
						(arc
							(start -0.1016 0.1778)
							(mid -0.137521 0.162921)
							(end -0.1524 0.127)
						)
						(arc
							(start -0.1524 -0.127)
							(mid -0.137521 -0.162921)
							(end -0.1016 -0.1778)
						)
						(arc
							(start 0.1016 -0.1778)
							(mid 0.137521 -0.162921)
							(end 0.1524 -0.127)
						)
					)
					(width 0)
					(fill yes)
				)
			)
		)
		(pad "2" smd custom
			(at 0 0.2794 270)
			(size 0.0762 0.0762)
			(layers "B.Cu" "B.Mask" "B.Paste")
			(net "GND")
			(options
				(clearance outline)
				(anchor circle)
			)
			(primitives
				(gr_poly
					(pts
						(arc
							(start 0.1524 0.127)
							(mid 0.137521 0.162921)
							(end 0.1016 0.1778)
						)
						(arc
							(start -0.1016 0.1778)
							(mid -0.137521 0.162921)
							(end -0.1524 0.127)
						)
						(arc
							(start -0.1524 -0.127)
							(mid -0.137521 -0.162921)
							(end -0.1016 -0.1778)
						)
						(arc
							(start 0.1016 -0.1778)
							(mid 0.137521 -0.162921)
							(end 0.1524 -0.127)
						)
					)
					(width 0)
					(fill yes)
				)
			)
		)
	)
	(footprint ""
		(layer "B.Cu")
		(at 107.696 -95.758 -90)
		(property "Reference" "STP83"
			(at 0 0 90)
			(layer "B.SilkS")
			(hide yes)
			(effects
				(font
					(size 1.27 1.27)
				)
				(justify mirror)
			)
		)
		(property "Value" "TPAD28"
			(at -0.0127 -1.8034 270)
			(unlocked yes)
			(layer "B.Fab")
			(hide yes)
			(effects
				(font
					(size 1.016 1.016)
					(thickness 0.1524)
				)
				(justify mirror)
			)
		)
		(property "Device Type" "TPAD28"
			(at -0.0127 -3.3274 270)
			(unlocked yes)
			(layer "B.Fab")
			(hide yes)
			(effects
				(font
					(size 1.016 1.016)
					(thickness 0.1524)
				)
				(justify mirror)
			)
		)
		(duplicate_pad_numbers_are_jumpers no)
		(fp_poly
			(pts
				(arc
					(start 0 -0.3556)
					(mid 0 0.3556)
					(end 0 -0.3556)
				)
			)
			(stroke
				(width 0)
				(type default)
			)
			(fill no)
			(layer "B.CrtYd")
		)
		(fp_poly
			(pts
				(arc
					(start 0 -0.6096)
					(mid 0 0.6096)
					(end 0 -0.6096)
				)
			)
			(stroke
				(width 0)
				(type default)
			)
			(fill no)
			(layer "B.Fab")
		)
		(pad "1" smd circle
			(at 0 0 90)
			(size 0.7112 0.7112)
			(layers "B.Cu" "B.Mask" "B.Paste")
			(net "EXP_TACH_IN3")
		)
	)
	(footprint ""
		(layer "B.Cu")
		(at 107.169966 -46.609 90)
		(property "Reference" "SC1036"
			(at 0 0 90)
			(layer "B.SilkS")
			(hide yes)
			(effects
				(font
					(size 1.27 1.27)
				)
				(justify mirror)
			)
		)
		(property "Value" "SC1KP50V2KX-1GP"
			(at -1.1811 -2.7051 90)
			(unlocked yes)
			(layer "B.Fab")
			(hide yes)
			(effects
				(font
					(size 1.016 1.016)
					(thickness 0.1524)
				)
				(justify mirror)
			)
		)
		(property "Device Type" "C402H22"
			(at -1.1811 -4.2291 90)
			(unlocked yes)
			(layer "B.Fab")
			(hide yes)
			(effects
				(font
					(size 1.016 1.016)
					(thickness 0.1524)
				)
				(justify mirror)
			)
		)
		(duplicate_pad_numbers_are_jumpers no)
		(fp_rect
			(start 0.4318 0.9525)
			(end -0.4318 -0.9525)
			(stroke
				(width 0)
				(type default)
			)
			(fill no)
			(layer "B.CrtYd")
		)
		(fp_rect
			(start 0.4318 0.9525)
			(end -0.4318 -0.9525)
			(stroke
				(width 0)
				(type default)
			)
			(fill no)
			(layer "B.Fab")
		)
		(pad "1" smd custom
			(at 0 -0.4445 270)
			(size 0.1524 0.1524)
			(layers "B.Cu" "B.Mask" "B.Paste")
			(net "P0V955_C")
			(options
				(clearance outline)
				(anchor circle)
			)
			(primitives
				(gr_poly
					(pts
						(arc
							(start 0.3048 0.2032)
							(mid 0.275042 0.275042)
							(end 0.2032 0.3048)
						)
						(arc
							(start -0.2032 0.3048)
							(mid -0.275042 0.275042)
							(end -0.3048 0.2032)
						)
						(arc
							(start -0.3048 -0.2032)
							(mid -0.275042 -0.275042)
							(end -0.2032 -0.3048)
						)
						(arc
							(start 0.2032 -0.3048)
							(mid 0.275042 -0.275042)
							(end 0.3048 -0.2032)
						)
					)
					(width 0)
					(fill yes)
				)
			)
		)
		(pad "2" smd custom
			(at 0 0.4445 270)
			(size 0.1524 0.1524)
			(layers "B.Cu" "B.Mask" "B.Paste")
			(net "GND")
			(options
				(clearance outline)
				(anchor circle)
			)
			(primitives
				(gr_poly
					(pts
						(arc
							(start 0.3048 0.2032)
							(mid 0.275042 0.275042)
							(end 0.2032 0.3048)
						)
						(arc
							(start -0.2032 0.3048)
							(mid -0.275042 0.275042)
							(end -0.3048 0.2032)
						)
						(arc
							(start -0.3048 -0.2032)
							(mid -0.275042 -0.275042)
							(end -0.2032 -0.3048)
						)
						(arc
							(start 0.2032 -0.3048)
							(mid 0.275042 -0.275042)
							(end 0.3048 -0.2032)
						)
					)
					(width 0)
					(fill yes)
				)
			)
		)
	)
	(footprint ""
		(layer "B.Cu")
		(at 111.762286 -57.299606)
		(property "Reference" "STP152"
			(at 0 0 0)
			(layer "B.SilkS")
			(hide yes)
			(effects
				(font
					(size 1.27 1.27)
				)
				(justify mirror)
			)
		)
		(property "Value" "TPAD28"
			(at -0.0127 -1.8034 0)
			(unlocked yes)
			(layer "B.Fab")
			(hide yes)
			(effects
				(font
					(size 1.016 1.016)
					(thickness 0.1524)
				)
				(justify mirror)
			)
		)
		(property "Device Type" "TPAD28"
			(at -0.0127 -3.3274 0)
			(unlocked yes)
			(layer "B.Fab")
			(hide yes)
			(effects
				(font
					(size 1.016 1.016)
					(thickness 0.1524)
				)
				(justify mirror)
			)
		)
		(duplicate_pad_numbers_are_jumpers no)
		(fp_poly
			(pts
				(arc
					(start 0.3556 0)
					(mid -0.3556 0)
					(end 0.3556 0)
				)
			)
			(stroke
				(width 0)
				(type default)
			)
			(fill no)
			(layer "B.CrtYd")
		)
		(fp_poly
			(pts
				(arc
					(start 0.6096 0)
					(mid -0.6096 0)
					(end 0.6096 0)
				)
			)
			(stroke
				(width 0)
				(type default)
			)
			(fill no)
			(layer "B.Fab")
		)
		(pad "1" smd circle
			(at 0 0 180)
			(size 0.7112 0.7112)
			(layers "B.Cu" "B.Mask" "B.Paste")
			(net "XM_ALE")
		)
	)
	(footprint ""
		(layer "B.Cu")
		(at 115.27917 -96.52)
		(property "Reference" "SC1247"
			(at 0 0 0)
			(layer "B.SilkS")
			(hide yes)
			(effects
				(font
					(size 1.27 1.27)
				)
				(justify mirror)
			)
		)
		(property "Value" "SCD1U6D3V1KX-GP"
			(at 2.8321 -1.7399 0)
			(unlocked yes)
			(layer "B.Fab")
			(hide yes)
			(effects
				(font
					(size 1.016 1.016)
					(thickness 0.1524)
				)
				(justify mirror)
			)
		)
		(property "Device Type" "C0201H13"
			(at 2.8321 -3.2639 0)
			(unlocked yes)
			(layer "B.Fab")
			(hide yes)
			(effects
				(font
					(size 1.016 1.016)
					(thickness 0.1524)
				)
				(justify mirror)
			)
		)
		(duplicate_pad_numbers_are_jumpers no)
		(fp_rect
			(start 0.2794 0.6477)
			(end -0.2794 -0.6477)
			(stroke
				(width 0)
				(type default)
			)
			(fill no)
			(layer "B.CrtYd")
		)
		(fp_rect
			(start 0.2794 0.6477)
			(end -0.2794 -0.6477)
			(stroke
				(width 0)
				(type default)
			)
			(fill no)
			(layer "B.Fab")
		)
		(pad "1" smd custom
			(at 0 -0.2794 180)
			(size 0.0762 0.0762)
			(layers "B.Cu" "B.Mask" "B.Paste")
			(net "P0V9_E")
			(options
				(clearance outline)
				(anchor circle)
			)
			(primitives
				(gr_poly
					(pts
						(arc
							(start 0.1524 0.127)
							(mid 0.137521 0.162921)
							(end 0.1016 0.1778)
						)
						(arc
							(start -0.1016 0.1778)
							(mid -0.137521 0.162921)
							(end -0.1524 0.127)
						)
						(arc
							(start -0.1524 -0.127)
							(mid -0.137521 -0.162921)
							(end -0.1016 -0.1778)
						)
						(arc
							(start 0.1016 -0.1778)
							(mid 0.137521 -0.162921)
							(end 0.1524 -0.127)
						)
					)
					(width 0)
					(fill yes)
				)
			)
		)
		(pad "2" smd custom
			(at 0 0.2794 180)
			(size 0.0762 0.0762)
			(layers "B.Cu" "B.Mask" "B.Paste")
			(net "GND")
			(options
				(clearance outline)
				(anchor circle)
			)
			(primitives
				(gr_poly
					(pts
						(arc
							(start 0.1524 0.127)
							(mid 0.137521 0.162921)
							(end 0.1016 0.1778)
						)
						(arc
							(start -0.1016 0.1778)
							(mid -0.137521 0.162921)
							(end -0.1524 0.127)
						)
						(arc
							(start -0.1524 -0.127)
							(mid -0.137521 -0.162921)
							(end -0.1016 -0.1778)
						)
						(arc
							(start 0.1016 -0.1778)
							(mid 0.137521 -0.162921)
							(end 0.1524 -0.127)
						)
					)
					(width 0)
					(fill yes)
				)
			)
		)
	)
	(footprint ""
		(layer "B.Cu")
		(at 105.264966 -44.958 90)
		(property "Reference" "SC1033"
			(at 0 0 90)
			(layer "B.SilkS")
			(hide yes)
			(effects
				(font
					(size 1.27 1.27)
				)
				(justify mirror)
			)
		)
		(property "Value" "SC1KP50V2KX-1GP"
			(at -1.1811 -2.7051 90)
			(unlocked yes)
			(layer "B.Fab")
			(hide yes)
			(effects
				(font
					(size 1.016 1.016)
					(thickness 0.1524)
				)
				(justify mirror)
			)
		)
		(property "Device Type" "C402H22"
			(at -1.1811 -4.2291 90)
			(unlocked yes)
			(layer "B.Fab")
			(hide yes)
			(effects
				(font
					(size 1.016 1.016)
					(thickness 0.1524)
				)
				(justify mirror)
			)
		)
		(duplicate_pad_numbers_are_jumpers no)
		(fp_rect
			(start 0.4318 0.9525)
			(end -0.4318 -0.9525)
			(stroke
				(width 0)
				(type default)
			)
			(fill no)
			(layer "B.CrtYd")
		)
		(fp_rect
			(start 0.4318 0.9525)
			(end -0.4318 -0.9525)
			(stroke
				(width 0)
				(type default)
			)
			(fill no)
			(layer "B.Fab")
		)
		(pad "1" smd custom
			(at 0 -0.4445 270)
			(size 0.1524 0.1524)
			(layers "B.Cu" "B.Mask" "B.Paste")
			(net "P0V955_C")
			(options
				(clearance outline)
				(anchor circle)
			)
			(primitives
				(gr_poly
					(pts
						(arc
							(start 0.3048 0.2032)
							(mid 0.275042 0.275042)
							(end 0.2032 0.3048)
						)
						(arc
							(start -0.2032 0.3048)
							(mid -0.275042 0.275042)
							(end -0.3048 0.2032)
						)
						(arc
							(start -0.3048 -0.2032)
							(mid -0.275042 -0.275042)
							(end -0.2032 -0.3048)
						)
						(arc
							(start 0.2032 -0.3048)
							(mid 0.275042 -0.275042)
							(end 0.3048 -0.2032)
						)
					)
					(width 0)
					(fill yes)
				)
			)
		)
		(pad "2" smd custom
			(at 0 0.4445 270)
			(size 0.1524 0.1524)
			(layers "B.Cu" "B.Mask" "B.Paste")
			(net "GND")
			(options
				(clearance outline)
				(anchor circle)
			)
			(primitives
				(gr_poly
					(pts
						(arc
							(start 0.3048 0.2032)
							(mid 0.275042 0.275042)
							(end 0.2032 0.3048)
						)
						(arc
							(start -0.2032 0.3048)
							(mid -0.275042 0.275042)
							(end -0.3048 0.2032)
						)
						(arc
							(start -0.3048 -0.2032)
							(mid -0.275042 -0.275042)
							(end -0.2032 -0.3048)
						)
						(arc
							(start 0.2032 -0.3048)
							(mid 0.275042 -0.275042)
							(end 0.3048 -0.2032)
						)
					)
					(width 0)
					(fill yes)
				)
			)
		)
	)
	(footprint ""
		(layer "B.Cu")
		(at 118.37797 -94.615 90)
		(property "Reference" "SC1217"
			(at 0 0 90)
			(layer "B.SilkS")
			(hide yes)
			(effects
				(font
					(size 1.27 1.27)
				)
				(justify mirror)
			)
		)
		(property "Value" "SC1KP50V2KX-1GP"
			(at -1.1811 -2.7051 90)
			(unlocked yes)
			(layer "B.Fab")
			(hide yes)
			(effects
				(font
					(size 1.016 1.016)
					(thickness 0.1524)
				)
				(justify mirror)
			)
		)
		(property "Device Type" "C402H22"
			(at -1.1811 -4.2291 90)
			(unlocked yes)
			(layer "B.Fab")
			(hide yes)
			(effects
				(font
					(size 1.016 1.016)
					(thickness 0.1524)
				)
				(justify mirror)
			)
		)
		(duplicate_pad_numbers_are_jumpers no)
		(fp_rect
			(start 0.4318 0.9525)
			(end -0.4318 -0.9525)
			(stroke
				(width 0)
				(type default)
			)
			(fill no)
			(layer "B.CrtYd")
		)
		(fp_rect
			(start 0.4318 0.9525)
			(end -0.4318 -0.9525)
			(stroke
				(width 0)
				(type default)
			)
			(fill no)
			(layer "B.Fab")
		)
		(pad "1" smd custom
			(at 0 -0.4445 270)
			(size 0.1524 0.1524)
			(layers "B.Cu" "B.Mask" "B.Paste")
			(net "P0V9_E")
			(options
				(clearance outline)
				(anchor circle)
			)
			(primitives
				(gr_poly
					(pts
						(arc
							(start 0.3048 0.2032)
							(mid 0.275042 0.275042)
							(end 0.2032 0.3048)
						)
						(arc
							(start -0.2032 0.3048)
							(mid -0.275042 0.275042)
							(end -0.3048 0.2032)
						)
						(arc
							(start -0.3048 -0.2032)
							(mid -0.275042 -0.275042)
							(end -0.2032 -0.3048)
						)
						(arc
							(start 0.2032 -0.3048)
							(mid 0.275042 -0.275042)
							(end 0.3048 -0.2032)
						)
					)
					(width 0)
					(fill yes)
				)
			)
		)
		(pad "2" smd custom
			(at 0 0.4445 270)
			(size 0.1524 0.1524)
			(layers "B.Cu" "B.Mask" "B.Paste")
			(net "GND")
			(options
				(clearance outline)
				(anchor circle)
			)
			(primitives
				(gr_poly
					(pts
						(arc
							(start 0.3048 0.2032)
							(mid 0.275042 0.275042)
							(end 0.2032 0.3048)
						)
						(arc
							(start -0.2032 0.3048)
							(mid -0.275042 0.275042)
							(end -0.3048 0.2032)
						)
						(arc
							(start -0.3048 -0.2032)
							(mid -0.275042 -0.275042)
							(end -0.2032 -0.3048)
						)
						(arc
							(start 0.2032 -0.3048)
							(mid 0.275042 -0.275042)
							(end 0.3048 -0.2032)
						)
					)
					(width 0)
					(fill yes)
				)
			)
		)
	)
	(footprint ""
		(layer "B.Cu")
		(at 290.2966 -179.1462)
		(property "Reference" "TP151"
			(at 0 0 0)
			(layer "B.SilkS")
			(hide yes)
			(effects
				(font
					(size 1.27 1.27)
				)
				(justify mirror)
			)
		)
		(property "Value" "TPAD28"
			(at -0.0127 -1.8034 0)
			(unlocked yes)
			(layer "B.Fab")
			(hide yes)
			(effects
				(font
					(size 1.016 1.016)
					(thickness 0.1524)
				)
				(justify mirror)
			)
		)
		(property "Device Type" "TPAD28"
			(at -0.0127 -3.3274 0)
			(unlocked yes)
			(layer "B.Fab")
			(hide yes)
			(effects
				(font
					(size 1.016 1.016)
					(thickness 0.1524)
				)
				(justify mirror)
			)
		)
		(duplicate_pad_numbers_are_jumpers no)
		(fp_poly
			(pts
				(arc
					(start 0.3556 0)
					(mid -0.3556 0)
					(end 0.3556 0)
				)
			)
			(stroke
				(width 0)
				(type default)
			)
			(fill no)
			(layer "B.CrtYd")
		)
		(fp_poly
			(pts
				(arc
					(start 0.6096 0)
					(mid -0.6096 0)
					(end 0.6096 0)
				)
			)
			(stroke
				(width 0)
				(type default)
			)
			(fill no)
			(layer "B.Fab")
		)
		(pad "1" smd circle
			(at 0 0 180)
			(size 0.7112 0.7112)
			(layers "B.Cu" "B.Mask" "B.Paste")
			(net "TP_BMC_GPIOR3")
		)
	)
	(footprint ""
		(layer "B.Cu")
		(at 274.193 -178.689 90)
		(property "Reference" "R356"
			(at 0 0 90)
			(layer "B.SilkS")
			(hide yes)
			(effects
				(font
					(size 1.27 1.27)
				)
				(justify mirror)
			)
		)
		(property "Value" "3K3R2F-2-GP"
			(at -0.064008 -3.993896 90)
			(unlocked yes)
			(layer "B.Fab")
			(hide yes)
			(effects
				(font
					(size 1.016 1.016)
					(thickness 0.1524)
				)
				(justify mirror)
			)
		)
		(property "Device Type" "R402H16"
			(at -0.064008 -5.517896 90)
			(unlocked yes)
			(layer "B.Fab")
			(hide yes)
			(effects
				(font
					(size 1.016 1.016)
					(thickness 0.1524)
				)
				(justify mirror)
			)
		)
		(duplicate_pad_numbers_are_jumpers no)
		(fp_line
			(start 0.508 -0.9398)
			(end 0.508 0.9398)
			(stroke
				(width 0.1524)
				(type default)
			)
			(layer "B.SilkS")
		)
		(fp_line
			(start -0.508 -0.9398)
			(end 0.508 -0.9398)
			(stroke
				(width 0.1524)
				(type default)
			)
			(layer "B.SilkS")
		)
		(fp_rect
			(start 0.508 0.9398)
			(end -0.508 -0.9398)
			(stroke
				(width 0)
				(type default)
			)
			(fill no)
			(layer "B.CrtYd")
		)
		(fp_rect
			(start 0.508 0.9398)
			(end -0.508 -0.9398)
			(stroke
				(width 0)
				(type default)
			)
			(fill no)
			(layer "B.Fab")
		)
		(pad "1" smd custom
			(at 0 -0.4445 270)
			(size 0.1397 0.1397)
			(layers "B.Cu" "B.Mask" "B.Paste")
			(net "P3V3_STBY")
			(options
				(clearance outline)
				(anchor circle)
			)
			(primitives
				(gr_poly
					(pts
						(arc
							(start -0.1778 0.2794)
							(mid -0.249642 0.249642)
							(end -0.2794 0.1778)
						)
						(arc
							(start -0.2794 -0.1778)
							(mid -0.249642 -0.249642)
							(end -0.1778 -0.2794)
						)
						(arc
							(start 0.1778 -0.2794)
							(mid 0.249642 -0.249642)
							(end 0.2794 -0.1778)
						)
						(arc
							(start 0.2794 0.1778)
							(mid 0.249642 0.249642)
							(end 0.1778 0.2794)
						)
					)
					(width 0)
					(fill yes)
				)
			)
		)
		(pad "2" smd custom
			(at 0 0.4445 270)
			(size 0.1397 0.1397)
			(layers "B.Cu" "B.Mask" "B.Paste")
			(net "ROMA12")
			(options
				(clearance outline)
				(anchor circle)
			)
			(primitives
				(gr_poly
					(pts
						(arc
							(start -0.1778 0.2794)
							(mid -0.249642 0.249642)
							(end -0.2794 0.1778)
						)
						(arc
							(start -0.2794 -0.1778)
							(mid -0.249642 -0.249642)
							(end -0.1778 -0.2794)
						)
						(arc
							(start 0.1778 -0.2794)
							(mid 0.249642 -0.249642)
							(end 0.2794 -0.1778)
						)
						(arc
							(start 0.2794 0.1778)
							(mid 0.249642 0.249642)
							(end 0.1778 0.2794)
						)
					)
					(width 0)
					(fill yes)
				)
			)
		)
	)
	(footprint ""
		(layer "B.Cu")
		(at 95.155766 -43.7388 180)
		(property "Reference" "SC963"
			(at 0 0 0)
			(layer "B.SilkS")
			(hide yes)
			(effects
				(font
					(size 1.27 1.27)
				)
				(justify mirror)
			)
		)
		(property "Value" "SCD1U6D3V1KX-GP"
			(at 2.8321 -1.7399 180)
			(unlocked yes)
			(layer "B.Fab")
			(hide yes)
			(effects
				(font
					(size 1.016 1.016)
					(thickness 0.1524)
				)
				(justify mirror)
			)
		)
		(property "Device Type" "C0201H13"
			(at 2.8321 -3.2639 180)
			(unlocked yes)
			(layer "B.Fab")
			(hide yes)
			(effects
				(font
					(size 1.016 1.016)
					(thickness 0.1524)
				)
				(justify mirror)
			)
		)
		(duplicate_pad_numbers_are_jumpers no)
		(fp_rect
			(start 0.2794 0.6477)
			(end -0.2794 -0.6477)
			(stroke
				(width 0)
				(type default)
			)
			(fill no)
			(layer "B.CrtYd")
		)
		(fp_rect
			(start 0.2794 0.6477)
			(end -0.2794 -0.6477)
			(stroke
				(width 0)
				(type default)
			)
			(fill no)
			(layer "B.Fab")
		)
		(pad "1" smd custom
			(at 0 -0.2794)
			(size 0.0762 0.0762)
			(layers "B.Cu" "B.Mask" "B.Paste")
			(net "SAS0_AVDD")
			(options
				(clearance outline)
				(anchor circle)
			)
			(primitives
				(gr_poly
					(pts
						(arc
							(start 0.1524 0.127)
							(mid 0.137521 0.162921)
							(end 0.1016 0.1778)
						)
						(arc
							(start -0.1016 0.1778)
							(mid -0.137521 0.162921)
							(end -0.1524 0.127)
						)
						(arc
							(start -0.1524 -0.127)
							(mid -0.137521 -0.162921)
							(end -0.1016 -0.1778)
						)
						(arc
							(start 0.1016 -0.1778)
							(mid 0.137521 -0.162921)
							(end 0.1524 -0.127)
						)
					)
					(width 0)
					(fill yes)
				)
			)
		)
		(pad "2" smd custom
			(at 0 0.2794)
			(size 0.0762 0.0762)
			(layers "B.Cu" "B.Mask" "B.Paste")
			(net "GND")
			(options
				(clearance outline)
				(anchor circle)
			)
			(primitives
				(gr_poly
					(pts
						(arc
							(start 0.1524 0.127)
							(mid 0.137521 0.162921)
							(end 0.1016 0.1778)
						)
						(arc
							(start -0.1016 0.1778)
							(mid -0.137521 0.162921)
							(end -0.1524 0.127)
						)
						(arc
							(start -0.1524 -0.127)
							(mid -0.137521 -0.162921)
							(end -0.1016 -0.1778)
						)
						(arc
							(start 0.1016 -0.1778)
							(mid 0.137521 -0.162921)
							(end 0.1524 -0.127)
						)
					)
					(width 0)
					(fill yes)
				)
			)
		)
	)
	(footprint ""
		(layer "B.Cu")
		(at 256.667 -19.431)
		(property "Reference" "R407"
			(at 0 0 0)
			(layer "B.SilkS")
			(hide yes)
			(effects
				(font
					(size 1.27 1.27)
				)
				(justify mirror)
			)
		)
		(property "Value" "10KR2F-2-GP"
			(at -0.064008 -3.993896 0)
			(unlocked yes)
			(layer "B.Fab")
			(hide yes)
			(effects
				(font
					(size 1.016 1.016)
					(thickness 0.1524)
				)
				(justify mirror)
			)
		)
		(property "Device Type" "R402H16"
			(at -0.064008 -5.517896 0)
			(unlocked yes)
			(layer "B.Fab")
			(hide yes)
			(effects
				(font
					(size 1.016 1.016)
					(thickness 0.1524)
				)
				(justify mirror)
			)
		)
		(duplicate_pad_numbers_are_jumpers no)
		(fp_line
			(start -0.508 -0.9398)
			(end 0.508 -0.9398)
			(stroke
				(width 0.1524)
				(type default)
			)
			(layer "B.SilkS")
		)
		(fp_line
			(start 0.508 -0.9398)
			(end 0.508 0.9398)
			(stroke
				(width 0.1524)
				(type default)
			)
			(layer "B.SilkS")
		)
		(fp_rect
			(start 0.508 0.9398)
			(end -0.508 -0.9398)
			(stroke
				(width 0)
				(type default)
			)
			(fill no)
			(layer "B.CrtYd")
		)
		(fp_rect
			(start 0.508 0.9398)
			(end -0.508 -0.9398)
			(stroke
				(width 0)
				(type default)
			)
			(fill no)
			(layer "B.Fab")
		)
		(pad "1" smd custom
			(at 0 -0.4445 180)
			(size 0.1397 0.1397)
			(layers "B.Cu" "B.Mask" "B.Paste")
			(net "P5V_STBY")
			(options
				(clearance outline)
				(anchor circle)
			)
			(primitives
				(gr_poly
					(pts
						(arc
							(start -0.1778 0.2794)
							(mid -0.249642 0.249642)
							(end -0.2794 0.1778)
						)
						(arc
							(start -0.2794 -0.1778)
							(mid -0.249642 -0.249642)
							(end -0.1778 -0.2794)
						)
						(arc
							(start 0.1778 -0.2794)
							(mid 0.249642 -0.249642)
							(end 0.2794 -0.1778)
						)
						(arc
							(start 0.2794 0.1778)
							(mid 0.249642 0.249642)
							(end 0.1778 0.2794)
						)
					)
					(width 0)
					(fill yes)
				)
			)
		)
		(pad "2" smd custom
			(at 0 0.4445 180)
			(size 0.1397 0.1397)
			(layers "B.Cu" "B.Mask" "B.Paste")
			(net "USB_OCS_N1")
			(options
				(clearance outline)
				(anchor circle)
			)
			(primitives
				(gr_poly
					(pts
						(arc
							(start -0.1778 0.2794)
							(mid -0.249642 0.249642)
							(end -0.2794 0.1778)
						)
						(arc
							(start -0.2794 -0.1778)
							(mid -0.249642 -0.249642)
							(end -0.1778 -0.2794)
						)
						(arc
							(start 0.1778 -0.2794)
							(mid 0.249642 -0.249642)
							(end 0.2794 -0.1778)
						)
						(arc
							(start 0.2794 0.1778)
							(mid 0.249642 0.249642)
							(end 0.1778 0.2794)
						)
					)
					(width 0)
					(fill yes)
				)
			)
		)
	)
	(footprint ""
		(layer "B.Cu")
		(at 307.594 -180.086)
		(property "Reference" "L4"
			(at 0 0 0)
			(layer "B.SilkS")
			(hide yes)
			(effects
				(font
					(size 1.27 1.27)
				)
				(justify mirror)
			)
		)
		(property "Value" "MMZ2012S601ATA1N-GP"
			(at 0 -4.2418 0)
			(unlocked yes)
			(layer "B.Fab")
			(hide yes)
			(effects
				(font
					(size 1.016 1.016)
					(thickness 0.1524)
				)
				(justify mirror)
			)
		)
		(property "Device Type" "L805H42"
			(at 0 -5.7912 0)
			(unlocked yes)
			(layer "B.Fab")
			(hide yes)
			(effects
				(font
					(size 1.016 1.016)
					(thickness 0.1524)
				)
				(justify mirror)
			)
		)
		(duplicate_pad_numbers_are_jumpers no)
		(fp_line
			(start -0.889 -1.7018)
			(end -0.889 1.7018)
			(stroke
				(width 0.1524)
				(type default)
			)
			(layer "B.SilkS")
		)
		(fp_line
			(start -0.889 1.7018)
			(end 0.889 1.7018)
			(stroke
				(width 0.1524)
				(type default)
			)
			(layer "B.SilkS")
		)
		(fp_line
			(start 0.889 -1.7018)
			(end -0.889 -1.7018)
			(stroke
				(width 0.1524)
				(type default)
			)
			(layer "B.SilkS")
		)
		(fp_line
			(start 0.889 1.7018)
			(end 0.889 -1.7018)
			(stroke
				(width 0.1524)
				(type default)
			)
			(layer "B.SilkS")
		)
		(fp_rect
			(start 0.9652 1.778)
			(end -0.9652 -1.778)
			(stroke
				(width 0)
				(type default)
			)
			(fill no)
			(layer "B.CrtYd")
		)
		(fp_rect
			(start 0.9652 1.778)
			(end -0.9652 -1.778)
			(stroke
				(width 0)
				(type default)
			)
			(fill no)
			(layer "B.Fab")
		)
		(pad "1" smd rect
			(at 0 -0.9652 180)
			(size 1.397 1.143)
			(layers "B.Cu" "B.Mask" "B.Paste")
			(net "P3V3_STBY")
		)
		(pad "2" smd rect
			(at 0 0.9652 180)
			(size 1.397 1.143)
			(layers "B.Cu" "B.Mask" "B.Paste")
			(net "ADCAV33")
		)
	)
	(footprint ""
		(layer "B.Cu")
		(at 296.48912 -170.7007)
		(property "Reference" "TP93"
			(at 0 0 0)
			(layer "B.SilkS")
			(hide yes)
			(effects
				(font
					(size 1.27 1.27)
				)
				(justify mirror)
			)
		)
		(property "Value" "TPAD28"
			(at -0.0127 -1.8034 0)
			(unlocked yes)
			(layer "B.Fab")
			(hide yes)
			(effects
				(font
					(size 1.016 1.016)
					(thickness 0.1524)
				)
				(justify mirror)
			)
		)
		(property "Device Type" "TPAD28"
			(at -0.0127 -3.3274 0)
			(unlocked yes)
			(layer "B.Fab")
			(hide yes)
			(effects
				(font
					(size 1.016 1.016)
					(thickness 0.1524)
				)
				(justify mirror)
			)
		)
		(duplicate_pad_numbers_are_jumpers no)
		(fp_poly
			(pts
				(arc
					(start 0.3556 0)
					(mid -0.3556 0)
					(end 0.3556 0)
				)
			)
			(stroke
				(width 0)
				(type default)
			)
			(fill no)
			(layer "B.CrtYd")
		)
		(fp_poly
			(pts
				(arc
					(start 0.6096 0)
					(mid -0.6096 0)
					(end 0.6096 0)
				)
			)
			(stroke
				(width 0)
				(type default)
			)
			(fill no)
			(layer "B.Fab")
		)
		(pad "1" smd circle
			(at 0 0 180)
			(size 0.7112 0.7112)
			(layers "B.Cu" "B.Mask" "B.Paste")
			(net "TP_GPIOH4")
		)
	)
	(footprint ""
		(layer "B.Cu")
		(at 108.020612 -218.44 -90)
		(property "Reference" "SR912"
			(at 0 0 90)
			(layer "B.SilkS")
			(hide yes)
			(effects
				(font
					(size 1.27 1.27)
				)
				(justify mirror)
			)
		)
		(property "Value" "4K7R2F-GP"
			(at -0.064008 -3.993896 270)
			(unlocked yes)
			(layer "B.Fab")
			(hide yes)
			(effects
				(font
					(size 1.016 1.016)
					(thickness 0.1524)
				)
				(justify mirror)
			)
		)
		(property "Device Type" "R402H16"
			(at -0.064008 -5.517896 270)
			(unlocked yes)
			(layer "B.Fab")
			(hide yes)
			(effects
				(font
					(size 1.016 1.016)
					(thickness 0.1524)
				)
				(justify mirror)
			)
		)
		(duplicate_pad_numbers_are_jumpers no)
		(fp_line
			(start -0.508 -0.9398)
			(end 0.508 -0.9398)
			(stroke
				(width 0.1524)
				(type default)
			)
			(layer "B.SilkS")
		)
		(fp_line
			(start 0.508 -0.9398)
			(end 0.508 0.9398)
			(stroke
				(width 0.1524)
				(type default)
			)
			(layer "B.SilkS")
		)
		(fp_rect
			(start 0.508 0.9398)
			(end -0.508 -0.9398)
			(stroke
				(width 0)
				(type default)
			)
			(fill no)
			(layer "B.CrtYd")
		)
		(fp_rect
			(start 0.508 0.9398)
			(end -0.508 -0.9398)
			(stroke
				(width 0)
				(type default)
			)
			(fill no)
			(layer "B.Fab")
		)
		(pad "1" smd custom
			(at 0 -0.4445 90)
			(size 0.1397 0.1397)
			(layers "B.Cu" "B.Mask" "B.Paste")
			(net "REDV_I2C_SEL1B")
			(options
				(clearance outline)
				(anchor circle)
			)
			(primitives
				(gr_poly
					(pts
						(arc
							(start -0.1778 0.2794)
							(mid -0.249642 0.249642)
							(end -0.2794 0.1778)
						)
						(arc
							(start -0.2794 -0.1778)
							(mid -0.249642 -0.249642)
							(end -0.1778 -0.2794)
						)
						(arc
							(start 0.1778 -0.2794)
							(mid 0.249642 -0.249642)
							(end 0.2794 -0.1778)
						)
						(arc
							(start 0.2794 0.1778)
							(mid 0.249642 0.249642)
							(end 0.1778 0.2794)
						)
					)
					(width 0)
					(fill yes)
				)
			)
		)
		(pad "2" smd custom
			(at 0 0.4445 90)
			(size 0.1397 0.1397)
			(layers "B.Cu" "B.Mask" "B.Paste")
			(net "GND")
			(options
				(clearance outline)
				(anchor circle)
			)
			(primitives
				(gr_poly
					(pts
						(arc
							(start -0.1778 0.2794)
							(mid -0.249642 0.249642)
							(end -0.2794 0.1778)
						)
						(arc
							(start -0.2794 -0.1778)
							(mid -0.249642 -0.249642)
							(end -0.1778 -0.2794)
						)
						(arc
							(start 0.1778 -0.2794)
							(mid 0.249642 -0.249642)
							(end 0.2794 -0.1778)
						)
						(arc
							(start 0.2794 0.1778)
							(mid 0.249642 0.249642)
							(end 0.1778 0.2794)
						)
					)
					(width 0)
					(fill yes)
				)
			)
		)
	)
	(footprint ""
		(layer "B.Cu")
		(at 350.5962 -71.8058 180)
		(property "Reference" "R295"
			(at 0 0 0)
			(layer "B.SilkS")
			(hide yes)
			(effects
				(font
					(size 1.27 1.27)
				)
				(justify mirror)
			)
		)
		(property "Value" "0R0402-PAD-1-GP"
			(at -0.064008 -3.993896 180)
			(unlocked yes)
			(layer "B.Fab")
			(hide yes)
			(effects
				(font
					(size 1.016 1.016)
					(thickness 0.1524)
				)
				(justify mirror)
			)
		)
		(property "Device Type" "0R0402-PAD"
			(at -0.064008 -5.517896 180)
			(unlocked yes)
			(layer "B.Fab")
			(hide yes)
			(effects
				(font
					(size 1.016 1.016)
					(thickness 0.1524)
				)
				(justify mirror)
			)
		)
		(duplicate_pad_numbers_are_jumpers no)
		(fp_line
			(start 0.508 -0.9398)
			(end 0.508 0.9398)
			(stroke
				(width 0.1524)
				(type default)
			)
			(layer "B.SilkS")
		)
		(fp_line
			(start -0.508 -0.9398)
			(end 0.508 -0.9398)
			(stroke
				(width 0.1524)
				(type default)
			)
			(layer "B.SilkS")
		)
		(fp_rect
			(start 0.508 0.9398)
			(end -0.508 -0.9398)
			(stroke
				(width 0)
				(type default)
			)
			(fill no)
			(layer "B.CrtYd")
		)
		(fp_rect
			(start 0.508 0.9398)
			(end -0.508 -0.9398)
			(stroke
				(width 0)
				(type default)
			)
			(fill no)
			(layer "B.Fab")
		)
		(pad "1" smd custom
			(at 0 -0.4445)
			(size 0.1397 0.1397)
			(layers "B.Cu" "B.Mask" "B.Paste")
			(net "ROMD0_R")
			(options
				(clearance outline)
				(anchor circle)
			)
			(primitives
				(gr_poly
					(pts
						(xy -0.2794 -0.3683)
						(arc
							(start -0.2794 0.2667)
							(mid -0.249642 0.338542)
							(end -0.1778 0.3683)
						)
						(arc
							(start 0.1778 0.3683)
							(mid 0.249642 0.338542)
							(end 0.2794 0.2667)
						)
						(xy 0.2794 -0.3683)
					)
					(width 0)
					(fill yes)
				)
			)
		)
		(pad "2" smd custom
			(at 0 0.4445)
			(size 0.1397 0.1397)
			(layers "B.Cu" "B.Mask" "B.Paste")
			(net "ROMD0")
			(options
				(clearance outline)
				(anchor circle)
			)
			(primitives
				(gr_poly
					(pts
						(arc
							(start -0.1778 -0.3683)
							(mid -0.249642 -0.338542)
							(end -0.2794 -0.2667)
						)
						(xy -0.2794 0.3683) (xy 0.2794 0.3683)
						(arc
							(start 0.2794 -0.2667)
							(mid 0.249642 -0.338542)
							(end 0.1778 -0.3683)
						)
					)
					(width 0)
					(fill yes)
				)
			)
		)
	)
	(footprint ""
		(layer "B.Cu")
		(at 319.913 -164.338 -90)
		(property "Reference" "R438"
			(at 0 0 90)
			(layer "B.SilkS")
			(hide yes)
			(effects
				(font
					(size 1.27 1.27)
				)
				(justify mirror)
			)
		)
		(property "Value" "10KR2F-2-GP"
			(at -0.064008 -3.993896 270)
			(unlocked yes)
			(layer "B.Fab")
			(hide yes)
			(effects
				(font
					(size 1.016 1.016)
					(thickness 0.1524)
				)
				(justify mirror)
			)
		)
		(property "Device Type" "R402H16"
			(at -0.064008 -5.517896 270)
			(unlocked yes)
			(layer "B.Fab")
			(hide yes)
			(effects
				(font
					(size 1.016 1.016)
					(thickness 0.1524)
				)
				(justify mirror)
			)
		)
		(duplicate_pad_numbers_are_jumpers no)
		(fp_line
			(start -0.508 -0.9398)
			(end 0.508 -0.9398)
			(stroke
				(width 0.1524)
				(type default)
			)
			(layer "B.SilkS")
		)
		(fp_line
			(start 0.508 -0.9398)
			(end 0.508 0.9398)
			(stroke
				(width 0.1524)
				(type default)
			)
			(layer "B.SilkS")
		)
		(fp_rect
			(start 0.508 0.9398)
			(end -0.508 -0.9398)
			(stroke
				(width 0)
				(type default)
			)
			(fill no)
			(layer "B.CrtYd")
		)
		(fp_rect
			(start 0.508 0.9398)
			(end -0.508 -0.9398)
			(stroke
				(width 0)
				(type default)
			)
			(fill no)
			(layer "B.Fab")
		)
		(pad "1" smd custom
			(at 0 -0.4445 90)
			(size 0.1397 0.1397)
			(layers "B.Cu" "B.Mask" "B.Paste")
			(net "P3V3_STBY")
			(options
				(clearance outline)
				(anchor circle)
			)
			(primitives
				(gr_poly
					(pts
						(arc
							(start -0.1778 0.2794)
							(mid -0.249642 0.249642)
							(end -0.2794 0.1778)
						)
						(arc
							(start -0.2794 -0.1778)
							(mid -0.249642 -0.249642)
							(end -0.1778 -0.2794)
						)
						(arc
							(start 0.1778 -0.2794)
							(mid 0.249642 -0.249642)
							(end 0.2794 -0.1778)
						)
						(arc
							(start 0.2794 0.1778)
							(mid 0.249642 0.249642)
							(end 0.1778 0.2794)
						)
					)
					(width 0)
					(fill yes)
				)
			)
		)
		(pad "2" smd custom
			(at 0 0.4445 90)
			(size 0.1397 0.1397)
			(layers "B.Cu" "B.Mask" "B.Paste")
			(net "NIC_SMBUS_SDA")
			(options
				(clearance outline)
				(anchor circle)
			)
			(primitives
				(gr_poly
					(pts
						(arc
							(start -0.1778 0.2794)
							(mid -0.249642 0.249642)
							(end -0.2794 0.1778)
						)
						(arc
							(start -0.2794 -0.1778)
							(mid -0.249642 -0.249642)
							(end -0.1778 -0.2794)
						)
						(arc
							(start 0.1778 -0.2794)
							(mid 0.249642 -0.249642)
							(end 0.2794 -0.1778)
						)
						(arc
							(start 0.2794 0.1778)
							(mid 0.249642 0.249642)
							(end 0.1778 0.2794)
						)
					)
					(width 0)
					(fill yes)
				)
			)
		)
	)
	(footprint ""
		(layer "B.Cu")
		(at 105.264966 -46.609 90)
		(property "Reference" "SC1035"
			(at 0 0 90)
			(layer "B.SilkS")
			(hide yes)
			(effects
				(font
					(size 1.27 1.27)
				)
				(justify mirror)
			)
		)
		(property "Value" "SC1KP50V2KX-1GP"
			(at -1.1811 -2.7051 90)
			(unlocked yes)
			(layer "B.Fab")
			(hide yes)
			(effects
				(font
					(size 1.016 1.016)
					(thickness 0.1524)
				)
				(justify mirror)
			)
		)
		(property "Device Type" "C402H22"
			(at -1.1811 -4.2291 90)
			(unlocked yes)
			(layer "B.Fab")
			(hide yes)
			(effects
				(font
					(size 1.016 1.016)
					(thickness 0.1524)
				)
				(justify mirror)
			)
		)
		(duplicate_pad_numbers_are_jumpers no)
		(fp_rect
			(start 0.4318 0.9525)
			(end -0.4318 -0.9525)
			(stroke
				(width 0)
				(type default)
			)
			(fill no)
			(layer "B.CrtYd")
		)
		(fp_rect
			(start 0.4318 0.9525)
			(end -0.4318 -0.9525)
			(stroke
				(width 0)
				(type default)
			)
			(fill no)
			(layer "B.Fab")
		)
		(pad "1" smd custom
			(at 0 -0.4445 270)
			(size 0.1524 0.1524)
			(layers "B.Cu" "B.Mask" "B.Paste")
			(net "P0V955_C")
			(options
				(clearance outline)
				(anchor circle)
			)
			(primitives
				(gr_poly
					(pts
						(arc
							(start 0.3048 0.2032)
							(mid 0.275042 0.275042)
							(end 0.2032 0.3048)
						)
						(arc
							(start -0.2032 0.3048)
							(mid -0.275042 0.275042)
							(end -0.3048 0.2032)
						)
						(arc
							(start -0.3048 -0.2032)
							(mid -0.275042 -0.275042)
							(end -0.2032 -0.3048)
						)
						(arc
							(start 0.2032 -0.3048)
							(mid 0.275042 -0.275042)
							(end 0.3048 -0.2032)
						)
					)
					(width 0)
					(fill yes)
				)
			)
		)
		(pad "2" smd custom
			(at 0 0.4445 270)
			(size 0.1524 0.1524)
			(layers "B.Cu" "B.Mask" "B.Paste")
			(net "GND")
			(options
				(clearance outline)
				(anchor circle)
			)
			(primitives
				(gr_poly
					(pts
						(arc
							(start 0.3048 0.2032)
							(mid 0.275042 0.275042)
							(end 0.2032 0.3048)
						)
						(arc
							(start -0.2032 0.3048)
							(mid -0.275042 0.275042)
							(end -0.3048 0.2032)
						)
						(arc
							(start -0.3048 -0.2032)
							(mid -0.275042 -0.275042)
							(end -0.2032 -0.3048)
						)
						(arc
							(start 0.2032 -0.3048)
							(mid 0.275042 -0.275042)
							(end 0.3048 -0.2032)
						)
					)
					(width 0)
					(fill yes)
				)
			)
		)
	)
	(footprint ""
		(layer "B.Cu")
		(at 114.360198 -50.89525)
		(property "Reference" "STP161"
			(at 0 0 0)
			(layer "B.SilkS")
			(hide yes)
			(effects
				(font
					(size 1.27 1.27)
				)
				(justify mirror)
			)
		)
		(property "Value" "TPAD28"
			(at -0.0127 -1.8034 0)
			(unlocked yes)
			(layer "B.Fab")
			(hide yes)
			(effects
				(font
					(size 1.016 1.016)
					(thickness 0.1524)
				)
				(justify mirror)
			)
		)
		(property "Device Type" "TPAD28"
			(at -0.0127 -3.3274 0)
			(unlocked yes)
			(layer "B.Fab")
			(hide yes)
			(effects
				(font
					(size 1.016 1.016)
					(thickness 0.1524)
				)
				(justify mirror)
			)
		)
		(duplicate_pad_numbers_are_jumpers no)
		(fp_poly
			(pts
				(arc
					(start 0.3556 0)
					(mid -0.3556 0)
					(end 0.3556 0)
				)
			)
			(stroke
				(width 0)
				(type default)
			)
			(fill no)
			(layer "B.CrtYd")
		)
		(fp_poly
			(pts
				(arc
					(start 0.6096 0)
					(mid -0.6096 0)
					(end 0.6096 0)
				)
			)
			(stroke
				(width 0)
				(type default)
			)
			(fill no)
			(layer "B.Fab")
		)
		(pad "1" smd circle
			(at 0 0 180)
			(size 0.7112 0.7112)
			(layers "B.Cu" "B.Mask" "B.Paste")
			(net "XM_ADDR_25")
		)
	)
	(footprint ""
		(layer "B.Cu")
		(at 319.913 -169.545 90)
		(property "Reference" "R436"
			(at 0 0 90)
			(layer "B.SilkS")
			(hide yes)
			(effects
				(font
					(size 1.27 1.27)
				)
				(justify mirror)
			)
		)
		(property "Value" "4K7R2F-GP"
			(at -0.064008 -3.993896 90)
			(unlocked yes)
			(layer "B.Fab")
			(hide yes)
			(effects
				(font
					(size 1.016 1.016)
					(thickness 0.1524)
				)
				(justify mirror)
			)
		)
		(property "Device Type" "R402H16"
			(at -0.064008 -5.517896 90)
			(unlocked yes)
			(layer "B.Fab")
			(hide yes)
			(effects
				(font
					(size 1.016 1.016)
					(thickness 0.1524)
				)
				(justify mirror)
			)
		)
		(duplicate_pad_numbers_are_jumpers no)
		(fp_line
			(start 0.508 -0.9398)
			(end 0.508 0.9398)
			(stroke
				(width 0.1524)
				(type default)
			)
			(layer "B.SilkS")
		)
		(fp_line
			(start -0.508 -0.9398)
			(end 0.508 -0.9398)
			(stroke
				(width 0.1524)
				(type default)
			)
			(layer "B.SilkS")
		)
		(fp_rect
			(start 0.508 0.9398)
			(end -0.508 -0.9398)
			(stroke
				(width 0)
				(type default)
			)
			(fill no)
			(layer "B.CrtYd")
		)
		(fp_rect
			(start 0.508 0.9398)
			(end -0.508 -0.9398)
			(stroke
				(width 0)
				(type default)
			)
			(fill no)
			(layer "B.Fab")
		)
		(pad "1" smd custom
			(at 0 -0.4445 270)
			(size 0.1397 0.1397)
			(layers "B.Cu" "B.Mask" "B.Paste")
			(net "BMC_I2C_A_SDA")
			(options
				(clearance outline)
				(anchor circle)
			)
			(primitives
				(gr_poly
					(pts
						(arc
							(start -0.1778 0.2794)
							(mid -0.249642 0.249642)
							(end -0.2794 0.1778)
						)
						(arc
							(start -0.2794 -0.1778)
							(mid -0.249642 -0.249642)
							(end -0.1778 -0.2794)
						)
						(arc
							(start 0.1778 -0.2794)
							(mid 0.249642 -0.249642)
							(end 0.2794 -0.1778)
						)
						(arc
							(start 0.2794 0.1778)
							(mid 0.249642 0.249642)
							(end 0.1778 0.2794)
						)
					)
					(width 0)
					(fill yes)
				)
			)
		)
		(pad "2" smd custom
			(at 0 0.4445 270)
			(size 0.1397 0.1397)
			(layers "B.Cu" "B.Mask" "B.Paste")
			(net "P3V3_STBY")
			(options
				(clearance outline)
				(anchor circle)
			)
			(primitives
				(gr_poly
					(pts
						(arc
							(start -0.1778 0.2794)
							(mid -0.249642 0.249642)
							(end -0.2794 0.1778)
						)
						(arc
							(start -0.2794 -0.1778)
							(mid -0.249642 -0.249642)
							(end -0.1778 -0.2794)
						)
						(arc
							(start 0.1778 -0.2794)
							(mid 0.249642 -0.249642)
							(end 0.2794 -0.1778)
						)
						(arc
							(start 0.2794 0.1778)
							(mid 0.249642 0.249642)
							(end 0.1778 0.2794)
						)
					)
					(width 0)
					(fill yes)
				)
			)
		)
	)
	(footprint ""
		(layer "B.Cu")
		(at 289.306 -172.3644)
		(property "Reference" "TP182"
			(at 0 0 0)
			(layer "B.SilkS")
			(hide yes)
			(effects
				(font
					(size 1.27 1.27)
				)
				(justify mirror)
			)
		)
		(property "Value" "TPAD28"
			(at -0.0127 -1.8034 0)
			(unlocked yes)
			(layer "B.Fab")
			(hide yes)
			(effects
				(font
					(size 1.016 1.016)
					(thickness 0.1524)
				)
				(justify mirror)
			)
		)
		(property "Device Type" "TPAD28"
			(at -0.0127 -3.3274 0)
			(unlocked yes)
			(layer "B.Fab")
			(hide yes)
			(effects
				(font
					(size 1.016 1.016)
					(thickness 0.1524)
				)
				(justify mirror)
			)
		)
		(duplicate_pad_numbers_are_jumpers no)
		(fp_poly
			(pts
				(arc
					(start 0.3556 0)
					(mid -0.3556 0)
					(end 0.3556 0)
				)
			)
			(stroke
				(width 0)
				(type default)
			)
			(fill no)
			(layer "B.CrtYd")
		)
		(fp_poly
			(pts
				(arc
					(start 0.6096 0)
					(mid -0.6096 0)
					(end 0.6096 0)
				)
			)
			(stroke
				(width 0)
				(type default)
			)
			(fill no)
			(layer "B.Fab")
		)
		(pad "1" smd circle
			(at 0 0 180)
			(size 0.7112 0.7112)
			(layers "B.Cu" "B.Mask" "B.Paste")
			(net "TP_BMC_GPIOF6")
		)
	)
	(footprint ""
		(layer "B.Cu")
		(at 317.5 -181.737 -90)
		(property "Reference" "R373"
			(at 0 0 90)
			(layer "B.SilkS")
			(hide yes)
			(effects
				(font
					(size 1.27 1.27)
				)
				(justify mirror)
			)
		)
		(property "Value" "0R2J-2-GP"
			(at -0.064008 -3.993896 270)
			(unlocked yes)
			(layer "B.Fab")
			(hide yes)
			(effects
				(font
					(size 1.016 1.016)
					(thickness 0.1524)
				)
				(justify mirror)
			)
		)
		(property "Device Type" "R402H16"
			(at -0.064008 -5.517896 270)
			(unlocked yes)
			(layer "B.Fab")
			(hide yes)
			(effects
				(font
					(size 1.016 1.016)
					(thickness 0.1524)
				)
				(justify mirror)
			)
		)
		(duplicate_pad_numbers_are_jumpers no)
		(fp_line
			(start -0.508 -0.9398)
			(end 0.508 -0.9398)
			(stroke
				(width 0.1524)
				(type default)
			)
			(layer "B.SilkS")
		)
		(fp_line
			(start 0.508 -0.9398)
			(end 0.508 0.9398)
			(stroke
				(width 0.1524)
				(type default)
			)
			(layer "B.SilkS")
		)
		(fp_rect
			(start 0.508 0.9398)
			(end -0.508 -0.9398)
			(stroke
				(width 0)
				(type default)
			)
			(fill no)
			(layer "B.CrtYd")
		)
		(fp_rect
			(start 0.508 0.9398)
			(end -0.508 -0.9398)
			(stroke
				(width 0)
				(type default)
			)
			(fill no)
			(layer "B.Fab")
		)
		(pad "1" smd custom
			(at 0 -0.4445 90)
			(size 0.1397 0.1397)
			(layers "B.Cu" "B.Mask" "B.Paste")
			(net "ADC_P1V5_E")
			(options
				(clearance outline)
				(anchor circle)
			)
			(primitives
				(gr_poly
					(pts
						(arc
							(start -0.1778 0.2794)
							(mid -0.249642 0.249642)
							(end -0.2794 0.1778)
						)
						(arc
							(start -0.2794 -0.1778)
							(mid -0.249642 -0.249642)
							(end -0.1778 -0.2794)
						)
						(arc
							(start 0.1778 -0.2794)
							(mid 0.249642 -0.249642)
							(end 0.2794 -0.1778)
						)
						(arc
							(start 0.2794 0.1778)
							(mid 0.249642 0.249642)
							(end 0.1778 0.2794)
						)
					)
					(width 0)
					(fill yes)
				)
			)
		)
		(pad "2" smd custom
			(at 0 0.4445 90)
			(size 0.1397 0.1397)
			(layers "B.Cu" "B.Mask" "B.Paste")
			(net "ADC_P1V5_E_BMC")
			(options
				(clearance outline)
				(anchor circle)
			)
			(primitives
				(gr_poly
					(pts
						(arc
							(start -0.1778 0.2794)
							(mid -0.249642 0.249642)
							(end -0.2794 0.1778)
						)
						(arc
							(start -0.2794 -0.1778)
							(mid -0.249642 -0.249642)
							(end -0.1778 -0.2794)
						)
						(arc
							(start 0.1778 -0.2794)
							(mid 0.249642 -0.249642)
							(end 0.2794 -0.1778)
						)
						(arc
							(start 0.2794 0.1778)
							(mid 0.249642 0.249642)
							(end 0.1778 0.2794)
						)
					)
					(width 0)
					(fill yes)
				)
			)
		)
	)
	(footprint ""
		(layer "B.Cu")
		(at 123.298966 -42.164 90)
		(property "Reference" "SC994"
			(at 0 0 90)
			(layer "B.SilkS")
			(hide yes)
			(effects
				(font
					(size 1.27 1.27)
				)
				(justify mirror)
			)
		)
		(property "Value" "SCD1U16V2KX-3GP"
			(at -1.1811 -2.7051 90)
			(unlocked yes)
			(layer "B.Fab")
			(hide yes)
			(effects
				(font
					(size 1.016 1.016)
					(thickness 0.1524)
				)
				(justify mirror)
			)
		)
		(property "Device Type" "C402H22"
			(at -1.1811 -4.2291 90)
			(unlocked yes)
			(layer "B.Fab")
			(hide yes)
			(effects
				(font
					(size 1.016 1.016)
					(thickness 0.1524)
				)
				(justify mirror)
			)
		)
		(duplicate_pad_numbers_are_jumpers no)
		(fp_rect
			(start 0.4318 0.9525)
			(end -0.4318 -0.9525)
			(stroke
				(width 0)
				(type default)
			)
			(fill no)
			(layer "B.CrtYd")
		)
		(fp_rect
			(start 0.4318 0.9525)
			(end -0.4318 -0.9525)
			(stroke
				(width 0)
				(type default)
			)
			(fill no)
			(layer "B.Fab")
		)
		(pad "1" smd custom
			(at 0 -0.4445 270)
			(size 0.1524 0.1524)
			(layers "B.Cu" "B.Mask" "B.Paste")
			(net "P1V8_C")
			(options
				(clearance outline)
				(anchor circle)
			)
			(primitives
				(gr_poly
					(pts
						(arc
							(start 0.3048 0.2032)
							(mid 0.275042 0.275042)
							(end 0.2032 0.3048)
						)
						(arc
							(start -0.2032 0.3048)
							(mid -0.275042 0.275042)
							(end -0.3048 0.2032)
						)
						(arc
							(start -0.3048 -0.2032)
							(mid -0.275042 -0.275042)
							(end -0.2032 -0.3048)
						)
						(arc
							(start 0.2032 -0.3048)
							(mid 0.275042 -0.275042)
							(end 0.3048 -0.2032)
						)
					)
					(width 0)
					(fill yes)
				)
			)
		)
		(pad "2" smd custom
			(at 0 0.4445 270)
			(size 0.1524 0.1524)
			(layers "B.Cu" "B.Mask" "B.Paste")
			(net "GND")
			(options
				(clearance outline)
				(anchor circle)
			)
			(primitives
				(gr_poly
					(pts
						(arc
							(start 0.3048 0.2032)
							(mid 0.275042 0.275042)
							(end 0.2032 0.3048)
						)
						(arc
							(start -0.2032 0.3048)
							(mid -0.275042 0.275042)
							(end -0.3048 0.2032)
						)
						(arc
							(start -0.3048 -0.2032)
							(mid -0.275042 -0.275042)
							(end -0.2032 -0.3048)
						)
						(arc
							(start 0.2032 -0.3048)
							(mid 0.275042 -0.275042)
							(end 0.3048 -0.2032)
						)
					)
					(width 0)
					(fill yes)
				)
			)
		)
	)
	(footprint ""
		(layer "B.Cu")
		(at 108.020612 -205.867)
		(property "Reference" "SR897"
			(at 0 0 0)
			(layer "B.SilkS")
			(hide yes)
			(effects
				(font
					(size 1.27 1.27)
				)
				(justify mirror)
			)
		)
		(property "Value" "0R2J-2-GP"
			(at -0.064008 -3.993896 0)
			(unlocked yes)
			(layer "B.Fab")
			(hide yes)
			(effects
				(font
					(size 1.016 1.016)
					(thickness 0.1524)
				)
				(justify mirror)
			)
		)
		(property "Device Type" "R402H16"
			(at -0.064008 -5.517896 0)
			(unlocked yes)
			(layer "B.Fab")
			(hide yes)
			(effects
				(font
					(size 1.016 1.016)
					(thickness 0.1524)
				)
				(justify mirror)
			)
		)
		(duplicate_pad_numbers_are_jumpers no)
		(fp_line
			(start -0.508 -0.9398)
			(end 0.508 -0.9398)
			(stroke
				(width 0.1524)
				(type default)
			)
			(layer "B.SilkS")
		)
		(fp_line
			(start 0.508 -0.9398)
			(end 0.508 0.9398)
			(stroke
				(width 0.1524)
				(type default)
			)
			(layer "B.SilkS")
		)
		(fp_rect
			(start 0.508 0.9398)
			(end -0.508 -0.9398)
			(stroke
				(width 0)
				(type default)
			)
			(fill no)
			(layer "B.CrtYd")
		)
		(fp_rect
			(start 0.508 0.9398)
			(end -0.508 -0.9398)
			(stroke
				(width 0)
				(type default)
			)
			(fill no)
			(layer "B.Fab")
		)
		(pad "1" smd custom
			(at 0 -0.4445 180)
			(size 0.1397 0.1397)
			(layers "B.Cu" "B.Mask" "B.Paste")
			(net "SAS_HDD_REDV_SER_RX8_N")
			(options
				(clearance outline)
				(anchor circle)
			)
			(primitives
				(gr_poly
					(pts
						(arc
							(start -0.1778 0.2794)
							(mid -0.249642 0.249642)
							(end -0.2794 0.1778)
						)
						(arc
							(start -0.2794 -0.1778)
							(mid -0.249642 -0.249642)
							(end -0.1778 -0.2794)
						)
						(arc
							(start 0.1778 -0.2794)
							(mid 0.249642 -0.249642)
							(end 0.2794 -0.1778)
						)
						(arc
							(start 0.2794 0.1778)
							(mid 0.249642 0.249642)
							(end 0.1778 0.2794)
						)
					)
					(width 0)
					(fill yes)
				)
			)
		)
		(pad "2" smd custom
			(at 0 0.4445 180)
			(size 0.1397 0.1397)
			(layers "B.Cu" "B.Mask" "B.Paste")
			(net "SAS_HDD_CONN_RX8_N")
			(options
				(clearance outline)
				(anchor circle)
			)
			(primitives
				(gr_poly
					(pts
						(arc
							(start -0.1778 0.2794)
							(mid -0.249642 0.249642)
							(end -0.2794 0.1778)
						)
						(arc
							(start -0.2794 -0.1778)
							(mid -0.249642 -0.249642)
							(end -0.1778 -0.2794)
						)
						(arc
							(start 0.1778 -0.2794)
							(mid 0.249642 -0.249642)
							(end 0.2794 -0.1778)
						)
						(arc
							(start 0.2794 0.1778)
							(mid 0.249642 0.249642)
							(end 0.1778 0.2794)
						)
					)
					(width 0)
					(fill yes)
				)
			)
		)
	)
	(footprint ""
		(layer "B.Cu")
		(at 162.687 -89.154)
		(property "Reference" "PC176"
			(at 0 0 0)
			(layer "B.SilkS")
			(hide yes)
			(effects
				(font
					(size 1.27 1.27)
				)
				(justify mirror)
			)
		)
		(property "Value" "SC22U6D3V3MX-1-GP"
			(at 0 -2.8194 0)
			(unlocked yes)
			(layer "B.Fab")
			(hide yes)
			(effects
				(font
					(size 1.016 1.016)
					(thickness 0.1524)
				)
				(justify mirror)
			)
		)
		(property "Device Type" "C603H40"
			(at 0 -4.3434 0)
			(unlocked yes)
			(layer "B.Fab")
			(hide yes)
			(effects
				(font
					(size 1.016 1.016)
					(thickness 0.1524)
				)
				(justify mirror)
			)
		)
		(duplicate_pad_numbers_are_jumpers no)
		(fp_line
			(start -0.508 0)
			(end 0.508 0)
			(stroke
				(width 0.2032)
				(type default)
			)
			(layer "B.SilkS")
		)
		(fp_rect
			(start 0.5842 1.3335)
			(end -0.5842 -1.3335)
			(stroke
				(width 0)
				(type default)
			)
			(fill no)
			(layer "B.CrtYd")
		)
		(fp_rect
			(start 0.5842 1.3335)
			(end -0.5842 -1.3335)
			(stroke
				(width 0)
				(type default)
			)
			(fill no)
			(layer "B.Fab")
		)
		(pad "1" smd custom
			(at 0 -0.762 180)
			(size 0.2159 0.2159)
			(layers "B.Cu" "B.Mask" "B.Paste")
			(net "P0V9_E")
			(options
				(clearance outline)
				(anchor circle)
			)
			(primitives
				(gr_poly
					(pts
						(arc
							(start -0.3302 0.4318)
							(mid -0.402042 0.402042)
							(end -0.4318 0.3302)
						)
						(arc
							(start -0.4318 -0.3302)
							(mid -0.402042 -0.402042)
							(end -0.3302 -0.4318)
						)
						(arc
							(start 0.3302 -0.4318)
							(mid 0.402042 -0.402042)
							(end 0.4318 -0.3302)
						)
						(arc
							(start 0.4318 0.3302)
							(mid 0.402042 0.402042)
							(end 0.3302 0.4318)
						)
					)
					(width 0)
					(fill yes)
				)
			)
		)
		(pad "2" smd custom
			(at 0 0.762 180)
			(size 0.2159 0.2159)
			(layers "B.Cu" "B.Mask" "B.Paste")
			(net "GND")
			(options
				(clearance outline)
				(anchor circle)
			)
			(primitives
				(gr_poly
					(pts
						(arc
							(start -0.3302 0.4318)
							(mid -0.402042 0.402042)
							(end -0.4318 0.3302)
						)
						(arc
							(start -0.4318 -0.3302)
							(mid -0.402042 -0.402042)
							(end -0.3302 -0.4318)
						)
						(arc
							(start 0.3302 -0.4318)
							(mid 0.402042 -0.402042)
							(end 0.4318 -0.3302)
						)
						(arc
							(start 0.4318 0.3302)
							(mid 0.402042 0.402042)
							(end 0.3302 0.4318)
						)
					)
					(width 0)
					(fill yes)
				)
			)
		)
	)
	(footprint ""
		(layer "B.Cu")
		(at 26.366216 -232.33888)
		(property "Reference" "R503"
			(at 0 0 0)
			(layer "B.SilkS")
			(hide yes)
			(effects
				(font
					(size 1.27 1.27)
				)
				(justify mirror)
			)
		)
		(property "Value" "0R2J-2-GP"
			(at -0.064008 -3.993896 0)
			(unlocked yes)
			(layer "B.Fab")
			(hide yes)
			(effects
				(font
					(size 1.016 1.016)
					(thickness 0.1524)
				)
				(justify mirror)
			)
		)
		(property "Device Type" "R402H16"
			(at -0.064008 -5.517896 0)
			(unlocked yes)
			(layer "B.Fab")
			(hide yes)
			(effects
				(font
					(size 1.016 1.016)
					(thickness 0.1524)
				)
				(justify mirror)
			)
		)
		(duplicate_pad_numbers_are_jumpers no)
		(fp_line
			(start -0.508 -0.9398)
			(end 0.508 -0.9398)
			(stroke
				(width 0.1524)
				(type default)
			)
			(layer "B.SilkS")
		)
		(fp_line
			(start 0.508 -0.9398)
			(end 0.508 0.9398)
			(stroke
				(width 0.1524)
				(type default)
			)
			(layer "B.SilkS")
		)
		(fp_rect
			(start 0.508 0.9398)
			(end -0.508 -0.9398)
			(stroke
				(width 0)
				(type default)
			)
			(fill no)
			(layer "B.CrtYd")
		)
		(fp_rect
			(start 0.508 0.9398)
			(end -0.508 -0.9398)
			(stroke
				(width 0)
				(type default)
			)
			(fill no)
			(layer "B.Fab")
		)
		(pad "1" smd custom
			(at 0 -0.4445 180)
			(size 0.1397 0.1397)
			(layers "B.Cu" "B.Mask" "B.Paste")
			(net "SAS_HDD_PWR1_PCIE")
			(options
				(clearance outline)
				(anchor circle)
			)
			(primitives
				(gr_poly
					(pts
						(arc
							(start -0.1778 0.2794)
							(mid -0.249642 0.249642)
							(end -0.2794 0.1778)
						)
						(arc
							(start -0.2794 -0.1778)
							(mid -0.249642 -0.249642)
							(end -0.1778 -0.2794)
						)
						(arc
							(start 0.1778 -0.2794)
							(mid 0.249642 -0.249642)
							(end 0.2794 -0.1778)
						)
						(arc
							(start 0.2794 0.1778)
							(mid 0.249642 0.249642)
							(end 0.1778 0.2794)
						)
					)
					(width 0)
					(fill yes)
				)
			)
		)
		(pad "2" smd custom
			(at 0 0.4445 180)
			(size 0.1397 0.1397)
			(layers "B.Cu" "B.Mask" "B.Paste")
			(net "SAS_HDD_PWR1")
			(options
				(clearance outline)
				(anchor circle)
			)
			(primitives
				(gr_poly
					(pts
						(arc
							(start -0.1778 0.2794)
							(mid -0.249642 0.249642)
							(end -0.2794 0.1778)
						)
						(arc
							(start -0.2794 -0.1778)
							(mid -0.249642 -0.249642)
							(end -0.1778 -0.2794)
						)
						(arc
							(start 0.1778 -0.2794)
							(mid 0.249642 -0.249642)
							(end 0.2794 -0.1778)
						)
						(arc
							(start 0.2794 0.1778)
							(mid 0.249642 0.249642)
							(end 0.1778 0.2794)
						)
					)
					(width 0)
					(fill yes)
				)
			)
		)
	)
	(footprint ""
		(layer "B.Cu")
		(at 121.544842 -83.307682 90)
		(property "Reference" "SC1153"
			(at 0 0 90)
			(layer "B.SilkS")
			(hide yes)
			(effects
				(font
					(size 1.27 1.27)
				)
				(justify mirror)
			)
		)
		(property "Value" "SCD1U6D3V1KX-GP"
			(at 2.8321 -1.7399 90)
			(unlocked yes)
			(layer "B.Fab")
			(hide yes)
			(effects
				(font
					(size 1.016 1.016)
					(thickness 0.1524)
				)
				(justify mirror)
			)
		)
		(property "Device Type" "C0201H13"
			(at 2.8321 -3.2639 90)
			(unlocked yes)
			(layer "B.Fab")
			(hide yes)
			(effects
				(font
					(size 1.016 1.016)
					(thickness 0.1524)
				)
				(justify mirror)
			)
		)
		(duplicate_pad_numbers_are_jumpers no)
		(fp_rect
			(start 0.2794 0.6477)
			(end -0.2794 -0.6477)
			(stroke
				(width 0)
				(type default)
			)
			(fill no)
			(layer "B.CrtYd")
		)
		(fp_rect
			(start 0.2794 0.6477)
			(end -0.2794 -0.6477)
			(stroke
				(width 0)
				(type default)
			)
			(fill no)
			(layer "B.Fab")
		)
		(pad "1" smd custom
			(at 0 -0.2794 270)
			(size 0.0762 0.0762)
			(layers "B.Cu" "B.Mask" "B.Paste")
			(net "XTAL_VDDA18")
			(options
				(clearance outline)
				(anchor circle)
			)
			(primitives
				(gr_poly
					(pts
						(arc
							(start 0.1524 0.127)
							(mid 0.137521 0.162921)
							(end 0.1016 0.1778)
						)
						(arc
							(start -0.1016 0.1778)
							(mid -0.137521 0.162921)
							(end -0.1524 0.127)
						)
						(arc
							(start -0.1524 -0.127)
							(mid -0.137521 -0.162921)
							(end -0.1016 -0.1778)
						)
						(arc
							(start 0.1016 -0.1778)
							(mid 0.137521 -0.162921)
							(end 0.1524 -0.127)
						)
					)
					(width 0)
					(fill yes)
				)
			)
		)
		(pad "2" smd custom
			(at 0 0.2794 270)
			(size 0.0762 0.0762)
			(layers "B.Cu" "B.Mask" "B.Paste")
			(net "GND")
			(options
				(clearance outline)
				(anchor circle)
			)
			(primitives
				(gr_poly
					(pts
						(arc
							(start 0.1524 0.127)
							(mid 0.137521 0.162921)
							(end 0.1016 0.1778)
						)
						(arc
							(start -0.1016 0.1778)
							(mid -0.137521 0.162921)
							(end -0.1524 0.127)
						)
						(arc
							(start -0.1524 -0.127)
							(mid -0.137521 -0.162921)
							(end -0.1016 -0.1778)
						)
						(arc
							(start 0.1016 -0.1778)
							(mid 0.137521 -0.162921)
							(end 0.1524 -0.127)
						)
					)
					(width 0)
					(fill yes)
				)
			)
		)
	)
	(footprint ""
		(layer "B.Cu")
		(at 86.11616 -49.022 90)
		(property "Reference" "SR626"
			(at 0 0 90)
			(layer "B.SilkS")
			(hide yes)
			(effects
				(font
					(size 1.27 1.27)
				)
				(justify mirror)
			)
		)
		(property "Value" "2K2R2F-GP"
			(at -0.064008 -3.993896 90)
			(unlocked yes)
			(layer "B.Fab")
			(hide yes)
			(effects
				(font
					(size 1.016 1.016)
					(thickness 0.1524)
				)
				(justify mirror)
			)
		)
		(property "Device Type" "R402H16"
			(at -0.064008 -5.517896 90)
			(unlocked yes)
			(layer "B.Fab")
			(hide yes)
			(effects
				(font
					(size 1.016 1.016)
					(thickness 0.1524)
				)
				(justify mirror)
			)
		)
		(duplicate_pad_numbers_are_jumpers no)
		(fp_line
			(start 0.508 -0.9398)
			(end 0.508 0.9398)
			(stroke
				(width 0.1524)
				(type default)
			)
			(layer "B.SilkS")
		)
		(fp_line
			(start -0.508 -0.9398)
			(end 0.508 -0.9398)
			(stroke
				(width 0.1524)
				(type default)
			)
			(layer "B.SilkS")
		)
		(fp_rect
			(start 0.508 0.9398)
			(end -0.508 -0.9398)
			(stroke
				(width 0)
				(type default)
			)
			(fill no)
			(layer "B.CrtYd")
		)
		(fp_rect
			(start 0.508 0.9398)
			(end -0.508 -0.9398)
			(stroke
				(width 0)
				(type default)
			)
			(fill no)
			(layer "B.Fab")
		)
		(pad "1" smd custom
			(at 0 -0.4445 270)
			(size 0.1397 0.1397)
			(layers "B.Cu" "B.Mask" "B.Paste")
			(net "P1V8_C")
			(options
				(clearance outline)
				(anchor circle)
			)
			(primitives
				(gr_poly
					(pts
						(arc
							(start -0.1778 0.2794)
							(mid -0.249642 0.249642)
							(end -0.2794 0.1778)
						)
						(arc
							(start -0.2794 -0.1778)
							(mid -0.249642 -0.249642)
							(end -0.1778 -0.2794)
						)
						(arc
							(start 0.1778 -0.2794)
							(mid 0.249642 -0.249642)
							(end 0.2794 -0.1778)
						)
						(arc
							(start 0.2794 0.1778)
							(mid 0.249642 0.249642)
							(end 0.1778 0.2794)
						)
					)
					(width 0)
					(fill yes)
				)
			)
		)
		(pad "2" smd custom
			(at 0 0.4445 270)
			(size 0.1397 0.1397)
			(layers "B.Cu" "B.Mask" "B.Paste")
			(net "SIO_CLK_0")
			(options
				(clearance outline)
				(anchor circle)
			)
			(primitives
				(gr_poly
					(pts
						(arc
							(start -0.1778 0.2794)
							(mid -0.249642 0.249642)
							(end -0.2794 0.1778)
						)
						(arc
							(start -0.2794 -0.1778)
							(mid -0.249642 -0.249642)
							(end -0.1778 -0.2794)
						)
						(arc
							(start 0.1778 -0.2794)
							(mid 0.249642 -0.249642)
							(end 0.2794 -0.1778)
						)
						(arc
							(start 0.2794 0.1778)
							(mid 0.249642 0.249642)
							(end 0.1778 0.2794)
						)
					)
					(width 0)
					(fill yes)
				)
			)
		)
	)
	(footprint ""
		(layer "B.Cu")
		(at 79.248 -73.914 180)
		(property "Reference" "SR851"
			(at 0 0 0)
			(layer "B.SilkS")
			(hide yes)
			(effects
				(font
					(size 1.27 1.27)
				)
				(justify mirror)
			)
		)
		(property "Value" "4K7R2F-GP"
			(at -0.064008 -3.993896 180)
			(unlocked yes)
			(layer "B.Fab")
			(hide yes)
			(effects
				(font
					(size 1.016 1.016)
					(thickness 0.1524)
				)
				(justify mirror)
			)
		)
		(property "Device Type" "R402H16"
			(at -0.064008 -5.517896 180)
			(unlocked yes)
			(layer "B.Fab")
			(hide yes)
			(effects
				(font
					(size 1.016 1.016)
					(thickness 0.1524)
				)
				(justify mirror)
			)
		)
		(duplicate_pad_numbers_are_jumpers no)
		(fp_line
			(start 0.508 -0.9398)
			(end 0.508 0.9398)
			(stroke
				(width 0.1524)
				(type default)
			)
			(layer "B.SilkS")
		)
		(fp_line
			(start -0.508 -0.9398)
			(end 0.508 -0.9398)
			(stroke
				(width 0.1524)
				(type default)
			)
			(layer "B.SilkS")
		)
		(fp_rect
			(start 0.508 0.9398)
			(end -0.508 -0.9398)
			(stroke
				(width 0)
				(type default)
			)
			(fill no)
			(layer "B.CrtYd")
		)
		(fp_rect
			(start 0.508 0.9398)
			(end -0.508 -0.9398)
			(stroke
				(width 0)
				(type default)
			)
			(fill no)
			(layer "B.Fab")
		)
		(pad "1" smd custom
			(at 0 -0.4445)
			(size 0.1397 0.1397)
			(layers "B.Cu" "B.Mask" "B.Paste")
			(net "P1V8_C")
			(options
				(clearance outline)
				(anchor circle)
			)
			(primitives
				(gr_poly
					(pts
						(arc
							(start -0.1778 0.2794)
							(mid -0.249642 0.249642)
							(end -0.2794 0.1778)
						)
						(arc
							(start -0.2794 -0.1778)
							(mid -0.249642 -0.249642)
							(end -0.1778 -0.2794)
						)
						(arc
							(start 0.1778 -0.2794)
							(mid 0.249642 -0.249642)
							(end 0.2794 -0.1778)
						)
						(arc
							(start 0.2794 0.1778)
							(mid 0.249642 0.249642)
							(end 0.1778 0.2794)
						)
					)
					(width 0)
					(fill yes)
				)
			)
		)
		(pad "2" smd custom
			(at 0 0.4445)
			(size 0.1397 0.1397)
			(layers "B.Cu" "B.Mask" "B.Paste")
			(net "P0V955_C_PG_R")
			(options
				(clearance outline)
				(anchor circle)
			)
			(primitives
				(gr_poly
					(pts
						(arc
							(start -0.1778 0.2794)
							(mid -0.249642 0.249642)
							(end -0.2794 0.1778)
						)
						(arc
							(start -0.2794 -0.1778)
							(mid -0.249642 -0.249642)
							(end -0.1778 -0.2794)
						)
						(arc
							(start 0.1778 -0.2794)
							(mid 0.249642 -0.249642)
							(end 0.2794 -0.1778)
						)
						(arc
							(start 0.2794 0.1778)
							(mid 0.249642 0.249642)
							(end 0.1778 0.2794)
						)
					)
					(width 0)
					(fill yes)
				)
			)
		)
	)
	(footprint ""
		(layer "B.Cu")
		(at 127.09017 -87.4776 90)
		(property "Reference" "SC1160"
			(at 0 0 90)
			(layer "B.SilkS")
			(hide yes)
			(effects
				(font
					(size 1.27 1.27)
				)
				(justify mirror)
			)
		)
		(property "Value" "SC1U6D3V1MX-GP"
			(at -1.9177 2.0193 90)
			(unlocked yes)
			(layer "B.Fab")
			(hide yes)
			(effects
				(font
					(size 1.016 1.016)
					(thickness 0.1524)
				)
				(justify mirror)
			)
		)
		(property "Device Type" "C0201H14"
			(at -1.9177 0.4953 90)
			(unlocked yes)
			(layer "B.Fab")
			(hide yes)
			(effects
				(font
					(size 1.016 1.016)
					(thickness 0.1524)
				)
				(justify mirror)
			)
		)
		(duplicate_pad_numbers_are_jumpers no)
		(fp_rect
			(start 0.1524 0.3048)
			(end -0.1524 -0.3048)
			(stroke
				(width 0)
				(type default)
			)
			(fill no)
			(layer "B.CrtYd")
		)
		(fp_poly
			(pts
				(xy 0.2794 0.6477) (xy 0.2794 -0.6477) (xy -0.2794 -0.6477) (xy -0.2794 -0.1905) (xy -0.1524 -0.1905)
				(xy -0.1524 -0.3048) (xy 0.1524 -0.3048) (xy 0.1524 0.3048) (xy -0.1524 0.3048) (xy -0.1524 -0.1778)
				(xy -0.2794 -0.1778) (xy -0.2794 0.6477)
			)
			(stroke
				(width 0)
				(type default)
			)
			(fill no)
			(layer "B.CrtYd")
		)
		(fp_rect
			(start 0.2794 0.6477)
			(end -0.2794 -0.6477)
			(stroke
				(width 0)
				(type default)
			)
			(fill no)
			(layer "B.Fab")
		)
		(pad "1" smd custom
			(at 0 -0.2794 270)
			(size 0.0762 0.0762)
			(layers "B.Cu" "B.Mask" "B.Paste")
			(net "GB_VDDA")
			(options
				(clearance outline)
				(anchor circle)
			)
			(primitives
				(gr_poly
					(pts
						(arc
							(start 0.1524 0.127)
							(mid 0.137521 0.162921)
							(end 0.1016 0.1778)
						)
						(arc
							(start -0.1016 0.1778)
							(mid -0.137521 0.162921)
							(end -0.1524 0.127)
						)
						(arc
							(start -0.1524 -0.127)
							(mid -0.137521 -0.162921)
							(end -0.1016 -0.1778)
						)
						(arc
							(start 0.1016 -0.1778)
							(mid 0.137521 -0.162921)
							(end 0.1524 -0.127)
						)
					)
					(width 0)
					(fill yes)
				)
			)
		)
		(pad "2" smd custom
			(at 0 0.2794 270)
			(size 0.0762 0.0762)
			(layers "B.Cu" "B.Mask" "B.Paste")
			(net "GND")
			(options
				(clearance outline)
				(anchor circle)
			)
			(primitives
				(gr_poly
					(pts
						(arc
							(start 0.1524 0.127)
							(mid 0.137521 0.162921)
							(end 0.1016 0.1778)
						)
						(arc
							(start -0.1016 0.1778)
							(mid -0.137521 0.162921)
							(end -0.1524 0.127)
						)
						(arc
							(start -0.1524 -0.127)
							(mid -0.137521 -0.162921)
							(end -0.1016 -0.1778)
						)
						(arc
							(start 0.1016 -0.1778)
							(mid 0.137521 -0.162921)
							(end 0.1524 -0.127)
						)
					)
					(width 0)
					(fill yes)
				)
			)
		)
	)
	(footprint ""
		(layer "B.Cu")
		(at 96.314006 -54.70906 90)
		(property "Reference" "SC981"
			(at 0 0 90)
			(layer "B.SilkS")
			(hide yes)
			(effects
				(font
					(size 1.27 1.27)
				)
				(justify mirror)
			)
		)
		(property "Value" "SCD1U16V2KX-3GP"
			(at -1.1811 -2.7051 90)
			(unlocked yes)
			(layer "B.Fab")
			(hide yes)
			(effects
				(font
					(size 1.016 1.016)
					(thickness 0.1524)
				)
				(justify mirror)
			)
		)
		(property "Device Type" "C402H22"
			(at -1.1811 -4.2291 90)
			(unlocked yes)
			(layer "B.Fab")
			(hide yes)
			(effects
				(font
					(size 1.016 1.016)
					(thickness 0.1524)
				)
				(justify mirror)
			)
		)
		(duplicate_pad_numbers_are_jumpers no)
		(fp_rect
			(start 0.4318 0.9525)
			(end -0.4318 -0.9525)
			(stroke
				(width 0)
				(type default)
			)
			(fill no)
			(layer "B.CrtYd")
		)
		(fp_rect
			(start 0.4318 0.9525)
			(end -0.4318 -0.9525)
			(stroke
				(width 0)
				(type default)
			)
			(fill no)
			(layer "B.Fab")
		)
		(pad "1" smd custom
			(at 0 -0.4445 270)
			(size 0.1524 0.1524)
			(layers "B.Cu" "B.Mask" "B.Paste")
			(net "P1V8_C")
			(options
				(clearance outline)
				(anchor circle)
			)
			(primitives
				(gr_poly
					(pts
						(arc
							(start 0.3048 0.2032)
							(mid 0.275042 0.275042)
							(end 0.2032 0.3048)
						)
						(arc
							(start -0.2032 0.3048)
							(mid -0.275042 0.275042)
							(end -0.3048 0.2032)
						)
						(arc
							(start -0.3048 -0.2032)
							(mid -0.275042 -0.275042)
							(end -0.2032 -0.3048)
						)
						(arc
							(start 0.2032 -0.3048)
							(mid 0.275042 -0.275042)
							(end 0.3048 -0.2032)
						)
					)
					(width 0)
					(fill yes)
				)
			)
		)
		(pad "2" smd custom
			(at 0 0.4445 270)
			(size 0.1524 0.1524)
			(layers "B.Cu" "B.Mask" "B.Paste")
			(net "GND")
			(options
				(clearance outline)
				(anchor circle)
			)
			(primitives
				(gr_poly
					(pts
						(arc
							(start 0.3048 0.2032)
							(mid 0.275042 0.275042)
							(end 0.2032 0.3048)
						)
						(arc
							(start -0.2032 0.3048)
							(mid -0.275042 0.275042)
							(end -0.3048 0.2032)
						)
						(arc
							(start -0.3048 -0.2032)
							(mid -0.275042 -0.275042)
							(end -0.2032 -0.3048)
						)
						(arc
							(start 0.2032 -0.3048)
							(mid 0.275042 -0.275042)
							(end 0.3048 -0.2032)
						)
					)
					(width 0)
					(fill yes)
				)
			)
		)
	)
	(footprint ""
		(layer "B.Cu")
		(at 197.821296 -87.388192 180)
		(property "Reference" "SC1134"
			(at 0 0 0)
			(layer "B.SilkS")
			(hide yes)
			(effects
				(font
					(size 1.27 1.27)
				)
				(justify mirror)
			)
		)
		(property "Value" "SCD1U6D3V1KX-GP"
			(at 2.8321 -1.7399 180)
			(unlocked yes)
			(layer "B.Fab")
			(hide yes)
			(effects
				(font
					(size 1.016 1.016)
					(thickness 0.1524)
				)
				(justify mirror)
			)
		)
		(property "Device Type" "C0201H13"
			(at 2.8321 -3.2639 180)
			(unlocked yes)
			(layer "B.Fab")
			(hide yes)
			(effects
				(font
					(size 1.016 1.016)
					(thickness 0.1524)
				)
				(justify mirror)
			)
		)
		(duplicate_pad_numbers_are_jumpers no)
		(fp_rect
			(start 0.2794 0.6477)
			(end -0.2794 -0.6477)
			(stroke
				(width 0)
				(type default)
			)
			(fill no)
			(layer "B.CrtYd")
		)
		(fp_rect
			(start 0.2794 0.6477)
			(end -0.2794 -0.6477)
			(stroke
				(width 0)
				(type default)
			)
			(fill no)
			(layer "B.Fab")
		)
		(pad "1" smd custom
			(at 0 -0.2794)
			(size 0.0762 0.0762)
			(layers "B.Cu" "B.Mask" "B.Paste")
			(net "GB_VDDH2")
			(options
				(clearance outline)
				(anchor circle)
			)
			(primitives
				(gr_poly
					(pts
						(arc
							(start 0.1524 0.127)
							(mid 0.137521 0.162921)
							(end 0.1016 0.1778)
						)
						(arc
							(start -0.1016 0.1778)
							(mid -0.137521 0.162921)
							(end -0.1524 0.127)
						)
						(arc
							(start -0.1524 -0.127)
							(mid -0.137521 -0.162921)
							(end -0.1016 -0.1778)
						)
						(arc
							(start 0.1016 -0.1778)
							(mid 0.137521 -0.162921)
							(end 0.1524 -0.127)
						)
					)
					(width 0)
					(fill yes)
				)
			)
		)
		(pad "2" smd custom
			(at 0 0.2794)
			(size 0.0762 0.0762)
			(layers "B.Cu" "B.Mask" "B.Paste")
			(net "GND")
			(options
				(clearance outline)
				(anchor circle)
			)
			(primitives
				(gr_poly
					(pts
						(arc
							(start 0.1524 0.127)
							(mid 0.137521 0.162921)
							(end 0.1016 0.1778)
						)
						(arc
							(start -0.1016 0.1778)
							(mid -0.137521 0.162921)
							(end -0.1524 0.127)
						)
						(arc
							(start -0.1524 -0.127)
							(mid -0.137521 -0.162921)
							(end -0.1016 -0.1778)
						)
						(arc
							(start 0.1016 -0.1778)
							(mid 0.137521 -0.162921)
							(end 0.1524 -0.127)
						)
					)
					(width 0)
					(fill yes)
				)
			)
		)
	)
	(footprint ""
		(layer "B.Cu")
		(at 92.583 -34.163 -90)
		(property "Reference" "SC947"
			(at 0 0 90)
			(layer "B.SilkS")
			(hide yes)
			(effects
				(font
					(size 1.27 1.27)
				)
				(justify mirror)
			)
		)
		(property "Value" "SC1U6D3V1MX-GP"
			(at -1.9177 2.0193 270)
			(unlocked yes)
			(layer "B.Fab")
			(hide yes)
			(effects
				(font
					(size 1.016 1.016)
					(thickness 0.1524)
				)
				(justify mirror)
			)
		)
		(property "Device Type" "C0201H14"
			(at -1.9177 0.4953 270)
			(unlocked yes)
			(layer "B.Fab")
			(hide yes)
			(effects
				(font
					(size 1.016 1.016)
					(thickness 0.1524)
				)
				(justify mirror)
			)
		)
		(duplicate_pad_numbers_are_jumpers no)
		(fp_rect
			(start 0.1524 0.3048)
			(end -0.1524 -0.3048)
			(stroke
				(width 0)
				(type default)
			)
			(fill no)
			(layer "B.CrtYd")
		)
		(fp_poly
			(pts
				(xy 0.2794 0.6477) (xy 0.2794 -0.6477) (xy -0.2794 -0.6477) (xy -0.2794 -0.1905) (xy -0.1524 -0.1905)
				(xy -0.1524 -0.3048) (xy 0.1524 -0.3048) (xy 0.1524 0.3048) (xy -0.1524 0.3048) (xy -0.1524 -0.1778)
				(xy -0.2794 -0.1778) (xy -0.2794 0.6477)
			)
			(stroke
				(width 0)
				(type default)
			)
			(fill no)
			(layer "B.CrtYd")
		)
		(fp_rect
			(start 0.2794 0.6477)
			(end -0.2794 -0.6477)
			(stroke
				(width 0)
				(type default)
			)
			(fill no)
			(layer "B.Fab")
		)
		(pad "1" smd custom
			(at 0 -0.2794 90)
			(size 0.0762 0.0762)
			(layers "B.Cu" "B.Mask" "B.Paste")
			(net "PCE_AVDD")
			(options
				(clearance outline)
				(anchor circle)
			)
			(primitives
				(gr_poly
					(pts
						(arc
							(start 0.1524 0.127)
							(mid 0.137521 0.162921)
							(end 0.1016 0.1778)
						)
						(arc
							(start -0.1016 0.1778)
							(mid -0.137521 0.162921)
							(end -0.1524 0.127)
						)
						(arc
							(start -0.1524 -0.127)
							(mid -0.137521 -0.162921)
							(end -0.1016 -0.1778)
						)
						(arc
							(start 0.1016 -0.1778)
							(mid 0.137521 -0.162921)
							(end 0.1524 -0.127)
						)
					)
					(width 0)
					(fill yes)
				)
			)
		)
		(pad "2" smd custom
			(at 0 0.2794 90)
			(size 0.0762 0.0762)
			(layers "B.Cu" "B.Mask" "B.Paste")
			(net "GND")
			(options
				(clearance outline)
				(anchor circle)
			)
			(primitives
				(gr_poly
					(pts
						(arc
							(start 0.1524 0.127)
							(mid 0.137521 0.162921)
							(end 0.1016 0.1778)
						)
						(arc
							(start -0.1016 0.1778)
							(mid -0.137521 0.162921)
							(end -0.1524 0.127)
						)
						(arc
							(start -0.1524 -0.127)
							(mid -0.137521 -0.162921)
							(end -0.1016 -0.1778)
						)
						(arc
							(start 0.1016 -0.1778)
							(mid 0.137521 -0.162921)
							(end 0.1524 -0.127)
						)
					)
					(width 0)
					(fill yes)
				)
			)
		)
	)
	(footprint ""
		(layer "B.Cu")
		(at 120.30837 -88.2142 90)
		(property "Reference" "SC1140"
			(at 0 0 90)
			(layer "B.SilkS")
			(hide yes)
			(effects
				(font
					(size 1.27 1.27)
				)
				(justify mirror)
			)
		)
		(property "Value" "SCD1U6D3V1KX-GP"
			(at 2.8321 -1.7399 90)
			(unlocked yes)
			(layer "B.Fab")
			(hide yes)
			(effects
				(font
					(size 1.016 1.016)
					(thickness 0.1524)
				)
				(justify mirror)
			)
		)
		(property "Device Type" "C0201H13"
			(at 2.8321 -3.2639 90)
			(unlocked yes)
			(layer "B.Fab")
			(hide yes)
			(effects
				(font
					(size 1.016 1.016)
					(thickness 0.1524)
				)
				(justify mirror)
			)
		)
		(duplicate_pad_numbers_are_jumpers no)
		(fp_rect
			(start 0.2794 0.6477)
			(end -0.2794 -0.6477)
			(stroke
				(width 0)
				(type default)
			)
			(fill no)
			(layer "B.CrtYd")
		)
		(fp_rect
			(start 0.2794 0.6477)
			(end -0.2794 -0.6477)
			(stroke
				(width 0)
				(type default)
			)
			(fill no)
			(layer "B.Fab")
		)
		(pad "1" smd custom
			(at 0 -0.2794 270)
			(size 0.0762 0.0762)
			(layers "B.Cu" "B.Mask" "B.Paste")
			(net "GB_VDDH2")
			(options
				(clearance outline)
				(anchor circle)
			)
			(primitives
				(gr_poly
					(pts
						(arc
							(start 0.1524 0.127)
							(mid 0.137521 0.162921)
							(end 0.1016 0.1778)
						)
						(arc
							(start -0.1016 0.1778)
							(mid -0.137521 0.162921)
							(end -0.1524 0.127)
						)
						(arc
							(start -0.1524 -0.127)
							(mid -0.137521 -0.162921)
							(end -0.1016 -0.1778)
						)
						(arc
							(start 0.1016 -0.1778)
							(mid 0.137521 -0.162921)
							(end 0.1524 -0.127)
						)
					)
					(width 0)
					(fill yes)
				)
			)
		)
		(pad "2" smd custom
			(at 0 0.2794 270)
			(size 0.0762 0.0762)
			(layers "B.Cu" "B.Mask" "B.Paste")
			(net "GND")
			(options
				(clearance outline)
				(anchor circle)
			)
			(primitives
				(gr_poly
					(pts
						(arc
							(start 0.1524 0.127)
							(mid 0.137521 0.162921)
							(end 0.1016 0.1778)
						)
						(arc
							(start -0.1016 0.1778)
							(mid -0.137521 0.162921)
							(end -0.1524 0.127)
						)
						(arc
							(start -0.1524 -0.127)
							(mid -0.137521 -0.162921)
							(end -0.1016 -0.1778)
						)
						(arc
							(start 0.1016 -0.1778)
							(mid 0.137521 -0.162921)
							(end 0.1524 -0.127)
						)
					)
					(width 0)
					(fill yes)
				)
			)
		)
	)
	(footprint ""
		(layer "B.Cu")
		(at 287.994852 -174.971456 -90)
		(property "Reference" "R230"
			(at 0 0 90)
			(layer "B.SilkS")
			(hide yes)
			(effects
				(font
					(size 1.27 1.27)
				)
				(justify mirror)
			)
		)
		(property "Value" "100KR2F-L1-GP"
			(at -0.064008 -3.993896 270)
			(unlocked yes)
			(layer "B.Fab")
			(hide yes)
			(effects
				(font
					(size 1.016 1.016)
					(thickness 0.1524)
				)
				(justify mirror)
			)
		)
		(property "Device Type" "R402H16"
			(at -0.064008 -5.517896 270)
			(unlocked yes)
			(layer "B.Fab")
			(hide yes)
			(effects
				(font
					(size 1.016 1.016)
					(thickness 0.1524)
				)
				(justify mirror)
			)
		)
		(duplicate_pad_numbers_are_jumpers no)
		(fp_line
			(start -0.508 -0.9398)
			(end 0.508 -0.9398)
			(stroke
				(width 0.1524)
				(type default)
			)
			(layer "B.SilkS")
		)
		(fp_line
			(start 0.508 -0.9398)
			(end 0.508 0.9398)
			(stroke
				(width 0.1524)
				(type default)
			)
			(layer "B.SilkS")
		)
		(fp_rect
			(start 0.508 0.9398)
			(end -0.508 -0.9398)
			(stroke
				(width 0)
				(type default)
			)
			(fill no)
			(layer "B.CrtYd")
		)
		(fp_rect
			(start 0.508 0.9398)
			(end -0.508 -0.9398)
			(stroke
				(width 0)
				(type default)
			)
			(fill no)
			(layer "B.Fab")
		)
		(pad "1" smd custom
			(at 0 -0.4445 90)
			(size 0.1397 0.1397)
			(layers "B.Cu" "B.Mask" "B.Paste")
			(net "GND")
			(options
				(clearance outline)
				(anchor circle)
			)
			(primitives
				(gr_poly
					(pts
						(arc
							(start -0.1778 0.2794)
							(mid -0.249642 0.249642)
							(end -0.2794 0.1778)
						)
						(arc
							(start -0.2794 -0.1778)
							(mid -0.249642 -0.249642)
							(end -0.1778 -0.2794)
						)
						(arc
							(start 0.1778 -0.2794)
							(mid 0.249642 -0.249642)
							(end 0.2794 -0.1778)
						)
						(arc
							(start 0.2794 0.1778)
							(mid 0.249642 0.249642)
							(end 0.1778 0.2794)
						)
					)
					(width 0)
					(fill yes)
				)
			)
		)
		(pad "2" smd custom
			(at 0 0.4445 90)
			(size 0.1397 0.1397)
			(layers "B.Cu" "B.Mask" "B.Paste")
			(net "PD_PERST_N")
			(options
				(clearance outline)
				(anchor circle)
			)
			(primitives
				(gr_poly
					(pts
						(arc
							(start -0.1778 0.2794)
							(mid -0.249642 0.249642)
							(end -0.2794 0.1778)
						)
						(arc
							(start -0.2794 -0.1778)
							(mid -0.249642 -0.249642)
							(end -0.1778 -0.2794)
						)
						(arc
							(start 0.1778 -0.2794)
							(mid 0.249642 -0.249642)
							(end 0.2794 -0.1778)
						)
						(arc
							(start 0.2794 0.1778)
							(mid 0.249642 0.249642)
							(end 0.1778 0.2794)
						)
					)
					(width 0)
					(fill yes)
				)
			)
		)
	)
	(footprint ""
		(layer "B.Cu")
		(at 68.498212 -244.856)
		(property "Reference" "C297"
			(at 0 0 0)
			(layer "B.SilkS")
			(hide yes)
			(effects
				(font
					(size 1.27 1.27)
				)
				(justify mirror)
			)
		)
		(property "Value" "SCD1U25V2KX-2-GP"
			(at -1.1811 -2.7051 0)
			(unlocked yes)
			(layer "B.Fab")
			(hide yes)
			(effects
				(font
					(size 1.016 1.016)
					(thickness 0.1524)
				)
				(justify mirror)
			)
		)
		(property "Device Type" "C402H22"
			(at -1.1811 -4.2291 0)
			(unlocked yes)
			(layer "B.Fab")
			(hide yes)
			(effects
				(font
					(size 1.016 1.016)
					(thickness 0.1524)
				)
				(justify mirror)
			)
		)
		(duplicate_pad_numbers_are_jumpers no)
		(fp_rect
			(start 0.4318 0.9525)
			(end -0.4318 -0.9525)
			(stroke
				(width 0)
				(type default)
			)
			(fill no)
			(layer "B.CrtYd")
		)
		(fp_rect
			(start 0.4318 0.9525)
			(end -0.4318 -0.9525)
			(stroke
				(width 0)
				(type default)
			)
			(fill no)
			(layer "B.Fab")
		)
		(pad "1" smd custom
			(at 0 -0.4445 180)
			(size 0.1524 0.1524)
			(layers "B.Cu" "B.Mask" "B.Paste")
			(net "P12V_PCIE")
			(options
				(clearance outline)
				(anchor circle)
			)
			(primitives
				(gr_poly
					(pts
						(arc
							(start 0.3048 0.2032)
							(mid 0.275042 0.275042)
							(end 0.2032 0.3048)
						)
						(arc
							(start -0.2032 0.3048)
							(mid -0.275042 0.275042)
							(end -0.3048 0.2032)
						)
						(arc
							(start -0.3048 -0.2032)
							(mid -0.275042 -0.275042)
							(end -0.2032 -0.3048)
						)
						(arc
							(start 0.2032 -0.3048)
							(mid 0.275042 -0.275042)
							(end 0.3048 -0.2032)
						)
					)
					(width 0)
					(fill yes)
				)
			)
		)
		(pad "2" smd custom
			(at 0 0.4445 180)
			(size 0.1524 0.1524)
			(layers "B.Cu" "B.Mask" "B.Paste")
			(net "GND")
			(options
				(clearance outline)
				(anchor circle)
			)
			(primitives
				(gr_poly
					(pts
						(arc
							(start 0.3048 0.2032)
							(mid 0.275042 0.275042)
							(end 0.2032 0.3048)
						)
						(arc
							(start -0.2032 0.3048)
							(mid -0.275042 0.275042)
							(end -0.3048 0.2032)
						)
						(arc
							(start -0.3048 -0.2032)
							(mid -0.275042 -0.275042)
							(end -0.2032 -0.3048)
						)
						(arc
							(start 0.2032 -0.3048)
							(mid 0.275042 -0.275042)
							(end 0.3048 -0.2032)
						)
					)
					(width 0)
					(fill yes)
				)
			)
		)
	)
	(footprint ""
		(layer "B.Cu")
		(at 124.403612 -217.678 -90)
		(property "Reference" "SR1261"
			(at 0 0 90)
			(layer "B.SilkS")
			(hide yes)
			(effects
				(font
					(size 1.27 1.27)
				)
				(justify mirror)
			)
		)
		(property "Value" "0R2J-2-GP"
			(at -0.064008 -3.993896 270)
			(unlocked yes)
			(layer "B.Fab")
			(hide yes)
			(effects
				(font
					(size 1.016 1.016)
					(thickness 0.1524)
				)
				(justify mirror)
			)
		)
		(property "Device Type" "R402H16"
			(at -0.064008 -5.517896 270)
			(unlocked yes)
			(layer "B.Fab")
			(hide yes)
			(effects
				(font
					(size 1.016 1.016)
					(thickness 0.1524)
				)
				(justify mirror)
			)
		)
		(duplicate_pad_numbers_are_jumpers no)
		(fp_line
			(start -0.508 -0.9398)
			(end 0.508 -0.9398)
			(stroke
				(width 0.1524)
				(type default)
			)
			(layer "B.SilkS")
		)
		(fp_line
			(start 0.508 -0.9398)
			(end 0.508 0.9398)
			(stroke
				(width 0.1524)
				(type default)
			)
			(layer "B.SilkS")
		)
		(fp_rect
			(start 0.508 0.9398)
			(end -0.508 -0.9398)
			(stroke
				(width 0)
				(type default)
			)
			(fill no)
			(layer "B.CrtYd")
		)
		(fp_rect
			(start 0.508 0.9398)
			(end -0.508 -0.9398)
			(stroke
				(width 0)
				(type default)
			)
			(fill no)
			(layer "B.Fab")
		)
		(pad "1" smd custom
			(at 0 -0.4445 90)
			(size 0.1397 0.1397)
			(layers "B.Cu" "B.Mask" "B.Paste")
			(net "EXP_SDA_L_0")
			(options
				(clearance outline)
				(anchor circle)
			)
			(primitives
				(gr_poly
					(pts
						(arc
							(start -0.1778 0.2794)
							(mid -0.249642 0.249642)
							(end -0.2794 0.1778)
						)
						(arc
							(start -0.2794 -0.1778)
							(mid -0.249642 -0.249642)
							(end -0.1778 -0.2794)
						)
						(arc
							(start 0.1778 -0.2794)
							(mid 0.249642 -0.249642)
							(end 0.2794 -0.1778)
						)
						(arc
							(start 0.2794 0.1778)
							(mid 0.249642 0.249642)
							(end 0.1778 0.2794)
						)
					)
					(width 0)
					(fill yes)
				)
			)
		)
		(pad "2" smd custom
			(at 0 0.4445 90)
			(size 0.1397 0.1397)
			(layers "B.Cu" "B.Mask" "B.Paste")
			(net "REDV_I2C_SDA")
			(options
				(clearance outline)
				(anchor circle)
			)
			(primitives
				(gr_poly
					(pts
						(arc
							(start -0.1778 0.2794)
							(mid -0.249642 0.249642)
							(end -0.2794 0.1778)
						)
						(arc
							(start -0.2794 -0.1778)
							(mid -0.249642 -0.249642)
							(end -0.1778 -0.2794)
						)
						(arc
							(start 0.1778 -0.2794)
							(mid 0.249642 -0.249642)
							(end 0.2794 -0.1778)
						)
						(arc
							(start 0.2794 0.1778)
							(mid 0.249642 0.249642)
							(end 0.1778 0.2794)
						)
					)
					(width 0)
					(fill yes)
				)
			)
		)
	)
	(footprint ""
		(layer "B.Cu")
		(at 93.99016 -31.623)
		(property "Reference" "SC862"
			(at 0 0 0)
			(layer "B.SilkS")
			(hide yes)
			(effects
				(font
					(size 1.27 1.27)
				)
				(justify mirror)
			)
		)
		(property "Value" "SCD22U6D3V1MX-1-GP"
			(at 2.8321 -1.7399 0)
			(unlocked yes)
			(layer "B.Fab")
			(hide yes)
			(effects
				(font
					(size 1.016 1.016)
					(thickness 0.1524)
				)
				(justify mirror)
			)
		)
		(property "Device Type" "C0201H13"
			(at 2.8321 -3.2639 0)
			(unlocked yes)
			(layer "B.Fab")
			(hide yes)
			(effects
				(font
					(size 1.016 1.016)
					(thickness 0.1524)
				)
				(justify mirror)
			)
		)
		(duplicate_pad_numbers_are_jumpers no)
		(fp_rect
			(start 0.2794 0.6477)
			(end -0.2794 -0.6477)
			(stroke
				(width 0)
				(type default)
			)
			(fill no)
			(layer "B.CrtYd")
		)
		(fp_rect
			(start 0.2794 0.6477)
			(end -0.2794 -0.6477)
			(stroke
				(width 0)
				(type default)
			)
			(fill no)
			(layer "B.Fab")
		)
		(pad "1" smd custom
			(at 0 -0.2794 180)
			(size 0.0762 0.0762)
			(layers "B.Cu" "B.Mask" "B.Paste")
			(net "PCIE_SAS_C_CPU_RX_N0")
			(options
				(clearance outline)
				(anchor circle)
			)
			(primitives
				(gr_poly
					(pts
						(arc
							(start 0.1524 0.127)
							(mid 0.137521 0.162921)
							(end 0.1016 0.1778)
						)
						(arc
							(start -0.1016 0.1778)
							(mid -0.137521 0.162921)
							(end -0.1524 0.127)
						)
						(arc
							(start -0.1524 -0.127)
							(mid -0.137521 -0.162921)
							(end -0.1016 -0.1778)
						)
						(arc
							(start 0.1016 -0.1778)
							(mid 0.137521 -0.162921)
							(end 0.1524 -0.127)
						)
					)
					(width 0)
					(fill yes)
				)
			)
		)
		(pad "2" smd custom
			(at 0 0.2794 180)
			(size 0.0762 0.0762)
			(layers "B.Cu" "B.Mask" "B.Paste")
			(net "PCIE_SAS_CPU_RX_N0")
			(options
				(clearance outline)
				(anchor circle)
			)
			(primitives
				(gr_poly
					(pts
						(arc
							(start 0.1524 0.127)
							(mid 0.137521 0.162921)
							(end 0.1016 0.1778)
						)
						(arc
							(start -0.1016 0.1778)
							(mid -0.137521 0.162921)
							(end -0.1524 0.127)
						)
						(arc
							(start -0.1524 -0.127)
							(mid -0.137521 -0.162921)
							(end -0.1016 -0.1778)
						)
						(arc
							(start 0.1016 -0.1778)
							(mid 0.137521 -0.162921)
							(end 0.1524 -0.127)
						)
					)
					(width 0)
					(fill yes)
				)
			)
		)
	)
	(footprint ""
		(layer "B.Cu")
		(at 84.836 -20.955)
		(property "Reference" "PC222"
			(at 0 0 0)
			(layer "B.SilkS")
			(hide yes)
			(effects
				(font
					(size 1.27 1.27)
				)
				(justify mirror)
			)
		)
		(property "Value" "SCD33U6D3V2KX-1-GP"
			(at -1.1811 -2.7051 0)
			(unlocked yes)
			(layer "B.Fab")
			(hide yes)
			(effects
				(font
					(size 1.016 1.016)
					(thickness 0.1524)
				)
				(justify mirror)
			)
		)
		(property "Device Type" "C402H22"
			(at -1.1811 -4.2291 0)
			(unlocked yes)
			(layer "B.Fab")
			(hide yes)
			(effects
				(font
					(size 1.016 1.016)
					(thickness 0.1524)
				)
				(justify mirror)
			)
		)
		(duplicate_pad_numbers_are_jumpers no)
		(fp_rect
			(start 0.4318 0.9525)
			(end -0.4318 -0.9525)
			(stroke
				(width 0)
				(type default)
			)
			(fill no)
			(layer "B.CrtYd")
		)
		(fp_rect
			(start 0.4318 0.9525)
			(end -0.4318 -0.9525)
			(stroke
				(width 0)
				(type default)
			)
			(fill no)
			(layer "B.Fab")
		)
		(pad "1" smd custom
			(at 0 -0.4445 180)
			(size 0.1524 0.1524)
			(layers "B.Cu" "B.Mask" "B.Paste")
			(net "AVSO_VREF")
			(options
				(clearance outline)
				(anchor circle)
			)
			(primitives
				(gr_poly
					(pts
						(arc
							(start 0.3048 0.2032)
							(mid 0.275042 0.275042)
							(end 0.2032 0.3048)
						)
						(arc
							(start -0.2032 0.3048)
							(mid -0.275042 0.275042)
							(end -0.3048 0.2032)
						)
						(arc
							(start -0.3048 -0.2032)
							(mid -0.275042 -0.275042)
							(end -0.2032 -0.3048)
						)
						(arc
							(start 0.2032 -0.3048)
							(mid 0.275042 -0.275042)
							(end 0.3048 -0.2032)
						)
					)
					(width 0)
					(fill yes)
				)
			)
		)
		(pad "2" smd custom
			(at 0 0.4445 180)
			(size 0.1524 0.1524)
			(layers "B.Cu" "B.Mask" "B.Paste")
			(net "GND")
			(options
				(clearance outline)
				(anchor circle)
			)
			(primitives
				(gr_poly
					(pts
						(arc
							(start 0.3048 0.2032)
							(mid 0.275042 0.275042)
							(end 0.2032 0.3048)
						)
						(arc
							(start -0.2032 0.3048)
							(mid -0.275042 0.275042)
							(end -0.3048 0.2032)
						)
						(arc
							(start -0.3048 -0.2032)
							(mid -0.275042 -0.275042)
							(end -0.2032 -0.3048)
						)
						(arc
							(start 0.2032 -0.3048)
							(mid 0.275042 -0.275042)
							(end 0.3048 -0.2032)
						)
					)
					(width 0)
					(fill yes)
				)
			)
		)
	)
	(footprint ""
		(layer "B.Cu")
		(at 117.710966 -35.306)
		(property "Reference" "STP11"
			(at 0 0 0)
			(layer "B.SilkS")
			(hide yes)
			(effects
				(font
					(size 1.27 1.27)
				)
				(justify mirror)
			)
		)
		(property "Value" "TPAD28"
			(at -0.0127 -1.8034 0)
			(unlocked yes)
			(layer "B.Fab")
			(hide yes)
			(effects
				(font
					(size 1.016 1.016)
					(thickness 0.1524)
				)
				(justify mirror)
			)
		)
		(property "Device Type" "TPAD28"
			(at -0.0127 -3.3274 0)
			(unlocked yes)
			(layer "B.Fab")
			(hide yes)
			(effects
				(font
					(size 1.016 1.016)
					(thickness 0.1524)
				)
				(justify mirror)
			)
		)
		(duplicate_pad_numbers_are_jumpers no)
		(fp_poly
			(pts
				(arc
					(start 0.3556 0)
					(mid -0.3556 0)
					(end 0.3556 0)
				)
			)
			(stroke
				(width 0)
				(type default)
			)
			(fill no)
			(layer "B.CrtYd")
		)
		(fp_poly
			(pts
				(arc
					(start 0.6096 0)
					(mid -0.6096 0)
					(end 0.6096 0)
				)
			)
			(stroke
				(width 0)
				(type default)
			)
			(fill no)
			(layer "B.Fab")
		)
		(pad "1" smd circle
			(at 0 0 180)
			(size 0.7112 0.7112)
			(layers "B.Cu" "B.Mask" "B.Paste")
			(net "IOC_GPIO_30")
		)
	)
	(footprint ""
		(layer "B.Cu")
		(at 296.164 -164.211 180)
		(property "Reference" "R282"
			(at 0 0 0)
			(layer "B.SilkS")
			(hide yes)
			(effects
				(font
					(size 1.27 1.27)
				)
				(justify mirror)
			)
		)
		(property "Value" "0R2J-2-GP"
			(at -0.064008 -3.993896 180)
			(unlocked yes)
			(layer "B.Fab")
			(hide yes)
			(effects
				(font
					(size 1.016 1.016)
					(thickness 0.1524)
				)
				(justify mirror)
			)
		)
		(property "Device Type" "R402H16"
			(at -0.064008 -5.517896 180)
			(unlocked yes)
			(layer "B.Fab")
			(hide yes)
			(effects
				(font
					(size 1.016 1.016)
					(thickness 0.1524)
				)
				(justify mirror)
			)
		)
		(duplicate_pad_numbers_are_jumpers no)
		(fp_line
			(start 0.508 -0.9398)
			(end 0.508 0.9398)
			(stroke
				(width 0.1524)
				(type default)
			)
			(layer "B.SilkS")
		)
		(fp_line
			(start -0.508 -0.9398)
			(end 0.508 -0.9398)
			(stroke
				(width 0.1524)
				(type default)
			)
			(layer "B.SilkS")
		)
		(fp_rect
			(start 0.508 0.9398)
			(end -0.508 -0.9398)
			(stroke
				(width 0)
				(type default)
			)
			(fill no)
			(layer "B.CrtYd")
		)
		(fp_rect
			(start 0.508 0.9398)
			(end -0.508 -0.9398)
			(stroke
				(width 0)
				(type default)
			)
			(fill no)
			(layer "B.Fab")
		)
		(pad "1" smd custom
			(at 0 -0.4445)
			(size 0.1397 0.1397)
			(layers "B.Cu" "B.Mask" "B.Paste")
			(net "RMII_PHY_BMC_RXD0")
			(options
				(clearance outline)
				(anchor circle)
			)
			(primitives
				(gr_poly
					(pts
						(arc
							(start -0.1778 0.2794)
							(mid -0.249642 0.249642)
							(end -0.2794 0.1778)
						)
						(arc
							(start -0.2794 -0.1778)
							(mid -0.249642 -0.249642)
							(end -0.1778 -0.2794)
						)
						(arc
							(start 0.1778 -0.2794)
							(mid 0.249642 -0.249642)
							(end 0.2794 -0.1778)
						)
						(arc
							(start 0.2794 0.1778)
							(mid 0.249642 0.249642)
							(end 0.1778 0.2794)
						)
					)
					(width 0)
					(fill yes)
				)
			)
		)
		(pad "2" smd custom
			(at 0 0.4445)
			(size 0.1397 0.1397)
			(layers "B.Cu" "B.Mask" "B.Paste")
			(net "RMII0_PHY_BMC_C_RXD0")
			(options
				(clearance outline)
				(anchor circle)
			)
			(primitives
				(gr_poly
					(pts
						(arc
							(start -0.1778 0.2794)
							(mid -0.249642 0.249642)
							(end -0.2794 0.1778)
						)
						(arc
							(start -0.2794 -0.1778)
							(mid -0.249642 -0.249642)
							(end -0.1778 -0.2794)
						)
						(arc
							(start 0.1778 -0.2794)
							(mid 0.249642 -0.249642)
							(end 0.2794 -0.1778)
						)
						(arc
							(start 0.2794 0.1778)
							(mid 0.249642 0.249642)
							(end 0.1778 0.2794)
						)
					)
					(width 0)
					(fill yes)
				)
			)
		)
	)
	(footprint ""
		(layer "B.Cu")
		(at 103.994966 -40.386)
		(property "Reference" "SC1056"
			(at 0 0 0)
			(layer "B.SilkS")
			(hide yes)
			(effects
				(font
					(size 1.27 1.27)
				)
				(justify mirror)
			)
		)
		(property "Value" "SCD1U16V2KX-3GP"
			(at -1.1811 -2.7051 0)
			(unlocked yes)
			(layer "B.Fab")
			(hide yes)
			(effects
				(font
					(size 1.016 1.016)
					(thickness 0.1524)
				)
				(justify mirror)
			)
		)
		(property "Device Type" "C402H22"
			(at -1.1811 -4.2291 0)
			(unlocked yes)
			(layer "B.Fab")
			(hide yes)
			(effects
				(font
					(size 1.016 1.016)
					(thickness 0.1524)
				)
				(justify mirror)
			)
		)
		(duplicate_pad_numbers_are_jumpers no)
		(fp_rect
			(start 0.4318 0.9525)
			(end -0.4318 -0.9525)
			(stroke
				(width 0)
				(type default)
			)
			(fill no)
			(layer "B.CrtYd")
		)
		(fp_rect
			(start 0.4318 0.9525)
			(end -0.4318 -0.9525)
			(stroke
				(width 0)
				(type default)
			)
			(fill no)
			(layer "B.Fab")
		)
		(pad "1" smd custom
			(at 0 -0.4445 180)
			(size 0.1524 0.1524)
			(layers "B.Cu" "B.Mask" "B.Paste")
			(net "P0V955_C")
			(options
				(clearance outline)
				(anchor circle)
			)
			(primitives
				(gr_poly
					(pts
						(arc
							(start 0.3048 0.2032)
							(mid 0.275042 0.275042)
							(end 0.2032 0.3048)
						)
						(arc
							(start -0.2032 0.3048)
							(mid -0.275042 0.275042)
							(end -0.3048 0.2032)
						)
						(arc
							(start -0.3048 -0.2032)
							(mid -0.275042 -0.275042)
							(end -0.2032 -0.3048)
						)
						(arc
							(start 0.2032 -0.3048)
							(mid 0.275042 -0.275042)
							(end 0.3048 -0.2032)
						)
					)
					(width 0)
					(fill yes)
				)
			)
		)
		(pad "2" smd custom
			(at 0 0.4445 180)
			(size 0.1524 0.1524)
			(layers "B.Cu" "B.Mask" "B.Paste")
			(net "GND")
			(options
				(clearance outline)
				(anchor circle)
			)
			(primitives
				(gr_poly
					(pts
						(arc
							(start 0.3048 0.2032)
							(mid 0.275042 0.275042)
							(end 0.2032 0.3048)
						)
						(arc
							(start -0.2032 0.3048)
							(mid -0.275042 0.275042)
							(end -0.3048 0.2032)
						)
						(arc
							(start -0.3048 -0.2032)
							(mid -0.275042 -0.275042)
							(end -0.2032 -0.3048)
						)
						(arc
							(start 0.2032 -0.3048)
							(mid 0.275042 -0.275042)
							(end 0.3048 -0.2032)
						)
					)
					(width 0)
					(fill yes)
				)
			)
		)
	)
	(footprint ""
		(layer "B.Cu")
		(at 120.28297 -104.14 -90)
		(property "Reference" "SC1179"
			(at 0 0 90)
			(layer "B.SilkS")
			(hide yes)
			(effects
				(font
					(size 1.27 1.27)
				)
				(justify mirror)
			)
		)
		(property "Value" "SCD1U6D3V1KX-GP"
			(at 2.8321 -1.7399 270)
			(unlocked yes)
			(layer "B.Fab")
			(hide yes)
			(effects
				(font
					(size 1.016 1.016)
					(thickness 0.1524)
				)
				(justify mirror)
			)
		)
		(property "Device Type" "C0201H13"
			(at 2.8321 -3.2639 270)
			(unlocked yes)
			(layer "B.Fab")
			(hide yes)
			(effects
				(font
					(size 1.016 1.016)
					(thickness 0.1524)
				)
				(justify mirror)
			)
		)
		(duplicate_pad_numbers_are_jumpers no)
		(fp_rect
			(start 0.2794 0.6477)
			(end -0.2794 -0.6477)
			(stroke
				(width 0)
				(type default)
			)
			(fill no)
			(layer "B.CrtYd")
		)
		(fp_rect
			(start 0.2794 0.6477)
			(end -0.2794 -0.6477)
			(stroke
				(width 0)
				(type default)
			)
			(fill no)
			(layer "B.Fab")
		)
		(pad "1" smd custom
			(at 0 -0.2794 90)
			(size 0.0762 0.0762)
			(layers "B.Cu" "B.Mask" "B.Paste")
			(net "GB_VDDA")
			(options
				(clearance outline)
				(anchor circle)
			)
			(primitives
				(gr_poly
					(pts
						(arc
							(start 0.1524 0.127)
							(mid 0.137521 0.162921)
							(end 0.1016 0.1778)
						)
						(arc
							(start -0.1016 0.1778)
							(mid -0.137521 0.162921)
							(end -0.1524 0.127)
						)
						(arc
							(start -0.1524 -0.127)
							(mid -0.137521 -0.162921)
							(end -0.1016 -0.1778)
						)
						(arc
							(start 0.1016 -0.1778)
							(mid 0.137521 -0.162921)
							(end 0.1524 -0.127)
						)
					)
					(width 0)
					(fill yes)
				)
			)
		)
		(pad "2" smd custom
			(at 0 0.2794 90)
			(size 0.0762 0.0762)
			(layers "B.Cu" "B.Mask" "B.Paste")
			(net "GND")
			(options
				(clearance outline)
				(anchor circle)
			)
			(primitives
				(gr_poly
					(pts
						(arc
							(start 0.1524 0.127)
							(mid 0.137521 0.162921)
							(end 0.1016 0.1778)
						)
						(arc
							(start -0.1016 0.1778)
							(mid -0.137521 0.162921)
							(end -0.1524 0.127)
						)
						(arc
							(start -0.1524 -0.127)
							(mid -0.137521 -0.162921)
							(end -0.1016 -0.1778)
						)
						(arc
							(start 0.1016 -0.1778)
							(mid 0.137521 -0.162921)
							(end 0.1524 -0.127)
						)
					)
					(width 0)
					(fill yes)
				)
			)
		)
	)
	(footprint ""
		(layer "B.Cu")
		(at 102.997 -227.965 -90)
		(property "Reference" "R663"
			(at 0 0 90)
			(layer "B.SilkS")
			(hide yes)
			(effects
				(font
					(size 1.27 1.27)
				)
				(justify mirror)
			)
		)
		(property "Value" "0R2J-2-GP"
			(at -0.064008 -3.993896 270)
			(unlocked yes)
			(layer "B.Fab")
			(hide yes)
			(effects
				(font
					(size 1.016 1.016)
					(thickness 0.1524)
				)
				(justify mirror)
			)
		)
		(property "Device Type" "R402H16"
			(at -0.064008 -5.517896 270)
			(unlocked yes)
			(layer "B.Fab")
			(hide yes)
			(effects
				(font
					(size 1.016 1.016)
					(thickness 0.1524)
				)
				(justify mirror)
			)
		)
		(duplicate_pad_numbers_are_jumpers no)
		(fp_line
			(start -0.508 -0.9398)
			(end 0.508 -0.9398)
			(stroke
				(width 0.1524)
				(type default)
			)
			(layer "B.SilkS")
		)
		(fp_line
			(start 0.508 -0.9398)
			(end 0.508 0.9398)
			(stroke
				(width 0.1524)
				(type default)
			)
			(layer "B.SilkS")
		)
		(fp_rect
			(start 0.508 0.9398)
			(end -0.508 -0.9398)
			(stroke
				(width 0)
				(type default)
			)
			(fill no)
			(layer "B.CrtYd")
		)
		(fp_rect
			(start 0.508 0.9398)
			(end -0.508 -0.9398)
			(stroke
				(width 0)
				(type default)
			)
			(fill no)
			(layer "B.Fab")
		)
		(pad "1" smd custom
			(at 0 -0.4445 90)
			(size 0.1397 0.1397)
			(layers "B.Cu" "B.Mask" "B.Paste")
			(net "SAS_FAULT_LED2")
			(options
				(clearance outline)
				(anchor circle)
			)
			(primitives
				(gr_poly
					(pts
						(arc
							(start -0.1778 0.2794)
							(mid -0.249642 0.249642)
							(end -0.2794 0.1778)
						)
						(arc
							(start -0.2794 -0.1778)
							(mid -0.249642 -0.249642)
							(end -0.1778 -0.2794)
						)
						(arc
							(start 0.1778 -0.2794)
							(mid 0.249642 -0.249642)
							(end 0.2794 -0.1778)
						)
						(arc
							(start 0.2794 0.1778)
							(mid 0.249642 0.249642)
							(end 0.1778 0.2794)
						)
					)
					(width 0)
					(fill yes)
				)
			)
		)
		(pad "2" smd custom
			(at 0 0.4445 90)
			(size 0.1397 0.1397)
			(layers "B.Cu" "B.Mask" "B.Paste")
			(net "SAS_HDD_LED_2")
			(options
				(clearance outline)
				(anchor circle)
			)
			(primitives
				(gr_poly
					(pts
						(arc
							(start -0.1778 0.2794)
							(mid -0.249642 0.249642)
							(end -0.2794 0.1778)
						)
						(arc
							(start -0.2794 -0.1778)
							(mid -0.249642 -0.249642)
							(end -0.1778 -0.2794)
						)
						(arc
							(start 0.1778 -0.2794)
							(mid 0.249642 -0.249642)
							(end 0.2794 -0.1778)
						)
						(arc
							(start 0.2794 0.1778)
							(mid 0.249642 0.249642)
							(end 0.1778 0.2794)
						)
					)
					(width 0)
					(fill yes)
				)
			)
		)
	)
	(footprint ""
		(layer "B.Cu")
		(at 158.42996 -108.356654 90)
		(property "Reference" "SC1244"
			(at 0 0 90)
			(layer "B.SilkS")
			(hide yes)
			(effects
				(font
					(size 1.27 1.27)
				)
				(justify mirror)
			)
		)
		(property "Value" "SCD1U6D3V1KX-GP"
			(at 2.8321 -1.7399 90)
			(unlocked yes)
			(layer "B.Fab")
			(hide yes)
			(effects
				(font
					(size 1.016 1.016)
					(thickness 0.1524)
				)
				(justify mirror)
			)
		)
		(property "Device Type" "C0201H13"
			(at 2.8321 -3.2639 90)
			(unlocked yes)
			(layer "B.Fab")
			(hide yes)
			(effects
				(font
					(size 1.016 1.016)
					(thickness 0.1524)
				)
				(justify mirror)
			)
		)
		(duplicate_pad_numbers_are_jumpers no)
		(fp_rect
			(start 0.2794 0.6477)
			(end -0.2794 -0.6477)
			(stroke
				(width 0)
				(type default)
			)
			(fill no)
			(layer "B.CrtYd")
		)
		(fp_rect
			(start 0.2794 0.6477)
			(end -0.2794 -0.6477)
			(stroke
				(width 0)
				(type default)
			)
			(fill no)
			(layer "B.Fab")
		)
		(pad "1" smd custom
			(at 0 -0.2794 270)
			(size 0.0762 0.0762)
			(layers "B.Cu" "B.Mask" "B.Paste")
			(net "P0V9_E")
			(options
				(clearance outline)
				(anchor circle)
			)
			(primitives
				(gr_poly
					(pts
						(arc
							(start 0.1524 0.127)
							(mid 0.137521 0.162921)
							(end 0.1016 0.1778)
						)
						(arc
							(start -0.1016 0.1778)
							(mid -0.137521 0.162921)
							(end -0.1524 0.127)
						)
						(arc
							(start -0.1524 -0.127)
							(mid -0.137521 -0.162921)
							(end -0.1016 -0.1778)
						)
						(arc
							(start 0.1016 -0.1778)
							(mid 0.137521 -0.162921)
							(end 0.1524 -0.127)
						)
					)
					(width 0)
					(fill yes)
				)
			)
		)
		(pad "2" smd custom
			(at 0 0.2794 270)
			(size 0.0762 0.0762)
			(layers "B.Cu" "B.Mask" "B.Paste")
			(net "GND")
			(options
				(clearance outline)
				(anchor circle)
			)
			(primitives
				(gr_poly
					(pts
						(arc
							(start 0.1524 0.127)
							(mid 0.137521 0.162921)
							(end 0.1016 0.1778)
						)
						(arc
							(start -0.1016 0.1778)
							(mid -0.137521 0.162921)
							(end -0.1524 0.127)
						)
						(arc
							(start -0.1524 -0.127)
							(mid -0.137521 -0.162921)
							(end -0.1016 -0.1778)
						)
						(arc
							(start 0.1016 -0.1778)
							(mid 0.137521 -0.162921)
							(end 0.1524 -0.127)
						)
					)
					(width 0)
					(fill yes)
				)
			)
		)
	)
	(footprint ""
		(layer "B.Cu")
		(at 303.26584 -181.1655)
		(property "Reference" "TP161"
			(at 0 0 0)
			(layer "B.SilkS")
			(hide yes)
			(effects
				(font
					(size 1.27 1.27)
				)
				(justify mirror)
			)
		)
		(property "Value" "TPAD28"
			(at -0.0127 -1.8034 0)
			(unlocked yes)
			(layer "B.Fab")
			(hide yes)
			(effects
				(font
					(size 1.016 1.016)
					(thickness 0.1524)
				)
				(justify mirror)
			)
		)
		(property "Device Type" "TPAD28"
			(at -0.0127 -3.3274 0)
			(unlocked yes)
			(layer "B.Fab")
			(hide yes)
			(effects
				(font
					(size 1.016 1.016)
					(thickness 0.1524)
				)
				(justify mirror)
			)
		)
		(duplicate_pad_numbers_are_jumpers no)
		(fp_poly
			(pts
				(arc
					(start 0.3556 0)
					(mid -0.3556 0)
					(end 0.3556 0)
				)
			)
			(stroke
				(width 0)
				(type default)
			)
			(fill no)
			(layer "B.CrtYd")
		)
		(fp_poly
			(pts
				(arc
					(start 0.6096 0)
					(mid -0.6096 0)
					(end 0.6096 0)
				)
			)
			(stroke
				(width 0)
				(type default)
			)
			(fill no)
			(layer "B.Fab")
		)
		(pad "1" smd circle
			(at 0 0 180)
			(size 0.7112 0.7112)
			(layers "B.Cu" "B.Mask" "B.Paste")
			(net "TP_BMC_GPIOJ6")
		)
	)
	(footprint ""
		(layer "B.Cu")
		(at 290.01466 -169.45102)
		(property "Reference" "TP141"
			(at 0 0 0)
			(layer "B.SilkS")
			(hide yes)
			(effects
				(font
					(size 1.27 1.27)
				)
				(justify mirror)
			)
		)
		(property "Value" "TPAD28"
			(at -0.0127 -1.8034 0)
			(unlocked yes)
			(layer "B.Fab")
			(hide yes)
			(effects
				(font
					(size 1.016 1.016)
					(thickness 0.1524)
				)
				(justify mirror)
			)
		)
		(property "Device Type" "TPAD28"
			(at -0.0127 -3.3274 0)
			(unlocked yes)
			(layer "B.Fab")
			(hide yes)
			(effects
				(font
					(size 1.016 1.016)
					(thickness 0.1524)
				)
				(justify mirror)
			)
		)
		(duplicate_pad_numbers_are_jumpers no)
		(fp_poly
			(pts
				(arc
					(start 0.3556 0)
					(mid -0.3556 0)
					(end 0.3556 0)
				)
			)
			(stroke
				(width 0)
				(type default)
			)
			(fill no)
			(layer "B.CrtYd")
		)
		(fp_poly
			(pts
				(arc
					(start 0.6096 0)
					(mid -0.6096 0)
					(end 0.6096 0)
				)
			)
			(stroke
				(width 0)
				(type default)
			)
			(fill no)
			(layer "B.Fab")
		)
		(pad "1" smd circle
			(at 0 0 180)
			(size 0.7112 0.7112)
			(layers "B.Cu" "B.Mask" "B.Paste")
			(net "TP_BMC_GPIOE4")
		)
	)
	(footprint ""
		(layer "B.Cu")
		(at 104.02316 -31.623)
		(property "Reference" "SC875"
			(at 0 0 0)
			(layer "B.SilkS")
			(hide yes)
			(effects
				(font
					(size 1.27 1.27)
				)
				(justify mirror)
			)
		)
		(property "Value" "SCD22U6D3V1MX-1-GP"
			(at 2.8321 -1.7399 0)
			(unlocked yes)
			(layer "B.Fab")
			(hide yes)
			(effects
				(font
					(size 1.016 1.016)
					(thickness 0.1524)
				)
				(justify mirror)
			)
		)
		(property "Device Type" "C0201H13"
			(at 2.8321 -3.2639 0)
			(unlocked yes)
			(layer "B.Fab")
			(hide yes)
			(effects
				(font
					(size 1.016 1.016)
					(thickness 0.1524)
				)
				(justify mirror)
			)
		)
		(duplicate_pad_numbers_are_jumpers no)
		(fp_rect
			(start 0.2794 0.6477)
			(end -0.2794 -0.6477)
			(stroke
				(width 0)
				(type default)
			)
			(fill no)
			(layer "B.CrtYd")
		)
		(fp_rect
			(start 0.2794 0.6477)
			(end -0.2794 -0.6477)
			(stroke
				(width 0)
				(type default)
			)
			(fill no)
			(layer "B.Fab")
		)
		(pad "1" smd custom
			(at 0 -0.2794 180)
			(size 0.0762 0.0762)
			(layers "B.Cu" "B.Mask" "B.Paste")
			(net "PCIE_SAS_C_CPU_RX_P7")
			(options
				(clearance outline)
				(anchor circle)
			)
			(primitives
				(gr_poly
					(pts
						(arc
							(start 0.1524 0.127)
							(mid 0.137521 0.162921)
							(end 0.1016 0.1778)
						)
						(arc
							(start -0.1016 0.1778)
							(mid -0.137521 0.162921)
							(end -0.1524 0.127)
						)
						(arc
							(start -0.1524 -0.127)
							(mid -0.137521 -0.162921)
							(end -0.1016 -0.1778)
						)
						(arc
							(start 0.1016 -0.1778)
							(mid 0.137521 -0.162921)
							(end 0.1524 -0.127)
						)
					)
					(width 0)
					(fill yes)
				)
			)
		)
		(pad "2" smd custom
			(at 0 0.2794 180)
			(size 0.0762 0.0762)
			(layers "B.Cu" "B.Mask" "B.Paste")
			(net "PCIE_SAS_CPU_RX_P7")
			(options
				(clearance outline)
				(anchor circle)
			)
			(primitives
				(gr_poly
					(pts
						(arc
							(start 0.1524 0.127)
							(mid 0.137521 0.162921)
							(end 0.1016 0.1778)
						)
						(arc
							(start -0.1016 0.1778)
							(mid -0.137521 0.162921)
							(end -0.1524 0.127)
						)
						(arc
							(start -0.1524 -0.127)
							(mid -0.137521 -0.162921)
							(end -0.1016 -0.1778)
						)
						(arc
							(start 0.1016 -0.1778)
							(mid 0.137521 -0.162921)
							(end 0.1524 -0.127)
						)
					)
					(width 0)
					(fill yes)
				)
			)
		)
	)
	(footprint ""
		(layer "B.Cu")
		(at 319.913 -167.894 90)
		(property "Reference" "R437"
			(at 0 0 90)
			(layer "B.SilkS")
			(hide yes)
			(effects
				(font
					(size 1.27 1.27)
				)
				(justify mirror)
			)
		)
		(property "Value" "4K7R2F-GP"
			(at -0.064008 -3.993896 90)
			(unlocked yes)
			(layer "B.Fab")
			(hide yes)
			(effects
				(font
					(size 1.016 1.016)
					(thickness 0.1524)
				)
				(justify mirror)
			)
		)
		(property "Device Type" "R402H16"
			(at -0.064008 -5.517896 90)
			(unlocked yes)
			(layer "B.Fab")
			(hide yes)
			(effects
				(font
					(size 1.016 1.016)
					(thickness 0.1524)
				)
				(justify mirror)
			)
		)
		(duplicate_pad_numbers_are_jumpers no)
		(fp_line
			(start 0.508 -0.9398)
			(end 0.508 0.9398)
			(stroke
				(width 0.1524)
				(type default)
			)
			(layer "B.SilkS")
		)
		(fp_line
			(start -0.508 -0.9398)
			(end 0.508 -0.9398)
			(stroke
				(width 0.1524)
				(type default)
			)
			(layer "B.SilkS")
		)
		(fp_rect
			(start 0.508 0.9398)
			(end -0.508 -0.9398)
			(stroke
				(width 0)
				(type default)
			)
			(fill no)
			(layer "B.CrtYd")
		)
		(fp_rect
			(start 0.508 0.9398)
			(end -0.508 -0.9398)
			(stroke
				(width 0)
				(type default)
			)
			(fill no)
			(layer "B.Fab")
		)
		(pad "1" smd custom
			(at 0 -0.4445 270)
			(size 0.1397 0.1397)
			(layers "B.Cu" "B.Mask" "B.Paste")
			(net "BMC_I2C_A_SCL")
			(options
				(clearance outline)
				(anchor circle)
			)
			(primitives
				(gr_poly
					(pts
						(arc
							(start -0.1778 0.2794)
							(mid -0.249642 0.249642)
							(end -0.2794 0.1778)
						)
						(arc
							(start -0.2794 -0.1778)
							(mid -0.249642 -0.249642)
							(end -0.1778 -0.2794)
						)
						(arc
							(start 0.1778 -0.2794)
							(mid 0.249642 -0.249642)
							(end 0.2794 -0.1778)
						)
						(arc
							(start 0.2794 0.1778)
							(mid 0.249642 0.249642)
							(end 0.1778 0.2794)
						)
					)
					(width 0)
					(fill yes)
				)
			)
		)
		(pad "2" smd custom
			(at 0 0.4445 270)
			(size 0.1397 0.1397)
			(layers "B.Cu" "B.Mask" "B.Paste")
			(net "P3V3_STBY")
			(options
				(clearance outline)
				(anchor circle)
			)
			(primitives
				(gr_poly
					(pts
						(arc
							(start -0.1778 0.2794)
							(mid -0.249642 0.249642)
							(end -0.2794 0.1778)
						)
						(arc
							(start -0.2794 -0.1778)
							(mid -0.249642 -0.249642)
							(end -0.1778 -0.2794)
						)
						(arc
							(start 0.1778 -0.2794)
							(mid 0.249642 -0.249642)
							(end 0.2794 -0.1778)
						)
						(arc
							(start 0.2794 0.1778)
							(mid 0.249642 0.249642)
							(end 0.1778 0.2794)
						)
					)
					(width 0)
					(fill yes)
				)
			)
		)
	)
	(footprint ""
		(layer "B.Cu")
		(at 110.587282 -37.008054 -90)
		(property "Reference" "SR669"
			(at 0 0 90)
			(layer "B.SilkS")
			(hide yes)
			(effects
				(font
					(size 1.27 1.27)
				)
				(justify mirror)
			)
		)
		(property "Value" "10KR2F-2-GP"
			(at -0.064008 -3.993896 270)
			(unlocked yes)
			(layer "B.Fab")
			(hide yes)
			(effects
				(font
					(size 1.016 1.016)
					(thickness 0.1524)
				)
				(justify mirror)
			)
		)
		(property "Device Type" "R402H16"
			(at -0.064008 -5.517896 270)
			(unlocked yes)
			(layer "B.Fab")
			(hide yes)
			(effects
				(font
					(size 1.016 1.016)
					(thickness 0.1524)
				)
				(justify mirror)
			)
		)
		(duplicate_pad_numbers_are_jumpers no)
		(fp_line
			(start -0.508 -0.9398)
			(end 0.508 -0.9398)
			(stroke
				(width 0.1524)
				(type default)
			)
			(layer "B.SilkS")
		)
		(fp_line
			(start 0.508 -0.9398)
			(end 0.508 0.9398)
			(stroke
				(width 0.1524)
				(type default)
			)
			(layer "B.SilkS")
		)
		(fp_rect
			(start 0.508 0.9398)
			(end -0.508 -0.9398)
			(stroke
				(width 0)
				(type default)
			)
			(fill no)
			(layer "B.CrtYd")
		)
		(fp_rect
			(start 0.508 0.9398)
			(end -0.508 -0.9398)
			(stroke
				(width 0)
				(type default)
			)
			(fill no)
			(layer "B.Fab")
		)
		(pad "1" smd custom
			(at 0 -0.4445 90)
			(size 0.1397 0.1397)
			(layers "B.Cu" "B.Mask" "B.Paste")
			(net "P1V8_C")
			(options
				(clearance outline)
				(anchor circle)
			)
			(primitives
				(gr_poly
					(pts
						(arc
							(start -0.1778 0.2794)
							(mid -0.249642 0.249642)
							(end -0.2794 0.1778)
						)
						(arc
							(start -0.2794 -0.1778)
							(mid -0.249642 -0.249642)
							(end -0.1778 -0.2794)
						)
						(arc
							(start 0.1778 -0.2794)
							(mid 0.249642 -0.249642)
							(end 0.2794 -0.1778)
						)
						(arc
							(start 0.2794 0.1778)
							(mid 0.249642 0.249642)
							(end 0.1778 0.2794)
						)
					)
					(width 0)
					(fill yes)
				)
			)
		)
		(pad "2" smd custom
			(at 0 0.4445 90)
			(size 0.1397 0.1397)
			(layers "B.Cu" "B.Mask" "B.Paste")
			(net "SYS_RST_N_1")
			(options
				(clearance outline)
				(anchor circle)
			)
			(primitives
				(gr_poly
					(pts
						(arc
							(start -0.1778 0.2794)
							(mid -0.249642 0.249642)
							(end -0.2794 0.1778)
						)
						(arc
							(start -0.2794 -0.1778)
							(mid -0.249642 -0.249642)
							(end -0.1778 -0.2794)
						)
						(arc
							(start 0.1778 -0.2794)
							(mid 0.249642 -0.249642)
							(end 0.2794 -0.1778)
						)
						(arc
							(start 0.2794 0.1778)
							(mid 0.249642 0.249642)
							(end 0.1778 0.2794)
						)
					)
					(width 0)
					(fill yes)
				)
			)
		)
	)
	(footprint ""
		(layer "B.Cu")
		(at 295.148 -164.211 180)
		(property "Reference" "R288"
			(at 0 0 0)
			(layer "B.SilkS")
			(hide yes)
			(effects
				(font
					(size 1.27 1.27)
				)
				(justify mirror)
			)
		)
		(property "Value" "47KR2F-GP"
			(at -0.064008 -3.993896 180)
			(unlocked yes)
			(layer "B.Fab")
			(hide yes)
			(effects
				(font
					(size 1.016 1.016)
					(thickness 0.1524)
				)
				(justify mirror)
			)
		)
		(property "Device Type" "R402H16"
			(at -0.064008 -5.517896 180)
			(unlocked yes)
			(layer "B.Fab")
			(hide yes)
			(effects
				(font
					(size 1.016 1.016)
					(thickness 0.1524)
				)
				(justify mirror)
			)
		)
		(duplicate_pad_numbers_are_jumpers no)
		(fp_line
			(start 0.508 -0.9398)
			(end 0.508 0.9398)
			(stroke
				(width 0.1524)
				(type default)
			)
			(layer "B.SilkS")
		)
		(fp_line
			(start -0.508 -0.9398)
			(end 0.508 -0.9398)
			(stroke
				(width 0.1524)
				(type default)
			)
			(layer "B.SilkS")
		)
		(fp_rect
			(start 0.508 0.9398)
			(end -0.508 -0.9398)
			(stroke
				(width 0)
				(type default)
			)
			(fill no)
			(layer "B.CrtYd")
		)
		(fp_rect
			(start 0.508 0.9398)
			(end -0.508 -0.9398)
			(stroke
				(width 0)
				(type default)
			)
			(fill no)
			(layer "B.Fab")
		)
		(pad "1" smd custom
			(at 0 -0.4445)
			(size 0.1397 0.1397)
			(layers "B.Cu" "B.Mask" "B.Paste")
			(net "GND")
			(options
				(clearance outline)
				(anchor circle)
			)
			(primitives
				(gr_poly
					(pts
						(arc
							(start -0.1778 0.2794)
							(mid -0.249642 0.249642)
							(end -0.2794 0.1778)
						)
						(arc
							(start -0.2794 -0.1778)
							(mid -0.249642 -0.249642)
							(end -0.1778 -0.2794)
						)
						(arc
							(start 0.1778 -0.2794)
							(mid 0.249642 -0.249642)
							(end 0.2794 -0.1778)
						)
						(arc
							(start 0.2794 0.1778)
							(mid 0.249642 0.249642)
							(end 0.1778 0.2794)
						)
					)
					(width 0)
					(fill yes)
				)
			)
		)
		(pad "2" smd custom
			(at 0 0.4445)
			(size 0.1397 0.1397)
			(layers "B.Cu" "B.Mask" "B.Paste")
			(net "RMII0_BMC_C_RX_ER")
			(options
				(clearance outline)
				(anchor circle)
			)
			(primitives
				(gr_poly
					(pts
						(arc
							(start -0.1778 0.2794)
							(mid -0.249642 0.249642)
							(end -0.2794 0.1778)
						)
						(arc
							(start -0.2794 -0.1778)
							(mid -0.249642 -0.249642)
							(end -0.1778 -0.2794)
						)
						(arc
							(start 0.1778 -0.2794)
							(mid 0.249642 -0.249642)
							(end 0.2794 -0.1778)
						)
						(arc
							(start 0.2794 0.1778)
							(mid 0.249642 0.249642)
							(end 0.1778 0.2794)
						)
					)
					(width 0)
					(fill yes)
				)
			)
		)
	)
	(footprint ""
		(layer "B.Cu")
		(at 124.85497 -94.361 90)
		(property "Reference" "SC1166"
			(at 0 0 90)
			(layer "B.SilkS")
			(hide yes)
			(effects
				(font
					(size 1.27 1.27)
				)
				(justify mirror)
			)
		)
		(property "Value" "SC1U6D3V1MX-GP"
			(at -1.9177 2.0193 90)
			(unlocked yes)
			(layer "B.Fab")
			(hide yes)
			(effects
				(font
					(size 1.016 1.016)
					(thickness 0.1524)
				)
				(justify mirror)
			)
		)
		(property "Device Type" "C0201H14"
			(at -1.9177 0.4953 90)
			(unlocked yes)
			(layer "B.Fab")
			(hide yes)
			(effects
				(font
					(size 1.016 1.016)
					(thickness 0.1524)
				)
				(justify mirror)
			)
		)
		(duplicate_pad_numbers_are_jumpers no)
		(fp_rect
			(start 0.1524 0.3048)
			(end -0.1524 -0.3048)
			(stroke
				(width 0)
				(type default)
			)
			(fill no)
			(layer "B.CrtYd")
		)
		(fp_poly
			(pts
				(xy 0.2794 0.6477) (xy 0.2794 -0.6477) (xy -0.2794 -0.6477) (xy -0.2794 -0.1905) (xy -0.1524 -0.1905)
				(xy -0.1524 -0.3048) (xy 0.1524 -0.3048) (xy 0.1524 0.3048) (xy -0.1524 0.3048) (xy -0.1524 -0.1778)
				(xy -0.2794 -0.1778) (xy -0.2794 0.6477)
			)
			(stroke
				(width 0)
				(type default)
			)
			(fill no)
			(layer "B.CrtYd")
		)
		(fp_rect
			(start 0.2794 0.6477)
			(end -0.2794 -0.6477)
			(stroke
				(width 0)
				(type default)
			)
			(fill no)
			(layer "B.Fab")
		)
		(pad "1" smd custom
			(at 0 -0.2794 270)
			(size 0.0762 0.0762)
			(layers "B.Cu" "B.Mask" "B.Paste")
			(net "GB_VDDA")
			(options
				(clearance outline)
				(anchor circle)
			)
			(primitives
				(gr_poly
					(pts
						(arc
							(start 0.1524 0.127)
							(mid 0.137521 0.162921)
							(end 0.1016 0.1778)
						)
						(arc
							(start -0.1016 0.1778)
							(mid -0.137521 0.162921)
							(end -0.1524 0.127)
						)
						(arc
							(start -0.1524 -0.127)
							(mid -0.137521 -0.162921)
							(end -0.1016 -0.1778)
						)
						(arc
							(start 0.1016 -0.1778)
							(mid 0.137521 -0.162921)
							(end 0.1524 -0.127)
						)
					)
					(width 0)
					(fill yes)
				)
			)
		)
		(pad "2" smd custom
			(at 0 0.2794 270)
			(size 0.0762 0.0762)
			(layers "B.Cu" "B.Mask" "B.Paste")
			(net "GND")
			(options
				(clearance outline)
				(anchor circle)
			)
			(primitives
				(gr_poly
					(pts
						(arc
							(start 0.1524 0.127)
							(mid 0.137521 0.162921)
							(end 0.1016 0.1778)
						)
						(arc
							(start -0.1016 0.1778)
							(mid -0.137521 0.162921)
							(end -0.1524 0.127)
						)
						(arc
							(start -0.1524 -0.127)
							(mid -0.137521 -0.162921)
							(end -0.1016 -0.1778)
						)
						(arc
							(start 0.1016 -0.1778)
							(mid 0.137521 -0.162921)
							(end 0.1524 -0.127)
						)
					)
					(width 0)
					(fill yes)
				)
			)
		)
	)
	(footprint ""
		(layer "B.Cu")
		(at 114.36477 -35.625532)
		(property "Reference" "STP4"
			(at 0 0 0)
			(layer "B.SilkS")
			(hide yes)
			(effects
				(font
					(size 1.27 1.27)
				)
				(justify mirror)
			)
		)
		(property "Value" "TPAD28"
			(at -0.0127 -1.8034 0)
			(unlocked yes)
			(layer "B.Fab")
			(hide yes)
			(effects
				(font
					(size 1.016 1.016)
					(thickness 0.1524)
				)
				(justify mirror)
			)
		)
		(property "Device Type" "TPAD28"
			(at -0.0127 -3.3274 0)
			(unlocked yes)
			(layer "B.Fab")
			(hide yes)
			(effects
				(font
					(size 1.016 1.016)
					(thickness 0.1524)
				)
				(justify mirror)
			)
		)
		(duplicate_pad_numbers_are_jumpers no)
		(fp_poly
			(pts
				(arc
					(start 0.3556 0)
					(mid -0.3556 0)
					(end 0.3556 0)
				)
			)
			(stroke
				(width 0)
				(type default)
			)
			(fill no)
			(layer "B.CrtYd")
		)
		(fp_poly
			(pts
				(arc
					(start 0.6096 0)
					(mid -0.6096 0)
					(end 0.6096 0)
				)
			)
			(stroke
				(width 0)
				(type default)
			)
			(fill no)
			(layer "B.Fab")
		)
		(pad "1" smd circle
			(at 0 0 180)
			(size 0.7112 0.7112)
			(layers "B.Cu" "B.Mask" "B.Paste")
			(net "IOC_GPIO_26")
		)
	)
	(footprint ""
		(layer "B.Cu")
		(at 274.193 -180.721 90)
		(property "Reference" "R349"
			(at 0 0 90)
			(layer "B.SilkS")
			(hide yes)
			(effects
				(font
					(size 1.27 1.27)
				)
				(justify mirror)
			)
		)
		(property "Value" "3K3R2F-2-GP"
			(at -0.064008 -3.993896 90)
			(unlocked yes)
			(layer "B.Fab")
			(hide yes)
			(effects
				(font
					(size 1.016 1.016)
					(thickness 0.1524)
				)
				(justify mirror)
			)
		)
		(property "Device Type" "R402H16"
			(at -0.064008 -5.517896 90)
			(unlocked yes)
			(layer "B.Fab")
			(hide yes)
			(effects
				(font
					(size 1.016 1.016)
					(thickness 0.1524)
				)
				(justify mirror)
			)
		)
		(duplicate_pad_numbers_are_jumpers no)
		(fp_line
			(start 0.508 -0.9398)
			(end 0.508 0.9398)
			(stroke
				(width 0.1524)
				(type default)
			)
			(layer "B.SilkS")
		)
		(fp_line
			(start -0.508 -0.9398)
			(end 0.508 -0.9398)
			(stroke
				(width 0.1524)
				(type default)
			)
			(layer "B.SilkS")
		)
		(fp_rect
			(start 0.508 0.9398)
			(end -0.508 -0.9398)
			(stroke
				(width 0)
				(type default)
			)
			(fill no)
			(layer "B.CrtYd")
		)
		(fp_rect
			(start 0.508 0.9398)
			(end -0.508 -0.9398)
			(stroke
				(width 0)
				(type default)
			)
			(fill no)
			(layer "B.Fab")
		)
		(pad "1" smd custom
			(at 0 -0.4445 270)
			(size 0.1397 0.1397)
			(layers "B.Cu" "B.Mask" "B.Paste")
			(net "P3V3_STBY")
			(options
				(clearance outline)
				(anchor circle)
			)
			(primitives
				(gr_poly
					(pts
						(arc
							(start -0.1778 0.2794)
							(mid -0.249642 0.249642)
							(end -0.2794 0.1778)
						)
						(arc
							(start -0.2794 -0.1778)
							(mid -0.249642 -0.249642)
							(end -0.1778 -0.2794)
						)
						(arc
							(start 0.1778 -0.2794)
							(mid 0.249642 -0.249642)
							(end 0.2794 -0.1778)
						)
						(arc
							(start 0.2794 0.1778)
							(mid 0.249642 0.249642)
							(end 0.1778 0.2794)
						)
					)
					(width 0)
					(fill yes)
				)
			)
		)
		(pad "2" smd custom
			(at 0 0.4445 270)
			(size 0.1397 0.1397)
			(layers "B.Cu" "B.Mask" "B.Paste")
			(net "ROMA18")
			(options
				(clearance outline)
				(anchor circle)
			)
			(primitives
				(gr_poly
					(pts
						(arc
							(start -0.1778 0.2794)
							(mid -0.249642 0.249642)
							(end -0.2794 0.1778)
						)
						(arc
							(start -0.2794 -0.1778)
							(mid -0.249642 -0.249642)
							(end -0.1778 -0.2794)
						)
						(arc
							(start 0.1778 -0.2794)
							(mid 0.249642 -0.249642)
							(end 0.2794 -0.1778)
						)
						(arc
							(start 0.2794 0.1778)
							(mid 0.249642 0.249642)
							(end 0.1778 0.2794)
						)
					)
					(width 0)
					(fill yes)
				)
			)
		)
	)
	(footprint ""
		(layer "B.Cu")
		(at 96.349566 -40.2844 90)
		(property "Reference" "SC966"
			(at 0 0 90)
			(layer "B.SilkS")
			(hide yes)
			(effects
				(font
					(size 1.27 1.27)
				)
				(justify mirror)
			)
		)
		(property "Value" "SCD1U6D3V1KX-GP"
			(at 2.8321 -1.7399 90)
			(unlocked yes)
			(layer "B.Fab")
			(hide yes)
			(effects
				(font
					(size 1.016 1.016)
					(thickness 0.1524)
				)
				(justify mirror)
			)
		)
		(property "Device Type" "C0201H13"
			(at 2.8321 -3.2639 90)
			(unlocked yes)
			(layer "B.Fab")
			(hide yes)
			(effects
				(font
					(size 1.016 1.016)
					(thickness 0.1524)
				)
				(justify mirror)
			)
		)
		(duplicate_pad_numbers_are_jumpers no)
		(fp_rect
			(start 0.2794 0.6477)
			(end -0.2794 -0.6477)
			(stroke
				(width 0)
				(type default)
			)
			(fill no)
			(layer "B.CrtYd")
		)
		(fp_rect
			(start 0.2794 0.6477)
			(end -0.2794 -0.6477)
			(stroke
				(width 0)
				(type default)
			)
			(fill no)
			(layer "B.Fab")
		)
		(pad "1" smd custom
			(at 0 -0.2794 270)
			(size 0.0762 0.0762)
			(layers "B.Cu" "B.Mask" "B.Paste")
			(net "SAS0_AVDD")
			(options
				(clearance outline)
				(anchor circle)
			)
			(primitives
				(gr_poly
					(pts
						(arc
							(start 0.1524 0.127)
							(mid 0.137521 0.162921)
							(end 0.1016 0.1778)
						)
						(arc
							(start -0.1016 0.1778)
							(mid -0.137521 0.162921)
							(end -0.1524 0.127)
						)
						(arc
							(start -0.1524 -0.127)
							(mid -0.137521 -0.162921)
							(end -0.1016 -0.1778)
						)
						(arc
							(start 0.1016 -0.1778)
							(mid 0.137521 -0.162921)
							(end 0.1524 -0.127)
						)
					)
					(width 0)
					(fill yes)
				)
			)
		)
		(pad "2" smd custom
			(at 0 0.2794 270)
			(size 0.0762 0.0762)
			(layers "B.Cu" "B.Mask" "B.Paste")
			(net "GND")
			(options
				(clearance outline)
				(anchor circle)
			)
			(primitives
				(gr_poly
					(pts
						(arc
							(start 0.1524 0.127)
							(mid 0.137521 0.162921)
							(end 0.1016 0.1778)
						)
						(arc
							(start -0.1016 0.1778)
							(mid -0.137521 0.162921)
							(end -0.1524 0.127)
						)
						(arc
							(start -0.1524 -0.127)
							(mid -0.137521 -0.162921)
							(end -0.1016 -0.1778)
						)
						(arc
							(start 0.1016 -0.1778)
							(mid 0.137521 -0.162921)
							(end 0.1524 -0.127)
						)
					)
					(width 0)
					(fill yes)
				)
			)
		)
	)
	(footprint ""
		(layer "B.Cu")
		(at 93.35516 -31.623)
		(property "Reference" "SC861"
			(at 0 0 0)
			(layer "B.SilkS")
			(hide yes)
			(effects
				(font
					(size 1.27 1.27)
				)
				(justify mirror)
			)
		)
		(property "Value" "SCD22U6D3V1MX-1-GP"
			(at 2.8321 -1.7399 0)
			(unlocked yes)
			(layer "B.Fab")
			(hide yes)
			(effects
				(font
					(size 1.016 1.016)
					(thickness 0.1524)
				)
				(justify mirror)
			)
		)
		(property "Device Type" "C0201H13"
			(at 2.8321 -3.2639 0)
			(unlocked yes)
			(layer "B.Fab")
			(hide yes)
			(effects
				(font
					(size 1.016 1.016)
					(thickness 0.1524)
				)
				(justify mirror)
			)
		)
		(duplicate_pad_numbers_are_jumpers no)
		(fp_rect
			(start 0.2794 0.6477)
			(end -0.2794 -0.6477)
			(stroke
				(width 0)
				(type default)
			)
			(fill no)
			(layer "B.CrtYd")
		)
		(fp_rect
			(start 0.2794 0.6477)
			(end -0.2794 -0.6477)
			(stroke
				(width 0)
				(type default)
			)
			(fill no)
			(layer "B.Fab")
		)
		(pad "1" smd custom
			(at 0 -0.2794 180)
			(size 0.0762 0.0762)
			(layers "B.Cu" "B.Mask" "B.Paste")
			(net "PCIE_SAS_C_CPU_RX_P0")
			(options
				(clearance outline)
				(anchor circle)
			)
			(primitives
				(gr_poly
					(pts
						(arc
							(start 0.1524 0.127)
							(mid 0.137521 0.162921)
							(end 0.1016 0.1778)
						)
						(arc
							(start -0.1016 0.1778)
							(mid -0.137521 0.162921)
							(end -0.1524 0.127)
						)
						(arc
							(start -0.1524 -0.127)
							(mid -0.137521 -0.162921)
							(end -0.1016 -0.1778)
						)
						(arc
							(start 0.1016 -0.1778)
							(mid 0.137521 -0.162921)
							(end 0.1524 -0.127)
						)
					)
					(width 0)
					(fill yes)
				)
			)
		)
		(pad "2" smd custom
			(at 0 0.2794 180)
			(size 0.0762 0.0762)
			(layers "B.Cu" "B.Mask" "B.Paste")
			(net "PCIE_SAS_CPU_RX_P0")
			(options
				(clearance outline)
				(anchor circle)
			)
			(primitives
				(gr_poly
					(pts
						(arc
							(start 0.1524 0.127)
							(mid 0.137521 0.162921)
							(end 0.1016 0.1778)
						)
						(arc
							(start -0.1016 0.1778)
							(mid -0.137521 0.162921)
							(end -0.1524 0.127)
						)
						(arc
							(start -0.1524 -0.127)
							(mid -0.137521 -0.162921)
							(end -0.1016 -0.1778)
						)
						(arc
							(start 0.1016 -0.1778)
							(mid 0.137521 -0.162921)
							(end 0.1524 -0.127)
						)
					)
					(width 0)
					(fill yes)
				)
			)
		)
	)
	(footprint ""
		(layer "B.Cu")
		(at 123.298966 -40.259 90)
		(property "Reference" "SC973"
			(at 0 0 90)
			(layer "B.SilkS")
			(hide yes)
			(effects
				(font
					(size 1.27 1.27)
				)
				(justify mirror)
			)
		)
		(property "Value" "SCD1U16V2KX-3GP"
			(at -1.1811 -2.7051 90)
			(unlocked yes)
			(layer "B.Fab")
			(hide yes)
			(effects
				(font
					(size 1.016 1.016)
					(thickness 0.1524)
				)
				(justify mirror)
			)
		)
		(property "Device Type" "C402H22"
			(at -1.1811 -4.2291 90)
			(unlocked yes)
			(layer "B.Fab")
			(hide yes)
			(effects
				(font
					(size 1.016 1.016)
					(thickness 0.1524)
				)
				(justify mirror)
			)
		)
		(duplicate_pad_numbers_are_jumpers no)
		(fp_rect
			(start 0.4318 0.9525)
			(end -0.4318 -0.9525)
			(stroke
				(width 0)
				(type default)
			)
			(fill no)
			(layer "B.CrtYd")
		)
		(fp_rect
			(start 0.4318 0.9525)
			(end -0.4318 -0.9525)
			(stroke
				(width 0)
				(type default)
			)
			(fill no)
			(layer "B.Fab")
		)
		(pad "1" smd custom
			(at 0 -0.4445 270)
			(size 0.1524 0.1524)
			(layers "B.Cu" "B.Mask" "B.Paste")
			(net "P1V8_C")
			(options
				(clearance outline)
				(anchor circle)
			)
			(primitives
				(gr_poly
					(pts
						(arc
							(start 0.3048 0.2032)
							(mid 0.275042 0.275042)
							(end 0.2032 0.3048)
						)
						(arc
							(start -0.2032 0.3048)
							(mid -0.275042 0.275042)
							(end -0.3048 0.2032)
						)
						(arc
							(start -0.3048 -0.2032)
							(mid -0.275042 -0.275042)
							(end -0.2032 -0.3048)
						)
						(arc
							(start 0.2032 -0.3048)
							(mid 0.275042 -0.275042)
							(end 0.3048 -0.2032)
						)
					)
					(width 0)
					(fill yes)
				)
			)
		)
		(pad "2" smd custom
			(at 0 0.4445 270)
			(size 0.1524 0.1524)
			(layers "B.Cu" "B.Mask" "B.Paste")
			(net "GND")
			(options
				(clearance outline)
				(anchor circle)
			)
			(primitives
				(gr_poly
					(pts
						(arc
							(start 0.3048 0.2032)
							(mid 0.275042 0.275042)
							(end 0.2032 0.3048)
						)
						(arc
							(start -0.2032 0.3048)
							(mid -0.275042 0.275042)
							(end -0.3048 0.2032)
						)
						(arc
							(start -0.3048 -0.2032)
							(mid -0.275042 -0.275042)
							(end -0.2032 -0.3048)
						)
						(arc
							(start 0.2032 -0.3048)
							(mid 0.275042 -0.275042)
							(end 0.3048 -0.2032)
						)
					)
					(width 0)
					(fill yes)
				)
			)
		)
	)
	(footprint ""
		(layer "B.Cu")
		(at 102.089966 -57.2262)
		(property "Reference" "STP58"
			(at 0 0 0)
			(layer "B.SilkS")
			(hide yes)
			(effects
				(font
					(size 1.27 1.27)
				)
				(justify mirror)
			)
		)
		(property "Value" "TPAD28"
			(at -0.0127 -1.8034 0)
			(unlocked yes)
			(layer "B.Fab")
			(hide yes)
			(effects
				(font
					(size 1.016 1.016)
					(thickness 0.1524)
				)
				(justify mirror)
			)
		)
		(property "Device Type" "TPAD28"
			(at -0.0127 -3.3274 0)
			(unlocked yes)
			(layer "B.Fab")
			(hide yes)
			(effects
				(font
					(size 1.016 1.016)
					(thickness 0.1524)
				)
				(justify mirror)
			)
		)
		(duplicate_pad_numbers_are_jumpers no)
		(fp_poly
			(pts
				(arc
					(start 0.3556 0)
					(mid -0.3556 0)
					(end 0.3556 0)
				)
			)
			(stroke
				(width 0)
				(type default)
			)
			(fill no)
			(layer "B.CrtYd")
		)
		(fp_poly
			(pts
				(arc
					(start 0.6096 0)
					(mid -0.6096 0)
					(end 0.6096 0)
				)
			)
			(stroke
				(width 0)
				(type default)
			)
			(fill no)
			(layer "B.Fab")
		)
		(pad "1" smd circle
			(at 0 0 180)
			(size 0.7112 0.7112)
			(layers "B.Cu" "B.Mask" "B.Paste")
			(net "JTAG_IOC_TCK")
		)
	)
	(footprint ""
		(layer "B.Cu")
		(at 91.821 -3.429)
		(property "Reference" "SC1050"
			(at 0 0 0)
			(layer "B.SilkS")
			(hide yes)
			(effects
				(font
					(size 1.27 1.27)
				)
				(justify mirror)
			)
		)
		(property "Value" "SCD1U16V2KX-3GP"
			(at -1.1811 -2.7051 0)
			(unlocked yes)
			(layer "B.Fab")
			(hide yes)
			(effects
				(font
					(size 1.016 1.016)
					(thickness 0.1524)
				)
				(justify mirror)
			)
		)
		(property "Device Type" "C402H22"
			(at -1.1811 -4.2291 0)
			(unlocked yes)
			(layer "B.Fab")
			(hide yes)
			(effects
				(font
					(size 1.016 1.016)
					(thickness 0.1524)
				)
				(justify mirror)
			)
		)
		(duplicate_pad_numbers_are_jumpers no)
		(fp_rect
			(start 0.4318 0.9525)
			(end -0.4318 -0.9525)
			(stroke
				(width 0)
				(type default)
			)
			(fill no)
			(layer "B.CrtYd")
		)
		(fp_rect
			(start 0.4318 0.9525)
			(end -0.4318 -0.9525)
			(stroke
				(width 0)
				(type default)
			)
			(fill no)
			(layer "B.Fab")
		)
		(pad "1" smd custom
			(at 0 -0.4445 180)
			(size 0.1524 0.1524)
			(layers "B.Cu" "B.Mask" "B.Paste")
			(net "P0V955_C")
			(options
				(clearance outline)
				(anchor circle)
			)
			(primitives
				(gr_poly
					(pts
						(arc
							(start 0.3048 0.2032)
							(mid 0.275042 0.275042)
							(end 0.2032 0.3048)
						)
						(arc
							(start -0.2032 0.3048)
							(mid -0.275042 0.275042)
							(end -0.3048 0.2032)
						)
						(arc
							(start -0.3048 -0.2032)
							(mid -0.275042 -0.275042)
							(end -0.2032 -0.3048)
						)
						(arc
							(start 0.2032 -0.3048)
							(mid 0.275042 -0.275042)
							(end 0.3048 -0.2032)
						)
					)
					(width 0)
					(fill yes)
				)
			)
		)
		(pad "2" smd custom
			(at 0 0.4445 180)
			(size 0.1524 0.1524)
			(layers "B.Cu" "B.Mask" "B.Paste")
			(net "GND")
			(options
				(clearance outline)
				(anchor circle)
			)
			(primitives
				(gr_poly
					(pts
						(arc
							(start 0.3048 0.2032)
							(mid 0.275042 0.275042)
							(end 0.2032 0.3048)
						)
						(arc
							(start -0.2032 0.3048)
							(mid -0.275042 0.275042)
							(end -0.3048 0.2032)
						)
						(arc
							(start -0.3048 -0.2032)
							(mid -0.275042 -0.275042)
							(end -0.2032 -0.3048)
						)
						(arc
							(start 0.2032 -0.3048)
							(mid 0.275042 -0.275042)
							(end 0.3048 -0.2032)
						)
					)
					(width 0)
					(fill yes)
				)
			)
		)
	)
	(footprint ""
		(layer "B.Cu")
		(at 121.544842 -82.698082 90)
		(property "Reference" "SC1152"
			(at 0 0 90)
			(layer "B.SilkS")
			(hide yes)
			(effects
				(font
					(size 1.27 1.27)
				)
				(justify mirror)
			)
		)
		(property "Value" "SC1U6D3V1MX-GP"
			(at -1.9177 2.0193 90)
			(unlocked yes)
			(layer "B.Fab")
			(hide yes)
			(effects
				(font
					(size 1.016 1.016)
					(thickness 0.1524)
				)
				(justify mirror)
			)
		)
		(property "Device Type" "C0201H14"
			(at -1.9177 0.4953 90)
			(unlocked yes)
			(layer "B.Fab")
			(hide yes)
			(effects
				(font
					(size 1.016 1.016)
					(thickness 0.1524)
				)
				(justify mirror)
			)
		)
		(duplicate_pad_numbers_are_jumpers no)
		(fp_rect
			(start 0.1524 0.3048)
			(end -0.1524 -0.3048)
			(stroke
				(width 0)
				(type default)
			)
			(fill no)
			(layer "B.CrtYd")
		)
		(fp_poly
			(pts
				(xy 0.2794 0.6477) (xy 0.2794 -0.6477) (xy -0.2794 -0.6477) (xy -0.2794 -0.1905) (xy -0.1524 -0.1905)
				(xy -0.1524 -0.3048) (xy 0.1524 -0.3048) (xy 0.1524 0.3048) (xy -0.1524 0.3048) (xy -0.1524 -0.1778)
				(xy -0.2794 -0.1778) (xy -0.2794 0.6477)
			)
			(stroke
				(width 0)
				(type default)
			)
			(fill no)
			(layer "B.CrtYd")
		)
		(fp_rect
			(start 0.2794 0.6477)
			(end -0.2794 -0.6477)
			(stroke
				(width 0)
				(type default)
			)
			(fill no)
			(layer "B.Fab")
		)
		(pad "1" smd custom
			(at 0 -0.2794 270)
			(size 0.0762 0.0762)
			(layers "B.Cu" "B.Mask" "B.Paste")
			(net "XTAL_VDDA18")
			(options
				(clearance outline)
				(anchor circle)
			)
			(primitives
				(gr_poly
					(pts
						(arc
							(start 0.1524 0.127)
							(mid 0.137521 0.162921)
							(end 0.1016 0.1778)
						)
						(arc
							(start -0.1016 0.1778)
							(mid -0.137521 0.162921)
							(end -0.1524 0.127)
						)
						(arc
							(start -0.1524 -0.127)
							(mid -0.137521 -0.162921)
							(end -0.1016 -0.1778)
						)
						(arc
							(start 0.1016 -0.1778)
							(mid 0.137521 -0.162921)
							(end 0.1524 -0.127)
						)
					)
					(width 0)
					(fill yes)
				)
			)
		)
		(pad "2" smd custom
			(at 0 0.2794 270)
			(size 0.0762 0.0762)
			(layers "B.Cu" "B.Mask" "B.Paste")
			(net "GND")
			(options
				(clearance outline)
				(anchor circle)
			)
			(primitives
				(gr_poly
					(pts
						(arc
							(start 0.1524 0.127)
							(mid 0.137521 0.162921)
							(end 0.1016 0.1778)
						)
						(arc
							(start -0.1016 0.1778)
							(mid -0.137521 0.162921)
							(end -0.1524 0.127)
						)
						(arc
							(start -0.1524 -0.127)
							(mid -0.137521 -0.162921)
							(end -0.1016 -0.1778)
						)
						(arc
							(start 0.1016 -0.1778)
							(mid 0.137521 -0.162921)
							(end 0.1524 -0.127)
						)
					)
					(width 0)
					(fill yes)
				)
			)
		)
	)
	(footprint ""
		(layer "B.Cu")
		(at 80.518 -21.209 180)
		(property "Reference" "PR185"
			(at 0 0 0)
			(layer "B.SilkS")
			(hide yes)
			(effects
				(font
					(size 1.27 1.27)
				)
				(justify mirror)
			)
		)
		(property "Value" "69K8R2F-GP"
			(at -0.064008 -3.993896 180)
			(unlocked yes)
			(layer "B.Fab")
			(hide yes)
			(effects
				(font
					(size 1.016 1.016)
					(thickness 0.1524)
				)
				(justify mirror)
			)
		)
		(property "Device Type" "R402H16"
			(at -0.064008 -5.517896 180)
			(unlocked yes)
			(layer "B.Fab")
			(hide yes)
			(effects
				(font
					(size 1.016 1.016)
					(thickness 0.1524)
				)
				(justify mirror)
			)
		)
		(duplicate_pad_numbers_are_jumpers no)
		(fp_line
			(start 0.508 -0.9398)
			(end 0.508 0.9398)
			(stroke
				(width 0.1524)
				(type default)
			)
			(layer "B.SilkS")
		)
		(fp_line
			(start -0.508 -0.9398)
			(end 0.508 -0.9398)
			(stroke
				(width 0.1524)
				(type default)
			)
			(layer "B.SilkS")
		)
		(fp_rect
			(start 0.508 0.9398)
			(end -0.508 -0.9398)
			(stroke
				(width 0)
				(type default)
			)
			(fill no)
			(layer "B.CrtYd")
		)
		(fp_rect
			(start 0.508 0.9398)
			(end -0.508 -0.9398)
			(stroke
				(width 0)
				(type default)
			)
			(fill no)
			(layer "B.Fab")
		)
		(pad "1" smd custom
			(at 0 -0.4445)
			(size 0.1397 0.1397)
			(layers "B.Cu" "B.Mask" "B.Paste")
			(net "AGND_P0V9_C")
			(options
				(clearance outline)
				(anchor circle)
			)
			(primitives
				(gr_poly
					(pts
						(arc
							(start -0.1778 0.2794)
							(mid -0.249642 0.249642)
							(end -0.2794 0.1778)
						)
						(arc
							(start -0.2794 -0.1778)
							(mid -0.249642 -0.249642)
							(end -0.1778 -0.2794)
						)
						(arc
							(start 0.1778 -0.2794)
							(mid 0.249642 -0.249642)
							(end 0.2794 -0.1778)
						)
						(arc
							(start 0.2794 0.1778)
							(mid 0.249642 0.249642)
							(end 0.1778 0.2794)
						)
					)
					(width 0)
					(fill yes)
				)
			)
		)
		(pad "2" smd custom
			(at 0 0.4445)
			(size 0.1397 0.1397)
			(layers "B.Cu" "B.Mask" "B.Paste")
			(net "VT235_IRIP")
			(options
				(clearance outline)
				(anchor circle)
			)
			(primitives
				(gr_poly
					(pts
						(arc
							(start -0.1778 0.2794)
							(mid -0.249642 0.249642)
							(end -0.2794 0.1778)
						)
						(arc
							(start -0.2794 -0.1778)
							(mid -0.249642 -0.249642)
							(end -0.1778 -0.2794)
						)
						(arc
							(start 0.1778 -0.2794)
							(mid 0.249642 -0.249642)
							(end 0.2794 -0.1778)
						)
						(arc
							(start 0.2794 0.1778)
							(mid 0.249642 0.249642)
							(end 0.1778 0.2794)
						)
					)
					(width 0)
					(fill yes)
				)
			)
		)
	)
	(footprint ""
		(layer "B.Cu")
		(at 133.585966 -31.623 90)
		(property "Reference" "SR655"
			(at 0 0 90)
			(layer "B.SilkS")
			(hide yes)
			(effects
				(font
					(size 1.27 1.27)
				)
				(justify mirror)
			)
		)
		(property "Value" "4K7R2F-GP"
			(at -0.064008 -3.993896 90)
			(unlocked yes)
			(layer "B.Fab")
			(hide yes)
			(effects
				(font
					(size 1.016 1.016)
					(thickness 0.1524)
				)
				(justify mirror)
			)
		)
		(property "Device Type" "R402H16"
			(at -0.064008 -5.517896 90)
			(unlocked yes)
			(layer "B.Fab")
			(hide yes)
			(effects
				(font
					(size 1.016 1.016)
					(thickness 0.1524)
				)
				(justify mirror)
			)
		)
		(duplicate_pad_numbers_are_jumpers no)
		(fp_line
			(start 0.508 -0.9398)
			(end 0.508 0.9398)
			(stroke
				(width 0.1524)
				(type default)
			)
			(layer "B.SilkS")
		)
		(fp_line
			(start -0.508 -0.9398)
			(end 0.508 -0.9398)
			(stroke
				(width 0.1524)
				(type default)
			)
			(layer "B.SilkS")
		)
		(fp_rect
			(start 0.508 0.9398)
			(end -0.508 -0.9398)
			(stroke
				(width 0)
				(type default)
			)
			(fill no)
			(layer "B.CrtYd")
		)
		(fp_rect
			(start 0.508 0.9398)
			(end -0.508 -0.9398)
			(stroke
				(width 0)
				(type default)
			)
			(fill no)
			(layer "B.Fab")
		)
		(pad "1" smd custom
			(at 0 -0.4445 270)
			(size 0.1397 0.1397)
			(layers "B.Cu" "B.Mask" "B.Paste")
			(net "P3V3_STBY")
			(options
				(clearance outline)
				(anchor circle)
			)
			(primitives
				(gr_poly
					(pts
						(arc
							(start -0.1778 0.2794)
							(mid -0.249642 0.249642)
							(end -0.2794 0.1778)
						)
						(arc
							(start -0.2794 -0.1778)
							(mid -0.249642 -0.249642)
							(end -0.1778 -0.2794)
						)
						(arc
							(start 0.1778 -0.2794)
							(mid 0.249642 -0.249642)
							(end 0.2794 -0.1778)
						)
						(arc
							(start 0.2794 0.1778)
							(mid 0.249642 0.249642)
							(end 0.1778 0.2794)
						)
					)
					(width 0)
					(fill yes)
				)
			)
		)
		(pad "2" smd custom
			(at 0 0.4445 270)
			(size 0.1397 0.1397)
			(layers "B.Cu" "B.Mask" "B.Paste")
			(net "P3V3_STBY_R")
			(options
				(clearance outline)
				(anchor circle)
			)
			(primitives
				(gr_poly
					(pts
						(arc
							(start -0.1778 0.2794)
							(mid -0.249642 0.249642)
							(end -0.2794 0.1778)
						)
						(arc
							(start -0.2794 -0.1778)
							(mid -0.249642 -0.249642)
							(end -0.1778 -0.2794)
						)
						(arc
							(start 0.1778 -0.2794)
							(mid 0.249642 -0.249642)
							(end 0.2794 -0.1778)
						)
						(arc
							(start 0.2794 0.1778)
							(mid 0.249642 0.249642)
							(end 0.1778 0.2794)
						)
					)
					(width 0)
					(fill yes)
				)
			)
		)
	)
	(footprint ""
		(layer "B.Cu")
		(at 345.080336 -71.797672 180)
		(property "Reference" "R267"
			(at 0 0 0)
			(layer "B.SilkS")
			(hide yes)
			(effects
				(font
					(size 1.27 1.27)
				)
				(justify mirror)
			)
		)
		(property "Value" "2K2R2J-2-GP"
			(at -0.064008 -3.993896 180)
			(unlocked yes)
			(layer "B.Fab")
			(hide yes)
			(effects
				(font
					(size 1.016 1.016)
					(thickness 0.1524)
				)
				(justify mirror)
			)
		)
		(property "Device Type" "R402H16"
			(at -0.064008 -5.517896 180)
			(unlocked yes)
			(layer "B.Fab")
			(hide yes)
			(effects
				(font
					(size 1.016 1.016)
					(thickness 0.1524)
				)
				(justify mirror)
			)
		)
		(duplicate_pad_numbers_are_jumpers no)
		(fp_line
			(start 0.508 -0.9398)
			(end 0.508 0.9398)
			(stroke
				(width 0.1524)
				(type default)
			)
			(layer "B.SilkS")
		)
		(fp_line
			(start -0.508 -0.9398)
			(end 0.508 -0.9398)
			(stroke
				(width 0.1524)
				(type default)
			)
			(layer "B.SilkS")
		)
		(fp_rect
			(start 0.508 0.9398)
			(end -0.508 -0.9398)
			(stroke
				(width 0)
				(type default)
			)
			(fill no)
			(layer "B.CrtYd")
		)
		(fp_rect
			(start 0.508 0.9398)
			(end -0.508 -0.9398)
			(stroke
				(width 0)
				(type default)
			)
			(fill no)
			(layer "B.Fab")
		)
		(pad "1" smd custom
			(at 0 -0.4445)
			(size 0.1397 0.1397)
			(layers "B.Cu" "B.Mask" "B.Paste")
			(net "FLA_WPN")
			(options
				(clearance outline)
				(anchor circle)
			)
			(primitives
				(gr_poly
					(pts
						(arc
							(start -0.1778 0.2794)
							(mid -0.249642 0.249642)
							(end -0.2794 0.1778)
						)
						(arc
							(start -0.2794 -0.1778)
							(mid -0.249642 -0.249642)
							(end -0.1778 -0.2794)
						)
						(arc
							(start 0.1778 -0.2794)
							(mid 0.249642 -0.249642)
							(end 0.2794 -0.1778)
						)
						(arc
							(start 0.2794 0.1778)
							(mid 0.249642 0.249642)
							(end 0.1778 0.2794)
						)
					)
					(width 0)
					(fill yes)
				)
			)
		)
		(pad "2" smd custom
			(at 0 0.4445)
			(size 0.1397 0.1397)
			(layers "B.Cu" "B.Mask" "B.Paste")
			(net "GND")
			(options
				(clearance outline)
				(anchor circle)
			)
			(primitives
				(gr_poly
					(pts
						(arc
							(start -0.1778 0.2794)
							(mid -0.249642 0.249642)
							(end -0.2794 0.1778)
						)
						(arc
							(start -0.2794 -0.1778)
							(mid -0.249642 -0.249642)
							(end -0.1778 -0.2794)
						)
						(arc
							(start 0.1778 -0.2794)
							(mid 0.249642 -0.249642)
							(end 0.2794 -0.1778)
						)
						(arc
							(start 0.2794 0.1778)
							(mid 0.249642 0.249642)
							(end 0.1778 0.2794)
						)
					)
					(width 0)
					(fill yes)
				)
			)
		)
	)
	(footprint ""
		(layer "B.Cu")
		(at 30.811216 -202.36688 -90)
		(property "Reference" "C323"
			(at 0 0 90)
			(layer "B.SilkS")
			(hide yes)
			(effects
				(font
					(size 1.27 1.27)
				)
				(justify mirror)
			)
		)
		(property "Value" "SCD1U16V2KX-3GP"
			(at -1.1811 -2.7051 270)
			(unlocked yes)
			(layer "B.Fab")
			(hide yes)
			(effects
				(font
					(size 1.016 1.016)
					(thickness 0.1524)
				)
				(justify mirror)
			)
		)
		(property "Device Type" "C402H22"
			(at -1.1811 -4.2291 270)
			(unlocked yes)
			(layer "B.Fab")
			(hide yes)
			(effects
				(font
					(size 1.016 1.016)
					(thickness 0.1524)
				)
				(justify mirror)
			)
		)
		(duplicate_pad_numbers_are_jumpers no)
		(fp_rect
			(start 0.4318 0.9525)
			(end -0.4318 -0.9525)
			(stroke
				(width 0)
				(type default)
			)
			(fill no)
			(layer "B.CrtYd")
		)
		(fp_rect
			(start 0.4318 0.9525)
			(end -0.4318 -0.9525)
			(stroke
				(width 0)
				(type default)
			)
			(fill no)
			(layer "B.Fab")
		)
		(pad "1" smd custom
			(at 0 -0.4445 90)
			(size 0.1524 0.1524)
			(layers "B.Cu" "B.Mask" "B.Paste")
			(net "P3V3_STBY")
			(options
				(clearance outline)
				(anchor circle)
			)
			(primitives
				(gr_poly
					(pts
						(arc
							(start 0.3048 0.2032)
							(mid 0.275042 0.275042)
							(end 0.2032 0.3048)
						)
						(arc
							(start -0.2032 0.3048)
							(mid -0.275042 0.275042)
							(end -0.3048 0.2032)
						)
						(arc
							(start -0.3048 -0.2032)
							(mid -0.275042 -0.275042)
							(end -0.2032 -0.3048)
						)
						(arc
							(start 0.2032 -0.3048)
							(mid 0.275042 -0.275042)
							(end 0.3048 -0.2032)
						)
					)
					(width 0)
					(fill yes)
				)
			)
		)
		(pad "2" smd custom
			(at 0 0.4445 90)
			(size 0.1524 0.1524)
			(layers "B.Cu" "B.Mask" "B.Paste")
			(net "GND")
			(options
				(clearance outline)
				(anchor circle)
			)
			(primitives
				(gr_poly
					(pts
						(arc
							(start 0.3048 0.2032)
							(mid 0.275042 0.275042)
							(end 0.2032 0.3048)
						)
						(arc
							(start -0.2032 0.3048)
							(mid -0.275042 0.275042)
							(end -0.3048 0.2032)
						)
						(arc
							(start -0.3048 -0.2032)
							(mid -0.275042 -0.275042)
							(end -0.2032 -0.3048)
						)
						(arc
							(start 0.2032 -0.3048)
							(mid 0.275042 -0.275042)
							(end 0.3048 -0.2032)
						)
					)
					(width 0)
					(fill yes)
				)
			)
		)
	)
	(footprint ""
		(layer "B.Cu")
		(at 107.195366 -41.91 90)
		(property "Reference" "SC1052"
			(at 0 0 90)
			(layer "B.SilkS")
			(hide yes)
			(effects
				(font
					(size 1.27 1.27)
				)
				(justify mirror)
			)
		)
		(property "Value" "SCD1U16V2KX-3GP"
			(at -1.1811 -2.7051 90)
			(unlocked yes)
			(layer "B.Fab")
			(hide yes)
			(effects
				(font
					(size 1.016 1.016)
					(thickness 0.1524)
				)
				(justify mirror)
			)
		)
		(property "Device Type" "C402H22"
			(at -1.1811 -4.2291 90)
			(unlocked yes)
			(layer "B.Fab")
			(hide yes)
			(effects
				(font
					(size 1.016 1.016)
					(thickness 0.1524)
				)
				(justify mirror)
			)
		)
		(duplicate_pad_numbers_are_jumpers no)
		(fp_rect
			(start 0.4318 0.9525)
			(end -0.4318 -0.9525)
			(stroke
				(width 0)
				(type default)
			)
			(fill no)
			(layer "B.CrtYd")
		)
		(fp_rect
			(start 0.4318 0.9525)
			(end -0.4318 -0.9525)
			(stroke
				(width 0)
				(type default)
			)
			(fill no)
			(layer "B.Fab")
		)
		(pad "1" smd custom
			(at 0 -0.4445 270)
			(size 0.1524 0.1524)
			(layers "B.Cu" "B.Mask" "B.Paste")
			(net "P0V955_C")
			(options
				(clearance outline)
				(anchor circle)
			)
			(primitives
				(gr_poly
					(pts
						(arc
							(start 0.3048 0.2032)
							(mid 0.275042 0.275042)
							(end 0.2032 0.3048)
						)
						(arc
							(start -0.2032 0.3048)
							(mid -0.275042 0.275042)
							(end -0.3048 0.2032)
						)
						(arc
							(start -0.3048 -0.2032)
							(mid -0.275042 -0.275042)
							(end -0.2032 -0.3048)
						)
						(arc
							(start 0.2032 -0.3048)
							(mid 0.275042 -0.275042)
							(end 0.3048 -0.2032)
						)
					)
					(width 0)
					(fill yes)
				)
			)
		)
		(pad "2" smd custom
			(at 0 0.4445 270)
			(size 0.1524 0.1524)
			(layers "B.Cu" "B.Mask" "B.Paste")
			(net "GND")
			(options
				(clearance outline)
				(anchor circle)
			)
			(primitives
				(gr_poly
					(pts
						(arc
							(start 0.3048 0.2032)
							(mid 0.275042 0.275042)
							(end 0.2032 0.3048)
						)
						(arc
							(start -0.2032 0.3048)
							(mid -0.275042 0.275042)
							(end -0.3048 0.2032)
						)
						(arc
							(start -0.3048 -0.2032)
							(mid -0.275042 -0.275042)
							(end -0.2032 -0.3048)
						)
						(arc
							(start 0.2032 -0.3048)
							(mid 0.275042 -0.275042)
							(end 0.3048 -0.2032)
						)
					)
					(width 0)
					(fill yes)
				)
			)
		)
	)
	(footprint ""
		(layer "B.Cu")
		(at 310.896 -183.515 -90)
		(property "Reference" "SR944"
			(at 0 0 90)
			(layer "B.SilkS")
			(hide yes)
			(effects
				(font
					(size 1.27 1.27)
				)
				(justify mirror)
			)
		)
		(property "Value" "4K75R2F-1-GP"
			(at -0.064008 -3.993896 270)
			(unlocked yes)
			(layer "B.Fab")
			(hide yes)
			(effects
				(font
					(size 1.016 1.016)
					(thickness 0.1524)
				)
				(justify mirror)
			)
		)
		(property "Device Type" "R402H16"
			(at -0.064008 -5.517896 270)
			(unlocked yes)
			(layer "B.Fab")
			(hide yes)
			(effects
				(font
					(size 1.016 1.016)
					(thickness 0.1524)
				)
				(justify mirror)
			)
		)
		(duplicate_pad_numbers_are_jumpers no)
		(fp_line
			(start -0.508 -0.9398)
			(end 0.508 -0.9398)
			(stroke
				(width 0.1524)
				(type default)
			)
			(layer "B.SilkS")
		)
		(fp_line
			(start 0.508 -0.9398)
			(end 0.508 0.9398)
			(stroke
				(width 0.1524)
				(type default)
			)
			(layer "B.SilkS")
		)
		(fp_rect
			(start 0.508 0.9398)
			(end -0.508 -0.9398)
			(stroke
				(width 0)
				(type default)
			)
			(fill no)
			(layer "B.CrtYd")
		)
		(fp_rect
			(start 0.508 0.9398)
			(end -0.508 -0.9398)
			(stroke
				(width 0)
				(type default)
			)
			(fill no)
			(layer "B.Fab")
		)
		(pad "1" smd custom
			(at 0 -0.4445 90)
			(size 0.1397 0.1397)
			(layers "B.Cu" "B.Mask" "B.Paste")
			(net "P3V3_STBY")
			(options
				(clearance outline)
				(anchor circle)
			)
			(primitives
				(gr_poly
					(pts
						(arc
							(start -0.1778 0.2794)
							(mid -0.249642 0.249642)
							(end -0.2794 0.1778)
						)
						(arc
							(start -0.2794 -0.1778)
							(mid -0.249642 -0.249642)
							(end -0.1778 -0.2794)
						)
						(arc
							(start 0.1778 -0.2794)
							(mid 0.249642 -0.249642)
							(end 0.2794 -0.1778)
						)
						(arc
							(start 0.2794 0.1778)
							(mid 0.249642 0.249642)
							(end 0.1778 0.2794)
						)
					)
					(width 0)
					(fill yes)
				)
			)
		)
		(pad "2" smd custom
			(at 0 0.4445 90)
			(size 0.1397 0.1397)
			(layers "B.Cu" "B.Mask" "B.Paste")
			(net "BMC_FW_DET_BOARD_VER_0")
			(options
				(clearance outline)
				(anchor circle)
			)
			(primitives
				(gr_poly
					(pts
						(arc
							(start -0.1778 0.2794)
							(mid -0.249642 0.249642)
							(end -0.2794 0.1778)
						)
						(arc
							(start -0.2794 -0.1778)
							(mid -0.249642 -0.249642)
							(end -0.1778 -0.2794)
						)
						(arc
							(start 0.1778 -0.2794)
							(mid 0.249642 -0.249642)
							(end 0.2794 -0.1778)
						)
						(arc
							(start 0.2794 0.1778)
							(mid 0.249642 0.249642)
							(end 0.1778 0.2794)
						)
					)
					(width 0)
					(fill yes)
				)
			)
		)
	)
	(footprint ""
		(layer "B.Cu")
		(at 124.530612 -222.377 -90)
		(property "Reference" "SR870"
			(at 0 0 90)
			(layer "B.SilkS")
			(hide yes)
			(effects
				(font
					(size 1.27 1.27)
				)
				(justify mirror)
			)
		)
		(property "Value" "0R5J-5-GP"
			(at 0 -8.9535 270)
			(unlocked yes)
			(layer "B.Fab")
			(hide yes)
			(effects
				(font
					(size 1.27 1.016)
					(thickness 0.1524)
				)
				(justify mirror)
			)
		)
		(property "Device Type" "R805H24"
			(at 0 -10.6299 270)
			(unlocked yes)
			(layer "B.Fab")
			(hide yes)
			(effects
				(font
					(size 1.27 1.016)
					(thickness 0.1524)
				)
				(justify mirror)
			)
		)
		(duplicate_pad_numbers_are_jumpers no)
		(fp_line
			(start -0.889 1.7018)
			(end -0.889 -0.508)
			(stroke
				(width 0.1524)
				(type default)
			)
			(layer "B.SilkS")
		)
		(fp_line
			(start 0.889 1.7018)
			(end -0.889 1.7018)
			(stroke
				(width 0.1524)
				(type default)
			)
			(layer "B.SilkS")
		)
		(fp_line
			(start 0.889 0.0762)
			(end 0.889 1.7018)
			(stroke
				(width 0.1524)
				(type default)
			)
			(layer "B.SilkS")
		)
		(fp_line
			(start -0.889 -1.7018)
			(end -0.889 -0.381)
			(stroke
				(width 0.1524)
				(type default)
			)
			(layer "B.SilkS")
		)
		(fp_line
			(start -0.889 -1.7018)
			(end 0.889 -1.7018)
			(stroke
				(width 0.1524)
				(type default)
			)
			(layer "B.SilkS")
		)
		(fp_line
			(start 0.889 -1.7018)
			(end 0.889 0.2794)
			(stroke
				(width 0.1524)
				(type default)
			)
			(layer "B.SilkS")
		)
		(fp_poly
			(pts
				(xy -0.9652 -1.778) (xy -0.9652 1.778) (xy 0.9652 1.778) (xy 0.9652 -1.778)
			)
			(stroke
				(width 0)
				(type default)
			)
			(fill no)
			(layer "B.CrtYd")
		)
		(fp_rect
			(start 0.9652 1.778)
			(end -0.9652 -1.778)
			(stroke
				(width 0)
				(type default)
			)
			(fill no)
			(layer "B.Fab")
		)
		(pad "1" smd rect
			(at 0 -0.9652 90)
			(size 1.397 1.143)
			(layers "B.Cu" "B.Mask" "B.Paste")
			(net "P1V26_STBY")
		)
		(pad "2" smd rect
			(at 0 0.9652 90)
			(size 1.397 1.143)
			(layers "B.Cu" "B.Mask" "B.Paste")
			(net "1.2V_REDV")
		)
	)
	(footprint ""
		(layer "B.Cu")
		(at 106.103166 -36.957)
		(property "Reference" "STP53"
			(at 0 0 0)
			(layer "B.SilkS")
			(hide yes)
			(effects
				(font
					(size 1.27 1.27)
				)
				(justify mirror)
			)
		)
		(property "Value" "TPAD28"
			(at -0.0127 -1.8034 0)
			(unlocked yes)
			(layer "B.Fab")
			(hide yes)
			(effects
				(font
					(size 1.016 1.016)
					(thickness 0.1524)
				)
				(justify mirror)
			)
		)
		(property "Device Type" "TPAD28"
			(at -0.0127 -3.3274 0)
			(unlocked yes)
			(layer "B.Fab")
			(hide yes)
			(effects
				(font
					(size 1.016 1.016)
					(thickness 0.1524)
				)
				(justify mirror)
			)
		)
		(duplicate_pad_numbers_are_jumpers no)
		(fp_poly
			(pts
				(arc
					(start 0.3556 0)
					(mid -0.3556 0)
					(end 0.3556 0)
				)
			)
			(stroke
				(width 0)
				(type default)
			)
			(fill no)
			(layer "B.CrtYd")
		)
		(fp_poly
			(pts
				(arc
					(start 0.6096 0)
					(mid -0.6096 0)
					(end 0.6096 0)
				)
			)
			(stroke
				(width 0)
				(type default)
			)
			(fill no)
			(layer "B.Fab")
		)
		(pad "1" smd circle
			(at 0 0 180)
			(size 0.7112 0.7112)
			(layers "B.Cu" "B.Mask" "B.Paste")
			(net "SPARE3")
		)
	)
	(footprint ""
		(layer "B.Cu")
		(at 274.193 -171.577 90)
		(property "Reference" "R306"
			(at 0 0 90)
			(layer "B.SilkS")
			(hide yes)
			(effects
				(font
					(size 1.27 1.27)
				)
				(justify mirror)
			)
		)
		(property "Value" "10KR2F-2-GP"
			(at -0.064008 -3.993896 90)
			(unlocked yes)
			(layer "B.Fab")
			(hide yes)
			(effects
				(font
					(size 1.016 1.016)
					(thickness 0.1524)
				)
				(justify mirror)
			)
		)
		(property "Device Type" "R402H16"
			(at -0.064008 -5.517896 90)
			(unlocked yes)
			(layer "B.Fab")
			(hide yes)
			(effects
				(font
					(size 1.016 1.016)
					(thickness 0.1524)
				)
				(justify mirror)
			)
		)
		(duplicate_pad_numbers_are_jumpers no)
		(fp_line
			(start 0.508 -0.9398)
			(end 0.508 0.9398)
			(stroke
				(width 0.1524)
				(type default)
			)
			(layer "B.SilkS")
		)
		(fp_line
			(start -0.508 -0.9398)
			(end 0.508 -0.9398)
			(stroke
				(width 0.1524)
				(type default)
			)
			(layer "B.SilkS")
		)
		(fp_rect
			(start 0.508 0.9398)
			(end -0.508 -0.9398)
			(stroke
				(width 0)
				(type default)
			)
			(fill no)
			(layer "B.CrtYd")
		)
		(fp_rect
			(start 0.508 0.9398)
			(end -0.508 -0.9398)
			(stroke
				(width 0)
				(type default)
			)
			(fill no)
			(layer "B.Fab")
		)
		(pad "1" smd custom
			(at 0 -0.4445 270)
			(size 0.1397 0.1397)
			(layers "B.Cu" "B.Mask" "B.Paste")
			(net "P3V3_STBY")
			(options
				(clearance outline)
				(anchor circle)
			)
			(primitives
				(gr_poly
					(pts
						(arc
							(start -0.1778 0.2794)
							(mid -0.249642 0.249642)
							(end -0.2794 0.1778)
						)
						(arc
							(start -0.2794 -0.1778)
							(mid -0.249642 -0.249642)
							(end -0.1778 -0.2794)
						)
						(arc
							(start 0.1778 -0.2794)
							(mid 0.249642 -0.249642)
							(end 0.2794 -0.1778)
						)
						(arc
							(start 0.2794 0.1778)
							(mid 0.249642 0.249642)
							(end 0.1778 0.2794)
						)
					)
					(width 0)
					(fill yes)
				)
			)
		)
		(pad "2" smd custom
			(at 0 0.4445 270)
			(size 0.1397 0.1397)
			(layers "B.Cu" "B.Mask" "B.Paste")
			(net "BMC_10G_SDA_2")
			(options
				(clearance outline)
				(anchor circle)
			)
			(primitives
				(gr_poly
					(pts
						(arc
							(start -0.1778 0.2794)
							(mid -0.249642 0.249642)
							(end -0.2794 0.1778)
						)
						(arc
							(start -0.2794 -0.1778)
							(mid -0.249642 -0.249642)
							(end -0.1778 -0.2794)
						)
						(arc
							(start 0.1778 -0.2794)
							(mid 0.249642 -0.249642)
							(end 0.2794 -0.1778)
						)
						(arc
							(start 0.2794 0.1778)
							(mid 0.249642 0.249642)
							(end 0.1778 0.2794)
						)
					)
					(width 0)
					(fill yes)
				)
			)
		)
	)
	(footprint ""
		(layer "B.Cu")
		(at 276.733 -166.37 90)
		(property "Reference" "R540"
			(at 0 0 90)
			(layer "B.SilkS")
			(hide yes)
			(effects
				(font
					(size 1.27 1.27)
				)
				(justify mirror)
			)
		)
		(property "Value" "0R2J-2-GP"
			(at -0.064008 -3.993896 90)
			(unlocked yes)
			(layer "B.Fab")
			(hide yes)
			(effects
				(font
					(size 1.016 1.016)
					(thickness 0.1524)
				)
				(justify mirror)
			)
		)
		(property "Device Type" "R402H16"
			(at -0.064008 -5.517896 90)
			(unlocked yes)
			(layer "B.Fab")
			(hide yes)
			(effects
				(font
					(size 1.016 1.016)
					(thickness 0.1524)
				)
				(justify mirror)
			)
		)
		(duplicate_pad_numbers_are_jumpers no)
		(fp_line
			(start 0.508 -0.9398)
			(end 0.508 0.9398)
			(stroke
				(width 0.1524)
				(type default)
			)
			(layer "B.SilkS")
		)
		(fp_line
			(start -0.508 -0.9398)
			(end 0.508 -0.9398)
			(stroke
				(width 0.1524)
				(type default)
			)
			(layer "B.SilkS")
		)
		(fp_rect
			(start 0.508 0.9398)
			(end -0.508 -0.9398)
			(stroke
				(width 0)
				(type default)
			)
			(fill no)
			(layer "B.CrtYd")
		)
		(fp_rect
			(start 0.508 0.9398)
			(end -0.508 -0.9398)
			(stroke
				(width 0)
				(type default)
			)
			(fill no)
			(layer "B.Fab")
		)
		(pad "1" smd custom
			(at 0 -0.4445 270)
			(size 0.1397 0.1397)
			(layers "B.Cu" "B.Mask" "B.Paste")
			(net "BMC_1V8_C_EN")
			(options
				(clearance outline)
				(anchor circle)
			)
			(primitives
				(gr_poly
					(pts
						(arc
							(start -0.1778 0.2794)
							(mid -0.249642 0.249642)
							(end -0.2794 0.1778)
						)
						(arc
							(start -0.2794 -0.1778)
							(mid -0.249642 -0.249642)
							(end -0.1778 -0.2794)
						)
						(arc
							(start 0.1778 -0.2794)
							(mid 0.249642 -0.249642)
							(end 0.2794 -0.1778)
						)
						(arc
							(start 0.2794 0.1778)
							(mid 0.249642 0.249642)
							(end 0.1778 0.2794)
						)
					)
					(width 0)
					(fill yes)
				)
			)
		)
		(pad "2" smd custom
			(at 0 0.4445 270)
			(size 0.1397 0.1397)
			(layers "B.Cu" "B.Mask" "B.Paste")
			(net "BMC_1V8_C_EN_R")
			(options
				(clearance outline)
				(anchor circle)
			)
			(primitives
				(gr_poly
					(pts
						(arc
							(start -0.1778 0.2794)
							(mid -0.249642 0.249642)
							(end -0.2794 0.1778)
						)
						(arc
							(start -0.2794 -0.1778)
							(mid -0.249642 -0.249642)
							(end -0.1778 -0.2794)
						)
						(arc
							(start 0.1778 -0.2794)
							(mid 0.249642 -0.249642)
							(end 0.2794 -0.1778)
						)
						(arc
							(start 0.2794 0.1778)
							(mid 0.249642 0.249642)
							(end 0.1778 0.2794)
						)
					)
					(width 0)
					(fill yes)
				)
			)
		)
	)
	(footprint ""
		(layer "B.Cu")
		(at 310.896 -184.658 90)
		(property "Reference" "R313"
			(at 0 0 90)
			(layer "B.SilkS")
			(hide yes)
			(effects
				(font
					(size 1.27 1.27)
				)
				(justify mirror)
			)
		)
		(property "Value" "0R2J-2-GP"
			(at -0.064008 -3.993896 90)
			(unlocked yes)
			(layer "B.Fab")
			(hide yes)
			(effects
				(font
					(size 1.016 1.016)
					(thickness 0.1524)
				)
				(justify mirror)
			)
		)
		(property "Device Type" "R402H16"
			(at -0.064008 -5.517896 90)
			(unlocked yes)
			(layer "B.Fab")
			(hide yes)
			(effects
				(font
					(size 1.016 1.016)
					(thickness 0.1524)
				)
				(justify mirror)
			)
		)
		(duplicate_pad_numbers_are_jumpers no)
		(fp_line
			(start 0.508 -0.9398)
			(end 0.508 0.9398)
			(stroke
				(width 0.1524)
				(type default)
			)
			(layer "B.SilkS")
		)
		(fp_line
			(start -0.508 -0.9398)
			(end 0.508 -0.9398)
			(stroke
				(width 0.1524)
				(type default)
			)
			(layer "B.SilkS")
		)
		(fp_rect
			(start 0.508 0.9398)
			(end -0.508 -0.9398)
			(stroke
				(width 0)
				(type default)
			)
			(fill no)
			(layer "B.CrtYd")
		)
		(fp_rect
			(start 0.508 0.9398)
			(end -0.508 -0.9398)
			(stroke
				(width 0)
				(type default)
			)
			(fill no)
			(layer "B.Fab")
		)
		(pad "1" smd custom
			(at 0 -0.4445 270)
			(size 0.1397 0.1397)
			(layers "B.Cu" "B.Mask" "B.Paste")
			(net "BMC0_I2C_IO_EXP_RESET#")
			(options
				(clearance outline)
				(anchor circle)
			)
			(primitives
				(gr_poly
					(pts
						(arc
							(start -0.1778 0.2794)
							(mid -0.249642 0.249642)
							(end -0.2794 0.1778)
						)
						(arc
							(start -0.2794 -0.1778)
							(mid -0.249642 -0.249642)
							(end -0.1778 -0.2794)
						)
						(arc
							(start 0.1778 -0.2794)
							(mid 0.249642 -0.249642)
							(end 0.2794 -0.1778)
						)
						(arc
							(start 0.2794 0.1778)
							(mid 0.249642 0.249642)
							(end 0.1778 0.2794)
						)
					)
					(width 0)
					(fill yes)
				)
			)
		)
		(pad "2" smd custom
			(at 0 0.4445 270)
			(size 0.1397 0.1397)
			(layers "B.Cu" "B.Mask" "B.Paste")
			(net "I2C_IO_EXP_RESET#")
			(options
				(clearance outline)
				(anchor circle)
			)
			(primitives
				(gr_poly
					(pts
						(arc
							(start -0.1778 0.2794)
							(mid -0.249642 0.249642)
							(end -0.2794 0.1778)
						)
						(arc
							(start -0.2794 -0.1778)
							(mid -0.249642 -0.249642)
							(end -0.1778 -0.2794)
						)
						(arc
							(start 0.1778 -0.2794)
							(mid 0.249642 -0.249642)
							(end 0.2794 -0.1778)
						)
						(arc
							(start 0.2794 0.1778)
							(mid 0.249642 0.249642)
							(end 0.1778 0.2794)
						)
					)
					(width 0)
					(fill yes)
				)
			)
		)
	)
	(footprint ""
		(layer "B.Cu")
		(at 11.05408 -231.822752)
		(property "Reference" "R512"
			(at 0 0 0)
			(layer "B.SilkS")
			(hide yes)
			(effects
				(font
					(size 1.27 1.27)
				)
				(justify mirror)
			)
		)
		(property "Value" "0R2J-2-GP"
			(at -0.064008 -3.993896 0)
			(unlocked yes)
			(layer "B.Fab")
			(hide yes)
			(effects
				(font
					(size 1.016 1.016)
					(thickness 0.1524)
				)
				(justify mirror)
			)
		)
		(property "Device Type" "R402H16"
			(at -0.064008 -5.517896 0)
			(unlocked yes)
			(layer "B.Fab")
			(hide yes)
			(effects
				(font
					(size 1.016 1.016)
					(thickness 0.1524)
				)
				(justify mirror)
			)
		)
		(duplicate_pad_numbers_are_jumpers no)
		(fp_line
			(start -0.508 -0.9398)
			(end 0.508 -0.9398)
			(stroke
				(width 0.1524)
				(type default)
			)
			(layer "B.SilkS")
		)
		(fp_line
			(start 0.508 -0.9398)
			(end 0.508 0.9398)
			(stroke
				(width 0.1524)
				(type default)
			)
			(layer "B.SilkS")
		)
		(fp_rect
			(start 0.508 0.9398)
			(end -0.508 -0.9398)
			(stroke
				(width 0)
				(type default)
			)
			(fill no)
			(layer "B.CrtYd")
		)
		(fp_rect
			(start 0.508 0.9398)
			(end -0.508 -0.9398)
			(stroke
				(width 0)
				(type default)
			)
			(fill no)
			(layer "B.Fab")
		)
		(pad "1" smd custom
			(at 0 -0.4445 180)
			(size 0.1397 0.1397)
			(layers "B.Cu" "B.Mask" "B.Paste")
			(net "SAS_HDD_PWR10_PCIE")
			(options
				(clearance outline)
				(anchor circle)
			)
			(primitives
				(gr_poly
					(pts
						(arc
							(start -0.1778 0.2794)
							(mid -0.249642 0.249642)
							(end -0.2794 0.1778)
						)
						(arc
							(start -0.2794 -0.1778)
							(mid -0.249642 -0.249642)
							(end -0.1778 -0.2794)
						)
						(arc
							(start 0.1778 -0.2794)
							(mid 0.249642 -0.249642)
							(end 0.2794 -0.1778)
						)
						(arc
							(start 0.2794 0.1778)
							(mid 0.249642 0.249642)
							(end 0.1778 0.2794)
						)
					)
					(width 0)
					(fill yes)
				)
			)
		)
		(pad "2" smd custom
			(at 0 0.4445 180)
			(size 0.1397 0.1397)
			(layers "B.Cu" "B.Mask" "B.Paste")
			(net "SAS_HDD_PWR10")
			(options
				(clearance outline)
				(anchor circle)
			)
			(primitives
				(gr_poly
					(pts
						(arc
							(start -0.1778 0.2794)
							(mid -0.249642 0.249642)
							(end -0.2794 0.1778)
						)
						(arc
							(start -0.2794 -0.1778)
							(mid -0.249642 -0.249642)
							(end -0.1778 -0.2794)
						)
						(arc
							(start 0.1778 -0.2794)
							(mid 0.249642 -0.249642)
							(end 0.2794 -0.1778)
						)
						(arc
							(start 0.2794 0.1778)
							(mid 0.249642 0.249642)
							(end 0.1778 0.2794)
						)
					)
					(width 0)
					(fill yes)
				)
			)
		)
	)
	(footprint ""
		(layer "B.Cu")
		(at 118.688612 -221.996)
		(property "Reference" "SR885"
			(at 0 0 0)
			(layer "B.SilkS")
			(hide yes)
			(effects
				(font
					(size 1.27 1.27)
				)
				(justify mirror)
			)
		)
		(property "Value" "0R2J-2-GP"
			(at -0.064008 -3.993896 0)
			(unlocked yes)
			(layer "B.Fab")
			(hide yes)
			(effects
				(font
					(size 1.016 1.016)
					(thickness 0.1524)
				)
				(justify mirror)
			)
		)
		(property "Device Type" "R402H16"
			(at -0.064008 -5.517896 0)
			(unlocked yes)
			(layer "B.Fab")
			(hide yes)
			(effects
				(font
					(size 1.016 1.016)
					(thickness 0.1524)
				)
				(justify mirror)
			)
		)
		(duplicate_pad_numbers_are_jumpers no)
		(fp_line
			(start -0.508 -0.9398)
			(end 0.508 -0.9398)
			(stroke
				(width 0.1524)
				(type default)
			)
			(layer "B.SilkS")
		)
		(fp_line
			(start 0.508 -0.9398)
			(end 0.508 0.9398)
			(stroke
				(width 0.1524)
				(type default)
			)
			(layer "B.SilkS")
		)
		(fp_rect
			(start 0.508 0.9398)
			(end -0.508 -0.9398)
			(stroke
				(width 0)
				(type default)
			)
			(fill no)
			(layer "B.CrtYd")
		)
		(fp_rect
			(start 0.508 0.9398)
			(end -0.508 -0.9398)
			(stroke
				(width 0)
				(type default)
			)
			(fill no)
			(layer "B.Fab")
		)
		(pad "1" smd custom
			(at 0 -0.4445 180)
			(size 0.1397 0.1397)
			(layers "B.Cu" "B.Mask" "B.Paste")
			(net "SAS_GF_EXP_RX_DP7")
			(options
				(clearance outline)
				(anchor circle)
			)
			(primitives
				(gr_poly
					(pts
						(arc
							(start -0.1778 0.2794)
							(mid -0.249642 0.249642)
							(end -0.2794 0.1778)
						)
						(arc
							(start -0.2794 -0.1778)
							(mid -0.249642 -0.249642)
							(end -0.1778 -0.2794)
						)
						(arc
							(start 0.1778 -0.2794)
							(mid 0.249642 -0.249642)
							(end 0.2794 -0.1778)
						)
						(arc
							(start 0.2794 0.1778)
							(mid 0.249642 0.249642)
							(end 0.1778 0.2794)
						)
					)
					(width 0)
					(fill yes)
				)
			)
		)
		(pad "2" smd custom
			(at 0 0.4445 180)
			(size 0.1397 0.1397)
			(layers "B.Cu" "B.Mask" "B.Paste")
			(net "SAS_HDD_CONN_SER_RX7_P")
			(options
				(clearance outline)
				(anchor circle)
			)
			(primitives
				(gr_poly
					(pts
						(arc
							(start -0.1778 0.2794)
							(mid -0.249642 0.249642)
							(end -0.2794 0.1778)
						)
						(arc
							(start -0.2794 -0.1778)
							(mid -0.249642 -0.249642)
							(end -0.1778 -0.2794)
						)
						(arc
							(start 0.1778 -0.2794)
							(mid 0.249642 -0.249642)
							(end 0.2794 -0.1778)
						)
						(arc
							(start 0.2794 0.1778)
							(mid 0.249642 0.249642)
							(end 0.1778 0.2794)
						)
					)
					(width 0)
					(fill yes)
				)
			)
		)
	)
	(footprint ""
		(layer "B.Cu")
		(at 95.51416 -31.623)
		(property "Reference" "SC864"
			(at 0 0 0)
			(layer "B.SilkS")
			(hide yes)
			(effects
				(font
					(size 1.27 1.27)
				)
				(justify mirror)
			)
		)
		(property "Value" "SCD22U6D3V1MX-1-GP"
			(at 2.8321 -1.7399 0)
			(unlocked yes)
			(layer "B.Fab")
			(hide yes)
			(effects
				(font
					(size 1.016 1.016)
					(thickness 0.1524)
				)
				(justify mirror)
			)
		)
		(property "Device Type" "C0201H13"
			(at 2.8321 -3.2639 0)
			(unlocked yes)
			(layer "B.Fab")
			(hide yes)
			(effects
				(font
					(size 1.016 1.016)
					(thickness 0.1524)
				)
				(justify mirror)
			)
		)
		(duplicate_pad_numbers_are_jumpers no)
		(fp_rect
			(start 0.2794 0.6477)
			(end -0.2794 -0.6477)
			(stroke
				(width 0)
				(type default)
			)
			(fill no)
			(layer "B.CrtYd")
		)
		(fp_rect
			(start 0.2794 0.6477)
			(end -0.2794 -0.6477)
			(stroke
				(width 0)
				(type default)
			)
			(fill no)
			(layer "B.Fab")
		)
		(pad "1" smd custom
			(at 0 -0.2794 180)
			(size 0.0762 0.0762)
			(layers "B.Cu" "B.Mask" "B.Paste")
			(net "PCIE_SAS_C_CPU_RX_N1")
			(options
				(clearance outline)
				(anchor circle)
			)
			(primitives
				(gr_poly
					(pts
						(arc
							(start 0.1524 0.127)
							(mid 0.137521 0.162921)
							(end 0.1016 0.1778)
						)
						(arc
							(start -0.1016 0.1778)
							(mid -0.137521 0.162921)
							(end -0.1524 0.127)
						)
						(arc
							(start -0.1524 -0.127)
							(mid -0.137521 -0.162921)
							(end -0.1016 -0.1778)
						)
						(arc
							(start 0.1016 -0.1778)
							(mid 0.137521 -0.162921)
							(end 0.1524 -0.127)
						)
					)
					(width 0)
					(fill yes)
				)
			)
		)
		(pad "2" smd custom
			(at 0 0.2794 180)
			(size 0.0762 0.0762)
			(layers "B.Cu" "B.Mask" "B.Paste")
			(net "PCIE_SAS_CPU_RX_N1")
			(options
				(clearance outline)
				(anchor circle)
			)
			(primitives
				(gr_poly
					(pts
						(arc
							(start 0.1524 0.127)
							(mid 0.137521 0.162921)
							(end 0.1016 0.1778)
						)
						(arc
							(start -0.1016 0.1778)
							(mid -0.137521 0.162921)
							(end -0.1524 0.127)
						)
						(arc
							(start -0.1524 -0.127)
							(mid -0.137521 -0.162921)
							(end -0.1016 -0.1778)
						)
						(arc
							(start 0.1016 -0.1778)
							(mid 0.137521 -0.162921)
							(end 0.1524 -0.127)
						)
					)
					(width 0)
					(fill yes)
				)
			)
		)
	)
	(footprint ""
		(layer "B.Cu")
		(at 103.64597 -86.0679 -90)
		(property "Reference" "SC1211"
			(at 0 0 90)
			(layer "B.SilkS")
			(hide yes)
			(effects
				(font
					(size 1.27 1.27)
				)
				(justify mirror)
			)
		)
		(property "Value" "SC1KP50V2KX-1GP"
			(at -1.1811 -2.7051 270)
			(unlocked yes)
			(layer "B.Fab")
			(hide yes)
			(effects
				(font
					(size 1.016 1.016)
					(thickness 0.1524)
				)
				(justify mirror)
			)
		)
		(property "Device Type" "C402H22"
			(at -1.1811 -4.2291 270)
			(unlocked yes)
			(layer "B.Fab")
			(hide yes)
			(effects
				(font
					(size 1.016 1.016)
					(thickness 0.1524)
				)
				(justify mirror)
			)
		)
		(duplicate_pad_numbers_are_jumpers no)
		(fp_rect
			(start 0.4318 0.9525)
			(end -0.4318 -0.9525)
			(stroke
				(width 0)
				(type default)
			)
			(fill no)
			(layer "B.CrtYd")
		)
		(fp_rect
			(start 0.4318 0.9525)
			(end -0.4318 -0.9525)
			(stroke
				(width 0)
				(type default)
			)
			(fill no)
			(layer "B.Fab")
		)
		(pad "1" smd custom
			(at 0 -0.4445 90)
			(size 0.1524 0.1524)
			(layers "B.Cu" "B.Mask" "B.Paste")
			(net "P1V8_E")
			(options
				(clearance outline)
				(anchor circle)
			)
			(primitives
				(gr_poly
					(pts
						(arc
							(start 0.3048 0.2032)
							(mid 0.275042 0.275042)
							(end 0.2032 0.3048)
						)
						(arc
							(start -0.2032 0.3048)
							(mid -0.275042 0.275042)
							(end -0.3048 0.2032)
						)
						(arc
							(start -0.3048 -0.2032)
							(mid -0.275042 -0.275042)
							(end -0.2032 -0.3048)
						)
						(arc
							(start 0.2032 -0.3048)
							(mid 0.275042 -0.275042)
							(end 0.3048 -0.2032)
						)
					)
					(width 0)
					(fill yes)
				)
			)
		)
		(pad "2" smd custom
			(at 0 0.4445 90)
			(size 0.1524 0.1524)
			(layers "B.Cu" "B.Mask" "B.Paste")
			(net "GND")
			(options
				(clearance outline)
				(anchor circle)
			)
			(primitives
				(gr_poly
					(pts
						(arc
							(start 0.3048 0.2032)
							(mid 0.275042 0.275042)
							(end 0.2032 0.3048)
						)
						(arc
							(start -0.2032 0.3048)
							(mid -0.275042 0.275042)
							(end -0.3048 0.2032)
						)
						(arc
							(start -0.3048 -0.2032)
							(mid -0.275042 -0.275042)
							(end -0.2032 -0.3048)
						)
						(arc
							(start 0.2032 -0.3048)
							(mid 0.275042 -0.275042)
							(end 0.3048 -0.2032)
						)
					)
					(width 0)
					(fill yes)
				)
			)
		)
	)
	(footprint ""
		(layer "B.Cu")
		(at 327.025 -109.982 90)
		(property "Reference" "PC27"
			(at 0 0 90)
			(layer "B.SilkS")
			(hide yes)
			(effects
				(font
					(size 1.27 1.27)
				)
				(justify mirror)
			)
		)
		(property "Value" "SCD1U50V3KX-GP"
			(at 0 -2.8194 90)
			(unlocked yes)
			(layer "B.Fab")
			(hide yes)
			(effects
				(font
					(size 1.016 1.016)
					(thickness 0.1524)
				)
				(justify mirror)
			)
		)
		(property "Device Type" "C603H36"
			(at 0 -4.3434 90)
			(unlocked yes)
			(layer "B.Fab")
			(hide yes)
			(effects
				(font
					(size 1.016 1.016)
					(thickness 0.1524)
				)
				(justify mirror)
			)
		)
		(duplicate_pad_numbers_are_jumpers no)
		(fp_line
			(start -0.508 0)
			(end 0.508 0)
			(stroke
				(width 0.2032)
				(type default)
			)
			(layer "B.SilkS")
		)
		(fp_rect
			(start 0.5842 1.3335)
			(end -0.5842 -1.3335)
			(stroke
				(width 0)
				(type default)
			)
			(fill no)
			(layer "B.CrtYd")
		)
		(fp_rect
			(start 0.5842 1.3335)
			(end -0.5842 -1.3335)
			(stroke
				(width 0)
				(type default)
			)
			(fill no)
			(layer "B.Fab")
		)
		(pad "1" smd custom
			(at 0 -0.762 270)
			(size 0.2159 0.2159)
			(layers "B.Cu" "B.Mask" "B.Paste")
			(net "P3V3_STBY_VBST_RC")
			(options
				(clearance outline)
				(anchor circle)
			)
			(primitives
				(gr_poly
					(pts
						(arc
							(start -0.3302 0.4318)
							(mid -0.402042 0.402042)
							(end -0.4318 0.3302)
						)
						(arc
							(start -0.4318 -0.3302)
							(mid -0.402042 -0.402042)
							(end -0.3302 -0.4318)
						)
						(arc
							(start 0.3302 -0.4318)
							(mid 0.402042 -0.402042)
							(end 0.4318 -0.3302)
						)
						(arc
							(start 0.4318 0.3302)
							(mid 0.402042 0.402042)
							(end 0.3302 0.4318)
						)
					)
					(width 0)
					(fill yes)
				)
			)
		)
		(pad "2" smd custom
			(at 0 0.762 270)
			(size 0.2159 0.2159)
			(layers "B.Cu" "B.Mask" "B.Paste")
			(net "P3V3_STBY_LL")
			(options
				(clearance outline)
				(anchor circle)
			)
			(primitives
				(gr_poly
					(pts
						(arc
							(start -0.3302 0.4318)
							(mid -0.402042 0.402042)
							(end -0.4318 0.3302)
						)
						(arc
							(start -0.4318 -0.3302)
							(mid -0.402042 -0.402042)
							(end -0.3302 -0.4318)
						)
						(arc
							(start 0.3302 -0.4318)
							(mid 0.402042 -0.402042)
							(end 0.4318 -0.3302)
						)
						(arc
							(start 0.4318 0.3302)
							(mid 0.402042 0.402042)
							(end 0.3302 0.4318)
						)
					)
					(width 0)
					(fill yes)
				)
			)
		)
	)
	(footprint ""
		(layer "B.Cu")
		(at 96.339406 -41.81602 90)
		(property "Reference" "SC962"
			(at 0 0 90)
			(layer "B.SilkS")
			(hide yes)
			(effects
				(font
					(size 1.27 1.27)
				)
				(justify mirror)
			)
		)
		(property "Value" "SCD1U6D3V1KX-GP"
			(at 2.8321 -1.7399 90)
			(unlocked yes)
			(layer "B.Fab")
			(hide yes)
			(effects
				(font
					(size 1.016 1.016)
					(thickness 0.1524)
				)
				(justify mirror)
			)
		)
		(property "Device Type" "C0201H13"
			(at 2.8321 -3.2639 90)
			(unlocked yes)
			(layer "B.Fab")
			(hide yes)
			(effects
				(font
					(size 1.016 1.016)
					(thickness 0.1524)
				)
				(justify mirror)
			)
		)
		(duplicate_pad_numbers_are_jumpers no)
		(fp_rect
			(start 0.2794 0.6477)
			(end -0.2794 -0.6477)
			(stroke
				(width 0)
				(type default)
			)
			(fill no)
			(layer "B.CrtYd")
		)
		(fp_rect
			(start 0.2794 0.6477)
			(end -0.2794 -0.6477)
			(stroke
				(width 0)
				(type default)
			)
			(fill no)
			(layer "B.Fab")
		)
		(pad "1" smd custom
			(at 0 -0.2794 270)
			(size 0.0762 0.0762)
			(layers "B.Cu" "B.Mask" "B.Paste")
			(net "SAS0_AVDD")
			(options
				(clearance outline)
				(anchor circle)
			)
			(primitives
				(gr_poly
					(pts
						(arc
							(start 0.1524 0.127)
							(mid 0.137521 0.162921)
							(end 0.1016 0.1778)
						)
						(arc
							(start -0.1016 0.1778)
							(mid -0.137521 0.162921)
							(end -0.1524 0.127)
						)
						(arc
							(start -0.1524 -0.127)
							(mid -0.137521 -0.162921)
							(end -0.1016 -0.1778)
						)
						(arc
							(start 0.1016 -0.1778)
							(mid 0.137521 -0.162921)
							(end 0.1524 -0.127)
						)
					)
					(width 0)
					(fill yes)
				)
			)
		)
		(pad "2" smd custom
			(at 0 0.2794 270)
			(size 0.0762 0.0762)
			(layers "B.Cu" "B.Mask" "B.Paste")
			(net "GND")
			(options
				(clearance outline)
				(anchor circle)
			)
			(primitives
				(gr_poly
					(pts
						(arc
							(start 0.1524 0.127)
							(mid 0.137521 0.162921)
							(end 0.1016 0.1778)
						)
						(arc
							(start -0.1016 0.1778)
							(mid -0.137521 0.162921)
							(end -0.1524 0.127)
						)
						(arc
							(start -0.1524 -0.127)
							(mid -0.137521 -0.162921)
							(end -0.1016 -0.1778)
						)
						(arc
							(start 0.1016 -0.1778)
							(mid 0.137521 -0.162921)
							(end 0.1524 -0.127)
						)
					)
					(width 0)
					(fill yes)
				)
			)
		)
	)
	(footprint ""
		(layer "B.Cu")
		(at 186.744864 -28.266136 180)
		(property "Reference" "C228"
			(at 0 0 0)
			(layer "B.SilkS")
			(hide yes)
			(effects
				(font
					(size 1.27 1.27)
				)
				(justify mirror)
			)
		)
		(property "Value" "SCD1U16V2KX-3GP"
			(at -1.1811 -2.7051 180)
			(unlocked yes)
			(layer "B.Fab")
			(hide yes)
			(effects
				(font
					(size 1.016 1.016)
					(thickness 0.1524)
				)
				(justify mirror)
			)
		)
		(property "Device Type" "C402H22"
			(at -1.1811 -4.2291 180)
			(unlocked yes)
			(layer "B.Fab")
			(hide yes)
			(effects
				(font
					(size 1.016 1.016)
					(thickness 0.1524)
				)
				(justify mirror)
			)
		)
		(duplicate_pad_numbers_are_jumpers no)
		(fp_rect
			(start 0.4318 0.9525)
			(end -0.4318 -0.9525)
			(stroke
				(width 0)
				(type default)
			)
			(fill no)
			(layer "B.CrtYd")
		)
		(fp_rect
			(start 0.4318 0.9525)
			(end -0.4318 -0.9525)
			(stroke
				(width 0)
				(type default)
			)
			(fill no)
			(layer "B.Fab")
		)
		(pad "1" smd custom
			(at 0 -0.4445)
			(size 0.1524 0.1524)
			(layers "B.Cu" "B.Mask" "B.Paste")
			(net "P3V3_STBY")
			(options
				(clearance outline)
				(anchor circle)
			)
			(primitives
				(gr_poly
					(pts
						(arc
							(start 0.3048 0.2032)
							(mid 0.275042 0.275042)
							(end 0.2032 0.3048)
						)
						(arc
							(start -0.2032 0.3048)
							(mid -0.275042 0.275042)
							(end -0.3048 0.2032)
						)
						(arc
							(start -0.3048 -0.2032)
							(mid -0.275042 -0.275042)
							(end -0.2032 -0.3048)
						)
						(arc
							(start 0.2032 -0.3048)
							(mid 0.275042 -0.275042)
							(end 0.3048 -0.2032)
						)
					)
					(width 0)
					(fill yes)
				)
			)
		)
		(pad "2" smd custom
			(at 0 0.4445)
			(size 0.1524 0.1524)
			(layers "B.Cu" "B.Mask" "B.Paste")
			(net "GND")
			(options
				(clearance outline)
				(anchor circle)
			)
			(primitives
				(gr_poly
					(pts
						(arc
							(start 0.3048 0.2032)
							(mid 0.275042 0.275042)
							(end 0.2032 0.3048)
						)
						(arc
							(start -0.2032 0.3048)
							(mid -0.275042 0.275042)
							(end -0.3048 0.2032)
						)
						(arc
							(start -0.3048 -0.2032)
							(mid -0.275042 -0.275042)
							(end -0.2032 -0.3048)
						)
						(arc
							(start 0.2032 -0.3048)
							(mid 0.275042 -0.275042)
							(end 0.3048 -0.2032)
						)
					)
					(width 0)
					(fill yes)
				)
			)
		)
	)
	(footprint ""
		(layer "B.Cu")
		(at 48.20793 -78.412086)
		(property "Reference" "TP148"
			(at 0 0 0)
			(layer "B.SilkS")
			(hide yes)
			(effects
				(font
					(size 1.27 1.27)
				)
				(justify mirror)
			)
		)
		(property "Value" "TPAD32-GP"
			(at 0 -3.166364 0)
			(unlocked yes)
			(layer "B.Fab")
			(hide yes)
			(effects
				(font
					(size 1.016 1.016)
					(thickness 0.1524)
				)
				(justify mirror)
			)
		)
		(property "Device Type" "TPAD32"
			(at 0 -4.690618 0)
			(unlocked yes)
			(layer "B.Fab")
			(hide yes)
			(effects
				(font
					(size 1.016 1.016)
					(thickness 0.1524)
				)
				(justify mirror)
			)
		)
		(duplicate_pad_numbers_are_jumpers no)
		(fp_poly
			(pts
				(arc
					(start 0.4064 0)
					(mid -0.4064 0)
					(end 0.4064 0)
				)
			)
			(stroke
				(width 0)
				(type default)
			)
			(fill no)
			(layer "B.CrtYd")
		)
		(fp_poly
			(pts
				(arc
					(start 0.7112 0)
					(mid -0.7112 0)
					(end 0.7112 0)
				)
			)
			(stroke
				(width 0)
				(type default)
			)
			(fill no)
			(layer "B.Fab")
		)
		(pad "1" smd circle
			(at 0 0 180)
			(size 0.8128 0.8128)
			(layers "B.Cu" "B.Mask" "B.Paste")
			(net "INT_CONN_A_SB2")
		)
	)
	(footprint ""
		(layer "B.Cu")
		(at 290.068 -177.927 90)
		(property "Reference" "C207"
			(at 0 0 90)
			(layer "B.SilkS")
			(hide yes)
			(effects
				(font
					(size 1.27 1.27)
				)
				(justify mirror)
			)
		)
		(property "Value" "SC1U10V3KX-4GP-U"
			(at 0 -2.8194 90)
			(unlocked yes)
			(layer "B.Fab")
			(hide yes)
			(effects
				(font
					(size 1.016 1.016)
					(thickness 0.1524)
				)
				(justify mirror)
			)
		)
		(property "Device Type" "C603H36"
			(at 0 -4.3434 90)
			(unlocked yes)
			(layer "B.Fab")
			(hide yes)
			(effects
				(font
					(size 1.016 1.016)
					(thickness 0.1524)
				)
				(justify mirror)
			)
		)
		(duplicate_pad_numbers_are_jumpers no)
		(fp_line
			(start -0.508 0)
			(end 0.508 0)
			(stroke
				(width 0.2032)
				(type default)
			)
			(layer "B.SilkS")
		)
		(fp_rect
			(start 0.5842 1.3335)
			(end -0.5842 -1.3335)
			(stroke
				(width 0)
				(type default)
			)
			(fill no)
			(layer "B.CrtYd")
		)
		(fp_rect
			(start 0.5842 1.3335)
			(end -0.5842 -1.3335)
			(stroke
				(width 0)
				(type default)
			)
			(fill no)
			(layer "B.Fab")
		)
		(pad "1" smd custom
			(at 0 -0.762 270)
			(size 0.2159 0.2159)
			(layers "B.Cu" "B.Mask" "B.Paste")
			(net "P1V26_STBY")
			(options
				(clearance outline)
				(anchor circle)
			)
			(primitives
				(gr_poly
					(pts
						(arc
							(start -0.3302 0.4318)
							(mid -0.402042 0.402042)
							(end -0.4318 0.3302)
						)
						(arc
							(start -0.4318 -0.3302)
							(mid -0.402042 -0.402042)
							(end -0.3302 -0.4318)
						)
						(arc
							(start 0.3302 -0.4318)
							(mid 0.402042 -0.402042)
							(end 0.4318 -0.3302)
						)
						(arc
							(start 0.4318 0.3302)
							(mid 0.402042 0.402042)
							(end 0.3302 0.4318)
						)
					)
					(width 0)
					(fill yes)
				)
			)
		)
		(pad "2" smd custom
			(at 0 0.762 270)
			(size 0.2159 0.2159)
			(layers "B.Cu" "B.Mask" "B.Paste")
			(net "GND")
			(options
				(clearance outline)
				(anchor circle)
			)
			(primitives
				(gr_poly
					(pts
						(arc
							(start -0.3302 0.4318)
							(mid -0.402042 0.402042)
							(end -0.4318 0.3302)
						)
						(arc
							(start -0.4318 -0.3302)
							(mid -0.402042 -0.402042)
							(end -0.3302 -0.4318)
						)
						(arc
							(start 0.3302 -0.4318)
							(mid 0.402042 -0.402042)
							(end 0.4318 -0.3302)
						)
						(arc
							(start 0.4318 0.3302)
							(mid 0.402042 0.402042)
							(end 0.3302 0.4318)
						)
					)
					(width 0)
					(fill yes)
				)
			)
		)
	)
	(footprint ""
		(layer "B.Cu")
		(at 117.484906 -36.64458)
		(property "Reference" "STP54"
			(at 0 0 0)
			(layer "B.SilkS")
			(hide yes)
			(effects
				(font
					(size 1.27 1.27)
				)
				(justify mirror)
			)
		)
		(property "Value" "TPAD28"
			(at -0.0127 -1.8034 0)
			(unlocked yes)
			(layer "B.Fab")
			(hide yes)
			(effects
				(font
					(size 1.016 1.016)
					(thickness 0.1524)
				)
				(justify mirror)
			)
		)
		(property "Device Type" "TPAD28"
			(at -0.0127 -3.3274 0)
			(unlocked yes)
			(layer "B.Fab")
			(hide yes)
			(effects
				(font
					(size 1.016 1.016)
					(thickness 0.1524)
				)
				(justify mirror)
			)
		)
		(duplicate_pad_numbers_are_jumpers no)
		(fp_poly
			(pts
				(arc
					(start 0.3556 0)
					(mid -0.3556 0)
					(end 0.3556 0)
				)
			)
			(stroke
				(width 0)
				(type default)
			)
			(fill no)
			(layer "B.CrtYd")
		)
		(fp_poly
			(pts
				(arc
					(start 0.6096 0)
					(mid -0.6096 0)
					(end 0.6096 0)
				)
			)
			(stroke
				(width 0)
				(type default)
			)
			(fill no)
			(layer "B.Fab")
		)
		(pad "1" smd circle
			(at 0 0 180)
			(size 0.7112 0.7112)
			(layers "B.Cu" "B.Mask" "B.Paste")
			(net "SPARE4")
		)
	)
	(footprint ""
		(layer "B.Cu")
		(at 274.193 -174.625 90)
		(property "Reference" "R360"
			(at 0 0 90)
			(layer "B.SilkS")
			(hide yes)
			(effects
				(font
					(size 1.27 1.27)
				)
				(justify mirror)
			)
		)
		(property "Value" "3K3R2F-2-GP"
			(at -0.064008 -3.993896 90)
			(unlocked yes)
			(layer "B.Fab")
			(hide yes)
			(effects
				(font
					(size 1.016 1.016)
					(thickness 0.1524)
				)
				(justify mirror)
			)
		)
		(property "Device Type" "R402H16"
			(at -0.064008 -5.517896 90)
			(unlocked yes)
			(layer "B.Fab")
			(hide yes)
			(effects
				(font
					(size 1.016 1.016)
					(thickness 0.1524)
				)
				(justify mirror)
			)
		)
		(duplicate_pad_numbers_are_jumpers no)
		(fp_line
			(start 0.508 -0.9398)
			(end 0.508 0.9398)
			(stroke
				(width 0.1524)
				(type default)
			)
			(layer "B.SilkS")
		)
		(fp_line
			(start -0.508 -0.9398)
			(end 0.508 -0.9398)
			(stroke
				(width 0.1524)
				(type default)
			)
			(layer "B.SilkS")
		)
		(fp_rect
			(start 0.508 0.9398)
			(end -0.508 -0.9398)
			(stroke
				(width 0)
				(type default)
			)
			(fill no)
			(layer "B.CrtYd")
		)
		(fp_rect
			(start 0.508 0.9398)
			(end -0.508 -0.9398)
			(stroke
				(width 0)
				(type default)
			)
			(fill no)
			(layer "B.Fab")
		)
		(pad "1" smd custom
			(at 0 -0.4445 270)
			(size 0.1397 0.1397)
			(layers "B.Cu" "B.Mask" "B.Paste")
			(net "P3V3_STBY")
			(options
				(clearance outline)
				(anchor circle)
			)
			(primitives
				(gr_poly
					(pts
						(arc
							(start -0.1778 0.2794)
							(mid -0.249642 0.249642)
							(end -0.2794 0.1778)
						)
						(arc
							(start -0.2794 -0.1778)
							(mid -0.249642 -0.249642)
							(end -0.1778 -0.2794)
						)
						(arc
							(start 0.1778 -0.2794)
							(mid 0.249642 -0.249642)
							(end 0.2794 -0.1778)
						)
						(arc
							(start 0.2794 0.1778)
							(mid 0.249642 0.249642)
							(end 0.1778 0.2794)
						)
					)
					(width 0)
					(fill yes)
				)
			)
		)
		(pad "2" smd custom
			(at 0 0.4445 270)
			(size 0.1397 0.1397)
			(layers "B.Cu" "B.Mask" "B.Paste")
			(net "ROMA13")
			(options
				(clearance outline)
				(anchor circle)
			)
			(primitives
				(gr_poly
					(pts
						(arc
							(start -0.1778 0.2794)
							(mid -0.249642 0.249642)
							(end -0.2794 0.1778)
						)
						(arc
							(start -0.2794 -0.1778)
							(mid -0.249642 -0.249642)
							(end -0.1778 -0.2794)
						)
						(arc
							(start 0.1778 -0.2794)
							(mid 0.249642 -0.249642)
							(end 0.2794 -0.1778)
						)
						(arc
							(start 0.2794 0.1778)
							(mid 0.249642 0.249642)
							(end 0.1778 0.2794)
						)
					)
					(width 0)
					(fill yes)
				)
			)
		)
	)
	(footprint ""
		(layer "B.Cu")
		(at 90.659966 -55.245 180)
		(property "Reference" "SC977"
			(at 0 0 0)
			(layer "B.SilkS")
			(hide yes)
			(effects
				(font
					(size 1.27 1.27)
				)
				(justify mirror)
			)
		)
		(property "Value" "SCD1U16V2KX-3GP"
			(at -1.1811 -2.7051 180)
			(unlocked yes)
			(layer "B.Fab")
			(hide yes)
			(effects
				(font
					(size 1.016 1.016)
					(thickness 0.1524)
				)
				(justify mirror)
			)
		)
		(property "Device Type" "C402H22"
			(at -1.1811 -4.2291 180)
			(unlocked yes)
			(layer "B.Fab")
			(hide yes)
			(effects
				(font
					(size 1.016 1.016)
					(thickness 0.1524)
				)
				(justify mirror)
			)
		)
		(duplicate_pad_numbers_are_jumpers no)
		(fp_rect
			(start 0.4318 0.9525)
			(end -0.4318 -0.9525)
			(stroke
				(width 0)
				(type default)
			)
			(fill no)
			(layer "B.CrtYd")
		)
		(fp_rect
			(start 0.4318 0.9525)
			(end -0.4318 -0.9525)
			(stroke
				(width 0)
				(type default)
			)
			(fill no)
			(layer "B.Fab")
		)
		(pad "1" smd custom
			(at 0 -0.4445)
			(size 0.1524 0.1524)
			(layers "B.Cu" "B.Mask" "B.Paste")
			(net "P1V8_C")
			(options
				(clearance outline)
				(anchor circle)
			)
			(primitives
				(gr_poly
					(pts
						(arc
							(start 0.3048 0.2032)
							(mid 0.275042 0.275042)
							(end 0.2032 0.3048)
						)
						(arc
							(start -0.2032 0.3048)
							(mid -0.275042 0.275042)
							(end -0.3048 0.2032)
						)
						(arc
							(start -0.3048 -0.2032)
							(mid -0.275042 -0.275042)
							(end -0.2032 -0.3048)
						)
						(arc
							(start 0.2032 -0.3048)
							(mid 0.275042 -0.275042)
							(end 0.3048 -0.2032)
						)
					)
					(width 0)
					(fill yes)
				)
			)
		)
		(pad "2" smd custom
			(at 0 0.4445)
			(size 0.1524 0.1524)
			(layers "B.Cu" "B.Mask" "B.Paste")
			(net "GND")
			(options
				(clearance outline)
				(anchor circle)
			)
			(primitives
				(gr_poly
					(pts
						(arc
							(start 0.3048 0.2032)
							(mid 0.275042 0.275042)
							(end 0.2032 0.3048)
						)
						(arc
							(start -0.2032 0.3048)
							(mid -0.275042 0.275042)
							(end -0.3048 0.2032)
						)
						(arc
							(start -0.3048 -0.2032)
							(mid -0.275042 -0.275042)
							(end -0.2032 -0.3048)
						)
						(arc
							(start 0.2032 -0.3048)
							(mid 0.275042 -0.275042)
							(end 0.3048 -0.2032)
						)
					)
					(width 0)
					(fill yes)
				)
			)
		)
	)
	(footprint ""
		(layer "B.Cu")
		(at 318.008 -174.625 90)
		(property "Reference" "R468"
			(at 0 0 90)
			(layer "B.SilkS")
			(hide yes)
			(effects
				(font
					(size 1.27 1.27)
				)
				(justify mirror)
			)
		)
		(property "Value" "0R2J-2-GP"
			(at -0.064008 -3.993896 90)
			(unlocked yes)
			(layer "B.Fab")
			(hide yes)
			(effects
				(font
					(size 1.016 1.016)
					(thickness 0.1524)
				)
				(justify mirror)
			)
		)
		(property "Device Type" "R402H16"
			(at -0.064008 -5.517896 90)
			(unlocked yes)
			(layer "B.Fab")
			(hide yes)
			(effects
				(font
					(size 1.016 1.016)
					(thickness 0.1524)
				)
				(justify mirror)
			)
		)
		(duplicate_pad_numbers_are_jumpers no)
		(fp_line
			(start 0.508 -0.9398)
			(end 0.508 0.9398)
			(stroke
				(width 0.1524)
				(type default)
			)
			(layer "B.SilkS")
		)
		(fp_line
			(start -0.508 -0.9398)
			(end 0.508 -0.9398)
			(stroke
				(width 0.1524)
				(type default)
			)
			(layer "B.SilkS")
		)
		(fp_rect
			(start 0.508 0.9398)
			(end -0.508 -0.9398)
			(stroke
				(width 0)
				(type default)
			)
			(fill no)
			(layer "B.CrtYd")
		)
		(fp_rect
			(start 0.508 0.9398)
			(end -0.508 -0.9398)
			(stroke
				(width 0)
				(type default)
			)
			(fill no)
			(layer "B.Fab")
		)
		(pad "1" smd custom
			(at 0 -0.4445 270)
			(size 0.1397 0.1397)
			(layers "B.Cu" "B.Mask" "B.Paste")
			(net "BMC0_SMB14_CLK")
			(options
				(clearance outline)
				(anchor circle)
			)
			(primitives
				(gr_poly
					(pts
						(arc
							(start -0.1778 0.2794)
							(mid -0.249642 0.249642)
							(end -0.2794 0.1778)
						)
						(arc
							(start -0.2794 -0.1778)
							(mid -0.249642 -0.249642)
							(end -0.1778 -0.2794)
						)
						(arc
							(start 0.1778 -0.2794)
							(mid 0.249642 -0.249642)
							(end 0.2794 -0.1778)
						)
						(arc
							(start 0.2794 0.1778)
							(mid 0.249642 0.249642)
							(end 0.1778 0.2794)
						)
					)
					(width 0)
					(fill yes)
				)
			)
		)
		(pad "2" smd custom
			(at 0 0.4445 270)
			(size 0.1397 0.1397)
			(layers "B.Cu" "B.Mask" "B.Paste")
			(net "EXP_IOC_BMC_SCL_14")
			(options
				(clearance outline)
				(anchor circle)
			)
			(primitives
				(gr_poly
					(pts
						(arc
							(start -0.1778 0.2794)
							(mid -0.249642 0.249642)
							(end -0.2794 0.1778)
						)
						(arc
							(start -0.2794 -0.1778)
							(mid -0.249642 -0.249642)
							(end -0.1778 -0.2794)
						)
						(arc
							(start 0.1778 -0.2794)
							(mid 0.249642 -0.249642)
							(end 0.2794 -0.1778)
						)
						(arc
							(start 0.2794 0.1778)
							(mid 0.249642 0.249642)
							(end 0.1778 0.2794)
						)
					)
					(width 0)
					(fill yes)
				)
			)
		)
	)
	(footprint ""
		(layer "B.Cu")
		(at 120.02897 -102.616 -90)
		(property "Reference" "SC1185"
			(at 0 0 90)
			(layer "B.SilkS")
			(hide yes)
			(effects
				(font
					(size 1.27 1.27)
				)
				(justify mirror)
			)
		)
		(property "Value" "SCD1U6D3V1KX-GP"
			(at 2.8321 -1.7399 270)
			(unlocked yes)
			(layer "B.Fab")
			(hide yes)
			(effects
				(font
					(size 1.016 1.016)
					(thickness 0.1524)
				)
				(justify mirror)
			)
		)
		(property "Device Type" "C0201H13"
			(at 2.8321 -3.2639 270)
			(unlocked yes)
			(layer "B.Fab")
			(hide yes)
			(effects
				(font
					(size 1.016 1.016)
					(thickness 0.1524)
				)
				(justify mirror)
			)
		)
		(duplicate_pad_numbers_are_jumpers no)
		(fp_rect
			(start 0.2794 0.6477)
			(end -0.2794 -0.6477)
			(stroke
				(width 0)
				(type default)
			)
			(fill no)
			(layer "B.CrtYd")
		)
		(fp_rect
			(start 0.2794 0.6477)
			(end -0.2794 -0.6477)
			(stroke
				(width 0)
				(type default)
			)
			(fill no)
			(layer "B.Fab")
		)
		(pad "1" smd custom
			(at 0 -0.2794 90)
			(size 0.0762 0.0762)
			(layers "B.Cu" "B.Mask" "B.Paste")
			(net "GB_VDDA")
			(options
				(clearance outline)
				(anchor circle)
			)
			(primitives
				(gr_poly
					(pts
						(arc
							(start 0.1524 0.127)
							(mid 0.137521 0.162921)
							(end 0.1016 0.1778)
						)
						(arc
							(start -0.1016 0.1778)
							(mid -0.137521 0.162921)
							(end -0.1524 0.127)
						)
						(arc
							(start -0.1524 -0.127)
							(mid -0.137521 -0.162921)
							(end -0.1016 -0.1778)
						)
						(arc
							(start 0.1016 -0.1778)
							(mid 0.137521 -0.162921)
							(end 0.1524 -0.127)
						)
					)
					(width 0)
					(fill yes)
				)
			)
		)
		(pad "2" smd custom
			(at 0 0.2794 90)
			(size 0.0762 0.0762)
			(layers "B.Cu" "B.Mask" "B.Paste")
			(net "GND")
			(options
				(clearance outline)
				(anchor circle)
			)
			(primitives
				(gr_poly
					(pts
						(arc
							(start 0.1524 0.127)
							(mid 0.137521 0.162921)
							(end 0.1016 0.1778)
						)
						(arc
							(start -0.1016 0.1778)
							(mid -0.137521 0.162921)
							(end -0.1524 0.127)
						)
						(arc
							(start -0.1524 -0.127)
							(mid -0.137521 -0.162921)
							(end -0.1016 -0.1778)
						)
						(arc
							(start 0.1016 -0.1778)
							(mid 0.137521 -0.162921)
							(end 0.1524 -0.127)
						)
					)
					(width 0)
					(fill yes)
				)
			)
		)
	)
	(footprint ""
		(layer "B.Cu")
		(at 122.428 -33.528)
		(property "Reference" "SC933"
			(at 0 0 0)
			(layer "B.SilkS")
			(hide yes)
			(effects
				(font
					(size 1.27 1.27)
				)
				(justify mirror)
			)
		)
		(property "Value" "SC1U6D3V1MX-GP"
			(at -1.9177 2.0193 0)
			(unlocked yes)
			(layer "B.Fab")
			(hide yes)
			(effects
				(font
					(size 1.016 1.016)
					(thickness 0.1524)
				)
				(justify mirror)
			)
		)
		(property "Device Type" "C0201H14"
			(at -1.9177 0.4953 0)
			(unlocked yes)
			(layer "B.Fab")
			(hide yes)
			(effects
				(font
					(size 1.016 1.016)
					(thickness 0.1524)
				)
				(justify mirror)
			)
		)
		(duplicate_pad_numbers_are_jumpers no)
		(fp_rect
			(start 0.1524 0.3048)
			(end -0.1524 -0.3048)
			(stroke
				(width 0)
				(type default)
			)
			(fill no)
			(layer "B.CrtYd")
		)
		(fp_poly
			(pts
				(xy 0.2794 0.6477) (xy 0.2794 -0.6477) (xy -0.2794 -0.6477) (xy -0.2794 -0.1905) (xy -0.1524 -0.1905)
				(xy -0.1524 -0.3048) (xy 0.1524 -0.3048) (xy 0.1524 0.3048) (xy -0.1524 0.3048) (xy -0.1524 -0.1778)
				(xy -0.2794 -0.1778) (xy -0.2794 0.6477)
			)
			(stroke
				(width 0)
				(type default)
			)
			(fill no)
			(layer "B.CrtYd")
		)
		(fp_rect
			(start 0.2794 0.6477)
			(end -0.2794 -0.6477)
			(stroke
				(width 0)
				(type default)
			)
			(fill no)
			(layer "B.Fab")
		)
		(pad "1" smd custom
			(at 0 -0.2794 180)
			(size 0.0762 0.0762)
			(layers "B.Cu" "B.Mask" "B.Paste")
			(net "PLL_VDD")
			(options
				(clearance outline)
				(anchor circle)
			)
			(primitives
				(gr_poly
					(pts
						(arc
							(start 0.1524 0.127)
							(mid 0.137521 0.162921)
							(end 0.1016 0.1778)
						)
						(arc
							(start -0.1016 0.1778)
							(mid -0.137521 0.162921)
							(end -0.1524 0.127)
						)
						(arc
							(start -0.1524 -0.127)
							(mid -0.137521 -0.162921)
							(end -0.1016 -0.1778)
						)
						(arc
							(start 0.1016 -0.1778)
							(mid 0.137521 -0.162921)
							(end 0.1524 -0.127)
						)
					)
					(width 0)
					(fill yes)
				)
			)
		)
		(pad "2" smd custom
			(at 0 0.2794 180)
			(size 0.0762 0.0762)
			(layers "B.Cu" "B.Mask" "B.Paste")
			(net "GND")
			(options
				(clearance outline)
				(anchor circle)
			)
			(primitives
				(gr_poly
					(pts
						(arc
							(start 0.1524 0.127)
							(mid 0.137521 0.162921)
							(end 0.1016 0.1778)
						)
						(arc
							(start -0.1016 0.1778)
							(mid -0.137521 0.162921)
							(end -0.1524 0.127)
						)
						(arc
							(start -0.1524 -0.127)
							(mid -0.137521 -0.162921)
							(end -0.1016 -0.1778)
						)
						(arc
							(start 0.1016 -0.1778)
							(mid 0.137521 -0.162921)
							(end 0.1524 -0.127)
						)
					)
					(width 0)
					(fill yes)
				)
			)
		)
	)
	(footprint ""
		(layer "B.Cu")
		(at 46.68393 -79.174086)
		(property "Reference" "TP185"
			(at 0 0 0)
			(layer "B.SilkS")
			(hide yes)
			(effects
				(font
					(size 1.27 1.27)
				)
				(justify mirror)
			)
		)
		(property "Value" "TPAD32-GP"
			(at 0 -3.166364 0)
			(unlocked yes)
			(layer "B.Fab")
			(hide yes)
			(effects
				(font
					(size 1.016 1.016)
					(thickness 0.1524)
				)
				(justify mirror)
			)
		)
		(property "Device Type" "TPAD32"
			(at 0 -4.690618 0)
			(unlocked yes)
			(layer "B.Fab")
			(hide yes)
			(effects
				(font
					(size 1.016 1.016)
					(thickness 0.1524)
				)
				(justify mirror)
			)
		)
		(duplicate_pad_numbers_are_jumpers no)
		(fp_poly
			(pts
				(arc
					(start 0.4064 0)
					(mid -0.4064 0)
					(end 0.4064 0)
				)
			)
			(stroke
				(width 0)
				(type default)
			)
			(fill no)
			(layer "B.CrtYd")
		)
		(fp_poly
			(pts
				(arc
					(start 0.7112 0)
					(mid -0.7112 0)
					(end 0.7112 0)
				)
			)
			(stroke
				(width 0)
				(type default)
			)
			(fill no)
			(layer "B.Fab")
		)
		(pad "1" smd circle
			(at 0 0 180)
			(size 0.8128 0.8128)
			(layers "B.Cu" "B.Mask" "B.Paste")
			(net "INT_CONN_A_SB0")
		)
	)
	(footprint ""
		(layer "B.Cu")
		(at 296.790872 -177.872136 -90)
		(property "Reference" "C205"
			(at 0 0 90)
			(layer "B.SilkS")
			(hide yes)
			(effects
				(font
					(size 1.27 1.27)
				)
				(justify mirror)
			)
		)
		(property "Value" "SC1U10V2KX-1GP"
			(at -1.1811 -2.7051 270)
			(unlocked yes)
			(layer "B.Fab")
			(hide yes)
			(effects
				(font
					(size 1.016 1.016)
					(thickness 0.1524)
				)
				(justify mirror)
			)
		)
		(property "Device Type" "C402H22"
			(at -1.1811 -4.2291 270)
			(unlocked yes)
			(layer "B.Fab")
			(hide yes)
			(effects
				(font
					(size 1.016 1.016)
					(thickness 0.1524)
				)
				(justify mirror)
			)
		)
		(duplicate_pad_numbers_are_jumpers no)
		(fp_rect
			(start 0.4318 0.9525)
			(end -0.4318 -0.9525)
			(stroke
				(width 0)
				(type default)
			)
			(fill no)
			(layer "B.CrtYd")
		)
		(fp_rect
			(start 0.4318 0.9525)
			(end -0.4318 -0.9525)
			(stroke
				(width 0)
				(type default)
			)
			(fill no)
			(layer "B.Fab")
		)
		(pad "1" smd custom
			(at 0 -0.4445 90)
			(size 0.1524 0.1524)
			(layers "B.Cu" "B.Mask" "B.Paste")
			(net "P1V26_STBY")
			(options
				(clearance outline)
				(anchor circle)
			)
			(primitives
				(gr_poly
					(pts
						(arc
							(start 0.3048 0.2032)
							(mid 0.275042 0.275042)
							(end 0.2032 0.3048)
						)
						(arc
							(start -0.2032 0.3048)
							(mid -0.275042 0.275042)
							(end -0.3048 0.2032)
						)
						(arc
							(start -0.3048 -0.2032)
							(mid -0.275042 -0.275042)
							(end -0.2032 -0.3048)
						)
						(arc
							(start 0.2032 -0.3048)
							(mid 0.275042 -0.275042)
							(end 0.3048 -0.2032)
						)
					)
					(width 0)
					(fill yes)
				)
			)
		)
		(pad "2" smd custom
			(at 0 0.4445 90)
			(size 0.1524 0.1524)
			(layers "B.Cu" "B.Mask" "B.Paste")
			(net "GND")
			(options
				(clearance outline)
				(anchor circle)
			)
			(primitives
				(gr_poly
					(pts
						(arc
							(start 0.3048 0.2032)
							(mid 0.275042 0.275042)
							(end 0.2032 0.3048)
						)
						(arc
							(start -0.2032 0.3048)
							(mid -0.275042 0.275042)
							(end -0.3048 0.2032)
						)
						(arc
							(start -0.3048 -0.2032)
							(mid -0.275042 -0.275042)
							(end -0.2032 -0.3048)
						)
						(arc
							(start 0.2032 -0.3048)
							(mid 0.275042 -0.275042)
							(end 0.3048 -0.2032)
						)
					)
					(width 0)
					(fill yes)
				)
			)
		)
	)
	(footprint ""
		(layer "B.Cu")
		(at 91.648026 -53.09616)
		(property "Reference" "SC1016"
			(at 0 0 0)
			(layer "B.SilkS")
			(hide yes)
			(effects
				(font
					(size 1.27 1.27)
				)
				(justify mirror)
			)
		)
		(property "Value" "SC1KP50V2KX-1GP"
			(at -1.1811 -2.7051 0)
			(unlocked yes)
			(layer "B.Fab")
			(hide yes)
			(effects
				(font
					(size 1.016 1.016)
					(thickness 0.1524)
				)
				(justify mirror)
			)
		)
		(property "Device Type" "C402H22"
			(at -1.1811 -4.2291 0)
			(unlocked yes)
			(layer "B.Fab")
			(hide yes)
			(effects
				(font
					(size 1.016 1.016)
					(thickness 0.1524)
				)
				(justify mirror)
			)
		)
		(duplicate_pad_numbers_are_jumpers no)
		(fp_rect
			(start 0.4318 0.9525)
			(end -0.4318 -0.9525)
			(stroke
				(width 0)
				(type default)
			)
			(fill no)
			(layer "B.CrtYd")
		)
		(fp_rect
			(start 0.4318 0.9525)
			(end -0.4318 -0.9525)
			(stroke
				(width 0)
				(type default)
			)
			(fill no)
			(layer "B.Fab")
		)
		(pad "1" smd custom
			(at 0 -0.4445 180)
			(size 0.1524 0.1524)
			(layers "B.Cu" "B.Mask" "B.Paste")
			(net "P1V8_C")
			(options
				(clearance outline)
				(anchor circle)
			)
			(primitives
				(gr_poly
					(pts
						(arc
							(start 0.3048 0.2032)
							(mid 0.275042 0.275042)
							(end 0.2032 0.3048)
						)
						(arc
							(start -0.2032 0.3048)
							(mid -0.275042 0.275042)
							(end -0.3048 0.2032)
						)
						(arc
							(start -0.3048 -0.2032)
							(mid -0.275042 -0.275042)
							(end -0.2032 -0.3048)
						)
						(arc
							(start 0.2032 -0.3048)
							(mid 0.275042 -0.275042)
							(end 0.3048 -0.2032)
						)
					)
					(width 0)
					(fill yes)
				)
			)
		)
		(pad "2" smd custom
			(at 0 0.4445 180)
			(size 0.1524 0.1524)
			(layers "B.Cu" "B.Mask" "B.Paste")
			(net "GND")
			(options
				(clearance outline)
				(anchor circle)
			)
			(primitives
				(gr_poly
					(pts
						(arc
							(start 0.3048 0.2032)
							(mid 0.275042 0.275042)
							(end 0.2032 0.3048)
						)
						(arc
							(start -0.2032 0.3048)
							(mid -0.275042 0.275042)
							(end -0.3048 0.2032)
						)
						(arc
							(start -0.3048 -0.2032)
							(mid -0.275042 -0.275042)
							(end -0.2032 -0.3048)
						)
						(arc
							(start 0.2032 -0.3048)
							(mid 0.275042 -0.275042)
							(end 0.3048 -0.2032)
						)
					)
					(width 0)
					(fill yes)
				)
			)
		)
	)
	(footprint ""
		(layer "B.Cu")
		(at 318.008 -180.721 -90)
		(property "Reference" "R322"
			(at 0 0 90)
			(layer "B.SilkS")
			(hide yes)
			(effects
				(font
					(size 1.27 1.27)
				)
				(justify mirror)
			)
		)
		(property "Value" "0R2J-2-GP"
			(at -0.064008 -3.993896 270)
			(unlocked yes)
			(layer "B.Fab")
			(hide yes)
			(effects
				(font
					(size 1.016 1.016)
					(thickness 0.1524)
				)
				(justify mirror)
			)
		)
		(property "Device Type" "R402H16"
			(at -0.064008 -5.517896 270)
			(unlocked yes)
			(layer "B.Fab")
			(hide yes)
			(effects
				(font
					(size 1.016 1.016)
					(thickness 0.1524)
				)
				(justify mirror)
			)
		)
		(duplicate_pad_numbers_are_jumpers no)
		(fp_line
			(start -0.508 -0.9398)
			(end 0.508 -0.9398)
			(stroke
				(width 0.1524)
				(type default)
			)
			(layer "B.SilkS")
		)
		(fp_line
			(start 0.508 -0.9398)
			(end 0.508 0.9398)
			(stroke
				(width 0.1524)
				(type default)
			)
			(layer "B.SilkS")
		)
		(fp_rect
			(start 0.508 0.9398)
			(end -0.508 -0.9398)
			(stroke
				(width 0)
				(type default)
			)
			(fill no)
			(layer "B.CrtYd")
		)
		(fp_rect
			(start 0.508 0.9398)
			(end -0.508 -0.9398)
			(stroke
				(width 0)
				(type default)
			)
			(fill no)
			(layer "B.Fab")
		)
		(pad "1" smd custom
			(at 0 -0.4445 90)
			(size 0.1397 0.1397)
			(layers "B.Cu" "B.Mask" "B.Paste")
			(net "ADC_P0V9_E")
			(options
				(clearance outline)
				(anchor circle)
			)
			(primitives
				(gr_poly
					(pts
						(arc
							(start -0.1778 0.2794)
							(mid -0.249642 0.249642)
							(end -0.2794 0.1778)
						)
						(arc
							(start -0.2794 -0.1778)
							(mid -0.249642 -0.249642)
							(end -0.1778 -0.2794)
						)
						(arc
							(start 0.1778 -0.2794)
							(mid 0.249642 -0.249642)
							(end 0.2794 -0.1778)
						)
						(arc
							(start 0.2794 0.1778)
							(mid 0.249642 0.249642)
							(end 0.1778 0.2794)
						)
					)
					(width 0)
					(fill yes)
				)
			)
		)
		(pad "2" smd custom
			(at 0 0.4445 90)
			(size 0.1397 0.1397)
			(layers "B.Cu" "B.Mask" "B.Paste")
			(net "ADC_P0V9_E_BMC")
			(options
				(clearance outline)
				(anchor circle)
			)
			(primitives
				(gr_poly
					(pts
						(arc
							(start -0.1778 0.2794)
							(mid -0.249642 0.249642)
							(end -0.2794 0.1778)
						)
						(arc
							(start -0.2794 -0.1778)
							(mid -0.249642 -0.249642)
							(end -0.1778 -0.2794)
						)
						(arc
							(start 0.1778 -0.2794)
							(mid 0.249642 -0.249642)
							(end 0.2794 -0.1778)
						)
						(arc
							(start 0.2794 0.1778)
							(mid 0.249642 0.249642)
							(end 0.1778 0.2794)
						)
					)
					(width 0)
					(fill yes)
				)
			)
		)
	)
	(footprint ""
		(layer "B.Cu")
		(at 113.29797 -82.931 -90)
		(property "Reference" "SC1233"
			(at 0 0 90)
			(layer "B.SilkS")
			(hide yes)
			(effects
				(font
					(size 1.27 1.27)
				)
				(justify mirror)
			)
		)
		(property "Value" "SCD1U6D3V1KX-GP"
			(at 2.8321 -1.7399 270)
			(unlocked yes)
			(layer "B.Fab")
			(hide yes)
			(effects
				(font
					(size 1.016 1.016)
					(thickness 0.1524)
				)
				(justify mirror)
			)
		)
		(property "Device Type" "C0201H13"
			(at 2.8321 -3.2639 270)
			(unlocked yes)
			(layer "B.Fab")
			(hide yes)
			(effects
				(font
					(size 1.016 1.016)
					(thickness 0.1524)
				)
				(justify mirror)
			)
		)
		(duplicate_pad_numbers_are_jumpers no)
		(fp_rect
			(start 0.2794 0.6477)
			(end -0.2794 -0.6477)
			(stroke
				(width 0)
				(type default)
			)
			(fill no)
			(layer "B.CrtYd")
		)
		(fp_rect
			(start 0.2794 0.6477)
			(end -0.2794 -0.6477)
			(stroke
				(width 0)
				(type default)
			)
			(fill no)
			(layer "B.Fab")
		)
		(pad "1" smd custom
			(at 0 -0.2794 90)
			(size 0.0762 0.0762)
			(layers "B.Cu" "B.Mask" "B.Paste")
			(net "P1V8_E")
			(options
				(clearance outline)
				(anchor circle)
			)
			(primitives
				(gr_poly
					(pts
						(arc
							(start 0.1524 0.127)
							(mid 0.137521 0.162921)
							(end 0.1016 0.1778)
						)
						(arc
							(start -0.1016 0.1778)
							(mid -0.137521 0.162921)
							(end -0.1524 0.127)
						)
						(arc
							(start -0.1524 -0.127)
							(mid -0.137521 -0.162921)
							(end -0.1016 -0.1778)
						)
						(arc
							(start 0.1016 -0.1778)
							(mid 0.137521 -0.162921)
							(end 0.1524 -0.127)
						)
					)
					(width 0)
					(fill yes)
				)
			)
		)
		(pad "2" smd custom
			(at 0 0.2794 90)
			(size 0.0762 0.0762)
			(layers "B.Cu" "B.Mask" "B.Paste")
			(net "GND")
			(options
				(clearance outline)
				(anchor circle)
			)
			(primitives
				(gr_poly
					(pts
						(arc
							(start 0.1524 0.127)
							(mid 0.137521 0.162921)
							(end 0.1016 0.1778)
						)
						(arc
							(start -0.1016 0.1778)
							(mid -0.137521 0.162921)
							(end -0.1524 0.127)
						)
						(arc
							(start -0.1524 -0.127)
							(mid -0.137521 -0.162921)
							(end -0.1016 -0.1778)
						)
						(arc
							(start 0.1016 -0.1778)
							(mid 0.137521 -0.162921)
							(end 0.1524 -0.127)
						)
					)
					(width 0)
					(fill yes)
				)
			)
		)
	)
	(footprint ""
		(layer "B.Cu")
		(at 81.661 -21.209 180)
		(property "Reference" "PR184"
			(at 0 0 0)
			(layer "B.SilkS")
			(hide yes)
			(effects
				(font
					(size 1.27 1.27)
				)
				(justify mirror)
			)
		)
		(property "Value" "10KR2F-2-GP"
			(at -0.064008 -3.993896 180)
			(unlocked yes)
			(layer "B.Fab")
			(hide yes)
			(effects
				(font
					(size 1.016 1.016)
					(thickness 0.1524)
				)
				(justify mirror)
			)
		)
		(property "Device Type" "R402H16"
			(at -0.064008 -5.517896 180)
			(unlocked yes)
			(layer "B.Fab")
			(hide yes)
			(effects
				(font
					(size 1.016 1.016)
					(thickness 0.1524)
				)
				(justify mirror)
			)
		)
		(duplicate_pad_numbers_are_jumpers no)
		(fp_line
			(start 0.508 -0.9398)
			(end 0.508 0.9398)
			(stroke
				(width 0.1524)
				(type default)
			)
			(layer "B.SilkS")
		)
		(fp_line
			(start -0.508 -0.9398)
			(end 0.508 -0.9398)
			(stroke
				(width 0.1524)
				(type default)
			)
			(layer "B.SilkS")
		)
		(fp_rect
			(start 0.508 0.9398)
			(end -0.508 -0.9398)
			(stroke
				(width 0)
				(type default)
			)
			(fill no)
			(layer "B.CrtYd")
		)
		(fp_rect
			(start 0.508 0.9398)
			(end -0.508 -0.9398)
			(stroke
				(width 0)
				(type default)
			)
			(fill no)
			(layer "B.Fab")
		)
		(pad "1" smd custom
			(at 0 -0.4445)
			(size 0.1397 0.1397)
			(layers "B.Cu" "B.Mask" "B.Paste")
			(net "AGND_P0V9_C")
			(options
				(clearance outline)
				(anchor circle)
			)
			(primitives
				(gr_poly
					(pts
						(arc
							(start -0.1778 0.2794)
							(mid -0.249642 0.249642)
							(end -0.2794 0.1778)
						)
						(arc
							(start -0.2794 -0.1778)
							(mid -0.249642 -0.249642)
							(end -0.1778 -0.2794)
						)
						(arc
							(start 0.1778 -0.2794)
							(mid 0.249642 -0.249642)
							(end 0.2794 -0.1778)
						)
						(arc
							(start 0.2794 0.1778)
							(mid 0.249642 0.249642)
							(end 0.1778 0.2794)
						)
					)
					(width 0)
					(fill yes)
				)
			)
		)
		(pad "2" smd custom
			(at 0 0.4445)
			(size 0.1397 0.1397)
			(layers "B.Cu" "B.Mask" "B.Paste")
			(net "VT235_IMAX")
			(options
				(clearance outline)
				(anchor circle)
			)
			(primitives
				(gr_poly
					(pts
						(arc
							(start -0.1778 0.2794)
							(mid -0.249642 0.249642)
							(end -0.2794 0.1778)
						)
						(arc
							(start -0.2794 -0.1778)
							(mid -0.249642 -0.249642)
							(end -0.1778 -0.2794)
						)
						(arc
							(start 0.1778 -0.2794)
							(mid 0.249642 -0.249642)
							(end 0.2794 -0.1778)
						)
						(arc
							(start 0.2794 0.1778)
							(mid 0.249642 0.249642)
							(end 0.1778 0.2794)
						)
					)
					(width 0)
					(fill yes)
				)
			)
		)
	)
	(footprint ""
		(layer "B.Cu")
		(at 165.354 -114.427 180)
		(property "Reference" "SR855"
			(at 0 0 0)
			(layer "B.SilkS")
			(hide yes)
			(effects
				(font
					(size 1.27 1.27)
				)
				(justify mirror)
			)
		)
		(property "Value" "10KR2F-2-GP"
			(at -0.064008 -3.993896 180)
			(unlocked yes)
			(layer "B.Fab")
			(hide yes)
			(effects
				(font
					(size 1.016 1.016)
					(thickness 0.1524)
				)
				(justify mirror)
			)
		)
		(property "Device Type" "R402H16"
			(at -0.064008 -5.517896 180)
			(unlocked yes)
			(layer "B.Fab")
			(hide yes)
			(effects
				(font
					(size 1.016 1.016)
					(thickness 0.1524)
				)
				(justify mirror)
			)
		)
		(duplicate_pad_numbers_are_jumpers no)
		(fp_line
			(start 0.508 -0.9398)
			(end 0.508 0.9398)
			(stroke
				(width 0.1524)
				(type default)
			)
			(layer "B.SilkS")
		)
		(fp_line
			(start -0.508 -0.9398)
			(end 0.508 -0.9398)
			(stroke
				(width 0.1524)
				(type default)
			)
			(layer "B.SilkS")
		)
		(fp_rect
			(start 0.508 0.9398)
			(end -0.508 -0.9398)
			(stroke
				(width 0)
				(type default)
			)
			(fill no)
			(layer "B.CrtYd")
		)
		(fp_rect
			(start 0.508 0.9398)
			(end -0.508 -0.9398)
			(stroke
				(width 0)
				(type default)
			)
			(fill no)
			(layer "B.Fab")
		)
		(pad "1" smd custom
			(at 0 -0.4445)
			(size 0.1397 0.1397)
			(layers "B.Cu" "B.Mask" "B.Paste")
			(net "P3V3_STBY_R4")
			(options
				(clearance outline)
				(anchor circle)
			)
			(primitives
				(gr_poly
					(pts
						(arc
							(start -0.1778 0.2794)
							(mid -0.249642 0.249642)
							(end -0.2794 0.1778)
						)
						(arc
							(start -0.2794 -0.1778)
							(mid -0.249642 -0.249642)
							(end -0.1778 -0.2794)
						)
						(arc
							(start 0.1778 -0.2794)
							(mid 0.249642 -0.249642)
							(end 0.2794 -0.1778)
						)
						(arc
							(start 0.2794 0.1778)
							(mid 0.249642 0.249642)
							(end 0.1778 0.2794)
						)
					)
					(width 0)
					(fill yes)
				)
			)
		)
		(pad "2" smd custom
			(at 0 0.4445)
			(size 0.1397 0.1397)
			(layers "B.Cu" "B.Mask" "B.Paste")
			(net "P3V3_STBY_G4")
			(options
				(clearance outline)
				(anchor circle)
			)
			(primitives
				(gr_poly
					(pts
						(arc
							(start -0.1778 0.2794)
							(mid -0.249642 0.249642)
							(end -0.2794 0.1778)
						)
						(arc
							(start -0.2794 -0.1778)
							(mid -0.249642 -0.249642)
							(end -0.1778 -0.2794)
						)
						(arc
							(start 0.1778 -0.2794)
							(mid 0.249642 -0.249642)
							(end 0.2794 -0.1778)
						)
						(arc
							(start 0.2794 0.1778)
							(mid 0.249642 0.249642)
							(end 0.1778 0.2794)
						)
					)
					(width 0)
					(fill yes)
				)
			)
		)
	)
	(footprint ""
		(layer "B.Cu")
		(at 100.057966 -56.642 180)
		(property "Reference" "SR642"
			(at 0 0 0)
			(layer "B.SilkS")
			(hide yes)
			(effects
				(font
					(size 1.27 1.27)
				)
				(justify mirror)
			)
		)
		(property "Value" "10KR2F-2-GP"
			(at -0.064008 -3.993896 180)
			(unlocked yes)
			(layer "B.Fab")
			(hide yes)
			(effects
				(font
					(size 1.016 1.016)
					(thickness 0.1524)
				)
				(justify mirror)
			)
		)
		(property "Device Type" "R402H16"
			(at -0.064008 -5.517896 180)
			(unlocked yes)
			(layer "B.Fab")
			(hide yes)
			(effects
				(font
					(size 1.016 1.016)
					(thickness 0.1524)
				)
				(justify mirror)
			)
		)
		(duplicate_pad_numbers_are_jumpers no)
		(fp_line
			(start 0.508 -0.9398)
			(end 0.508 0.9398)
			(stroke
				(width 0.1524)
				(type default)
			)
			(layer "B.SilkS")
		)
		(fp_line
			(start -0.508 -0.9398)
			(end 0.508 -0.9398)
			(stroke
				(width 0.1524)
				(type default)
			)
			(layer "B.SilkS")
		)
		(fp_rect
			(start 0.508 0.9398)
			(end -0.508 -0.9398)
			(stroke
				(width 0)
				(type default)
			)
			(fill no)
			(layer "B.CrtYd")
		)
		(fp_rect
			(start 0.508 0.9398)
			(end -0.508 -0.9398)
			(stroke
				(width 0)
				(type default)
			)
			(fill no)
			(layer "B.Fab")
		)
		(pad "1" smd custom
			(at 0 -0.4445)
			(size 0.1397 0.1397)
			(layers "B.Cu" "B.Mask" "B.Paste")
			(net "P1V8_C")
			(options
				(clearance outline)
				(anchor circle)
			)
			(primitives
				(gr_poly
					(pts
						(arc
							(start -0.1778 0.2794)
							(mid -0.249642 0.249642)
							(end -0.2794 0.1778)
						)
						(arc
							(start -0.2794 -0.1778)
							(mid -0.249642 -0.249642)
							(end -0.1778 -0.2794)
						)
						(arc
							(start 0.1778 -0.2794)
							(mid 0.249642 -0.249642)
							(end 0.2794 -0.1778)
						)
						(arc
							(start 0.2794 0.1778)
							(mid 0.249642 0.249642)
							(end 0.1778 0.2794)
						)
					)
					(width 0)
					(fill yes)
				)
			)
		)
		(pad "2" smd custom
			(at 0 0.4445)
			(size 0.1397 0.1397)
			(layers "B.Cu" "B.Mask" "B.Paste")
			(net "AVSO_IDDTN18")
			(options
				(clearance outline)
				(anchor circle)
			)
			(primitives
				(gr_poly
					(pts
						(arc
							(start -0.1778 0.2794)
							(mid -0.249642 0.249642)
							(end -0.2794 0.1778)
						)
						(arc
							(start -0.2794 -0.1778)
							(mid -0.249642 -0.249642)
							(end -0.1778 -0.2794)
						)
						(arc
							(start 0.1778 -0.2794)
							(mid 0.249642 -0.249642)
							(end 0.2794 -0.1778)
						)
						(arc
							(start 0.2794 0.1778)
							(mid 0.249642 0.249642)
							(end 0.1778 0.2794)
						)
					)
					(width 0)
					(fill yes)
				)
			)
		)
	)
	(footprint ""
		(layer "B.Cu")
		(at 308.102 -160.655 180)
		(property "Reference" "R462"
			(at 0 0 0)
			(layer "B.SilkS")
			(hide yes)
			(effects
				(font
					(size 1.27 1.27)
				)
				(justify mirror)
			)
		)
		(property "Value" "0R2J-2-GP"
			(at -0.064008 -3.993896 180)
			(unlocked yes)
			(layer "B.Fab")
			(hide yes)
			(effects
				(font
					(size 1.016 1.016)
					(thickness 0.1524)
				)
				(justify mirror)
			)
		)
		(property "Device Type" "R402H16"
			(at -0.064008 -5.517896 180)
			(unlocked yes)
			(layer "B.Fab")
			(hide yes)
			(effects
				(font
					(size 1.016 1.016)
					(thickness 0.1524)
				)
				(justify mirror)
			)
		)
		(duplicate_pad_numbers_are_jumpers no)
		(fp_line
			(start 0.508 -0.9398)
			(end 0.508 0.9398)
			(stroke
				(width 0.1524)
				(type default)
			)
			(layer "B.SilkS")
		)
		(fp_line
			(start -0.508 -0.9398)
			(end 0.508 -0.9398)
			(stroke
				(width 0.1524)
				(type default)
			)
			(layer "B.SilkS")
		)
		(fp_rect
			(start 0.508 0.9398)
			(end -0.508 -0.9398)
			(stroke
				(width 0)
				(type default)
			)
			(fill no)
			(layer "B.CrtYd")
		)
		(fp_rect
			(start 0.508 0.9398)
			(end -0.508 -0.9398)
			(stroke
				(width 0)
				(type default)
			)
			(fill no)
			(layer "B.Fab")
		)
		(pad "1" smd custom
			(at 0 -0.4445)
			(size 0.1397 0.1397)
			(layers "B.Cu" "B.Mask" "B.Paste")
			(net "BMC_I2C_SDA_9")
			(options
				(clearance outline)
				(anchor circle)
			)
			(primitives
				(gr_poly
					(pts
						(arc
							(start -0.1778 0.2794)
							(mid -0.249642 0.249642)
							(end -0.2794 0.1778)
						)
						(arc
							(start -0.2794 -0.1778)
							(mid -0.249642 -0.249642)
							(end -0.1778 -0.2794)
						)
						(arc
							(start 0.1778 -0.2794)
							(mid 0.249642 -0.249642)
							(end 0.2794 -0.1778)
						)
						(arc
							(start 0.2794 0.1778)
							(mid 0.249642 0.249642)
							(end 0.1778 0.2794)
						)
					)
					(width 0)
					(fill yes)
				)
			)
		)
		(pad "2" smd custom
			(at 0 0.4445)
			(size 0.1397 0.1397)
			(layers "B.Cu" "B.Mask" "B.Paste")
			(net "BMC0_SMB9_DAT")
			(options
				(clearance outline)
				(anchor circle)
			)
			(primitives
				(gr_poly
					(pts
						(arc
							(start -0.1778 0.2794)
							(mid -0.249642 0.249642)
							(end -0.2794 0.1778)
						)
						(arc
							(start -0.2794 -0.1778)
							(mid -0.249642 -0.249642)
							(end -0.1778 -0.2794)
						)
						(arc
							(start 0.1778 -0.2794)
							(mid 0.249642 -0.249642)
							(end 0.2794 -0.1778)
						)
						(arc
							(start 0.2794 0.1778)
							(mid 0.249642 0.249642)
							(end 0.1778 0.2794)
						)
					)
					(width 0)
					(fill yes)
				)
			)
		)
	)
	(footprint ""
		(layer "B.Cu")
		(at 117.037612 -221.996)
		(property "Reference" "SR889"
			(at 0 0 0)
			(layer "B.SilkS")
			(hide yes)
			(effects
				(font
					(size 1.27 1.27)
				)
				(justify mirror)
			)
		)
		(property "Value" "0R2J-2-GP"
			(at -0.064008 -3.993896 0)
			(unlocked yes)
			(layer "B.Fab")
			(hide yes)
			(effects
				(font
					(size 1.016 1.016)
					(thickness 0.1524)
				)
				(justify mirror)
			)
		)
		(property "Device Type" "R402H16"
			(at -0.064008 -5.517896 0)
			(unlocked yes)
			(layer "B.Fab")
			(hide yes)
			(effects
				(font
					(size 1.016 1.016)
					(thickness 0.1524)
				)
				(justify mirror)
			)
		)
		(duplicate_pad_numbers_are_jumpers no)
		(fp_line
			(start -0.508 -0.9398)
			(end 0.508 -0.9398)
			(stroke
				(width 0.1524)
				(type default)
			)
			(layer "B.SilkS")
		)
		(fp_line
			(start 0.508 -0.9398)
			(end 0.508 0.9398)
			(stroke
				(width 0.1524)
				(type default)
			)
			(layer "B.SilkS")
		)
		(fp_rect
			(start 0.508 0.9398)
			(end -0.508 -0.9398)
			(stroke
				(width 0)
				(type default)
			)
			(fill no)
			(layer "B.CrtYd")
		)
		(fp_rect
			(start 0.508 0.9398)
			(end -0.508 -0.9398)
			(stroke
				(width 0)
				(type default)
			)
			(fill no)
			(layer "B.Fab")
		)
		(pad "1" smd custom
			(at 0 -0.4445 180)
			(size 0.1397 0.1397)
			(layers "B.Cu" "B.Mask" "B.Paste")
			(net "SAS_GF_EXP_RX_DN7")
			(options
				(clearance outline)
				(anchor circle)
			)
			(primitives
				(gr_poly
					(pts
						(arc
							(start -0.1778 0.2794)
							(mid -0.249642 0.249642)
							(end -0.2794 0.1778)
						)
						(arc
							(start -0.2794 -0.1778)
							(mid -0.249642 -0.249642)
							(end -0.1778 -0.2794)
						)
						(arc
							(start 0.1778 -0.2794)
							(mid 0.249642 -0.249642)
							(end 0.2794 -0.1778)
						)
						(arc
							(start 0.2794 0.1778)
							(mid 0.249642 0.249642)
							(end 0.1778 0.2794)
						)
					)
					(width 0)
					(fill yes)
				)
			)
		)
		(pad "2" smd custom
			(at 0 0.4445 180)
			(size 0.1397 0.1397)
			(layers "B.Cu" "B.Mask" "B.Paste")
			(net "SAS_HDD_CONN_SER_RX7_N")
			(options
				(clearance outline)
				(anchor circle)
			)
			(primitives
				(gr_poly
					(pts
						(arc
							(start -0.1778 0.2794)
							(mid -0.249642 0.249642)
							(end -0.2794 0.1778)
						)
						(arc
							(start -0.2794 -0.1778)
							(mid -0.249642 -0.249642)
							(end -0.1778 -0.2794)
						)
						(arc
							(start 0.1778 -0.2794)
							(mid 0.249642 -0.249642)
							(end 0.2794 -0.1778)
						)
						(arc
							(start 0.2794 0.1778)
							(mid 0.249642 0.249642)
							(end 0.1778 0.2794)
						)
					)
					(width 0)
					(fill yes)
				)
			)
		)
	)
	(footprint ""
		(layer "B.Cu")
		(at 102.49916 -31.623)
		(property "Reference" "SC873"
			(at 0 0 0)
			(layer "B.SilkS")
			(hide yes)
			(effects
				(font
					(size 1.27 1.27)
				)
				(justify mirror)
			)
		)
		(property "Value" "SCD22U6D3V1MX-1-GP"
			(at 2.8321 -1.7399 0)
			(unlocked yes)
			(layer "B.Fab")
			(hide yes)
			(effects
				(font
					(size 1.016 1.016)
					(thickness 0.1524)
				)
				(justify mirror)
			)
		)
		(property "Device Type" "C0201H13"
			(at 2.8321 -3.2639 0)
			(unlocked yes)
			(layer "B.Fab")
			(hide yes)
			(effects
				(font
					(size 1.016 1.016)
					(thickness 0.1524)
				)
				(justify mirror)
			)
		)
		(duplicate_pad_numbers_are_jumpers no)
		(fp_rect
			(start 0.2794 0.6477)
			(end -0.2794 -0.6477)
			(stroke
				(width 0)
				(type default)
			)
			(fill no)
			(layer "B.CrtYd")
		)
		(fp_rect
			(start 0.2794 0.6477)
			(end -0.2794 -0.6477)
			(stroke
				(width 0)
				(type default)
			)
			(fill no)
			(layer "B.Fab")
		)
		(pad "1" smd custom
			(at 0 -0.2794 180)
			(size 0.0762 0.0762)
			(layers "B.Cu" "B.Mask" "B.Paste")
			(net "PCIE_SAS_C_CPU_RX_P6")
			(options
				(clearance outline)
				(anchor circle)
			)
			(primitives
				(gr_poly
					(pts
						(arc
							(start 0.1524 0.127)
							(mid 0.137521 0.162921)
							(end 0.1016 0.1778)
						)
						(arc
							(start -0.1016 0.1778)
							(mid -0.137521 0.162921)
							(end -0.1524 0.127)
						)
						(arc
							(start -0.1524 -0.127)
							(mid -0.137521 -0.162921)
							(end -0.1016 -0.1778)
						)
						(arc
							(start 0.1016 -0.1778)
							(mid 0.137521 -0.162921)
							(end 0.1524 -0.127)
						)
					)
					(width 0)
					(fill yes)
				)
			)
		)
		(pad "2" smd custom
			(at 0 0.2794 180)
			(size 0.0762 0.0762)
			(layers "B.Cu" "B.Mask" "B.Paste")
			(net "PCIE_SAS_CPU_RX_P6")
			(options
				(clearance outline)
				(anchor circle)
			)
			(primitives
				(gr_poly
					(pts
						(arc
							(start 0.1524 0.127)
							(mid 0.137521 0.162921)
							(end 0.1016 0.1778)
						)
						(arc
							(start -0.1016 0.1778)
							(mid -0.137521 0.162921)
							(end -0.1524 0.127)
						)
						(arc
							(start -0.1524 -0.127)
							(mid -0.137521 -0.162921)
							(end -0.1016 -0.1778)
						)
						(arc
							(start 0.1016 -0.1778)
							(mid 0.137521 -0.162921)
							(end 0.1524 -0.127)
						)
					)
					(width 0)
					(fill yes)
				)
			)
		)
	)
	(footprint ""
		(layer "B.Cu")
		(at 111.614966 -28.829 90)
		(property "Reference" "SR656"
			(at 0 0 90)
			(layer "B.SilkS")
			(hide yes)
			(effects
				(font
					(size 1.27 1.27)
				)
				(justify mirror)
			)
		)
		(property "Value" "0R2J-2-GP"
			(at -0.064008 -3.993896 90)
			(unlocked yes)
			(layer "B.Fab")
			(hide yes)
			(effects
				(font
					(size 1.016 1.016)
					(thickness 0.1524)
				)
				(justify mirror)
			)
		)
		(property "Device Type" "R402H16"
			(at -0.064008 -5.517896 90)
			(unlocked yes)
			(layer "B.Fab")
			(hide yes)
			(effects
				(font
					(size 1.016 1.016)
					(thickness 0.1524)
				)
				(justify mirror)
			)
		)
		(duplicate_pad_numbers_are_jumpers no)
		(fp_line
			(start 0.508 -0.9398)
			(end 0.508 0.9398)
			(stroke
				(width 0.1524)
				(type default)
			)
			(layer "B.SilkS")
		)
		(fp_line
			(start -0.508 -0.9398)
			(end 0.508 -0.9398)
			(stroke
				(width 0.1524)
				(type default)
			)
			(layer "B.SilkS")
		)
		(fp_rect
			(start 0.508 0.9398)
			(end -0.508 -0.9398)
			(stroke
				(width 0)
				(type default)
			)
			(fill no)
			(layer "B.CrtYd")
		)
		(fp_rect
			(start 0.508 0.9398)
			(end -0.508 -0.9398)
			(stroke
				(width 0)
				(type default)
			)
			(fill no)
			(layer "B.Fab")
		)
		(pad "1" smd custom
			(at 0 -0.4445 270)
			(size 0.1397 0.1397)
			(layers "B.Cu" "B.Mask" "B.Paste")
			(net "SYS_RST_N_0")
			(options
				(clearance outline)
				(anchor circle)
			)
			(primitives
				(gr_poly
					(pts
						(arc
							(start -0.1778 0.2794)
							(mid -0.249642 0.249642)
							(end -0.2794 0.1778)
						)
						(arc
							(start -0.2794 -0.1778)
							(mid -0.249642 -0.249642)
							(end -0.1778 -0.2794)
						)
						(arc
							(start 0.1778 -0.2794)
							(mid 0.249642 -0.249642)
							(end 0.2794 -0.1778)
						)
						(arc
							(start 0.2794 0.1778)
							(mid 0.249642 0.249642)
							(end 0.1778 0.2794)
						)
					)
					(width 0)
					(fill yes)
				)
			)
		)
		(pad "2" smd custom
			(at 0 0.4445 270)
			(size 0.1397 0.1397)
			(layers "B.Cu" "B.Mask" "B.Paste")
			(net "SYS_RST")
			(options
				(clearance outline)
				(anchor circle)
			)
			(primitives
				(gr_poly
					(pts
						(arc
							(start -0.1778 0.2794)
							(mid -0.249642 0.249642)
							(end -0.2794 0.1778)
						)
						(arc
							(start -0.2794 -0.1778)
							(mid -0.249642 -0.249642)
							(end -0.1778 -0.2794)
						)
						(arc
							(start 0.1778 -0.2794)
							(mid 0.249642 -0.249642)
							(end 0.2794 -0.1778)
						)
						(arc
							(start 0.2794 0.1778)
							(mid 0.249642 0.249642)
							(end 0.1778 0.2794)
						)
					)
					(width 0)
					(fill yes)
				)
			)
		)
	)
	(footprint ""
		(layer "B.Cu")
		(at 124.403612 -212.344 90)
		(property "Reference" "SR910"
			(at 0 0 90)
			(layer "B.SilkS")
			(hide yes)
			(effects
				(font
					(size 1.27 1.27)
				)
				(justify mirror)
			)
		)
		(property "Value" "4K7R2F-GP"
			(at -0.064008 -3.993896 90)
			(unlocked yes)
			(layer "B.Fab")
			(hide yes)
			(effects
				(font
					(size 1.016 1.016)
					(thickness 0.1524)
				)
				(justify mirror)
			)
		)
		(property "Device Type" "R402H16"
			(at -0.064008 -5.517896 90)
			(unlocked yes)
			(layer "B.Fab")
			(hide yes)
			(effects
				(font
					(size 1.016 1.016)
					(thickness 0.1524)
				)
				(justify mirror)
			)
		)
		(duplicate_pad_numbers_are_jumpers no)
		(fp_line
			(start 0.508 -0.9398)
			(end 0.508 0.9398)
			(stroke
				(width 0.1524)
				(type default)
			)
			(layer "B.SilkS")
		)
		(fp_line
			(start -0.508 -0.9398)
			(end 0.508 -0.9398)
			(stroke
				(width 0.1524)
				(type default)
			)
			(layer "B.SilkS")
		)
		(fp_rect
			(start 0.508 0.9398)
			(end -0.508 -0.9398)
			(stroke
				(width 0)
				(type default)
			)
			(fill no)
			(layer "B.CrtYd")
		)
		(fp_rect
			(start 0.508 0.9398)
			(end -0.508 -0.9398)
			(stroke
				(width 0)
				(type default)
			)
			(fill no)
			(layer "B.Fab")
		)
		(pad "1" smd custom
			(at 0 -0.4445 270)
			(size 0.1397 0.1397)
			(layers "B.Cu" "B.Mask" "B.Paste")
			(net "REDV_I2C_SEL1A")
			(options
				(clearance outline)
				(anchor circle)
			)
			(primitives
				(gr_poly
					(pts
						(arc
							(start -0.1778 0.2794)
							(mid -0.249642 0.249642)
							(end -0.2794 0.1778)
						)
						(arc
							(start -0.2794 -0.1778)
							(mid -0.249642 -0.249642)
							(end -0.1778 -0.2794)
						)
						(arc
							(start 0.1778 -0.2794)
							(mid 0.249642 -0.249642)
							(end 0.2794 -0.1778)
						)
						(arc
							(start 0.2794 0.1778)
							(mid 0.249642 0.249642)
							(end 0.1778 0.2794)
						)
					)
					(width 0)
					(fill yes)
				)
			)
		)
		(pad "2" smd custom
			(at 0 0.4445 270)
			(size 0.1397 0.1397)
			(layers "B.Cu" "B.Mask" "B.Paste")
			(net "GND")
			(options
				(clearance outline)
				(anchor circle)
			)
			(primitives
				(gr_poly
					(pts
						(arc
							(start -0.1778 0.2794)
							(mid -0.249642 0.249642)
							(end -0.2794 0.1778)
						)
						(arc
							(start -0.2794 -0.1778)
							(mid -0.249642 -0.249642)
							(end -0.1778 -0.2794)
						)
						(arc
							(start 0.1778 -0.2794)
							(mid 0.249642 -0.249642)
							(end 0.2794 -0.1778)
						)
						(arc
							(start 0.2794 0.1778)
							(mid 0.249642 0.249642)
							(end 0.1778 0.2794)
						)
					)
					(width 0)
					(fill yes)
				)
			)
		)
	)
	(footprint ""
		(layer "B.Cu")
		(at 101.454966 -43.307 -90)
		(property "Reference" "SC1061"
			(at 0 0 90)
			(layer "B.SilkS")
			(hide yes)
			(effects
				(font
					(size 1.27 1.27)
				)
				(justify mirror)
			)
		)
		(property "Value" "SCD1U16V2KX-3GP"
			(at -1.1811 -2.7051 270)
			(unlocked yes)
			(layer "B.Fab")
			(hide yes)
			(effects
				(font
					(size 1.016 1.016)
					(thickness 0.1524)
				)
				(justify mirror)
			)
		)
		(property "Device Type" "C402H22"
			(at -1.1811 -4.2291 270)
			(unlocked yes)
			(layer "B.Fab")
			(hide yes)
			(effects
				(font
					(size 1.016 1.016)
					(thickness 0.1524)
				)
				(justify mirror)
			)
		)
		(duplicate_pad_numbers_are_jumpers no)
		(fp_rect
			(start 0.4318 0.9525)
			(end -0.4318 -0.9525)
			(stroke
				(width 0)
				(type default)
			)
			(fill no)
			(layer "B.CrtYd")
		)
		(fp_rect
			(start 0.4318 0.9525)
			(end -0.4318 -0.9525)
			(stroke
				(width 0)
				(type default)
			)
			(fill no)
			(layer "B.Fab")
		)
		(pad "1" smd custom
			(at 0 -0.4445 90)
			(size 0.1524 0.1524)
			(layers "B.Cu" "B.Mask" "B.Paste")
			(net "P0V955_C")
			(options
				(clearance outline)
				(anchor circle)
			)
			(primitives
				(gr_poly
					(pts
						(arc
							(start 0.3048 0.2032)
							(mid 0.275042 0.275042)
							(end 0.2032 0.3048)
						)
						(arc
							(start -0.2032 0.3048)
							(mid -0.275042 0.275042)
							(end -0.3048 0.2032)
						)
						(arc
							(start -0.3048 -0.2032)
							(mid -0.275042 -0.275042)
							(end -0.2032 -0.3048)
						)
						(arc
							(start 0.2032 -0.3048)
							(mid 0.275042 -0.275042)
							(end 0.3048 -0.2032)
						)
					)
					(width 0)
					(fill yes)
				)
			)
		)
		(pad "2" smd custom
			(at 0 0.4445 90)
			(size 0.1524 0.1524)
			(layers "B.Cu" "B.Mask" "B.Paste")
			(net "GND")
			(options
				(clearance outline)
				(anchor circle)
			)
			(primitives
				(gr_poly
					(pts
						(arc
							(start 0.3048 0.2032)
							(mid 0.275042 0.275042)
							(end 0.2032 0.3048)
						)
						(arc
							(start -0.2032 0.3048)
							(mid -0.275042 0.275042)
							(end -0.3048 0.2032)
						)
						(arc
							(start -0.3048 -0.2032)
							(mid -0.275042 -0.275042)
							(end -0.2032 -0.3048)
						)
						(arc
							(start 0.2032 -0.3048)
							(mid 0.275042 -0.275042)
							(end 0.3048 -0.2032)
						)
					)
					(width 0)
					(fill yes)
				)
			)
		)
	)
	(footprint ""
		(layer "B.Cu")
		(at 28.398216 -232.33888)
		(property "Reference" "R505"
			(at 0 0 0)
			(layer "B.SilkS")
			(hide yes)
			(effects
				(font
					(size 1.27 1.27)
				)
				(justify mirror)
			)
		)
		(property "Value" "0R2J-2-GP"
			(at -0.064008 -3.993896 0)
			(unlocked yes)
			(layer "B.Fab")
			(hide yes)
			(effects
				(font
					(size 1.016 1.016)
					(thickness 0.1524)
				)
				(justify mirror)
			)
		)
		(property "Device Type" "R402H16"
			(at -0.064008 -5.517896 0)
			(unlocked yes)
			(layer "B.Fab")
			(hide yes)
			(effects
				(font
					(size 1.016 1.016)
					(thickness 0.1524)
				)
				(justify mirror)
			)
		)
		(duplicate_pad_numbers_are_jumpers no)
		(fp_line
			(start -0.508 -0.9398)
			(end 0.508 -0.9398)
			(stroke
				(width 0.1524)
				(type default)
			)
			(layer "B.SilkS")
		)
		(fp_line
			(start 0.508 -0.9398)
			(end 0.508 0.9398)
			(stroke
				(width 0.1524)
				(type default)
			)
			(layer "B.SilkS")
		)
		(fp_rect
			(start 0.508 0.9398)
			(end -0.508 -0.9398)
			(stroke
				(width 0)
				(type default)
			)
			(fill no)
			(layer "B.CrtYd")
		)
		(fp_rect
			(start 0.508 0.9398)
			(end -0.508 -0.9398)
			(stroke
				(width 0)
				(type default)
			)
			(fill no)
			(layer "B.Fab")
		)
		(pad "1" smd custom
			(at 0 -0.4445 180)
			(size 0.1397 0.1397)
			(layers "B.Cu" "B.Mask" "B.Paste")
			(net "SAS_HDD_PWR3_PCIE")
			(options
				(clearance outline)
				(anchor circle)
			)
			(primitives
				(gr_poly
					(pts
						(arc
							(start -0.1778 0.2794)
							(mid -0.249642 0.249642)
							(end -0.2794 0.1778)
						)
						(arc
							(start -0.2794 -0.1778)
							(mid -0.249642 -0.249642)
							(end -0.1778 -0.2794)
						)
						(arc
							(start 0.1778 -0.2794)
							(mid 0.249642 -0.249642)
							(end 0.2794 -0.1778)
						)
						(arc
							(start 0.2794 0.1778)
							(mid 0.249642 0.249642)
							(end 0.1778 0.2794)
						)
					)
					(width 0)
					(fill yes)
				)
			)
		)
		(pad "2" smd custom
			(at 0 0.4445 180)
			(size 0.1397 0.1397)
			(layers "B.Cu" "B.Mask" "B.Paste")
			(net "SAS_HDD_PWR3")
			(options
				(clearance outline)
				(anchor circle)
			)
			(primitives
				(gr_poly
					(pts
						(arc
							(start -0.1778 0.2794)
							(mid -0.249642 0.249642)
							(end -0.2794 0.1778)
						)
						(arc
							(start -0.2794 -0.1778)
							(mid -0.249642 -0.249642)
							(end -0.1778 -0.2794)
						)
						(arc
							(start 0.1778 -0.2794)
							(mid 0.249642 -0.249642)
							(end 0.2794 -0.1778)
						)
						(arc
							(start 0.2794 0.1778)
							(mid 0.249642 0.249642)
							(end 0.1778 0.2794)
						)
					)
					(width 0)
					(fill yes)
				)
			)
		)
	)
	(footprint ""
		(layer "B.Cu")
		(at 338.713318 -133.353048 90)
		(property "Reference" "R551"
			(at 0 0 90)
			(layer "B.SilkS")
			(hide yes)
			(effects
				(font
					(size 1.27 1.27)
				)
				(justify mirror)
			)
		)
		(property "Value" "0R3J-0-U-GP"
			(at 0.0254 -2.5146 90)
			(unlocked yes)
			(layer "B.Fab")
			(hide yes)
			(effects
				(font
					(size 1.016 1.016)
					(thickness 0.1524)
				)
				(justify mirror)
			)
		)
		(property "Device Type" "R603H22"
			(at 0.0254 -4.0386 90)
			(unlocked yes)
			(layer "B.Fab")
			(hide yes)
			(effects
				(font
					(size 1.016 1.016)
					(thickness 0.1524)
				)
				(justify mirror)
			)
		)
		(duplicate_pad_numbers_are_jumpers no)
		(fp_line
			(start 0.4826 0)
			(end 0.2032 0)
			(stroke
				(width 0.2032)
				(type default)
			)
			(layer "B.SilkS")
		)
		(fp_line
			(start -0.2032 0)
			(end -0.4826 0)
			(stroke
				(width 0.2032)
				(type default)
			)
			(layer "B.SilkS")
		)
		(fp_rect
			(start 0.5842 1.3335)
			(end -0.5842 -1.3335)
			(stroke
				(width 0)
				(type default)
			)
			(fill no)
			(layer "B.CrtYd")
		)
		(fp_rect
			(start 0.5842 1.3335)
			(end -0.5842 -1.3335)
			(stroke
				(width 0)
				(type default)
			)
			(fill no)
			(layer "B.Fab")
		)
		(pad "1" smd custom
			(at 0 -0.762 270)
			(size 0.2159 0.2159)
			(layers "B.Cu" "B.Mask" "B.Paste")
			(net "USB_P0_DP_R")
			(options
				(clearance outline)
				(anchor circle)
			)
			(primitives
				(gr_poly
					(pts
						(arc
							(start -0.3302 0.4318)
							(mid -0.402042 0.402042)
							(end -0.4318 0.3302)
						)
						(arc
							(start -0.4318 -0.3302)
							(mid -0.402042 -0.402042)
							(end -0.3302 -0.4318)
						)
						(arc
							(start 0.3302 -0.4318)
							(mid 0.402042 -0.402042)
							(end 0.4318 -0.3302)
						)
						(arc
							(start 0.4318 0.3302)
							(mid 0.402042 0.402042)
							(end 0.3302 0.4318)
						)
					)
					(width 0)
					(fill yes)
				)
			)
		)
		(pad "2" smd custom
			(at 0 0.762 270)
			(size 0.2159 0.2159)
			(layers "B.Cu" "B.Mask" "B.Paste")
			(net "USB_P0_DP")
			(options
				(clearance outline)
				(anchor circle)
			)
			(primitives
				(gr_poly
					(pts
						(arc
							(start -0.3302 0.4318)
							(mid -0.402042 0.402042)
							(end -0.4318 0.3302)
						)
						(arc
							(start -0.4318 -0.3302)
							(mid -0.402042 -0.402042)
							(end -0.3302 -0.4318)
						)
						(arc
							(start 0.3302 -0.4318)
							(mid 0.402042 -0.402042)
							(end 0.4318 -0.3302)
						)
						(arc
							(start 0.4318 0.3302)
							(mid 0.402042 0.402042)
							(end 0.3302 0.4318)
						)
					)
					(width 0)
					(fill yes)
				)
			)
		)
	)
	(footprint ""
		(layer "B.Cu")
		(at 96.66097 -103.378 -90)
		(property "Reference" "STP80"
			(at 0 0 90)
			(layer "B.SilkS")
			(hide yes)
			(effects
				(font
					(size 1.27 1.27)
				)
				(justify mirror)
			)
		)
		(property "Value" "TPAD28"
			(at -0.0127 -1.8034 270)
			(unlocked yes)
			(layer "B.Fab")
			(hide yes)
			(effects
				(font
					(size 1.016 1.016)
					(thickness 0.1524)
				)
				(justify mirror)
			)
		)
		(property "Device Type" "TPAD28"
			(at -0.0127 -3.3274 270)
			(unlocked yes)
			(layer "B.Fab")
			(hide yes)
			(effects
				(font
					(size 1.016 1.016)
					(thickness 0.1524)
				)
				(justify mirror)
			)
		)
		(duplicate_pad_numbers_are_jumpers no)
		(fp_poly
			(pts
				(arc
					(start 0 -0.3556)
					(mid 0 0.3556)
					(end 0 -0.3556)
				)
			)
			(stroke
				(width 0)
				(type default)
			)
			(fill no)
			(layer "B.CrtYd")
		)
		(fp_poly
			(pts
				(arc
					(start 0 -0.6096)
					(mid 0 0.6096)
					(end 0 -0.6096)
				)
			)
			(stroke
				(width 0)
				(type default)
			)
			(fill no)
			(layer "B.Fab")
		)
		(pad "1" smd circle
			(at 0 0 90)
			(size 0.7112 0.7112)
			(layers "B.Cu" "B.Mask" "B.Paste")
			(net "EXP_TACH_IN0")
		)
	)
	(footprint ""
		(layer "B.Cu")
		(at 292.862 -164.211 180)
		(property "Reference" "R285"
			(at 0 0 0)
			(layer "B.SilkS")
			(hide yes)
			(effects
				(font
					(size 1.27 1.27)
				)
				(justify mirror)
			)
		)
		(property "Value" "0R2J-2-GP"
			(at -0.064008 -3.993896 180)
			(unlocked yes)
			(layer "B.Fab")
			(hide yes)
			(effects
				(font
					(size 1.016 1.016)
					(thickness 0.1524)
				)
				(justify mirror)
			)
		)
		(property "Device Type" "R402H16"
			(at -0.064008 -5.517896 180)
			(unlocked yes)
			(layer "B.Fab")
			(hide yes)
			(effects
				(font
					(size 1.016 1.016)
					(thickness 0.1524)
				)
				(justify mirror)
			)
		)
		(duplicate_pad_numbers_are_jumpers no)
		(fp_line
			(start 0.508 -0.9398)
			(end 0.508 0.9398)
			(stroke
				(width 0.1524)
				(type default)
			)
			(layer "B.SilkS")
		)
		(fp_line
			(start -0.508 -0.9398)
			(end 0.508 -0.9398)
			(stroke
				(width 0.1524)
				(type default)
			)
			(layer "B.SilkS")
		)
		(fp_rect
			(start 0.508 0.9398)
			(end -0.508 -0.9398)
			(stroke
				(width 0)
				(type default)
			)
			(fill no)
			(layer "B.CrtYd")
		)
		(fp_rect
			(start 0.508 0.9398)
			(end -0.508 -0.9398)
			(stroke
				(width 0)
				(type default)
			)
			(fill no)
			(layer "B.Fab")
		)
		(pad "1" smd custom
			(at 0 -0.4445)
			(size 0.1397 0.1397)
			(layers "B.Cu" "B.Mask" "B.Paste")
			(net "RMII_BMC_PHY_TXD1")
			(options
				(clearance outline)
				(anchor circle)
			)
			(primitives
				(gr_poly
					(pts
						(arc
							(start -0.1778 0.2794)
							(mid -0.249642 0.249642)
							(end -0.2794 0.1778)
						)
						(arc
							(start -0.2794 -0.1778)
							(mid -0.249642 -0.249642)
							(end -0.1778 -0.2794)
						)
						(arc
							(start 0.1778 -0.2794)
							(mid 0.249642 -0.249642)
							(end 0.2794 -0.1778)
						)
						(arc
							(start 0.2794 0.1778)
							(mid 0.249642 0.249642)
							(end 0.1778 0.2794)
						)
					)
					(width 0)
					(fill yes)
				)
			)
		)
		(pad "2" smd custom
			(at 0 0.4445)
			(size 0.1397 0.1397)
			(layers "B.Cu" "B.Mask" "B.Paste")
			(net "RMII0_BMC_C_PHY_TXD1")
			(options
				(clearance outline)
				(anchor circle)
			)
			(primitives
				(gr_poly
					(pts
						(arc
							(start -0.1778 0.2794)
							(mid -0.249642 0.249642)
							(end -0.2794 0.1778)
						)
						(arc
							(start -0.2794 -0.1778)
							(mid -0.249642 -0.249642)
							(end -0.1778 -0.2794)
						)
						(arc
							(start 0.1778 -0.2794)
							(mid 0.249642 -0.249642)
							(end 0.2794 -0.1778)
						)
						(arc
							(start 0.2794 0.1778)
							(mid 0.249642 0.249642)
							(end 0.1778 0.2794)
						)
					)
					(width 0)
					(fill yes)
				)
			)
		)
	)
	(footprint ""
		(layer "B.Cu")
		(at 197.739 -245.999 -90)
		(property "Reference" "R627"
			(at 0 0 90)
			(layer "B.SilkS")
			(hide yes)
			(effects
				(font
					(size 1.27 1.27)
				)
				(justify mirror)
			)
		)
		(property "Value" "10KR2F-2-GP"
			(at -0.064008 -3.993896 270)
			(unlocked yes)
			(layer "B.Fab")
			(hide yes)
			(effects
				(font
					(size 1.016 1.016)
					(thickness 0.1524)
				)
				(justify mirror)
			)
		)
		(property "Device Type" "R402H16"
			(at -0.064008 -5.517896 270)
			(unlocked yes)
			(layer "B.Fab")
			(hide yes)
			(effects
				(font
					(size 1.016 1.016)
					(thickness 0.1524)
				)
				(justify mirror)
			)
		)
		(duplicate_pad_numbers_are_jumpers no)
		(fp_line
			(start -0.508 -0.9398)
			(end 0.508 -0.9398)
			(stroke
				(width 0.1524)
				(type default)
			)
			(layer "B.SilkS")
		)
		(fp_line
			(start 0.508 -0.9398)
			(end 0.508 0.9398)
			(stroke
				(width 0.1524)
				(type default)
			)
			(layer "B.SilkS")
		)
		(fp_rect
			(start 0.508 0.9398)
			(end -0.508 -0.9398)
			(stroke
				(width 0)
				(type default)
			)
			(fill no)
			(layer "B.CrtYd")
		)
		(fp_rect
			(start 0.508 0.9398)
			(end -0.508 -0.9398)
			(stroke
				(width 0)
				(type default)
			)
			(fill no)
			(layer "B.Fab")
		)
		(pad "1" smd custom
			(at 0 -0.4445 90)
			(size 0.1397 0.1397)
			(layers "B.Cu" "B.Mask" "B.Paste")
			(net "PCIE_MATED#_B")
			(options
				(clearance outline)
				(anchor circle)
			)
			(primitives
				(gr_poly
					(pts
						(arc
							(start -0.1778 0.2794)
							(mid -0.249642 0.249642)
							(end -0.2794 0.1778)
						)
						(arc
							(start -0.2794 -0.1778)
							(mid -0.249642 -0.249642)
							(end -0.1778 -0.2794)
						)
						(arc
							(start 0.1778 -0.2794)
							(mid 0.249642 -0.249642)
							(end 0.2794 -0.1778)
						)
						(arc
							(start 0.2794 0.1778)
							(mid 0.249642 0.249642)
							(end 0.1778 0.2794)
						)
					)
					(width 0)
					(fill yes)
				)
			)
		)
		(pad "2" smd custom
			(at 0 0.4445 90)
			(size 0.1397 0.1397)
			(layers "B.Cu" "B.Mask" "B.Paste")
			(net "GND")
			(options
				(clearance outline)
				(anchor circle)
			)
			(primitives
				(gr_poly
					(pts
						(arc
							(start -0.1778 0.2794)
							(mid -0.249642 0.249642)
							(end -0.2794 0.1778)
						)
						(arc
							(start -0.2794 -0.1778)
							(mid -0.249642 -0.249642)
							(end -0.1778 -0.2794)
						)
						(arc
							(start 0.1778 -0.2794)
							(mid 0.249642 -0.249642)
							(end 0.2794 -0.1778)
						)
						(arc
							(start 0.2794 0.1778)
							(mid 0.249642 0.249642)
							(end 0.1778 0.2794)
						)
					)
					(width 0)
					(fill yes)
				)
			)
		)
	)
	(footprint ""
		(layer "B.Cu")
		(at 79.229966 -56.515 -90)
		(property "Reference" "SC925"
			(at 0 0 90)
			(layer "B.SilkS")
			(hide yes)
			(effects
				(font
					(size 1.27 1.27)
				)
				(justify mirror)
			)
		)
		(property "Value" "SC1U6D3V1MX-GP"
			(at -1.9177 2.0193 270)
			(unlocked yes)
			(layer "B.Fab")
			(hide yes)
			(effects
				(font
					(size 1.016 1.016)
					(thickness 0.1524)
				)
				(justify mirror)
			)
		)
		(property "Device Type" "C0201H14"
			(at -1.9177 0.4953 270)
			(unlocked yes)
			(layer "B.Fab")
			(hide yes)
			(effects
				(font
					(size 1.016 1.016)
					(thickness 0.1524)
				)
				(justify mirror)
			)
		)
		(duplicate_pad_numbers_are_jumpers no)
		(fp_rect
			(start 0.1524 0.3048)
			(end -0.1524 -0.3048)
			(stroke
				(width 0)
				(type default)
			)
			(fill no)
			(layer "B.CrtYd")
		)
		(fp_poly
			(pts
				(xy 0.2794 0.6477) (xy 0.2794 -0.6477) (xy -0.2794 -0.6477) (xy -0.2794 -0.1905) (xy -0.1524 -0.1905)
				(xy -0.1524 -0.3048) (xy 0.1524 -0.3048) (xy 0.1524 0.3048) (xy -0.1524 0.3048) (xy -0.1524 -0.1778)
				(xy -0.2794 -0.1778) (xy -0.2794 0.6477)
			)
			(stroke
				(width 0)
				(type default)
			)
			(fill no)
			(layer "B.CrtYd")
		)
		(fp_rect
			(start 0.2794 0.6477)
			(end -0.2794 -0.6477)
			(stroke
				(width 0)
				(type default)
			)
			(fill no)
			(layer "B.Fab")
		)
		(pad "1" smd custom
			(at 0 -0.2794 90)
			(size 0.0762 0.0762)
			(layers "B.Cu" "B.Mask" "B.Paste")
			(net "VDDA_SAS_REF_CLK")
			(options
				(clearance outline)
				(anchor circle)
			)
			(primitives
				(gr_poly
					(pts
						(arc
							(start 0.1524 0.127)
							(mid 0.137521 0.162921)
							(end 0.1016 0.1778)
						)
						(arc
							(start -0.1016 0.1778)
							(mid -0.137521 0.162921)
							(end -0.1524 0.127)
						)
						(arc
							(start -0.1524 -0.127)
							(mid -0.137521 -0.162921)
							(end -0.1016 -0.1778)
						)
						(arc
							(start 0.1016 -0.1778)
							(mid 0.137521 -0.162921)
							(end 0.1524 -0.127)
						)
					)
					(width 0)
					(fill yes)
				)
			)
		)
		(pad "2" smd custom
			(at 0 0.2794 90)
			(size 0.0762 0.0762)
			(layers "B.Cu" "B.Mask" "B.Paste")
			(net "GND")
			(options
				(clearance outline)
				(anchor circle)
			)
			(primitives
				(gr_poly
					(pts
						(arc
							(start 0.1524 0.127)
							(mid 0.137521 0.162921)
							(end 0.1016 0.1778)
						)
						(arc
							(start -0.1016 0.1778)
							(mid -0.137521 0.162921)
							(end -0.1524 0.127)
						)
						(arc
							(start -0.1524 -0.127)
							(mid -0.137521 -0.162921)
							(end -0.1016 -0.1778)
						)
						(arc
							(start 0.1016 -0.1778)
							(mid 0.137521 -0.162921)
							(end 0.1524 -0.127)
						)
					)
					(width 0)
					(fill yes)
				)
			)
		)
	)
	(footprint ""
		(layer "B.Cu")
		(at 267.716 -35.687 90)
		(property "Reference" "PR41"
			(at 0 0 90)
			(layer "B.SilkS")
			(hide yes)
			(effects
				(font
					(size 1.27 1.27)
				)
				(justify mirror)
			)
		)
		(property "Value" "3D01R5F-GP"
			(at 0 -8.9535 90)
			(unlocked yes)
			(layer "B.Fab")
			(hide yes)
			(effects
				(font
					(size 1.27 1.016)
					(thickness 0.1524)
				)
				(justify mirror)
			)
		)
		(property "Device Type" "R805H24"
			(at 0 -10.6299 90)
			(unlocked yes)
			(layer "B.Fab")
			(hide yes)
			(effects
				(font
					(size 1.27 1.016)
					(thickness 0.1524)
				)
				(justify mirror)
			)
		)
		(duplicate_pad_numbers_are_jumpers no)
		(fp_line
			(start 0.889 -1.7018)
			(end 0.889 0.2794)
			(stroke
				(width 0.1524)
				(type default)
			)
			(layer "B.SilkS")
		)
		(fp_line
			(start -0.889 -1.7018)
			(end 0.889 -1.7018)
			(stroke
				(width 0.1524)
				(type default)
			)
			(layer "B.SilkS")
		)
		(fp_line
			(start -0.889 -1.7018)
			(end -0.889 -0.381)
			(stroke
				(width 0.1524)
				(type default)
			)
			(layer "B.SilkS")
		)
		(fp_line
			(start 0.889 0.0762)
			(end 0.889 1.7018)
			(stroke
				(width 0.1524)
				(type default)
			)
			(layer "B.SilkS")
		)
		(fp_line
			(start 0.889 1.7018)
			(end -0.889 1.7018)
			(stroke
				(width 0.1524)
				(type default)
			)
			(layer "B.SilkS")
		)
		(fp_line
			(start -0.889 1.7018)
			(end -0.889 -0.508)
			(stroke
				(width 0.1524)
				(type default)
			)
			(layer "B.SilkS")
		)
		(fp_poly
			(pts
				(xy -0.9652 -1.778) (xy -0.9652 1.778) (xy 0.9652 1.778) (xy 0.9652 -1.778)
			)
			(stroke
				(width 0)
				(type default)
			)
			(fill no)
			(layer "B.CrtYd")
		)
		(fp_rect
			(start 0.9652 1.778)
			(end -0.9652 -1.778)
			(stroke
				(width 0)
				(type default)
			)
			(fill no)
			(layer "B.Fab")
		)
		(pad "1" smd rect
			(at 0 -0.9652 270)
			(size 1.397 1.143)
			(layers "B.Cu" "B.Mask" "B.Paste")
			(net "P1V8_STBY_VBST")
		)
		(pad "2" smd rect
			(at 0 0.9652 270)
			(size 1.397 1.143)
			(layers "B.Cu" "B.Mask" "B.Paste")
			(net "P1V8_STBY_VBST_RC")
		)
	)
	(footprint ""
		(layer "B.Cu")
		(at 124.09297 -104.394)
		(property "Reference" "SC1178"
			(at 0 0 0)
			(layer "B.SilkS")
			(hide yes)
			(effects
				(font
					(size 1.27 1.27)
				)
				(justify mirror)
			)
		)
		(property "Value" "SC1U6D3V1MX-GP"
			(at -1.9177 2.0193 0)
			(unlocked yes)
			(layer "B.Fab")
			(hide yes)
			(effects
				(font
					(size 1.016 1.016)
					(thickness 0.1524)
				)
				(justify mirror)
			)
		)
		(property "Device Type" "C0201H14"
			(at -1.9177 0.4953 0)
			(unlocked yes)
			(layer "B.Fab")
			(hide yes)
			(effects
				(font
					(size 1.016 1.016)
					(thickness 0.1524)
				)
				(justify mirror)
			)
		)
		(duplicate_pad_numbers_are_jumpers no)
		(fp_rect
			(start 0.1524 0.3048)
			(end -0.1524 -0.3048)
			(stroke
				(width 0)
				(type default)
			)
			(fill no)
			(layer "B.CrtYd")
		)
		(fp_poly
			(pts
				(xy 0.2794 0.6477) (xy 0.2794 -0.6477) (xy -0.2794 -0.6477) (xy -0.2794 -0.1905) (xy -0.1524 -0.1905)
				(xy -0.1524 -0.3048) (xy 0.1524 -0.3048) (xy 0.1524 0.3048) (xy -0.1524 0.3048) (xy -0.1524 -0.1778)
				(xy -0.2794 -0.1778) (xy -0.2794 0.6477)
			)
			(stroke
				(width 0)
				(type default)
			)
			(fill no)
			(layer "B.CrtYd")
		)
		(fp_rect
			(start 0.2794 0.6477)
			(end -0.2794 -0.6477)
			(stroke
				(width 0)
				(type default)
			)
			(fill no)
			(layer "B.Fab")
		)
		(pad "1" smd custom
			(at 0 -0.2794 180)
			(size 0.0762 0.0762)
			(layers "B.Cu" "B.Mask" "B.Paste")
			(net "GB_VDDA")
			(options
				(clearance outline)
				(anchor circle)
			)
			(primitives
				(gr_poly
					(pts
						(arc
							(start 0.1524 0.127)
							(mid 0.137521 0.162921)
							(end 0.1016 0.1778)
						)
						(arc
							(start -0.1016 0.1778)
							(mid -0.137521 0.162921)
							(end -0.1524 0.127)
						)
						(arc
							(start -0.1524 -0.127)
							(mid -0.137521 -0.162921)
							(end -0.1016 -0.1778)
						)
						(arc
							(start 0.1016 -0.1778)
							(mid 0.137521 -0.162921)
							(end 0.1524 -0.127)
						)
					)
					(width 0)
					(fill yes)
				)
			)
		)
		(pad "2" smd custom
			(at 0 0.2794 180)
			(size 0.0762 0.0762)
			(layers "B.Cu" "B.Mask" "B.Paste")
			(net "GND")
			(options
				(clearance outline)
				(anchor circle)
			)
			(primitives
				(gr_poly
					(pts
						(arc
							(start 0.1524 0.127)
							(mid 0.137521 0.162921)
							(end 0.1016 0.1778)
						)
						(arc
							(start -0.1016 0.1778)
							(mid -0.137521 0.162921)
							(end -0.1524 0.127)
						)
						(arc
							(start -0.1524 -0.127)
							(mid -0.137521 -0.162921)
							(end -0.1016 -0.1778)
						)
						(arc
							(start 0.1016 -0.1778)
							(mid 0.137521 -0.162921)
							(end 0.1524 -0.127)
						)
					)
					(width 0)
					(fill yes)
				)
			)
		)
	)
	(footprint ""
		(layer "B.Cu")
		(at 54.30393 -76.761086)
		(property "Reference" "SC1281"
			(at 0 0 0)
			(layer "B.SilkS")
			(hide yes)
			(effects
				(font
					(size 1.27 1.27)
				)
				(justify mirror)
			)
		)
		(property "Value" "SCD01U50V2KX-1GP"
			(at -1.1811 -2.7051 0)
			(unlocked yes)
			(layer "B.Fab")
			(hide yes)
			(effects
				(font
					(size 1.016 1.016)
					(thickness 0.1524)
				)
				(justify mirror)
			)
		)
		(property "Device Type" "C402H22"
			(at -1.1811 -4.2291 0)
			(unlocked yes)
			(layer "B.Fab")
			(hide yes)
			(effects
				(font
					(size 1.016 1.016)
					(thickness 0.1524)
				)
				(justify mirror)
			)
		)
		(duplicate_pad_numbers_are_jumpers no)
		(fp_rect
			(start 0.4318 0.9525)
			(end -0.4318 -0.9525)
			(stroke
				(width 0)
				(type default)
			)
			(fill no)
			(layer "B.CrtYd")
		)
		(fp_rect
			(start 0.4318 0.9525)
			(end -0.4318 -0.9525)
			(stroke
				(width 0)
				(type default)
			)
			(fill no)
			(layer "B.Fab")
		)
		(pad "1" smd custom
			(at 0 -0.4445 180)
			(size 0.1524 0.1524)
			(layers "B.Cu" "B.Mask" "B.Paste")
			(net "SAS_EXP2CONN_RX_N_23")
			(options
				(clearance outline)
				(anchor circle)
			)
			(primitives
				(gr_poly
					(pts
						(arc
							(start 0.3048 0.2032)
							(mid 0.275042 0.275042)
							(end 0.2032 0.3048)
						)
						(arc
							(start -0.2032 0.3048)
							(mid -0.275042 0.275042)
							(end -0.3048 0.2032)
						)
						(arc
							(start -0.3048 -0.2032)
							(mid -0.275042 -0.275042)
							(end -0.2032 -0.3048)
						)
						(arc
							(start 0.2032 -0.3048)
							(mid 0.275042 -0.275042)
							(end 0.3048 -0.2032)
						)
					)
					(width 0)
					(fill yes)
				)
			)
		)
		(pad "2" smd custom
			(at 0 0.4445 180)
			(size 0.1524 0.1524)
			(layers "B.Cu" "B.Mask" "B.Paste")
			(net "MINI_RX_N_23")
			(options
				(clearance outline)
				(anchor circle)
			)
			(primitives
				(gr_poly
					(pts
						(arc
							(start 0.3048 0.2032)
							(mid 0.275042 0.275042)
							(end 0.2032 0.3048)
						)
						(arc
							(start -0.2032 0.3048)
							(mid -0.275042 0.275042)
							(end -0.3048 0.2032)
						)
						(arc
							(start -0.3048 -0.2032)
							(mid -0.275042 -0.275042)
							(end -0.2032 -0.3048)
						)
						(arc
							(start 0.2032 -0.3048)
							(mid 0.275042 -0.275042)
							(end 0.3048 -0.2032)
						)
					)
					(width 0)
					(fill yes)
				)
			)
		)
	)
	(footprint ""
		(layer "B.Cu")
		(at 349.5802 -71.8058 180)
		(property "Reference" "R293"
			(at 0 0 0)
			(layer "B.SilkS")
			(hide yes)
			(effects
				(font
					(size 1.27 1.27)
				)
				(justify mirror)
			)
		)
		(property "Value" "0R0402-PAD-1-GP"
			(at -0.064008 -3.993896 180)
			(unlocked yes)
			(layer "B.Fab")
			(hide yes)
			(effects
				(font
					(size 1.016 1.016)
					(thickness 0.1524)
				)
				(justify mirror)
			)
		)
		(property "Device Type" "0R0402-PAD"
			(at -0.064008 -5.517896 180)
			(unlocked yes)
			(layer "B.Fab")
			(hide yes)
			(effects
				(font
					(size 1.016 1.016)
					(thickness 0.1524)
				)
				(justify mirror)
			)
		)
		(duplicate_pad_numbers_are_jumpers no)
		(fp_line
			(start 0.508 -0.9398)
			(end 0.508 0.9398)
			(stroke
				(width 0.1524)
				(type default)
			)
			(layer "B.SilkS")
		)
		(fp_line
			(start -0.508 -0.9398)
			(end 0.508 -0.9398)
			(stroke
				(width 0.1524)
				(type default)
			)
			(layer "B.SilkS")
		)
		(fp_rect
			(start 0.508 0.9398)
			(end -0.508 -0.9398)
			(stroke
				(width 0)
				(type default)
			)
			(fill no)
			(layer "B.CrtYd")
		)
		(fp_rect
			(start 0.508 0.9398)
			(end -0.508 -0.9398)
			(stroke
				(width 0)
				(type default)
			)
			(fill no)
			(layer "B.Fab")
		)
		(pad "1" smd custom
			(at 0 -0.4445)
			(size 0.1397 0.1397)
			(layers "B.Cu" "B.Mask" "B.Paste")
			(net "ROMD1_R")
			(options
				(clearance outline)
				(anchor circle)
			)
			(primitives
				(gr_poly
					(pts
						(xy -0.2794 -0.3683)
						(arc
							(start -0.2794 0.2667)
							(mid -0.249642 0.338542)
							(end -0.1778 0.3683)
						)
						(arc
							(start 0.1778 0.3683)
							(mid 0.249642 0.338542)
							(end 0.2794 0.2667)
						)
						(xy 0.2794 -0.3683)
					)
					(width 0)
					(fill yes)
				)
			)
		)
		(pad "2" smd custom
			(at 0 0.4445)
			(size 0.1397 0.1397)
			(layers "B.Cu" "B.Mask" "B.Paste")
			(net "ROMD1")
			(options
				(clearance outline)
				(anchor circle)
			)
			(primitives
				(gr_poly
					(pts
						(arc
							(start -0.1778 -0.3683)
							(mid -0.249642 -0.338542)
							(end -0.2794 -0.2667)
						)
						(xy -0.2794 0.3683) (xy 0.2794 0.3683)
						(arc
							(start 0.2794 -0.2667)
							(mid 0.249642 -0.338542)
							(end 0.1778 -0.3683)
						)
					)
					(width 0)
					(fill yes)
				)
			)
		)
	)
	(footprint ""
		(layer "B.Cu")
		(at 110.807246 -51.42992 -90)
		(property "Reference" "SC1006"
			(at 0 0 90)
			(layer "B.SilkS")
			(hide yes)
			(effects
				(font
					(size 1.27 1.27)
				)
				(justify mirror)
			)
		)
		(property "Value" "SCD1U16V2KX-3GP"
			(at -1.1811 -2.7051 270)
			(unlocked yes)
			(layer "B.Fab")
			(hide yes)
			(effects
				(font
					(size 1.016 1.016)
					(thickness 0.1524)
				)
				(justify mirror)
			)
		)
		(property "Device Type" "C402H22"
			(at -1.1811 -4.2291 270)
			(unlocked yes)
			(layer "B.Fab")
			(hide yes)
			(effects
				(font
					(size 1.016 1.016)
					(thickness 0.1524)
				)
				(justify mirror)
			)
		)
		(duplicate_pad_numbers_are_jumpers no)
		(fp_rect
			(start 0.4318 0.9525)
			(end -0.4318 -0.9525)
			(stroke
				(width 0)
				(type default)
			)
			(fill no)
			(layer "B.CrtYd")
		)
		(fp_rect
			(start 0.4318 0.9525)
			(end -0.4318 -0.9525)
			(stroke
				(width 0)
				(type default)
			)
			(fill no)
			(layer "B.Fab")
		)
		(pad "1" smd custom
			(at 0 -0.4445 90)
			(size 0.1524 0.1524)
			(layers "B.Cu" "B.Mask" "B.Paste")
			(net "P1V8_C")
			(options
				(clearance outline)
				(anchor circle)
			)
			(primitives
				(gr_poly
					(pts
						(arc
							(start 0.3048 0.2032)
							(mid 0.275042 0.275042)
							(end 0.2032 0.3048)
						)
						(arc
							(start -0.2032 0.3048)
							(mid -0.275042 0.275042)
							(end -0.3048 0.2032)
						)
						(arc
							(start -0.3048 -0.2032)
							(mid -0.275042 -0.275042)
							(end -0.2032 -0.3048)
						)
						(arc
							(start 0.2032 -0.3048)
							(mid 0.275042 -0.275042)
							(end 0.3048 -0.2032)
						)
					)
					(width 0)
					(fill yes)
				)
			)
		)
		(pad "2" smd custom
			(at 0 0.4445 90)
			(size 0.1524 0.1524)
			(layers "B.Cu" "B.Mask" "B.Paste")
			(net "GND")
			(options
				(clearance outline)
				(anchor circle)
			)
			(primitives
				(gr_poly
					(pts
						(arc
							(start 0.3048 0.2032)
							(mid 0.275042 0.275042)
							(end 0.2032 0.3048)
						)
						(arc
							(start -0.2032 0.3048)
							(mid -0.275042 0.275042)
							(end -0.3048 0.2032)
						)
						(arc
							(start -0.3048 -0.2032)
							(mid -0.275042 -0.275042)
							(end -0.2032 -0.3048)
						)
						(arc
							(start 0.2032 -0.3048)
							(mid 0.275042 -0.275042)
							(end 0.3048 -0.2032)
						)
					)
					(width 0)
					(fill yes)
				)
			)
		)
	)
	(footprint ""
		(layer "B.Cu")
		(at 114.61877 -101.3968 180)
		(property "Reference" "SC1137"
			(at 0 0 0)
			(layer "B.SilkS")
			(hide yes)
			(effects
				(font
					(size 1.27 1.27)
				)
				(justify mirror)
			)
		)
		(property "Value" "SCD1U6D3V1KX-GP"
			(at 2.8321 -1.7399 180)
			(unlocked yes)
			(layer "B.Fab")
			(hide yes)
			(effects
				(font
					(size 1.016 1.016)
					(thickness 0.1524)
				)
				(justify mirror)
			)
		)
		(property "Device Type" "C0201H13"
			(at 2.8321 -3.2639 180)
			(unlocked yes)
			(layer "B.Fab")
			(hide yes)
			(effects
				(font
					(size 1.016 1.016)
					(thickness 0.1524)
				)
				(justify mirror)
			)
		)
		(duplicate_pad_numbers_are_jumpers no)
		(fp_rect
			(start 0.2794 0.6477)
			(end -0.2794 -0.6477)
			(stroke
				(width 0)
				(type default)
			)
			(fill no)
			(layer "B.CrtYd")
		)
		(fp_rect
			(start 0.2794 0.6477)
			(end -0.2794 -0.6477)
			(stroke
				(width 0)
				(type default)
			)
			(fill no)
			(layer "B.Fab")
		)
		(pad "1" smd custom
			(at 0 -0.2794)
			(size 0.0762 0.0762)
			(layers "B.Cu" "B.Mask" "B.Paste")
			(net "GB_VDDH2")
			(options
				(clearance outline)
				(anchor circle)
			)
			(primitives
				(gr_poly
					(pts
						(arc
							(start 0.1524 0.127)
							(mid 0.137521 0.162921)
							(end 0.1016 0.1778)
						)
						(arc
							(start -0.1016 0.1778)
							(mid -0.137521 0.162921)
							(end -0.1524 0.127)
						)
						(arc
							(start -0.1524 -0.127)
							(mid -0.137521 -0.162921)
							(end -0.1016 -0.1778)
						)
						(arc
							(start 0.1016 -0.1778)
							(mid 0.137521 -0.162921)
							(end 0.1524 -0.127)
						)
					)
					(width 0)
					(fill yes)
				)
			)
		)
		(pad "2" smd custom
			(at 0 0.2794)
			(size 0.0762 0.0762)
			(layers "B.Cu" "B.Mask" "B.Paste")
			(net "GND")
			(options
				(clearance outline)
				(anchor circle)
			)
			(primitives
				(gr_poly
					(pts
						(arc
							(start 0.1524 0.127)
							(mid 0.137521 0.162921)
							(end 0.1016 0.1778)
						)
						(arc
							(start -0.1016 0.1778)
							(mid -0.137521 0.162921)
							(end -0.1524 0.127)
						)
						(arc
							(start -0.1524 -0.127)
							(mid -0.137521 -0.162921)
							(end -0.1016 -0.1778)
						)
						(arc
							(start 0.1016 -0.1778)
							(mid 0.137521 -0.162921)
							(end 0.1524 -0.127)
						)
					)
					(width 0)
					(fill yes)
				)
			)
		)
	)
	(footprint ""
		(layer "B.Cu")
		(at 127.90297 -97.917 90)
		(property "Reference" "SC1165"
			(at 0 0 90)
			(layer "B.SilkS")
			(hide yes)
			(effects
				(font
					(size 1.27 1.27)
				)
				(justify mirror)
			)
		)
		(property "Value" "SC22U6D3V5MX-2GP"
			(at 0.0762 -6.1214 90)
			(unlocked yes)
			(layer "B.Fab")
			(hide yes)
			(effects
				(font
					(size 1.016 1.016)
					(thickness 0.1524)
				)
				(justify mirror)
			)
		)
		(property "Device Type" "C805H58"
			(at 0.0762 -8.1534 90)
			(unlocked yes)
			(layer "B.Fab")
			(hide yes)
			(effects
				(font
					(size 1.016 1.016)
					(thickness 0.1524)
				)
				(justify mirror)
			)
		)
		(duplicate_pad_numbers_are_jumpers no)
		(fp_line
			(start -0.635 0)
			(end 0.635 0)
			(stroke
				(width 0.508)
				(type default)
			)
			(layer "B.SilkS")
		)
		(fp_rect
			(start 0.9652 1.778)
			(end -0.9652 -1.778)
			(stroke
				(width 0)
				(type default)
			)
			(fill no)
			(layer "B.CrtYd")
		)
		(fp_poly
			(pts
				(xy 0.9652 -1.778) (xy -0.9652 -1.778) (xy -0.9652 1.778) (xy 0.9652 1.778)
			)
			(stroke
				(width 0)
				(type default)
			)
			(fill no)
			(layer "B.Fab")
		)
		(pad "1" smd rect
			(at 0 -0.9652 270)
			(size 1.397 1.143)
			(layers "B.Cu" "B.Mask" "B.Paste")
			(net "GB_VDDA")
		)
		(pad "2" smd rect
			(at 0 0.9652 270)
			(size 1.397 1.143)
			(layers "B.Cu" "B.Mask" "B.Paste")
			(net "GND")
		)
	)
	(footprint ""
		(layer "B.Cu")
		(at 319.913 -166.878 90)
		(property "Reference" "R411"
			(at 0 0 90)
			(layer "B.SilkS")
			(hide yes)
			(effects
				(font
					(size 1.27 1.27)
				)
				(justify mirror)
			)
		)
		(property "Value" "4K7R2F-GP"
			(at -0.064008 -3.993896 90)
			(unlocked yes)
			(layer "B.Fab")
			(hide yes)
			(effects
				(font
					(size 1.016 1.016)
					(thickness 0.1524)
				)
				(justify mirror)
			)
		)
		(property "Device Type" "R402H16"
			(at -0.064008 -5.517896 90)
			(unlocked yes)
			(layer "B.Fab")
			(hide yes)
			(effects
				(font
					(size 1.016 1.016)
					(thickness 0.1524)
				)
				(justify mirror)
			)
		)
		(duplicate_pad_numbers_are_jumpers no)
		(fp_line
			(start 0.508 -0.9398)
			(end 0.508 0.9398)
			(stroke
				(width 0.1524)
				(type default)
			)
			(layer "B.SilkS")
		)
		(fp_line
			(start -0.508 -0.9398)
			(end 0.508 -0.9398)
			(stroke
				(width 0.1524)
				(type default)
			)
			(layer "B.SilkS")
		)
		(fp_rect
			(start 0.508 0.9398)
			(end -0.508 -0.9398)
			(stroke
				(width 0)
				(type default)
			)
			(fill no)
			(layer "B.CrtYd")
		)
		(fp_rect
			(start 0.508 0.9398)
			(end -0.508 -0.9398)
			(stroke
				(width 0)
				(type default)
			)
			(fill no)
			(layer "B.Fab")
		)
		(pad "1" smd custom
			(at 0 -0.4445 270)
			(size 0.1397 0.1397)
			(layers "B.Cu" "B.Mask" "B.Paste")
			(net "BMC_I2C_D_SCL")
			(options
				(clearance outline)
				(anchor circle)
			)
			(primitives
				(gr_poly
					(pts
						(arc
							(start -0.1778 0.2794)
							(mid -0.249642 0.249642)
							(end -0.2794 0.1778)
						)
						(arc
							(start -0.2794 -0.1778)
							(mid -0.249642 -0.249642)
							(end -0.1778 -0.2794)
						)
						(arc
							(start 0.1778 -0.2794)
							(mid 0.249642 -0.249642)
							(end 0.2794 -0.1778)
						)
						(arc
							(start 0.2794 0.1778)
							(mid 0.249642 0.249642)
							(end 0.1778 0.2794)
						)
					)
					(width 0)
					(fill yes)
				)
			)
		)
		(pad "2" smd custom
			(at 0 0.4445 270)
			(size 0.1397 0.1397)
			(layers "B.Cu" "B.Mask" "B.Paste")
			(net "P3V3_STBY")
			(options
				(clearance outline)
				(anchor circle)
			)
			(primitives
				(gr_poly
					(pts
						(arc
							(start -0.1778 0.2794)
							(mid -0.249642 0.249642)
							(end -0.2794 0.1778)
						)
						(arc
							(start -0.2794 -0.1778)
							(mid -0.249642 -0.249642)
							(end -0.1778 -0.2794)
						)
						(arc
							(start 0.1778 -0.2794)
							(mid 0.249642 -0.249642)
							(end 0.2794 -0.1778)
						)
						(arc
							(start 0.2794 0.1778)
							(mid 0.249642 0.249642)
							(end 0.1778 0.2794)
						)
					)
					(width 0)
					(fill yes)
				)
			)
		)
	)
	(footprint ""
		(layer "B.Cu")
		(at 104.883966 -36.957)
		(property "Reference" "STP55"
			(at 0 0 0)
			(layer "B.SilkS")
			(hide yes)
			(effects
				(font
					(size 1.27 1.27)
				)
				(justify mirror)
			)
		)
		(property "Value" "TPAD28"
			(at -0.0127 -1.8034 0)
			(unlocked yes)
			(layer "B.Fab")
			(hide yes)
			(effects
				(font
					(size 1.016 1.016)
					(thickness 0.1524)
				)
				(justify mirror)
			)
		)
		(property "Device Type" "TPAD28"
			(at -0.0127 -3.3274 0)
			(unlocked yes)
			(layer "B.Fab")
			(hide yes)
			(effects
				(font
					(size 1.016 1.016)
					(thickness 0.1524)
				)
				(justify mirror)
			)
		)
		(duplicate_pad_numbers_are_jumpers no)
		(fp_poly
			(pts
				(arc
					(start 0.3556 0)
					(mid -0.3556 0)
					(end 0.3556 0)
				)
			)
			(stroke
				(width 0)
				(type default)
			)
			(fill no)
			(layer "B.CrtYd")
		)
		(fp_poly
			(pts
				(arc
					(start 0.6096 0)
					(mid -0.6096 0)
					(end 0.6096 0)
				)
			)
			(stroke
				(width 0)
				(type default)
			)
			(fill no)
			(layer "B.Fab")
		)
		(pad "1" smd circle
			(at 0 0 180)
			(size 0.7112 0.7112)
			(layers "B.Cu" "B.Mask" "B.Paste")
			(net "SPARE5")
		)
	)
	(footprint ""
		(layer "B.Cu")
		(at 297.2562 -203.962 180)
		(property "Reference" "C182"
			(at 0 0 0)
			(layer "B.SilkS")
			(hide yes)
			(effects
				(font
					(size 1.27 1.27)
				)
				(justify mirror)
			)
		)
		(property "Value" "SCD1U16V2KX-3GP"
			(at -1.1811 -2.7051 180)
			(unlocked yes)
			(layer "B.Fab")
			(hide yes)
			(effects
				(font
					(size 1.016 1.016)
					(thickness 0.1524)
				)
				(justify mirror)
			)
		)
		(property "Device Type" "C402H22"
			(at -1.1811 -4.2291 180)
			(unlocked yes)
			(layer "B.Fab")
			(hide yes)
			(effects
				(font
					(size 1.016 1.016)
					(thickness 0.1524)
				)
				(justify mirror)
			)
		)
		(duplicate_pad_numbers_are_jumpers no)
		(fp_rect
			(start 0.4318 0.9525)
			(end -0.4318 -0.9525)
			(stroke
				(width 0)
				(type default)
			)
			(fill no)
			(layer "B.CrtYd")
		)
		(fp_rect
			(start 0.4318 0.9525)
			(end -0.4318 -0.9525)
			(stroke
				(width 0)
				(type default)
			)
			(fill no)
			(layer "B.Fab")
		)
		(pad "1" smd custom
			(at 0 -0.4445)
			(size 0.1524 0.1524)
			(layers "B.Cu" "B.Mask" "B.Paste")
			(net "P1V53_STBY")
			(options
				(clearance outline)
				(anchor circle)
			)
			(primitives
				(gr_poly
					(pts
						(arc
							(start 0.3048 0.2032)
							(mid 0.275042 0.275042)
							(end 0.2032 0.3048)
						)
						(arc
							(start -0.2032 0.3048)
							(mid -0.275042 0.275042)
							(end -0.3048 0.2032)
						)
						(arc
							(start -0.3048 -0.2032)
							(mid -0.275042 -0.275042)
							(end -0.2032 -0.3048)
						)
						(arc
							(start 0.2032 -0.3048)
							(mid 0.275042 -0.275042)
							(end 0.3048 -0.2032)
						)
					)
					(width 0)
					(fill yes)
				)
			)
		)
		(pad "2" smd custom
			(at 0 0.4445)
			(size 0.1524 0.1524)
			(layers "B.Cu" "B.Mask" "B.Paste")
			(net "GND")
			(options
				(clearance outline)
				(anchor circle)
			)
			(primitives
				(gr_poly
					(pts
						(arc
							(start 0.3048 0.2032)
							(mid 0.275042 0.275042)
							(end 0.2032 0.3048)
						)
						(arc
							(start -0.2032 0.3048)
							(mid -0.275042 0.275042)
							(end -0.3048 0.2032)
						)
						(arc
							(start -0.3048 -0.2032)
							(mid -0.275042 -0.275042)
							(end -0.2032 -0.3048)
						)
						(arc
							(start 0.2032 -0.3048)
							(mid 0.275042 -0.275042)
							(end 0.3048 -0.2032)
						)
					)
					(width 0)
					(fill yes)
				)
			)
		)
	)
	(footprint ""
		(layer "B.Cu")
		(at 105.188766 -54.52872 -90)
		(property "Reference" "SC1011"
			(at 0 0 90)
			(layer "B.SilkS")
			(hide yes)
			(effects
				(font
					(size 1.27 1.27)
				)
				(justify mirror)
			)
		)
		(property "Value" "SC1KP50V2KX-1GP"
			(at -1.1811 -2.7051 270)
			(unlocked yes)
			(layer "B.Fab")
			(hide yes)
			(effects
				(font
					(size 1.016 1.016)
					(thickness 0.1524)
				)
				(justify mirror)
			)
		)
		(property "Device Type" "C402H22"
			(at -1.1811 -4.2291 270)
			(unlocked yes)
			(layer "B.Fab")
			(hide yes)
			(effects
				(font
					(size 1.016 1.016)
					(thickness 0.1524)
				)
				(justify mirror)
			)
		)
		(duplicate_pad_numbers_are_jumpers no)
		(fp_rect
			(start 0.4318 0.9525)
			(end -0.4318 -0.9525)
			(stroke
				(width 0)
				(type default)
			)
			(fill no)
			(layer "B.CrtYd")
		)
		(fp_rect
			(start 0.4318 0.9525)
			(end -0.4318 -0.9525)
			(stroke
				(width 0)
				(type default)
			)
			(fill no)
			(layer "B.Fab")
		)
		(pad "1" smd custom
			(at 0 -0.4445 90)
			(size 0.1524 0.1524)
			(layers "B.Cu" "B.Mask" "B.Paste")
			(net "P1V8_C")
			(options
				(clearance outline)
				(anchor circle)
			)
			(primitives
				(gr_poly
					(pts
						(arc
							(start 0.3048 0.2032)
							(mid 0.275042 0.275042)
							(end 0.2032 0.3048)
						)
						(arc
							(start -0.2032 0.3048)
							(mid -0.275042 0.275042)
							(end -0.3048 0.2032)
						)
						(arc
							(start -0.3048 -0.2032)
							(mid -0.275042 -0.275042)
							(end -0.2032 -0.3048)
						)
						(arc
							(start 0.2032 -0.3048)
							(mid 0.275042 -0.275042)
							(end 0.3048 -0.2032)
						)
					)
					(width 0)
					(fill yes)
				)
			)
		)
		(pad "2" smd custom
			(at 0 0.4445 90)
			(size 0.1524 0.1524)
			(layers "B.Cu" "B.Mask" "B.Paste")
			(net "GND")
			(options
				(clearance outline)
				(anchor circle)
			)
			(primitives
				(gr_poly
					(pts
						(arc
							(start 0.3048 0.2032)
							(mid 0.275042 0.275042)
							(end 0.2032 0.3048)
						)
						(arc
							(start -0.2032 0.3048)
							(mid -0.275042 0.275042)
							(end -0.3048 0.2032)
						)
						(arc
							(start -0.3048 -0.2032)
							(mid -0.275042 -0.275042)
							(end -0.2032 -0.3048)
						)
						(arc
							(start 0.2032 -0.3048)
							(mid 0.275042 -0.275042)
							(end 0.3048 -0.2032)
						)
					)
					(width 0)
					(fill yes)
				)
			)
		)
	)
	(footprint ""
		(layer "B.Cu")
		(at 112.630966 -26.416 -90)
		(property "Reference" "SQ2"
			(at 0 0 90)
			(layer "B.SilkS")
			(hide yes)
			(effects
				(font
					(size 1.27 1.27)
				)
				(justify mirror)
			)
		)
		(property "Value" "AO3400A-GP"
			(at -0.0254 -12.3444 270)
			(unlocked yes)
			(layer "B.Fab")
			(hide yes)
			(effects
				(font
					(size 1.016 1.016)
					(thickness 0.1524)
				)
				(justify mirror)
			)
		)
		(property "Device Type" "SOT23DGS2D8H50"
			(at -0.0254 -14.2494 270)
			(unlocked yes)
			(layer "B.Fab")
			(hide yes)
			(effects
				(font
					(size 1.016 1.016)
					(thickness 0.1524)
				)
				(justify mirror)
			)
		)
		(duplicate_pad_numbers_are_jumpers no)
		(fp_line
			(start -1.7018 0.254)
			(end 1.7018 0.254)
			(stroke
				(width 0.1524)
				(type default)
			)
			(layer "B.SilkS")
		)
		(fp_line
			(start 1.7018 0.254)
			(end 1.7018 -0.254)
			(stroke
				(width 0.1524)
				(type default)
			)
			(layer "B.SilkS")
		)
		(fp_line
			(start -1.7018 -0.254)
			(end -1.7018 0.254)
			(stroke
				(width 0.1524)
				(type default)
			)
			(layer "B.SilkS")
		)
		(fp_line
			(start 1.7018 -0.254)
			(end -1.7018 -0.254)
			(stroke
				(width 0.1524)
				(type default)
			)
			(layer "B.SilkS")
		)
		(fp_rect
			(start 1.778 1.9812)
			(end -1.778 -1.9812)
			(stroke
				(width 0)
				(type default)
			)
			(fill no)
			(layer "B.CrtYd")
		)
		(fp_poly
			(pts
				(xy 1.778 -1.9812) (xy -1.778 -1.9812) (xy -1.778 1.9812) (xy 1.778 1.9812)
			)
			(stroke
				(width 0)
				(type default)
			)
			(fill no)
			(layer "B.Fab")
		)
		(pad "D" smd custom
			(at 0 -1.1176 90)
			(size 0.254 0.254)
			(layers "B.Cu" "B.Mask" "B.Paste")
			(net "SYS_ERROR_LED_D")
			(options
				(clearance outline)
				(anchor circle)
			)
			(primitives
				(gr_poly
					(pts
						(arc
							(start -0.508 0.4064)
							(mid -0.448484 0.550084)
							(end -0.3048 0.6096)
						)
						(arc
							(start 0.3048 0.6096)
							(mid 0.448484 0.550084)
							(end 0.508 0.4064)
						)
						(arc
							(start 0.508 -0.4064)
							(mid 0.448484 -0.550084)
							(end 0.3048 -0.6096)
						)
						(arc
							(start -0.3048 -0.6096)
							(mid -0.448484 -0.550084)
							(end -0.508 -0.4064)
						)
					)
					(width 0)
					(fill yes)
				)
			)
		)
		(pad "G" smd custom
			(at 1.016 1.1176 90)
			(size 0.254 0.254)
			(layers "B.Cu" "B.Mask" "B.Paste")
			(net "SYS_ERR_0")
			(options
				(clearance outline)
				(anchor circle)
			)
			(primitives
				(gr_poly
					(pts
						(arc
							(start -0.508 0.4064)
							(mid -0.448484 0.550084)
							(end -0.3048 0.6096)
						)
						(arc
							(start 0.3048 0.6096)
							(mid 0.448484 0.550084)
							(end 0.508 0.4064)
						)
						(arc
							(start 0.508 -0.4064)
							(mid 0.448484 -0.550084)
							(end 0.3048 -0.6096)
						)
						(arc
							(start -0.3048 -0.6096)
							(mid -0.448484 -0.550084)
							(end -0.508 -0.4064)
						)
					)
					(width 0)
					(fill yes)
				)
			)
		)
		(pad "S" smd custom
			(at -1.016 1.1176 90)
			(size 0.254 0.254)
			(layers "B.Cu" "B.Mask" "B.Paste")
			(net "GND")
			(options
				(clearance outline)
				(anchor circle)
			)
			(primitives
				(gr_poly
					(pts
						(arc
							(start -0.508 0.4064)
							(mid -0.448484 0.550084)
							(end -0.3048 0.6096)
						)
						(arc
							(start 0.3048 0.6096)
							(mid 0.448484 0.550084)
							(end 0.508 0.4064)
						)
						(arc
							(start 0.508 -0.4064)
							(mid 0.448484 -0.550084)
							(end 0.3048 -0.6096)
						)
						(arc
							(start -0.3048 -0.6096)
							(mid -0.448484 -0.550084)
							(end -0.508 -0.4064)
						)
					)
					(width 0)
					(fill yes)
				)
			)
		)
	)
	(footprint ""
		(layer "B.Cu")
		(at 79.229966 -55.753 -90)
		(property "Reference" "SC926"
			(at 0 0 90)
			(layer "B.SilkS")
			(hide yes)
			(effects
				(font
					(size 1.27 1.27)
				)
				(justify mirror)
			)
		)
		(property "Value" "SCD1U6D3V1KX-GP"
			(at 2.8321 -1.7399 270)
			(unlocked yes)
			(layer "B.Fab")
			(hide yes)
			(effects
				(font
					(size 1.016 1.016)
					(thickness 0.1524)
				)
				(justify mirror)
			)
		)
		(property "Device Type" "C0201H13"
			(at 2.8321 -3.2639 270)
			(unlocked yes)
			(layer "B.Fab")
			(hide yes)
			(effects
				(font
					(size 1.016 1.016)
					(thickness 0.1524)
				)
				(justify mirror)
			)
		)
		(duplicate_pad_numbers_are_jumpers no)
		(fp_rect
			(start 0.2794 0.6477)
			(end -0.2794 -0.6477)
			(stroke
				(width 0)
				(type default)
			)
			(fill no)
			(layer "B.CrtYd")
		)
		(fp_rect
			(start 0.2794 0.6477)
			(end -0.2794 -0.6477)
			(stroke
				(width 0)
				(type default)
			)
			(fill no)
			(layer "B.Fab")
		)
		(pad "1" smd custom
			(at 0 -0.2794 90)
			(size 0.0762 0.0762)
			(layers "B.Cu" "B.Mask" "B.Paste")
			(net "VDDA_SAS_REF_CLK")
			(options
				(clearance outline)
				(anchor circle)
			)
			(primitives
				(gr_poly
					(pts
						(arc
							(start 0.1524 0.127)
							(mid 0.137521 0.162921)
							(end 0.1016 0.1778)
						)
						(arc
							(start -0.1016 0.1778)
							(mid -0.137521 0.162921)
							(end -0.1524 0.127)
						)
						(arc
							(start -0.1524 -0.127)
							(mid -0.137521 -0.162921)
							(end -0.1016 -0.1778)
						)
						(arc
							(start 0.1016 -0.1778)
							(mid 0.137521 -0.162921)
							(end 0.1524 -0.127)
						)
					)
					(width 0)
					(fill yes)
				)
			)
		)
		(pad "2" smd custom
			(at 0 0.2794 90)
			(size 0.0762 0.0762)
			(layers "B.Cu" "B.Mask" "B.Paste")
			(net "GND")
			(options
				(clearance outline)
				(anchor circle)
			)
			(primitives
				(gr_poly
					(pts
						(arc
							(start 0.1524 0.127)
							(mid 0.137521 0.162921)
							(end 0.1016 0.1778)
						)
						(arc
							(start -0.1016 0.1778)
							(mid -0.137521 0.162921)
							(end -0.1524 0.127)
						)
						(arc
							(start -0.1524 -0.127)
							(mid -0.137521 -0.162921)
							(end -0.1016 -0.1778)
						)
						(arc
							(start 0.1016 -0.1778)
							(mid 0.137521 -0.162921)
							(end 0.1524 -0.127)
						)
					)
					(width 0)
					(fill yes)
				)
			)
		)
	)
	(footprint ""
		(layer "B.Cu")
		(at 114.64417 -100.0506)
		(property "Reference" "SC1139"
			(at 0 0 0)
			(layer "B.SilkS")
			(hide yes)
			(effects
				(font
					(size 1.27 1.27)
				)
				(justify mirror)
			)
		)
		(property "Value" "SCD1U6D3V1KX-GP"
			(at 2.8321 -1.7399 0)
			(unlocked yes)
			(layer "B.Fab")
			(hide yes)
			(effects
				(font
					(size 1.016 1.016)
					(thickness 0.1524)
				)
				(justify mirror)
			)
		)
		(property "Device Type" "C0201H13"
			(at 2.8321 -3.2639 0)
			(unlocked yes)
			(layer "B.Fab")
			(hide yes)
			(effects
				(font
					(size 1.016 1.016)
					(thickness 0.1524)
				)
				(justify mirror)
			)
		)
		(duplicate_pad_numbers_are_jumpers no)
		(fp_rect
			(start 0.2794 0.6477)
			(end -0.2794 -0.6477)
			(stroke
				(width 0)
				(type default)
			)
			(fill no)
			(layer "B.CrtYd")
		)
		(fp_rect
			(start 0.2794 0.6477)
			(end -0.2794 -0.6477)
			(stroke
				(width 0)
				(type default)
			)
			(fill no)
			(layer "B.Fab")
		)
		(pad "1" smd custom
			(at 0 -0.2794 180)
			(size 0.0762 0.0762)
			(layers "B.Cu" "B.Mask" "B.Paste")
			(net "GB_VDDH2")
			(options
				(clearance outline)
				(anchor circle)
			)
			(primitives
				(gr_poly
					(pts
						(arc
							(start 0.1524 0.127)
							(mid 0.137521 0.162921)
							(end 0.1016 0.1778)
						)
						(arc
							(start -0.1016 0.1778)
							(mid -0.137521 0.162921)
							(end -0.1524 0.127)
						)
						(arc
							(start -0.1524 -0.127)
							(mid -0.137521 -0.162921)
							(end -0.1016 -0.1778)
						)
						(arc
							(start 0.1016 -0.1778)
							(mid 0.137521 -0.162921)
							(end 0.1524 -0.127)
						)
					)
					(width 0)
					(fill yes)
				)
			)
		)
		(pad "2" smd custom
			(at 0 0.2794 180)
			(size 0.0762 0.0762)
			(layers "B.Cu" "B.Mask" "B.Paste")
			(net "GND")
			(options
				(clearance outline)
				(anchor circle)
			)
			(primitives
				(gr_poly
					(pts
						(arc
							(start 0.1524 0.127)
							(mid 0.137521 0.162921)
							(end 0.1016 0.1778)
						)
						(arc
							(start -0.1016 0.1778)
							(mid -0.137521 0.162921)
							(end -0.1524 0.127)
						)
						(arc
							(start -0.1524 -0.127)
							(mid -0.137521 -0.162921)
							(end -0.1016 -0.1778)
						)
						(arc
							(start 0.1016 -0.1778)
							(mid 0.137521 -0.162921)
							(end 0.1524 -0.127)
						)
					)
					(width 0)
					(fill yes)
				)
			)
		)
	)
	(footprint ""
		(layer "B.Cu")
		(at 295.3004 -172.5422 90)
		(property "Reference" "C216"
			(at 0 0 90)
			(layer "B.SilkS")
			(hide yes)
			(effects
				(font
					(size 1.27 1.27)
				)
				(justify mirror)
			)
		)
		(property "Value" "SC1U10V2KX-1GP"
			(at -1.1811 -2.7051 90)
			(unlocked yes)
			(layer "B.Fab")
			(hide yes)
			(effects
				(font
					(size 1.016 1.016)
					(thickness 0.1524)
				)
				(justify mirror)
			)
		)
		(property "Device Type" "C402H22"
			(at -1.1811 -4.2291 90)
			(unlocked yes)
			(layer "B.Fab")
			(hide yes)
			(effects
				(font
					(size 1.016 1.016)
					(thickness 0.1524)
				)
				(justify mirror)
			)
		)
		(duplicate_pad_numbers_are_jumpers no)
		(fp_rect
			(start 0.4318 0.9525)
			(end -0.4318 -0.9525)
			(stroke
				(width 0)
				(type default)
			)
			(fill no)
			(layer "B.CrtYd")
		)
		(fp_rect
			(start 0.4318 0.9525)
			(end -0.4318 -0.9525)
			(stroke
				(width 0)
				(type default)
			)
			(fill no)
			(layer "B.Fab")
		)
		(pad "1" smd custom
			(at 0 -0.4445 270)
			(size 0.1524 0.1524)
			(layers "B.Cu" "B.Mask" "B.Paste")
			(net "P3V3_STBY")
			(options
				(clearance outline)
				(anchor circle)
			)
			(primitives
				(gr_poly
					(pts
						(arc
							(start 0.3048 0.2032)
							(mid 0.275042 0.275042)
							(end 0.2032 0.3048)
						)
						(arc
							(start -0.2032 0.3048)
							(mid -0.275042 0.275042)
							(end -0.3048 0.2032)
						)
						(arc
							(start -0.3048 -0.2032)
							(mid -0.275042 -0.275042)
							(end -0.2032 -0.3048)
						)
						(arc
							(start 0.2032 -0.3048)
							(mid 0.275042 -0.275042)
							(end 0.3048 -0.2032)
						)
					)
					(width 0)
					(fill yes)
				)
			)
		)
		(pad "2" smd custom
			(at 0 0.4445 270)
			(size 0.1524 0.1524)
			(layers "B.Cu" "B.Mask" "B.Paste")
			(net "GND")
			(options
				(clearance outline)
				(anchor circle)
			)
			(primitives
				(gr_poly
					(pts
						(arc
							(start 0.3048 0.2032)
							(mid 0.275042 0.275042)
							(end 0.2032 0.3048)
						)
						(arc
							(start -0.2032 0.3048)
							(mid -0.275042 0.275042)
							(end -0.3048 0.2032)
						)
						(arc
							(start -0.3048 -0.2032)
							(mid -0.275042 -0.275042)
							(end -0.2032 -0.3048)
						)
						(arc
							(start 0.2032 -0.3048)
							(mid 0.275042 -0.275042)
							(end 0.3048 -0.2032)
						)
					)
					(width 0)
					(fill yes)
				)
			)
		)
	)
	(footprint ""
		(layer "B.Cu")
		(at 87.38616 -53.086)
		(property "Reference" "SR630"
			(at 0 0 0)
			(layer "B.SilkS")
			(hide yes)
			(effects
				(font
					(size 1.27 1.27)
				)
				(justify mirror)
			)
		)
		(property "Value" "2K2R2F-GP"
			(at -0.064008 -3.993896 0)
			(unlocked yes)
			(layer "B.Fab")
			(hide yes)
			(effects
				(font
					(size 1.016 1.016)
					(thickness 0.1524)
				)
				(justify mirror)
			)
		)
		(property "Device Type" "R402H16"
			(at -0.064008 -5.517896 0)
			(unlocked yes)
			(layer "B.Fab")
			(hide yes)
			(effects
				(font
					(size 1.016 1.016)
					(thickness 0.1524)
				)
				(justify mirror)
			)
		)
		(duplicate_pad_numbers_are_jumpers no)
		(fp_line
			(start -0.508 -0.9398)
			(end 0.508 -0.9398)
			(stroke
				(width 0.1524)
				(type default)
			)
			(layer "B.SilkS")
		)
		(fp_line
			(start 0.508 -0.9398)
			(end 0.508 0.9398)
			(stroke
				(width 0.1524)
				(type default)
			)
			(layer "B.SilkS")
		)
		(fp_rect
			(start 0.508 0.9398)
			(end -0.508 -0.9398)
			(stroke
				(width 0)
				(type default)
			)
			(fill no)
			(layer "B.CrtYd")
		)
		(fp_rect
			(start 0.508 0.9398)
			(end -0.508 -0.9398)
			(stroke
				(width 0)
				(type default)
			)
			(fill no)
			(layer "B.Fab")
		)
		(pad "1" smd custom
			(at 0 -0.4445 180)
			(size 0.1397 0.1397)
			(layers "B.Cu" "B.Mask" "B.Paste")
			(net "P1V8_C")
			(options
				(clearance outline)
				(anchor circle)
			)
			(primitives
				(gr_poly
					(pts
						(arc
							(start -0.1778 0.2794)
							(mid -0.249642 0.249642)
							(end -0.2794 0.1778)
						)
						(arc
							(start -0.2794 -0.1778)
							(mid -0.249642 -0.249642)
							(end -0.1778 -0.2794)
						)
						(arc
							(start 0.1778 -0.2794)
							(mid 0.249642 -0.249642)
							(end 0.2794 -0.1778)
						)
						(arc
							(start 0.2794 0.1778)
							(mid 0.249642 0.249642)
							(end 0.1778 0.2794)
						)
					)
					(width 0)
					(fill yes)
				)
			)
		)
		(pad "2" smd custom
			(at 0 0.4445 180)
			(size 0.1397 0.1397)
			(layers "B.Cu" "B.Mask" "B.Paste")
			(net "SIO_CLK_1")
			(options
				(clearance outline)
				(anchor circle)
			)
			(primitives
				(gr_poly
					(pts
						(arc
							(start -0.1778 0.2794)
							(mid -0.249642 0.249642)
							(end -0.2794 0.1778)
						)
						(arc
							(start -0.2794 -0.1778)
							(mid -0.249642 -0.249642)
							(end -0.1778 -0.2794)
						)
						(arc
							(start 0.1778 -0.2794)
							(mid 0.249642 -0.249642)
							(end 0.2794 -0.1778)
						)
						(arc
							(start 0.2794 0.1778)
							(mid 0.249642 0.249642)
							(end 0.1778 0.2794)
						)
					)
					(width 0)
					(fill yes)
				)
			)
		)
	)
	(footprint ""
		(layer "B.Cu")
		(at 103.87457 -94.488 -90)
		(property "Reference" "SC1214"
			(at 0 0 90)
			(layer "B.SilkS")
			(hide yes)
			(effects
				(font
					(size 1.27 1.27)
				)
				(justify mirror)
			)
		)
		(property "Value" "SC1KP50V2KX-1GP"
			(at -1.1811 -2.7051 270)
			(unlocked yes)
			(layer "B.Fab")
			(hide yes)
			(effects
				(font
					(size 1.016 1.016)
					(thickness 0.1524)
				)
				(justify mirror)
			)
		)
		(property "Device Type" "C402H22"
			(at -1.1811 -4.2291 270)
			(unlocked yes)
			(layer "B.Fab")
			(hide yes)
			(effects
				(font
					(size 1.016 1.016)
					(thickness 0.1524)
				)
				(justify mirror)
			)
		)
		(duplicate_pad_numbers_are_jumpers no)
		(fp_rect
			(start 0.4318 0.9525)
			(end -0.4318 -0.9525)
			(stroke
				(width 0)
				(type default)
			)
			(fill no)
			(layer "B.CrtYd")
		)
		(fp_rect
			(start 0.4318 0.9525)
			(end -0.4318 -0.9525)
			(stroke
				(width 0)
				(type default)
			)
			(fill no)
			(layer "B.Fab")
		)
		(pad "1" smd custom
			(at 0 -0.4445 90)
			(size 0.1524 0.1524)
			(layers "B.Cu" "B.Mask" "B.Paste")
			(net "P1V8_E")
			(options
				(clearance outline)
				(anchor circle)
			)
			(primitives
				(gr_poly
					(pts
						(arc
							(start 0.3048 0.2032)
							(mid 0.275042 0.275042)
							(end 0.2032 0.3048)
						)
						(arc
							(start -0.2032 0.3048)
							(mid -0.275042 0.275042)
							(end -0.3048 0.2032)
						)
						(arc
							(start -0.3048 -0.2032)
							(mid -0.275042 -0.275042)
							(end -0.2032 -0.3048)
						)
						(arc
							(start 0.2032 -0.3048)
							(mid 0.275042 -0.275042)
							(end 0.3048 -0.2032)
						)
					)
					(width 0)
					(fill yes)
				)
			)
		)
		(pad "2" smd custom
			(at 0 0.4445 90)
			(size 0.1524 0.1524)
			(layers "B.Cu" "B.Mask" "B.Paste")
			(net "GND")
			(options
				(clearance outline)
				(anchor circle)
			)
			(primitives
				(gr_poly
					(pts
						(arc
							(start 0.3048 0.2032)
							(mid 0.275042 0.275042)
							(end 0.2032 0.3048)
						)
						(arc
							(start -0.2032 0.3048)
							(mid -0.275042 0.275042)
							(end -0.3048 0.2032)
						)
						(arc
							(start -0.3048 -0.2032)
							(mid -0.275042 -0.275042)
							(end -0.2032 -0.3048)
						)
						(arc
							(start 0.2032 -0.3048)
							(mid 0.275042 -0.275042)
							(end 0.3048 -0.2032)
						)
					)
					(width 0)
					(fill yes)
				)
			)
		)
	)
	(footprint ""
		(layer "B.Cu")
		(at 15.833344 -175.260762 90)
		(property "Reference" "SC1116"
			(at 0 0 90)
			(layer "B.SilkS")
			(hide yes)
			(effects
				(font
					(size 1.27 1.27)
				)
				(justify mirror)
			)
		)
		(property "Value" "SCD1U16V2KX-3GP"
			(at -1.1811 -2.7051 90)
			(unlocked yes)
			(layer "B.Fab")
			(hide yes)
			(effects
				(font
					(size 1.016 1.016)
					(thickness 0.1524)
				)
				(justify mirror)
			)
		)
		(property "Device Type" "C402H22"
			(at -1.1811 -4.2291 90)
			(unlocked yes)
			(layer "B.Fab")
			(hide yes)
			(effects
				(font
					(size 1.016 1.016)
					(thickness 0.1524)
				)
				(justify mirror)
			)
		)
		(duplicate_pad_numbers_are_jumpers no)
		(fp_rect
			(start 0.4318 0.9525)
			(end -0.4318 -0.9525)
			(stroke
				(width 0)
				(type default)
			)
			(fill no)
			(layer "B.CrtYd")
		)
		(fp_rect
			(start 0.4318 0.9525)
			(end -0.4318 -0.9525)
			(stroke
				(width 0)
				(type default)
			)
			(fill no)
			(layer "B.Fab")
		)
		(pad "1" smd custom
			(at 0 -0.4445 270)
			(size 0.1524 0.1524)
			(layers "B.Cu" "B.Mask" "B.Paste")
			(net "P3V3_STBY")
			(options
				(clearance outline)
				(anchor circle)
			)
			(primitives
				(gr_poly
					(pts
						(arc
							(start 0.3048 0.2032)
							(mid 0.275042 0.275042)
							(end 0.2032 0.3048)
						)
						(arc
							(start -0.2032 0.3048)
							(mid -0.275042 0.275042)
							(end -0.3048 0.2032)
						)
						(arc
							(start -0.3048 -0.2032)
							(mid -0.275042 -0.275042)
							(end -0.2032 -0.3048)
						)
						(arc
							(start 0.2032 -0.3048)
							(mid 0.275042 -0.275042)
							(end 0.3048 -0.2032)
						)
					)
					(width 0)
					(fill yes)
				)
			)
		)
		(pad "2" smd custom
			(at 0 0.4445 270)
			(size 0.1524 0.1524)
			(layers "B.Cu" "B.Mask" "B.Paste")
			(net "GND")
			(options
				(clearance outline)
				(anchor circle)
			)
			(primitives
				(gr_poly
					(pts
						(arc
							(start 0.3048 0.2032)
							(mid 0.275042 0.275042)
							(end 0.2032 0.3048)
						)
						(arc
							(start -0.2032 0.3048)
							(mid -0.275042 0.275042)
							(end -0.3048 0.2032)
						)
						(arc
							(start -0.3048 -0.2032)
							(mid -0.275042 -0.275042)
							(end -0.2032 -0.3048)
						)
						(arc
							(start 0.2032 -0.3048)
							(mid 0.275042 -0.275042)
							(end 0.3048 -0.2032)
						)
					)
					(width 0)
					(fill yes)
				)
			)
		)
	)
	(footprint ""
		(layer "B.Cu")
		(at 119.90197 -84.836)
		(property "Reference" "STP114"
			(at 0 0 0)
			(layer "B.SilkS")
			(hide yes)
			(effects
				(font
					(size 1.27 1.27)
				)
				(justify mirror)
			)
		)
		(property "Value" "TPAD28"
			(at -0.0127 -1.8034 0)
			(unlocked yes)
			(layer "B.Fab")
			(hide yes)
			(effects
				(font
					(size 1.016 1.016)
					(thickness 0.1524)
				)
				(justify mirror)
			)
		)
		(property "Device Type" "TPAD28"
			(at -0.0127 -3.3274 0)
			(unlocked yes)
			(layer "B.Fab")
			(hide yes)
			(effects
				(font
					(size 1.016 1.016)
					(thickness 0.1524)
				)
				(justify mirror)
			)
		)
		(duplicate_pad_numbers_are_jumpers no)
		(fp_poly
			(pts
				(arc
					(start 0.3556 0)
					(mid -0.3556 0)
					(end 0.3556 0)
				)
			)
			(stroke
				(width 0)
				(type default)
			)
			(fill no)
			(layer "B.CrtYd")
		)
		(fp_poly
			(pts
				(arc
					(start 0.6096 0)
					(mid -0.6096 0)
					(end 0.6096 0)
				)
			)
			(stroke
				(width 0)
				(type default)
			)
			(fill no)
			(layer "B.Fab")
		)
		(pad "1" smd circle
			(at 0 0 180)
			(size 0.7112 0.7112)
			(layers "B.Cu" "B.Mask" "B.Paste")
			(net "TEST_MUX_47")
		)
	)
	(footprint ""
		(layer "B.Cu")
		(at 105.010966 -60.579 180)
		(property "Reference" "SR924"
			(at 0 0 0)
			(layer "B.SilkS")
			(hide yes)
			(effects
				(font
					(size 1.27 1.27)
				)
				(justify mirror)
			)
		)
		(property "Value" "0R2J-2-GP"
			(at -0.064008 -3.993896 180)
			(unlocked yes)
			(layer "B.Fab")
			(hide yes)
			(effects
				(font
					(size 1.016 1.016)
					(thickness 0.1524)
				)
				(justify mirror)
			)
		)
		(property "Device Type" "R402H16"
			(at -0.064008 -5.517896 180)
			(unlocked yes)
			(layer "B.Fab")
			(hide yes)
			(effects
				(font
					(size 1.016 1.016)
					(thickness 0.1524)
				)
				(justify mirror)
			)
		)
		(duplicate_pad_numbers_are_jumpers no)
		(fp_line
			(start 0.508 -0.9398)
			(end 0.508 0.9398)
			(stroke
				(width 0.1524)
				(type default)
			)
			(layer "B.SilkS")
		)
		(fp_line
			(start -0.508 -0.9398)
			(end 0.508 -0.9398)
			(stroke
				(width 0.1524)
				(type default)
			)
			(layer "B.SilkS")
		)
		(fp_rect
			(start 0.508 0.9398)
			(end -0.508 -0.9398)
			(stroke
				(width 0)
				(type default)
			)
			(fill no)
			(layer "B.CrtYd")
		)
		(fp_rect
			(start 0.508 0.9398)
			(end -0.508 -0.9398)
			(stroke
				(width 0)
				(type default)
			)
			(fill no)
			(layer "B.Fab")
		)
		(pad "1" smd custom
			(at 0 -0.4445)
			(size 0.1397 0.1397)
			(layers "B.Cu" "B.Mask" "B.Paste")
			(net "IOC_TDO")
			(options
				(clearance outline)
				(anchor circle)
			)
			(primitives
				(gr_poly
					(pts
						(arc
							(start -0.1778 0.2794)
							(mid -0.249642 0.249642)
							(end -0.2794 0.1778)
						)
						(arc
							(start -0.2794 -0.1778)
							(mid -0.249642 -0.249642)
							(end -0.1778 -0.2794)
						)
						(arc
							(start 0.1778 -0.2794)
							(mid 0.249642 -0.249642)
							(end 0.2794 -0.1778)
						)
						(arc
							(start 0.2794 0.1778)
							(mid 0.249642 0.249642)
							(end 0.1778 0.2794)
						)
					)
					(width 0)
					(fill yes)
				)
			)
		)
		(pad "2" smd custom
			(at 0 0.4445)
			(size 0.1397 0.1397)
			(layers "B.Cu" "B.Mask" "B.Paste")
			(net "JTAG_IOC_TDO")
			(options
				(clearance outline)
				(anchor circle)
			)
			(primitives
				(gr_poly
					(pts
						(arc
							(start -0.1778 0.2794)
							(mid -0.249642 0.249642)
							(end -0.2794 0.1778)
						)
						(arc
							(start -0.2794 -0.1778)
							(mid -0.249642 -0.249642)
							(end -0.1778 -0.2794)
						)
						(arc
							(start 0.1778 -0.2794)
							(mid 0.249642 -0.249642)
							(end 0.2794 -0.1778)
						)
						(arc
							(start 0.2794 0.1778)
							(mid 0.249642 0.249642)
							(end 0.1778 0.2794)
						)
					)
					(width 0)
					(fill yes)
				)
			)
		)
	)
	(footprint ""
		(layer "B.Cu")
		(at 274.193 -179.705 90)
		(property "Reference" "R353"
			(at 0 0 90)
			(layer "B.SilkS")
			(hide yes)
			(effects
				(font
					(size 1.27 1.27)
				)
				(justify mirror)
			)
		)
		(property "Value" "3K3R2F-2-GP"
			(at -0.064008 -3.993896 90)
			(unlocked yes)
			(layer "B.Fab")
			(hide yes)
			(effects
				(font
					(size 1.016 1.016)
					(thickness 0.1524)
				)
				(justify mirror)
			)
		)
		(property "Device Type" "R402H16"
			(at -0.064008 -5.517896 90)
			(unlocked yes)
			(layer "B.Fab")
			(hide yes)
			(effects
				(font
					(size 1.016 1.016)
					(thickness 0.1524)
				)
				(justify mirror)
			)
		)
		(duplicate_pad_numbers_are_jumpers no)
		(fp_line
			(start 0.508 -0.9398)
			(end 0.508 0.9398)
			(stroke
				(width 0.1524)
				(type default)
			)
			(layer "B.SilkS")
		)
		(fp_line
			(start -0.508 -0.9398)
			(end 0.508 -0.9398)
			(stroke
				(width 0.1524)
				(type default)
			)
			(layer "B.SilkS")
		)
		(fp_rect
			(start 0.508 0.9398)
			(end -0.508 -0.9398)
			(stroke
				(width 0)
				(type default)
			)
			(fill no)
			(layer "B.CrtYd")
		)
		(fp_rect
			(start 0.508 0.9398)
			(end -0.508 -0.9398)
			(stroke
				(width 0)
				(type default)
			)
			(fill no)
			(layer "B.Fab")
		)
		(pad "1" smd custom
			(at 0 -0.4445 270)
			(size 0.1397 0.1397)
			(layers "B.Cu" "B.Mask" "B.Paste")
			(net "P3V3_STBY")
			(options
				(clearance outline)
				(anchor circle)
			)
			(primitives
				(gr_poly
					(pts
						(arc
							(start -0.1778 0.2794)
							(mid -0.249642 0.249642)
							(end -0.2794 0.1778)
						)
						(arc
							(start -0.2794 -0.1778)
							(mid -0.249642 -0.249642)
							(end -0.1778 -0.2794)
						)
						(arc
							(start 0.1778 -0.2794)
							(mid 0.249642 -0.249642)
							(end 0.2794 -0.1778)
						)
						(arc
							(start 0.2794 0.1778)
							(mid 0.249642 0.249642)
							(end 0.1778 0.2794)
						)
					)
					(width 0)
					(fill yes)
				)
			)
		)
		(pad "2" smd custom
			(at 0 0.4445 270)
			(size 0.1397 0.1397)
			(layers "B.Cu" "B.Mask" "B.Paste")
			(net "ROMA19")
			(options
				(clearance outline)
				(anchor circle)
			)
			(primitives
				(gr_poly
					(pts
						(arc
							(start -0.1778 0.2794)
							(mid -0.249642 0.249642)
							(end -0.2794 0.1778)
						)
						(arc
							(start -0.2794 -0.1778)
							(mid -0.249642 -0.249642)
							(end -0.1778 -0.2794)
						)
						(arc
							(start 0.1778 -0.2794)
							(mid 0.249642 -0.249642)
							(end 0.2794 -0.1778)
						)
						(arc
							(start 0.2794 0.1778)
							(mid 0.249642 0.249642)
							(end 0.1778 0.2794)
						)
					)
					(width 0)
					(fill yes)
				)
			)
		)
	)
	(footprint ""
		(layer "B.Cu")
		(at 90.02014 -44.82084)
		(property "Reference" "STP49"
			(at 0 0 0)
			(layer "B.SilkS")
			(hide yes)
			(effects
				(font
					(size 1.27 1.27)
				)
				(justify mirror)
			)
		)
		(property "Value" "TPAD28"
			(at -0.0127 -1.8034 0)
			(unlocked yes)
			(layer "B.Fab")
			(hide yes)
			(effects
				(font
					(size 1.016 1.016)
					(thickness 0.1524)
				)
				(justify mirror)
			)
		)
		(property "Device Type" "TPAD28"
			(at -0.0127 -3.3274 0)
			(unlocked yes)
			(layer "B.Fab")
			(hide yes)
			(effects
				(font
					(size 1.016 1.016)
					(thickness 0.1524)
				)
				(justify mirror)
			)
		)
		(duplicate_pad_numbers_are_jumpers no)
		(fp_poly
			(pts
				(arc
					(start 0.3556 0)
					(mid -0.3556 0)
					(end 0.3556 0)
				)
			)
			(stroke
				(width 0)
				(type default)
			)
			(fill no)
			(layer "B.CrtYd")
		)
		(fp_poly
			(pts
				(arc
					(start 0.6096 0)
					(mid -0.6096 0)
					(end 0.6096 0)
				)
			)
			(stroke
				(width 0)
				(type default)
			)
			(fill no)
			(layer "B.Fab")
		)
		(pad "1" smd circle
			(at 0 0 180)
			(size 0.7112 0.7112)
			(layers "B.Cu" "B.Mask" "B.Paste")
			(net "OSC_REF_CLK")
		)
	)
	(footprint ""
		(layer "B.Cu")
		(at 291.914072 -172.131736 180)
		(property "Reference" "C218"
			(at 0 0 0)
			(layer "B.SilkS")
			(hide yes)
			(effects
				(font
					(size 1.27 1.27)
				)
				(justify mirror)
			)
		)
		(property "Value" "SC1U10V2KX-1GP"
			(at -1.1811 -2.7051 180)
			(unlocked yes)
			(layer "B.Fab")
			(hide yes)
			(effects
				(font
					(size 1.016 1.016)
					(thickness 0.1524)
				)
				(justify mirror)
			)
		)
		(property "Device Type" "C402H22"
			(at -1.1811 -4.2291 180)
			(unlocked yes)
			(layer "B.Fab")
			(hide yes)
			(effects
				(font
					(size 1.016 1.016)
					(thickness 0.1524)
				)
				(justify mirror)
			)
		)
		(duplicate_pad_numbers_are_jumpers no)
		(fp_rect
			(start 0.4318 0.9525)
			(end -0.4318 -0.9525)
			(stroke
				(width 0)
				(type default)
			)
			(fill no)
			(layer "B.CrtYd")
		)
		(fp_rect
			(start 0.4318 0.9525)
			(end -0.4318 -0.9525)
			(stroke
				(width 0)
				(type default)
			)
			(fill no)
			(layer "B.Fab")
		)
		(pad "1" smd custom
			(at 0 -0.4445)
			(size 0.1524 0.1524)
			(layers "B.Cu" "B.Mask" "B.Paste")
			(net "P3V3_STBY")
			(options
				(clearance outline)
				(anchor circle)
			)
			(primitives
				(gr_poly
					(pts
						(arc
							(start 0.3048 0.2032)
							(mid 0.275042 0.275042)
							(end 0.2032 0.3048)
						)
						(arc
							(start -0.2032 0.3048)
							(mid -0.275042 0.275042)
							(end -0.3048 0.2032)
						)
						(arc
							(start -0.3048 -0.2032)
							(mid -0.275042 -0.275042)
							(end -0.2032 -0.3048)
						)
						(arc
							(start 0.2032 -0.3048)
							(mid 0.275042 -0.275042)
							(end 0.3048 -0.2032)
						)
					)
					(width 0)
					(fill yes)
				)
			)
		)
		(pad "2" smd custom
			(at 0 0.4445)
			(size 0.1524 0.1524)
			(layers "B.Cu" "B.Mask" "B.Paste")
			(net "GND")
			(options
				(clearance outline)
				(anchor circle)
			)
			(primitives
				(gr_poly
					(pts
						(arc
							(start 0.3048 0.2032)
							(mid 0.275042 0.275042)
							(end 0.2032 0.3048)
						)
						(arc
							(start -0.2032 0.3048)
							(mid -0.275042 0.275042)
							(end -0.3048 0.2032)
						)
						(arc
							(start -0.3048 -0.2032)
							(mid -0.275042 -0.275042)
							(end -0.2032 -0.3048)
						)
						(arc
							(start 0.2032 -0.3048)
							(mid 0.275042 -0.275042)
							(end 0.3048 -0.2032)
						)
					)
					(width 0)
					(fill yes)
				)
			)
		)
	)
	(footprint ""
		(layer "B.Cu")
		(at 257.048 -13.97)
		(property "Reference" "U194"
			(at 0 0 0)
			(layer "B.SilkS")
			(hide yes)
			(effects
				(font
					(size 1.27 1.27)
				)
				(justify mirror)
			)
		)
		(property "Value" "TPS2065DBVT-GP"
			(at 0 -5.1308 0)
			(unlocked yes)
			(layer "B.Fab")
			(hide yes)
			(effects
				(font
					(size 1.016 1.016)
					(thickness 0.1524)
				)
				(justify mirror)
			)
		)
		(property "Device Type" "SOT-23-5H58"
			(at 0 -6.7564 0)
			(unlocked yes)
			(layer "B.Fab")
			(hide yes)
			(effects
				(font
					(size 1.016 1.016)
					(thickness 0.1524)
				)
				(justify mirror)
			)
		)
		(duplicate_pad_numbers_are_jumpers no)
		(fp_line
			(start -1.778 -2.286)
			(end 1.778 -2.286)
			(stroke
				(width 0.1524)
				(type default)
			)
			(layer "B.SilkS")
		)
		(fp_line
			(start -1.778 2.286)
			(end -1.778 -2.286)
			(stroke
				(width 0.1524)
				(type default)
			)
			(layer "B.SilkS")
		)
		(fp_line
			(start 0.254 2.286)
			(end -1.778 2.286)
			(stroke
				(width 0.1524)
				(type default)
			)
			(layer "B.SilkS")
		)
		(fp_line
			(start 0.7112 2.2352)
			(end 1.7272 2.2352)
			(stroke
				(width 0.3302)
				(type default)
			)
			(layer "B.SilkS")
		)
		(fp_line
			(start 1.7272 2.2352)
			(end 1.7272 0.762)
			(stroke
				(width 0.3302)
				(type default)
			)
			(layer "B.SilkS")
		)
		(fp_line
			(start 1.778 -2.286)
			(end 1.778 2.286)
			(stroke
				(width 0.1524)
				(type default)
			)
			(layer "B.SilkS")
		)
		(fp_line
			(start 1.778 2.286)
			(end -1.778 2.286)
			(stroke
				(width 0.1524)
				(type default)
			)
			(layer "B.SilkS")
		)
		(fp_line
			(start 1.778 2.286)
			(end 0.254 2.286)
			(stroke
				(width 0.1524)
				(type default)
			)
			(layer "B.SilkS")
		)
		(fp_poly
			(pts
				(xy 0.9652 2.4384) (xy 1.3208 2.794) (xy 0.6096 2.794)
			)
			(stroke
				(width 0)
				(type default)
			)
			(fill yes)
			(layer "B.SilkS")
		)
		(fp_rect
			(start 1.778 2.286)
			(end -1.778 -2.286)
			(stroke
				(width 0)
				(type default)
			)
			(fill no)
			(layer "B.CrtYd")
		)
		(fp_rect
			(start 1.778 2.286)
			(end -1.778 -2.286)
			(stroke
				(width 0)
				(type default)
			)
			(fill no)
			(layer "B.Fab")
		)
		(pad "1" smd rect
			(at 0.94996 1.143 180)
			(size 0.508 1.524)
			(layers "B.Cu" "B.Mask" "B.Paste")
			(net "P5V_USB")
		)
		(pad "2" smd rect
			(at 0 1.143 180)
			(size 0.508 1.524)
			(layers "B.Cu" "B.Mask" "B.Paste")
			(net "GND")
		)
		(pad "3" smd rect
			(at -0.94996 1.143 180)
			(size 0.508 1.524)
			(layers "B.Cu" "B.Mask" "B.Paste")
			(net "USB_OCS_N1")
		)
		(pad "4" smd rect
			(at -0.94996 -1.143 180)
			(size 0.508 1.524)
			(layers "B.Cu" "B.Mask" "B.Paste")
			(net "USB_EN_1")
		)
		(pad "5" smd rect
			(at 0.94996 -1.143 180)
			(size 0.508 1.524)
			(layers "B.Cu" "B.Mask" "B.Paste")
			(net "P5V_USB_BP1_F")
		)
	)
	(footprint ""
		(layer "B.Cu")
		(at 113.93297 -85.852 90)
		(property "Reference" "STP57"
			(at 0 0 90)
			(layer "B.SilkS")
			(hide yes)
			(effects
				(font
					(size 1.27 1.27)
				)
				(justify mirror)
			)
		)
		(property "Value" "TPAD28"
			(at -0.0127 -1.8034 90)
			(unlocked yes)
			(layer "B.Fab")
			(hide yes)
			(effects
				(font
					(size 1.016 1.016)
					(thickness 0.1524)
				)
				(justify mirror)
			)
		)
		(property "Device Type" "TPAD28"
			(at -0.0127 -3.3274 90)
			(unlocked yes)
			(layer "B.Fab")
			(hide yes)
			(effects
				(font
					(size 1.016 1.016)
					(thickness 0.1524)
				)
				(justify mirror)
			)
		)
		(duplicate_pad_numbers_are_jumpers no)
		(fp_poly
			(pts
				(arc
					(start 0 0.3556)
					(mid 0 -0.3556)
					(end 0 0.3556)
				)
			)
			(stroke
				(width 0)
				(type default)
			)
			(fill no)
			(layer "B.CrtYd")
		)
		(fp_poly
			(pts
				(arc
					(start 0 0.6096)
					(mid 0 -0.6096)
					(end 0 0.6096)
				)
			)
			(stroke
				(width 0)
				(type default)
			)
			(fill no)
			(layer "B.Fab")
		)
		(pad "1" smd circle
			(at 0 0 270)
			(size 0.7112 0.7112)
			(layers "B.Cu" "B.Mask" "B.Paste")
			(net "EXP_LED19")
		)
	)
	(footprint ""
		(layer "B.Cu")
		(at 127.11557 -89.281 90)
		(property "Reference" "SC1174"
			(at 0 0 90)
			(layer "B.SilkS")
			(hide yes)
			(effects
				(font
					(size 1.27 1.27)
				)
				(justify mirror)
			)
		)
		(property "Value" "SCD1U16V2KX-3GP"
			(at -1.1811 -2.7051 90)
			(unlocked yes)
			(layer "B.Fab")
			(hide yes)
			(effects
				(font
					(size 1.016 1.016)
					(thickness 0.1524)
				)
				(justify mirror)
			)
		)
		(property "Device Type" "C402H22"
			(at -1.1811 -4.2291 90)
			(unlocked yes)
			(layer "B.Fab")
			(hide yes)
			(effects
				(font
					(size 1.016 1.016)
					(thickness 0.1524)
				)
				(justify mirror)
			)
		)
		(duplicate_pad_numbers_are_jumpers no)
		(fp_rect
			(start 0.4318 0.9525)
			(end -0.4318 -0.9525)
			(stroke
				(width 0)
				(type default)
			)
			(fill no)
			(layer "B.CrtYd")
		)
		(fp_rect
			(start 0.4318 0.9525)
			(end -0.4318 -0.9525)
			(stroke
				(width 0)
				(type default)
			)
			(fill no)
			(layer "B.Fab")
		)
		(pad "1" smd custom
			(at 0 -0.4445 270)
			(size 0.1524 0.1524)
			(layers "B.Cu" "B.Mask" "B.Paste")
			(net "GB_VDDA")
			(options
				(clearance outline)
				(anchor circle)
			)
			(primitives
				(gr_poly
					(pts
						(arc
							(start 0.3048 0.2032)
							(mid 0.275042 0.275042)
							(end 0.2032 0.3048)
						)
						(arc
							(start -0.2032 0.3048)
							(mid -0.275042 0.275042)
							(end -0.3048 0.2032)
						)
						(arc
							(start -0.3048 -0.2032)
							(mid -0.275042 -0.275042)
							(end -0.2032 -0.3048)
						)
						(arc
							(start 0.2032 -0.3048)
							(mid 0.275042 -0.275042)
							(end 0.3048 -0.2032)
						)
					)
					(width 0)
					(fill yes)
				)
			)
		)
		(pad "2" smd custom
			(at 0 0.4445 270)
			(size 0.1524 0.1524)
			(layers "B.Cu" "B.Mask" "B.Paste")
			(net "GND")
			(options
				(clearance outline)
				(anchor circle)
			)
			(primitives
				(gr_poly
					(pts
						(arc
							(start 0.3048 0.2032)
							(mid 0.275042 0.275042)
							(end 0.2032 0.3048)
						)
						(arc
							(start -0.2032 0.3048)
							(mid -0.275042 0.275042)
							(end -0.3048 0.2032)
						)
						(arc
							(start -0.3048 -0.2032)
							(mid -0.275042 -0.275042)
							(end -0.2032 -0.3048)
						)
						(arc
							(start 0.2032 -0.3048)
							(mid 0.275042 -0.275042)
							(end 0.3048 -0.2032)
						)
					)
					(width 0)
					(fill yes)
				)
			)
		)
	)
	(footprint ""
		(layer "B.Cu")
		(at 115.628166 -41.26484)
		(property "Reference" "STP1"
			(at 0 0 0)
			(layer "B.SilkS")
			(hide yes)
			(effects
				(font
					(size 1.27 1.27)
				)
				(justify mirror)
			)
		)
		(property "Value" "TPAD28"
			(at -0.0127 -1.8034 0)
			(unlocked yes)
			(layer "B.Fab")
			(hide yes)
			(effects
				(font
					(size 1.016 1.016)
					(thickness 0.1524)
				)
				(justify mirror)
			)
		)
		(property "Device Type" "TPAD28"
			(at -0.0127 -3.3274 0)
			(unlocked yes)
			(layer "B.Fab")
			(hide yes)
			(effects
				(font
					(size 1.016 1.016)
					(thickness 0.1524)
				)
				(justify mirror)
			)
		)
		(duplicate_pad_numbers_are_jumpers no)
		(fp_poly
			(pts
				(arc
					(start 0.3556 0)
					(mid -0.3556 0)
					(end 0.3556 0)
				)
			)
			(stroke
				(width 0)
				(type default)
			)
			(fill no)
			(layer "B.CrtYd")
		)
		(fp_poly
			(pts
				(arc
					(start 0.6096 0)
					(mid -0.6096 0)
					(end 0.6096 0)
				)
			)
			(stroke
				(width 0)
				(type default)
			)
			(fill no)
			(layer "B.Fab")
		)
		(pad "1" smd circle
			(at 0 0 180)
			(size 0.7112 0.7112)
			(layers "B.Cu" "B.Mask" "B.Paste")
			(net "IOC_GPIO_24")
		)
	)
	(footprint ""
		(layer "B.Cu")
		(at 110.713266 -40.28948 -90)
		(property "Reference" "SC987"
			(at 0 0 90)
			(layer "B.SilkS")
			(hide yes)
			(effects
				(font
					(size 1.27 1.27)
				)
				(justify mirror)
			)
		)
		(property "Value" "SCD1U16V2KX-3GP"
			(at -1.1811 -2.7051 270)
			(unlocked yes)
			(layer "B.Fab")
			(hide yes)
			(effects
				(font
					(size 1.016 1.016)
					(thickness 0.1524)
				)
				(justify mirror)
			)
		)
		(property "Device Type" "C402H22"
			(at -1.1811 -4.2291 270)
			(unlocked yes)
			(layer "B.Fab")
			(hide yes)
			(effects
				(font
					(size 1.016 1.016)
					(thickness 0.1524)
				)
				(justify mirror)
			)
		)
		(duplicate_pad_numbers_are_jumpers no)
		(fp_rect
			(start 0.4318 0.9525)
			(end -0.4318 -0.9525)
			(stroke
				(width 0)
				(type default)
			)
			(fill no)
			(layer "B.CrtYd")
		)
		(fp_rect
			(start 0.4318 0.9525)
			(end -0.4318 -0.9525)
			(stroke
				(width 0)
				(type default)
			)
			(fill no)
			(layer "B.Fab")
		)
		(pad "1" smd custom
			(at 0 -0.4445 90)
			(size 0.1524 0.1524)
			(layers "B.Cu" "B.Mask" "B.Paste")
			(net "P1V8_C")
			(options
				(clearance outline)
				(anchor circle)
			)
			(primitives
				(gr_poly
					(pts
						(arc
							(start 0.3048 0.2032)
							(mid 0.275042 0.275042)
							(end 0.2032 0.3048)
						)
						(arc
							(start -0.2032 0.3048)
							(mid -0.275042 0.275042)
							(end -0.3048 0.2032)
						)
						(arc
							(start -0.3048 -0.2032)
							(mid -0.275042 -0.275042)
							(end -0.2032 -0.3048)
						)
						(arc
							(start 0.2032 -0.3048)
							(mid 0.275042 -0.275042)
							(end 0.3048 -0.2032)
						)
					)
					(width 0)
					(fill yes)
				)
			)
		)
		(pad "2" smd custom
			(at 0 0.4445 90)
			(size 0.1524 0.1524)
			(layers "B.Cu" "B.Mask" "B.Paste")
			(net "GND")
			(options
				(clearance outline)
				(anchor circle)
			)
			(primitives
				(gr_poly
					(pts
						(arc
							(start 0.3048 0.2032)
							(mid 0.275042 0.275042)
							(end 0.2032 0.3048)
						)
						(arc
							(start -0.2032 0.3048)
							(mid -0.275042 0.275042)
							(end -0.3048 0.2032)
						)
						(arc
							(start -0.3048 -0.2032)
							(mid -0.275042 -0.275042)
							(end -0.2032 -0.3048)
						)
						(arc
							(start 0.2032 -0.3048)
							(mid 0.275042 -0.275042)
							(end 0.3048 -0.2032)
						)
					)
					(width 0)
					(fill yes)
				)
			)
		)
	)
	(footprint ""
		(layer "B.Cu")
		(at 100.21697 -109.982 180)
		(property "Reference" "SR748"
			(at 0 0 0)
			(layer "B.SilkS")
			(hide yes)
			(effects
				(font
					(size 1.27 1.27)
				)
				(justify mirror)
			)
		)
		(property "Value" "4K7R2F-GP"
			(at -0.064008 -3.993896 180)
			(unlocked yes)
			(layer "B.Fab")
			(hide yes)
			(effects
				(font
					(size 1.016 1.016)
					(thickness 0.1524)
				)
				(justify mirror)
			)
		)
		(property "Device Type" "R402H16"
			(at -0.064008 -5.517896 180)
			(unlocked yes)
			(layer "B.Fab")
			(hide yes)
			(effects
				(font
					(size 1.016 1.016)
					(thickness 0.1524)
				)
				(justify mirror)
			)
		)
		(duplicate_pad_numbers_are_jumpers no)
		(fp_line
			(start 0.508 -0.9398)
			(end 0.508 0.9398)
			(stroke
				(width 0.1524)
				(type default)
			)
			(layer "B.SilkS")
		)
		(fp_line
			(start -0.508 -0.9398)
			(end 0.508 -0.9398)
			(stroke
				(width 0.1524)
				(type default)
			)
			(layer "B.SilkS")
		)
		(fp_rect
			(start 0.508 0.9398)
			(end -0.508 -0.9398)
			(stroke
				(width 0)
				(type default)
			)
			(fill no)
			(layer "B.CrtYd")
		)
		(fp_rect
			(start 0.508 0.9398)
			(end -0.508 -0.9398)
			(stroke
				(width 0)
				(type default)
			)
			(fill no)
			(layer "B.Fab")
		)
		(pad "1" smd custom
			(at 0 -0.4445)
			(size 0.1397 0.1397)
			(layers "B.Cu" "B.Mask" "B.Paste")
			(net "SIO_D_OUT")
			(options
				(clearance outline)
				(anchor circle)
			)
			(primitives
				(gr_poly
					(pts
						(arc
							(start -0.1778 0.2794)
							(mid -0.249642 0.249642)
							(end -0.2794 0.1778)
						)
						(arc
							(start -0.2794 -0.1778)
							(mid -0.249642 -0.249642)
							(end -0.1778 -0.2794)
						)
						(arc
							(start 0.1778 -0.2794)
							(mid 0.249642 -0.249642)
							(end 0.2794 -0.1778)
						)
						(arc
							(start 0.2794 0.1778)
							(mid 0.249642 0.249642)
							(end 0.1778 0.2794)
						)
					)
					(width 0)
					(fill yes)
				)
			)
		)
		(pad "2" smd custom
			(at 0 0.4445)
			(size 0.1397 0.1397)
			(layers "B.Cu" "B.Mask" "B.Paste")
			(net "P1V8_E")
			(options
				(clearance outline)
				(anchor circle)
			)
			(primitives
				(gr_poly
					(pts
						(arc
							(start -0.1778 0.2794)
							(mid -0.249642 0.249642)
							(end -0.2794 0.1778)
						)
						(arc
							(start -0.2794 -0.1778)
							(mid -0.249642 -0.249642)
							(end -0.1778 -0.2794)
						)
						(arc
							(start 0.1778 -0.2794)
							(mid 0.249642 -0.249642)
							(end 0.2794 -0.1778)
						)
						(arc
							(start 0.2794 0.1778)
							(mid 0.249642 0.249642)
							(end 0.1778 0.2794)
						)
					)
					(width 0)
					(fill yes)
				)
			)
		)
	)
	(footprint ""
		(layer "B.Cu")
		(at 103.13416 -31.623)
		(property "Reference" "SC874"
			(at 0 0 0)
			(layer "B.SilkS")
			(hide yes)
			(effects
				(font
					(size 1.27 1.27)
				)
				(justify mirror)
			)
		)
		(property "Value" "SCD22U6D3V1MX-1-GP"
			(at 2.8321 -1.7399 0)
			(unlocked yes)
			(layer "B.Fab")
			(hide yes)
			(effects
				(font
					(size 1.016 1.016)
					(thickness 0.1524)
				)
				(justify mirror)
			)
		)
		(property "Device Type" "C0201H13"
			(at 2.8321 -3.2639 0)
			(unlocked yes)
			(layer "B.Fab")
			(hide yes)
			(effects
				(font
					(size 1.016 1.016)
					(thickness 0.1524)
				)
				(justify mirror)
			)
		)
		(duplicate_pad_numbers_are_jumpers no)
		(fp_rect
			(start 0.2794 0.6477)
			(end -0.2794 -0.6477)
			(stroke
				(width 0)
				(type default)
			)
			(fill no)
			(layer "B.CrtYd")
		)
		(fp_rect
			(start 0.2794 0.6477)
			(end -0.2794 -0.6477)
			(stroke
				(width 0)
				(type default)
			)
			(fill no)
			(layer "B.Fab")
		)
		(pad "1" smd custom
			(at 0 -0.2794 180)
			(size 0.0762 0.0762)
			(layers "B.Cu" "B.Mask" "B.Paste")
			(net "PCIE_SAS_C_CPU_RX_N6")
			(options
				(clearance outline)
				(anchor circle)
			)
			(primitives
				(gr_poly
					(pts
						(arc
							(start 0.1524 0.127)
							(mid 0.137521 0.162921)
							(end 0.1016 0.1778)
						)
						(arc
							(start -0.1016 0.1778)
							(mid -0.137521 0.162921)
							(end -0.1524 0.127)
						)
						(arc
							(start -0.1524 -0.127)
							(mid -0.137521 -0.162921)
							(end -0.1016 -0.1778)
						)
						(arc
							(start 0.1016 -0.1778)
							(mid 0.137521 -0.162921)
							(end 0.1524 -0.127)
						)
					)
					(width 0)
					(fill yes)
				)
			)
		)
		(pad "2" smd custom
			(at 0 0.2794 180)
			(size 0.0762 0.0762)
			(layers "B.Cu" "B.Mask" "B.Paste")
			(net "PCIE_SAS_CPU_RX_N6")
			(options
				(clearance outline)
				(anchor circle)
			)
			(primitives
				(gr_poly
					(pts
						(arc
							(start 0.1524 0.127)
							(mid 0.137521 0.162921)
							(end 0.1016 0.1778)
						)
						(arc
							(start -0.1016 0.1778)
							(mid -0.137521 0.162921)
							(end -0.1524 0.127)
						)
						(arc
							(start -0.1524 -0.127)
							(mid -0.137521 -0.162921)
							(end -0.1016 -0.1778)
						)
						(arc
							(start 0.1016 -0.1778)
							(mid 0.137521 -0.162921)
							(end 0.1524 -0.127)
						)
					)
					(width 0)
					(fill yes)
				)
			)
		)
	)
	(footprint ""
		(layer "B.Cu")
		(at 108.839 -62.23 -90)
		(property "Reference" "PR191"
			(at 0 0 90)
			(layer "B.SilkS")
			(hide yes)
			(effects
				(font
					(size 1.27 1.27)
				)
				(justify mirror)
			)
		)
		(property "Value" "221R2F-2-GP"
			(at -0.064008 -3.993896 270)
			(unlocked yes)
			(layer "B.Fab")
			(hide yes)
			(effects
				(font
					(size 1.016 1.016)
					(thickness 0.1524)
				)
				(justify mirror)
			)
		)
		(property "Device Type" "R402H16"
			(at -0.064008 -5.517896 270)
			(unlocked yes)
			(layer "B.Fab")
			(hide yes)
			(effects
				(font
					(size 1.016 1.016)
					(thickness 0.1524)
				)
				(justify mirror)
			)
		)
		(duplicate_pad_numbers_are_jumpers no)
		(fp_line
			(start -0.508 -0.9398)
			(end 0.508 -0.9398)
			(stroke
				(width 0.1524)
				(type default)
			)
			(layer "B.SilkS")
		)
		(fp_line
			(start 0.508 -0.9398)
			(end 0.508 0.9398)
			(stroke
				(width 0.1524)
				(type default)
			)
			(layer "B.SilkS")
		)
		(fp_rect
			(start 0.508 0.9398)
			(end -0.508 -0.9398)
			(stroke
				(width 0)
				(type default)
			)
			(fill no)
			(layer "B.CrtYd")
		)
		(fp_rect
			(start 0.508 0.9398)
			(end -0.508 -0.9398)
			(stroke
				(width 0)
				(type default)
			)
			(fill no)
			(layer "B.Fab")
		)
		(pad "1" smd custom
			(at 0 -0.4445 90)
			(size 0.1397 0.1397)
			(layers "B.Cu" "B.Mask" "B.Paste")
			(net "VT235_VDES_RCC")
			(options
				(clearance outline)
				(anchor circle)
			)
			(primitives
				(gr_poly
					(pts
						(arc
							(start -0.1778 0.2794)
							(mid -0.249642 0.249642)
							(end -0.2794 0.1778)
						)
						(arc
							(start -0.2794 -0.1778)
							(mid -0.249642 -0.249642)
							(end -0.1778 -0.2794)
						)
						(arc
							(start 0.1778 -0.2794)
							(mid 0.249642 -0.249642)
							(end 0.2794 -0.1778)
						)
						(arc
							(start 0.2794 0.1778)
							(mid 0.249642 0.249642)
							(end 0.1778 0.2794)
						)
					)
					(width 0)
					(fill yes)
				)
			)
		)
		(pad "2" smd custom
			(at 0 0.4445 90)
			(size 0.1397 0.1397)
			(layers "B.Cu" "B.Mask" "B.Paste")
			(net "GND")
			(options
				(clearance outline)
				(anchor circle)
			)
			(primitives
				(gr_poly
					(pts
						(arc
							(start -0.1778 0.2794)
							(mid -0.249642 0.249642)
							(end -0.2794 0.1778)
						)
						(arc
							(start -0.2794 -0.1778)
							(mid -0.249642 -0.249642)
							(end -0.1778 -0.2794)
						)
						(arc
							(start 0.1778 -0.2794)
							(mid 0.249642 -0.249642)
							(end 0.2794 -0.1778)
						)
						(arc
							(start 0.2794 0.1778)
							(mid 0.249642 0.249642)
							(end 0.1778 0.2794)
						)
					)
					(width 0)
					(fill yes)
				)
			)
		)
	)
	(footprint ""
		(layer "B.Cu")
		(at 89.789 -3.429 180)
		(property "Reference" "PR179"
			(at 0 0 0)
			(layer "B.SilkS")
			(hide yes)
			(effects
				(font
					(size 1.27 1.27)
				)
				(justify mirror)
			)
		)
		(property "Value" "10KR2F-2-GP"
			(at -0.064008 -3.993896 180)
			(unlocked yes)
			(layer "B.Fab")
			(hide yes)
			(effects
				(font
					(size 1.016 1.016)
					(thickness 0.1524)
				)
				(justify mirror)
			)
		)
		(property "Device Type" "R402H16"
			(at -0.064008 -5.517896 180)
			(unlocked yes)
			(layer "B.Fab")
			(hide yes)
			(effects
				(font
					(size 1.016 1.016)
					(thickness 0.1524)
				)
				(justify mirror)
			)
		)
		(duplicate_pad_numbers_are_jumpers no)
		(fp_line
			(start 0.508 -0.9398)
			(end 0.508 0.9398)
			(stroke
				(width 0.1524)
				(type default)
			)
			(layer "B.SilkS")
		)
		(fp_line
			(start -0.508 -0.9398)
			(end 0.508 -0.9398)
			(stroke
				(width 0.1524)
				(type default)
			)
			(layer "B.SilkS")
		)
		(fp_rect
			(start 0.508 0.9398)
			(end -0.508 -0.9398)
			(stroke
				(width 0)
				(type default)
			)
			(fill no)
			(layer "B.CrtYd")
		)
		(fp_rect
			(start 0.508 0.9398)
			(end -0.508 -0.9398)
			(stroke
				(width 0)
				(type default)
			)
			(fill no)
			(layer "B.Fab")
		)
		(pad "1" smd custom
			(at 0 -0.4445)
			(size 0.1397 0.1397)
			(layers "B.Cu" "B.Mask" "B.Paste")
			(net "GND")
			(options
				(clearance outline)
				(anchor circle)
			)
			(primitives
				(gr_poly
					(pts
						(arc
							(start -0.1778 0.2794)
							(mid -0.249642 0.249642)
							(end -0.2794 0.1778)
						)
						(arc
							(start -0.2794 -0.1778)
							(mid -0.249642 -0.249642)
							(end -0.1778 -0.2794)
						)
						(arc
							(start 0.1778 -0.2794)
							(mid 0.249642 -0.249642)
							(end 0.2794 -0.1778)
						)
						(arc
							(start 0.2794 0.1778)
							(mid 0.249642 0.249642)
							(end 0.1778 0.2794)
						)
					)
					(width 0)
					(fill yes)
				)
			)
		)
		(pad "2" smd custom
			(at 0 0.4445)
			(size 0.1397 0.1397)
			(layers "B.Cu" "B.Mask" "B.Paste")
			(net "P0V955_C")
			(options
				(clearance outline)
				(anchor circle)
			)
			(primitives
				(gr_poly
					(pts
						(arc
							(start -0.1778 0.2794)
							(mid -0.249642 0.249642)
							(end -0.2794 0.1778)
						)
						(arc
							(start -0.2794 -0.1778)
							(mid -0.249642 -0.249642)
							(end -0.1778 -0.2794)
						)
						(arc
							(start 0.1778 -0.2794)
							(mid 0.249642 -0.249642)
							(end 0.2794 -0.1778)
						)
						(arc
							(start 0.2794 0.1778)
							(mid 0.249642 0.249642)
							(end 0.1778 0.2794)
						)
					)
					(width 0)
					(fill yes)
				)
			)
		)
	)
	(footprint ""
		(layer "B.Cu")
		(at 107.525566 -36.98748)
		(property "Reference" "STP42"
			(at 0 0 0)
			(layer "B.SilkS")
			(hide yes)
			(effects
				(font
					(size 1.27 1.27)
				)
				(justify mirror)
			)
		)
		(property "Value" "TPAD28"
			(at -0.0127 -1.8034 0)
			(unlocked yes)
			(layer "B.Fab")
			(hide yes)
			(effects
				(font
					(size 1.016 1.016)
					(thickness 0.1524)
				)
				(justify mirror)
			)
		)
		(property "Device Type" "TPAD28"
			(at -0.0127 -3.3274 0)
			(unlocked yes)
			(layer "B.Fab")
			(hide yes)
			(effects
				(font
					(size 1.016 1.016)
					(thickness 0.1524)
				)
				(justify mirror)
			)
		)
		(duplicate_pad_numbers_are_jumpers no)
		(fp_poly
			(pts
				(arc
					(start 0.3556 0)
					(mid -0.3556 0)
					(end 0.3556 0)
				)
			)
			(stroke
				(width 0)
				(type default)
			)
			(fill no)
			(layer "B.CrtYd")
		)
		(fp_poly
			(pts
				(arc
					(start 0.6096 0)
					(mid -0.6096 0)
					(end 0.6096 0)
				)
			)
			(stroke
				(width 0)
				(type default)
			)
			(fill no)
			(layer "B.Fab")
		)
		(pad "1" smd circle
			(at 0 0 180)
			(size 0.7112 0.7112)
			(layers "B.Cu" "B.Mask" "B.Paste")
			(net "SYS_DBMODE0")
		)
	)
	(footprint ""
		(layer "B.Cu")
		(at 124.403612 -215.519 90)
		(property "Reference" "SR905"
			(at 0 0 90)
			(layer "B.SilkS")
			(hide yes)
			(effects
				(font
					(size 1.27 1.27)
				)
				(justify mirror)
			)
		)
		(property "Value" "4K7R2F-GP"
			(at -0.064008 -3.993896 90)
			(unlocked yes)
			(layer "B.Fab")
			(hide yes)
			(effects
				(font
					(size 1.016 1.016)
					(thickness 0.1524)
				)
				(justify mirror)
			)
		)
		(property "Device Type" "R402H16"
			(at -0.064008 -5.517896 90)
			(unlocked yes)
			(layer "B.Fab")
			(hide yes)
			(effects
				(font
					(size 1.016 1.016)
					(thickness 0.1524)
				)
				(justify mirror)
			)
		)
		(duplicate_pad_numbers_are_jumpers no)
		(fp_line
			(start 0.508 -0.9398)
			(end 0.508 0.9398)
			(stroke
				(width 0.1524)
				(type default)
			)
			(layer "B.SilkS")
		)
		(fp_line
			(start -0.508 -0.9398)
			(end 0.508 -0.9398)
			(stroke
				(width 0.1524)
				(type default)
			)
			(layer "B.SilkS")
		)
		(fp_rect
			(start 0.508 0.9398)
			(end -0.508 -0.9398)
			(stroke
				(width 0)
				(type default)
			)
			(fill no)
			(layer "B.CrtYd")
		)
		(fp_rect
			(start 0.508 0.9398)
			(end -0.508 -0.9398)
			(stroke
				(width 0)
				(type default)
			)
			(fill no)
			(layer "B.Fab")
		)
		(pad "1" smd custom
			(at 0 -0.4445 270)
			(size 0.1397 0.1397)
			(layers "B.Cu" "B.Mask" "B.Paste")
			(net "REDV_D2_A")
			(options
				(clearance outline)
				(anchor circle)
			)
			(primitives
				(gr_poly
					(pts
						(arc
							(start -0.1778 0.2794)
							(mid -0.249642 0.249642)
							(end -0.2794 0.1778)
						)
						(arc
							(start -0.2794 -0.1778)
							(mid -0.249642 -0.249642)
							(end -0.1778 -0.2794)
						)
						(arc
							(start 0.1778 -0.2794)
							(mid 0.249642 -0.249642)
							(end 0.2794 -0.1778)
						)
						(arc
							(start 0.2794 0.1778)
							(mid 0.249642 0.249642)
							(end 0.1778 0.2794)
						)
					)
					(width 0)
					(fill yes)
				)
			)
		)
		(pad "2" smd custom
			(at 0 0.4445 270)
			(size 0.1397 0.1397)
			(layers "B.Cu" "B.Mask" "B.Paste")
			(net "GND")
			(options
				(clearance outline)
				(anchor circle)
			)
			(primitives
				(gr_poly
					(pts
						(arc
							(start -0.1778 0.2794)
							(mid -0.249642 0.249642)
							(end -0.2794 0.1778)
						)
						(arc
							(start -0.2794 -0.1778)
							(mid -0.249642 -0.249642)
							(end -0.1778 -0.2794)
						)
						(arc
							(start 0.1778 -0.2794)
							(mid 0.249642 -0.249642)
							(end 0.2794 -0.1778)
						)
						(arc
							(start 0.2794 0.1778)
							(mid 0.249642 0.249642)
							(end 0.1778 0.2794)
						)
					)
					(width 0)
					(fill yes)
				)
			)
		)
	)
	(footprint ""
		(layer "B.Cu")
		(at 27.382216 -232.33888)
		(property "Reference" "R504"
			(at 0 0 0)
			(layer "B.SilkS")
			(hide yes)
			(effects
				(font
					(size 1.27 1.27)
				)
				(justify mirror)
			)
		)
		(property "Value" "0R2J-2-GP"
			(at -0.064008 -3.993896 0)
			(unlocked yes)
			(layer "B.Fab")
			(hide yes)
			(effects
				(font
					(size 1.016 1.016)
					(thickness 0.1524)
				)
				(justify mirror)
			)
		)
		(property "Device Type" "R402H16"
			(at -0.064008 -5.517896 0)
			(unlocked yes)
			(layer "B.Fab")
			(hide yes)
			(effects
				(font
					(size 1.016 1.016)
					(thickness 0.1524)
				)
				(justify mirror)
			)
		)
		(duplicate_pad_numbers_are_jumpers no)
		(fp_line
			(start -0.508 -0.9398)
			(end 0.508 -0.9398)
			(stroke
				(width 0.1524)
				(type default)
			)
			(layer "B.SilkS")
		)
		(fp_line
			(start 0.508 -0.9398)
			(end 0.508 0.9398)
			(stroke
				(width 0.1524)
				(type default)
			)
			(layer "B.SilkS")
		)
		(fp_rect
			(start 0.508 0.9398)
			(end -0.508 -0.9398)
			(stroke
				(width 0)
				(type default)
			)
			(fill no)
			(layer "B.CrtYd")
		)
		(fp_rect
			(start 0.508 0.9398)
			(end -0.508 -0.9398)
			(stroke
				(width 0)
				(type default)
			)
			(fill no)
			(layer "B.Fab")
		)
		(pad "1" smd custom
			(at 0 -0.4445 180)
			(size 0.1397 0.1397)
			(layers "B.Cu" "B.Mask" "B.Paste")
			(net "SAS_HDD_PWR2_PCIE")
			(options
				(clearance outline)
				(anchor circle)
			)
			(primitives
				(gr_poly
					(pts
						(arc
							(start -0.1778 0.2794)
							(mid -0.249642 0.249642)
							(end -0.2794 0.1778)
						)
						(arc
							(start -0.2794 -0.1778)
							(mid -0.249642 -0.249642)
							(end -0.1778 -0.2794)
						)
						(arc
							(start 0.1778 -0.2794)
							(mid 0.249642 -0.249642)
							(end 0.2794 -0.1778)
						)
						(arc
							(start 0.2794 0.1778)
							(mid 0.249642 0.249642)
							(end 0.1778 0.2794)
						)
					)
					(width 0)
					(fill yes)
				)
			)
		)
		(pad "2" smd custom
			(at 0 0.4445 180)
			(size 0.1397 0.1397)
			(layers "B.Cu" "B.Mask" "B.Paste")
			(net "SAS_HDD_PWR2")
			(options
				(clearance outline)
				(anchor circle)
			)
			(primitives
				(gr_poly
					(pts
						(arc
							(start -0.1778 0.2794)
							(mid -0.249642 0.249642)
							(end -0.2794 0.1778)
						)
						(arc
							(start -0.2794 -0.1778)
							(mid -0.249642 -0.249642)
							(end -0.1778 -0.2794)
						)
						(arc
							(start 0.1778 -0.2794)
							(mid 0.249642 -0.249642)
							(end 0.2794 -0.1778)
						)
						(arc
							(start 0.2794 0.1778)
							(mid 0.249642 0.249642)
							(end 0.1778 0.2794)
						)
					)
					(width 0)
					(fill yes)
				)
			)
		)
	)
	(footprint ""
		(layer "B.Cu")
		(at 90.68816 -39.37 90)
		(property "Reference" "SC939"
			(at 0 0 90)
			(layer "B.SilkS")
			(hide yes)
			(effects
				(font
					(size 1.27 1.27)
				)
				(justify mirror)
			)
		)
		(property "Value" "SCD1U6D3V1KX-GP"
			(at 2.8321 -1.7399 90)
			(unlocked yes)
			(layer "B.Fab")
			(hide yes)
			(effects
				(font
					(size 1.016 1.016)
					(thickness 0.1524)
				)
				(justify mirror)
			)
		)
		(property "Device Type" "C0201H13"
			(at 2.8321 -3.2639 90)
			(unlocked yes)
			(layer "B.Fab")
			(hide yes)
			(effects
				(font
					(size 1.016 1.016)
					(thickness 0.1524)
				)
				(justify mirror)
			)
		)
		(duplicate_pad_numbers_are_jumpers no)
		(fp_rect
			(start 0.2794 0.6477)
			(end -0.2794 -0.6477)
			(stroke
				(width 0)
				(type default)
			)
			(fill no)
			(layer "B.CrtYd")
		)
		(fp_rect
			(start 0.2794 0.6477)
			(end -0.2794 -0.6477)
			(stroke
				(width 0)
				(type default)
			)
			(fill no)
			(layer "B.Fab")
		)
		(pad "1" smd custom
			(at 0 -0.2794 270)
			(size 0.0762 0.0762)
			(layers "B.Cu" "B.Mask" "B.Paste")
			(net "SAS0_VDDH")
			(options
				(clearance outline)
				(anchor circle)
			)
			(primitives
				(gr_poly
					(pts
						(arc
							(start 0.1524 0.127)
							(mid 0.137521 0.162921)
							(end 0.1016 0.1778)
						)
						(arc
							(start -0.1016 0.1778)
							(mid -0.137521 0.162921)
							(end -0.1524 0.127)
						)
						(arc
							(start -0.1524 -0.127)
							(mid -0.137521 -0.162921)
							(end -0.1016 -0.1778)
						)
						(arc
							(start 0.1016 -0.1778)
							(mid 0.137521 -0.162921)
							(end 0.1524 -0.127)
						)
					)
					(width 0)
					(fill yes)
				)
			)
		)
		(pad "2" smd custom
			(at 0 0.2794 270)
			(size 0.0762 0.0762)
			(layers "B.Cu" "B.Mask" "B.Paste")
			(net "GND")
			(options
				(clearance outline)
				(anchor circle)
			)
			(primitives
				(gr_poly
					(pts
						(arc
							(start 0.1524 0.127)
							(mid 0.137521 0.162921)
							(end 0.1016 0.1778)
						)
						(arc
							(start -0.1016 0.1778)
							(mid -0.137521 0.162921)
							(end -0.1524 0.127)
						)
						(arc
							(start -0.1524 -0.127)
							(mid -0.137521 -0.162921)
							(end -0.1016 -0.1778)
						)
						(arc
							(start 0.1016 -0.1778)
							(mid 0.137521 -0.162921)
							(end 0.1524 -0.127)
						)
					)
					(width 0)
					(fill yes)
				)
			)
		)
	)
	(footprint ""
		(layer "B.Cu")
		(at 122.18797 -103.378 180)
		(property "Reference" "SC1180"
			(at 0 0 0)
			(layer "B.SilkS")
			(hide yes)
			(effects
				(font
					(size 1.27 1.27)
				)
				(justify mirror)
			)
		)
		(property "Value" "SCD1U6D3V1KX-GP"
			(at 2.8321 -1.7399 180)
			(unlocked yes)
			(layer "B.Fab")
			(hide yes)
			(effects
				(font
					(size 1.016 1.016)
					(thickness 0.1524)
				)
				(justify mirror)
			)
		)
		(property "Device Type" "C0201H13"
			(at 2.8321 -3.2639 180)
			(unlocked yes)
			(layer "B.Fab")
			(hide yes)
			(effects
				(font
					(size 1.016 1.016)
					(thickness 0.1524)
				)
				(justify mirror)
			)
		)
		(duplicate_pad_numbers_are_jumpers no)
		(fp_rect
			(start 0.2794 0.6477)
			(end -0.2794 -0.6477)
			(stroke
				(width 0)
				(type default)
			)
			(fill no)
			(layer "B.CrtYd")
		)
		(fp_rect
			(start 0.2794 0.6477)
			(end -0.2794 -0.6477)
			(stroke
				(width 0)
				(type default)
			)
			(fill no)
			(layer "B.Fab")
		)
		(pad "1" smd custom
			(at 0 -0.2794)
			(size 0.0762 0.0762)
			(layers "B.Cu" "B.Mask" "B.Paste")
			(net "GB_VDDA")
			(options
				(clearance outline)
				(anchor circle)
			)
			(primitives
				(gr_poly
					(pts
						(arc
							(start 0.1524 0.127)
							(mid 0.137521 0.162921)
							(end 0.1016 0.1778)
						)
						(arc
							(start -0.1016 0.1778)
							(mid -0.137521 0.162921)
							(end -0.1524 0.127)
						)
						(arc
							(start -0.1524 -0.127)
							(mid -0.137521 -0.162921)
							(end -0.1016 -0.1778)
						)
						(arc
							(start 0.1016 -0.1778)
							(mid 0.137521 -0.162921)
							(end 0.1524 -0.127)
						)
					)
					(width 0)
					(fill yes)
				)
			)
		)
		(pad "2" smd custom
			(at 0 0.2794)
			(size 0.0762 0.0762)
			(layers "B.Cu" "B.Mask" "B.Paste")
			(net "GND")
			(options
				(clearance outline)
				(anchor circle)
			)
			(primitives
				(gr_poly
					(pts
						(arc
							(start 0.1524 0.127)
							(mid 0.137521 0.162921)
							(end 0.1016 0.1778)
						)
						(arc
							(start -0.1016 0.1778)
							(mid -0.137521 0.162921)
							(end -0.1524 0.127)
						)
						(arc
							(start -0.1524 -0.127)
							(mid -0.137521 -0.162921)
							(end -0.1016 -0.1778)
						)
						(arc
							(start 0.1016 -0.1778)
							(mid 0.137521 -0.162921)
							(end 0.1524 -0.127)
						)
					)
					(width 0)
					(fill yes)
				)
			)
		)
	)
	(footprint ""
		(layer "B.Cu")
		(at 114.56797 -96.52 180)
		(property "Reference" "SC1216"
			(at 0 0 0)
			(layer "B.SilkS")
			(hide yes)
			(effects
				(font
					(size 1.27 1.27)
				)
				(justify mirror)
			)
		)
		(property "Value" "SC1KP50V2KX-1GP"
			(at -1.1811 -2.7051 180)
			(unlocked yes)
			(layer "B.Fab")
			(hide yes)
			(effects
				(font
					(size 1.016 1.016)
					(thickness 0.1524)
				)
				(justify mirror)
			)
		)
		(property "Device Type" "C402H22"
			(at -1.1811 -4.2291 180)
			(unlocked yes)
			(layer "B.Fab")
			(hide yes)
			(effects
				(font
					(size 1.016 1.016)
					(thickness 0.1524)
				)
				(justify mirror)
			)
		)
		(duplicate_pad_numbers_are_jumpers no)
		(fp_rect
			(start 0.4318 0.9525)
			(end -0.4318 -0.9525)
			(stroke
				(width 0)
				(type default)
			)
			(fill no)
			(layer "B.CrtYd")
		)
		(fp_rect
			(start 0.4318 0.9525)
			(end -0.4318 -0.9525)
			(stroke
				(width 0)
				(type default)
			)
			(fill no)
			(layer "B.Fab")
		)
		(pad "1" smd custom
			(at 0 -0.4445)
			(size 0.1524 0.1524)
			(layers "B.Cu" "B.Mask" "B.Paste")
			(net "P0V9_E")
			(options
				(clearance outline)
				(anchor circle)
			)
			(primitives
				(gr_poly
					(pts
						(arc
							(start 0.3048 0.2032)
							(mid 0.275042 0.275042)
							(end 0.2032 0.3048)
						)
						(arc
							(start -0.2032 0.3048)
							(mid -0.275042 0.275042)
							(end -0.3048 0.2032)
						)
						(arc
							(start -0.3048 -0.2032)
							(mid -0.275042 -0.275042)
							(end -0.2032 -0.3048)
						)
						(arc
							(start 0.2032 -0.3048)
							(mid 0.275042 -0.275042)
							(end 0.3048 -0.2032)
						)
					)
					(width 0)
					(fill yes)
				)
			)
		)
		(pad "2" smd custom
			(at 0 0.4445)
			(size 0.1524 0.1524)
			(layers "B.Cu" "B.Mask" "B.Paste")
			(net "GND")
			(options
				(clearance outline)
				(anchor circle)
			)
			(primitives
				(gr_poly
					(pts
						(arc
							(start 0.3048 0.2032)
							(mid 0.275042 0.275042)
							(end 0.2032 0.3048)
						)
						(arc
							(start -0.2032 0.3048)
							(mid -0.275042 0.275042)
							(end -0.3048 0.2032)
						)
						(arc
							(start -0.3048 -0.2032)
							(mid -0.275042 -0.275042)
							(end -0.2032 -0.3048)
						)
						(arc
							(start 0.2032 -0.3048)
							(mid 0.275042 -0.275042)
							(end 0.3048 -0.2032)
						)
					)
					(width 0)
					(fill yes)
				)
			)
		)
	)
	(footprint ""
		(layer "B.Cu")
		(at 13.34008 -231.822752)
		(property "Reference" "R514"
			(at 0 0 0)
			(layer "B.SilkS")
			(hide yes)
			(effects
				(font
					(size 1.27 1.27)
				)
				(justify mirror)
			)
		)
		(property "Value" "0R2J-2-GP"
			(at -0.064008 -3.993896 0)
			(unlocked yes)
			(layer "B.Fab")
			(hide yes)
			(effects
				(font
					(size 1.016 1.016)
					(thickness 0.1524)
				)
				(justify mirror)
			)
		)
		(property "Device Type" "R402H16"
			(at -0.064008 -5.517896 0)
			(unlocked yes)
			(layer "B.Fab")
			(hide yes)
			(effects
				(font
					(size 1.016 1.016)
					(thickness 0.1524)
				)
				(justify mirror)
			)
		)
		(duplicate_pad_numbers_are_jumpers no)
		(fp_line
			(start -0.508 -0.9398)
			(end 0.508 -0.9398)
			(stroke
				(width 0.1524)
				(type default)
			)
			(layer "B.SilkS")
		)
		(fp_line
			(start 0.508 -0.9398)
			(end 0.508 0.9398)
			(stroke
				(width 0.1524)
				(type default)
			)
			(layer "B.SilkS")
		)
		(fp_rect
			(start 0.508 0.9398)
			(end -0.508 -0.9398)
			(stroke
				(width 0)
				(type default)
			)
			(fill no)
			(layer "B.CrtYd")
		)
		(fp_rect
			(start 0.508 0.9398)
			(end -0.508 -0.9398)
			(stroke
				(width 0)
				(type default)
			)
			(fill no)
			(layer "B.Fab")
		)
		(pad "1" smd custom
			(at 0 -0.4445 180)
			(size 0.1397 0.1397)
			(layers "B.Cu" "B.Mask" "B.Paste")
			(net "SAS_HDD_PWR12_PCIE")
			(options
				(clearance outline)
				(anchor circle)
			)
			(primitives
				(gr_poly
					(pts
						(arc
							(start -0.1778 0.2794)
							(mid -0.249642 0.249642)
							(end -0.2794 0.1778)
						)
						(arc
							(start -0.2794 -0.1778)
							(mid -0.249642 -0.249642)
							(end -0.1778 -0.2794)
						)
						(arc
							(start 0.1778 -0.2794)
							(mid 0.249642 -0.249642)
							(end 0.2794 -0.1778)
						)
						(arc
							(start 0.2794 0.1778)
							(mid 0.249642 0.249642)
							(end 0.1778 0.2794)
						)
					)
					(width 0)
					(fill yes)
				)
			)
		)
		(pad "2" smd custom
			(at 0 0.4445 180)
			(size 0.1397 0.1397)
			(layers "B.Cu" "B.Mask" "B.Paste")
			(net "SAS_HDD_PWR12")
			(options
				(clearance outline)
				(anchor circle)
			)
			(primitives
				(gr_poly
					(pts
						(arc
							(start -0.1778 0.2794)
							(mid -0.249642 0.249642)
							(end -0.2794 0.1778)
						)
						(arc
							(start -0.2794 -0.1778)
							(mid -0.249642 -0.249642)
							(end -0.1778 -0.2794)
						)
						(arc
							(start 0.1778 -0.2794)
							(mid 0.249642 -0.249642)
							(end 0.2794 -0.1778)
						)
						(arc
							(start 0.2794 0.1778)
							(mid 0.249642 0.249642)
							(end 0.1778 0.2794)
						)
					)
					(width 0)
					(fill yes)
				)
			)
		)
	)
	(footprint ""
		(layer "B.Cu")
		(at 180.275992 -29.718 90)
		(property "Reference" "BC1"
			(at 0 0 90)
			(layer "B.SilkS")
			(hide yes)
			(effects
				(font
					(size 1.27 1.27)
				)
				(justify mirror)
			)
		)
		(property "Value" "SC2D2U10V3KX-1GP"
			(at 0 -2.8194 90)
			(unlocked yes)
			(layer "B.Fab")
			(hide yes)
			(effects
				(font
					(size 1.016 1.016)
					(thickness 0.1524)
				)
				(justify mirror)
			)
		)
		(property "Device Type" "C603H36"
			(at 0 -4.3434 90)
			(unlocked yes)
			(layer "B.Fab")
			(hide yes)
			(effects
				(font
					(size 1.016 1.016)
					(thickness 0.1524)
				)
				(justify mirror)
			)
		)
		(duplicate_pad_numbers_are_jumpers no)
		(fp_line
			(start -0.508 0)
			(end 0.508 0)
			(stroke
				(width 0.2032)
				(type default)
			)
			(layer "B.SilkS")
		)
		(fp_rect
			(start 0.5842 1.3335)
			(end -0.5842 -1.3335)
			(stroke
				(width 0)
				(type default)
			)
			(fill no)
			(layer "B.CrtYd")
		)
		(fp_rect
			(start 0.5842 1.3335)
			(end -0.5842 -1.3335)
			(stroke
				(width 0)
				(type default)
			)
			(fill no)
			(layer "B.Fab")
		)
		(pad "1" smd custom
			(at 0 -0.762 270)
			(size 0.2159 0.2159)
			(layers "B.Cu" "B.Mask" "B.Paste")
			(net "PHY_AVDD")
			(options
				(clearance outline)
				(anchor circle)
			)
			(primitives
				(gr_poly
					(pts
						(arc
							(start -0.3302 0.4318)
							(mid -0.402042 0.402042)
							(end -0.4318 0.3302)
						)
						(arc
							(start -0.4318 -0.3302)
							(mid -0.402042 -0.402042)
							(end -0.3302 -0.4318)
						)
						(arc
							(start 0.3302 -0.4318)
							(mid 0.402042 -0.402042)
							(end 0.4318 -0.3302)
						)
						(arc
							(start 0.4318 0.3302)
							(mid 0.402042 0.402042)
							(end 0.3302 0.4318)
						)
					)
					(width 0)
					(fill yes)
				)
			)
		)
		(pad "2" smd custom
			(at 0 0.762 270)
			(size 0.2159 0.2159)
			(layers "B.Cu" "B.Mask" "B.Paste")
			(net "GND")
			(options
				(clearance outline)
				(anchor circle)
			)
			(primitives
				(gr_poly
					(pts
						(arc
							(start -0.3302 0.4318)
							(mid -0.402042 0.402042)
							(end -0.4318 0.3302)
						)
						(arc
							(start -0.4318 -0.3302)
							(mid -0.402042 -0.402042)
							(end -0.3302 -0.4318)
						)
						(arc
							(start 0.3302 -0.4318)
							(mid 0.402042 -0.402042)
							(end 0.4318 -0.3302)
						)
						(arc
							(start 0.4318 0.3302)
							(mid 0.402042 0.402042)
							(end 0.3302 0.4318)
						)
					)
					(width 0)
					(fill yes)
				)
			)
		)
	)
	(footprint ""
		(layer "B.Cu")
		(at 110.725966 -43.39844 -90)
		(property "Reference" "SC988"
			(at 0 0 90)
			(layer "B.SilkS")
			(hide yes)
			(effects
				(font
					(size 1.27 1.27)
				)
				(justify mirror)
			)
		)
		(property "Value" "SCD1U16V2KX-3GP"
			(at -1.1811 -2.7051 270)
			(unlocked yes)
			(layer "B.Fab")
			(hide yes)
			(effects
				(font
					(size 1.016 1.016)
					(thickness 0.1524)
				)
				(justify mirror)
			)
		)
		(property "Device Type" "C402H22"
			(at -1.1811 -4.2291 270)
			(unlocked yes)
			(layer "B.Fab")
			(hide yes)
			(effects
				(font
					(size 1.016 1.016)
					(thickness 0.1524)
				)
				(justify mirror)
			)
		)
		(duplicate_pad_numbers_are_jumpers no)
		(fp_rect
			(start 0.4318 0.9525)
			(end -0.4318 -0.9525)
			(stroke
				(width 0)
				(type default)
			)
			(fill no)
			(layer "B.CrtYd")
		)
		(fp_rect
			(start 0.4318 0.9525)
			(end -0.4318 -0.9525)
			(stroke
				(width 0)
				(type default)
			)
			(fill no)
			(layer "B.Fab")
		)
		(pad "1" smd custom
			(at 0 -0.4445 90)
			(size 0.1524 0.1524)
			(layers "B.Cu" "B.Mask" "B.Paste")
			(net "P1V8_C")
			(options
				(clearance outline)
				(anchor circle)
			)
			(primitives
				(gr_poly
					(pts
						(arc
							(start 0.3048 0.2032)
							(mid 0.275042 0.275042)
							(end 0.2032 0.3048)
						)
						(arc
							(start -0.2032 0.3048)
							(mid -0.275042 0.275042)
							(end -0.3048 0.2032)
						)
						(arc
							(start -0.3048 -0.2032)
							(mid -0.275042 -0.275042)
							(end -0.2032 -0.3048)
						)
						(arc
							(start 0.2032 -0.3048)
							(mid 0.275042 -0.275042)
							(end 0.3048 -0.2032)
						)
					)
					(width 0)
					(fill yes)
				)
			)
		)
		(pad "2" smd custom
			(at 0 0.4445 90)
			(size 0.1524 0.1524)
			(layers "B.Cu" "B.Mask" "B.Paste")
			(net "GND")
			(options
				(clearance outline)
				(anchor circle)
			)
			(primitives
				(gr_poly
					(pts
						(arc
							(start 0.3048 0.2032)
							(mid 0.275042 0.275042)
							(end 0.2032 0.3048)
						)
						(arc
							(start -0.2032 0.3048)
							(mid -0.275042 0.275042)
							(end -0.3048 0.2032)
						)
						(arc
							(start -0.3048 -0.2032)
							(mid -0.275042 -0.275042)
							(end -0.2032 -0.3048)
						)
						(arc
							(start 0.2032 -0.3048)
							(mid 0.275042 -0.275042)
							(end 0.3048 -0.2032)
						)
					)
					(width 0)
					(fill yes)
				)
			)
		)
	)
	(footprint ""
		(layer "B.Cu")
		(at 118.894098 -76.890118 -90)
		(property "Reference" "SC1150"
			(at 0 0 90)
			(layer "B.SilkS")
			(hide yes)
			(effects
				(font
					(size 1.27 1.27)
				)
				(justify mirror)
			)
		)
		(property "Value" "SC22U6D3V5MX-2GP"
			(at 0.0762 -6.1214 270)
			(unlocked yes)
			(layer "B.Fab")
			(hide yes)
			(effects
				(font
					(size 1.016 1.016)
					(thickness 0.1524)
				)
				(justify mirror)
			)
		)
		(property "Device Type" "C805H58"
			(at 0.0762 -8.1534 270)
			(unlocked yes)
			(layer "B.Fab")
			(hide yes)
			(effects
				(font
					(size 1.016 1.016)
					(thickness 0.1524)
				)
				(justify mirror)
			)
		)
		(duplicate_pad_numbers_are_jumpers no)
		(fp_line
			(start -0.635 0)
			(end 0.635 0)
			(stroke
				(width 0.508)
				(type default)
			)
			(layer "B.SilkS")
		)
		(fp_rect
			(start 0.9652 1.778)
			(end -0.9652 -1.778)
			(stroke
				(width 0)
				(type default)
			)
			(fill no)
			(layer "B.CrtYd")
		)
		(fp_poly
			(pts
				(xy 0.9652 -1.778) (xy -0.9652 -1.778) (xy -0.9652 1.778) (xy 0.9652 1.778)
			)
			(stroke
				(width 0)
				(type default)
			)
			(fill no)
			(layer "B.Fab")
		)
		(pad "1" smd rect
			(at 0 -0.9652 90)
			(size 1.397 1.143)
			(layers "B.Cu" "B.Mask" "B.Paste")
			(net "XTAL_VDDA18")
		)
		(pad "2" smd rect
			(at 0 0.9652 90)
			(size 1.397 1.143)
			(layers "B.Cu" "B.Mask" "B.Paste")
			(net "GND")
		)
	)
	(footprint ""
		(layer "B.Cu")
		(at 101.962966 -51.054 180)
		(property "Reference" "SC1020"
			(at 0 0 0)
			(layer "B.SilkS")
			(hide yes)
			(effects
				(font
					(size 1.27 1.27)
				)
				(justify mirror)
			)
		)
		(property "Value" "SC10U6D3V5KX-4GP"
			(at 0.0762 -6.1214 180)
			(unlocked yes)
			(layer "B.Fab")
			(hide yes)
			(effects
				(font
					(size 1.016 1.016)
					(thickness 0.1524)
				)
				(justify mirror)
			)
		)
		(property "Device Type" "C805H58"
			(at 0.0762 -8.1534 180)
			(unlocked yes)
			(layer "B.Fab")
			(hide yes)
			(effects
				(font
					(size 1.016 1.016)
					(thickness 0.1524)
				)
				(justify mirror)
			)
		)
		(duplicate_pad_numbers_are_jumpers no)
		(fp_line
			(start -0.635 0)
			(end 0.635 0)
			(stroke
				(width 0.508)
				(type default)
			)
			(layer "B.SilkS")
		)
		(fp_rect
			(start 0.9652 1.778)
			(end -0.9652 -1.778)
			(stroke
				(width 0)
				(type default)
			)
			(fill no)
			(layer "B.CrtYd")
		)
		(fp_poly
			(pts
				(xy 0.9652 -1.778) (xy -0.9652 -1.778) (xy -0.9652 1.778) (xy 0.9652 1.778)
			)
			(stroke
				(width 0)
				(type default)
			)
			(fill no)
			(layer "B.Fab")
		)
		(pad "1" smd rect
			(at 0 -0.9652)
			(size 1.397 1.143)
			(layers "B.Cu" "B.Mask" "B.Paste")
			(net "P0V955_C")
		)
		(pad "2" smd rect
			(at 0 0.9652)
			(size 1.397 1.143)
			(layers "B.Cu" "B.Mask" "B.Paste")
			(net "GND")
		)
	)
	(footprint ""
		(layer "B.Cu")
		(at 120.53697 -106.426 180)
		(property "Reference" "SC1168"
			(at 0 0 0)
			(layer "B.SilkS")
			(hide yes)
			(effects
				(font
					(size 1.27 1.27)
				)
				(justify mirror)
			)
		)
		(property "Value" "SCD1U6D3V1KX-GP"
			(at 2.8321 -1.7399 180)
			(unlocked yes)
			(layer "B.Fab")
			(hide yes)
			(effects
				(font
					(size 1.016 1.016)
					(thickness 0.1524)
				)
				(justify mirror)
			)
		)
		(property "Device Type" "C0201H13"
			(at 2.8321 -3.2639 180)
			(unlocked yes)
			(layer "B.Fab")
			(hide yes)
			(effects
				(font
					(size 1.016 1.016)
					(thickness 0.1524)
				)
				(justify mirror)
			)
		)
		(duplicate_pad_numbers_are_jumpers no)
		(fp_rect
			(start 0.2794 0.6477)
			(end -0.2794 -0.6477)
			(stroke
				(width 0)
				(type default)
			)
			(fill no)
			(layer "B.CrtYd")
		)
		(fp_rect
			(start 0.2794 0.6477)
			(end -0.2794 -0.6477)
			(stroke
				(width 0)
				(type default)
			)
			(fill no)
			(layer "B.Fab")
		)
		(pad "1" smd custom
			(at 0 -0.2794)
			(size 0.0762 0.0762)
			(layers "B.Cu" "B.Mask" "B.Paste")
			(net "GB_VDDA")
			(options
				(clearance outline)
				(anchor circle)
			)
			(primitives
				(gr_poly
					(pts
						(arc
							(start 0.1524 0.127)
							(mid 0.137521 0.162921)
							(end 0.1016 0.1778)
						)
						(arc
							(start -0.1016 0.1778)
							(mid -0.137521 0.162921)
							(end -0.1524 0.127)
						)
						(arc
							(start -0.1524 -0.127)
							(mid -0.137521 -0.162921)
							(end -0.1016 -0.1778)
						)
						(arc
							(start 0.1016 -0.1778)
							(mid 0.137521 -0.162921)
							(end 0.1524 -0.127)
						)
					)
					(width 0)
					(fill yes)
				)
			)
		)
		(pad "2" smd custom
			(at 0 0.2794)
			(size 0.0762 0.0762)
			(layers "B.Cu" "B.Mask" "B.Paste")
			(net "GND")
			(options
				(clearance outline)
				(anchor circle)
			)
			(primitives
				(gr_poly
					(pts
						(arc
							(start 0.1524 0.127)
							(mid 0.137521 0.162921)
							(end 0.1016 0.1778)
						)
						(arc
							(start -0.1016 0.1778)
							(mid -0.137521 0.162921)
							(end -0.1524 0.127)
						)
						(arc
							(start -0.1524 -0.127)
							(mid -0.137521 -0.162921)
							(end -0.1016 -0.1778)
						)
						(arc
							(start 0.1016 -0.1778)
							(mid 0.137521 -0.162921)
							(end 0.1524 -0.127)
						)
					)
					(width 0)
					(fill yes)
				)
			)
		)
	)
	(footprint ""
		(layer "B.Cu")
		(at 295.656 -166.37)
		(property "Reference" "TP152"
			(at 0 0 0)
			(layer "B.SilkS")
			(hide yes)
			(effects
				(font
					(size 1.27 1.27)
				)
				(justify mirror)
			)
		)
		(property "Value" "TPAD28"
			(at -0.0127 -1.8034 0)
			(unlocked yes)
			(layer "B.Fab")
			(hide yes)
			(effects
				(font
					(size 1.016 1.016)
					(thickness 0.1524)
				)
				(justify mirror)
			)
		)
		(property "Device Type" "TPAD28"
			(at -0.0127 -3.3274 0)
			(unlocked yes)
			(layer "B.Fab")
			(hide yes)
			(effects
				(font
					(size 1.016 1.016)
					(thickness 0.1524)
				)
				(justify mirror)
			)
		)
		(duplicate_pad_numbers_are_jumpers no)
		(fp_poly
			(pts
				(arc
					(start 0.3556 0)
					(mid -0.3556 0)
					(end 0.3556 0)
				)
			)
			(stroke
				(width 0)
				(type default)
			)
			(fill no)
			(layer "B.CrtYd")
		)
		(fp_poly
			(pts
				(arc
					(start 0.6096 0)
					(mid -0.6096 0)
					(end 0.6096 0)
				)
			)
			(stroke
				(width 0)
				(type default)
			)
			(fill no)
			(layer "B.Fab")
		)
		(pad "1" smd circle
			(at 0 0 180)
			(size 0.7112 0.7112)
			(layers "B.Cu" "B.Mask" "B.Paste")
			(net "TP_BMC_GPIOU2")
		)
	)
	(footprint ""
		(layer "B.Cu")
		(at 92.564966 -33.401 -90)
		(property "Reference" "SC953"
			(at 0 0 90)
			(layer "B.SilkS")
			(hide yes)
			(effects
				(font
					(size 1.27 1.27)
				)
				(justify mirror)
			)
		)
		(property "Value" "SCD1U6D3V1KX-GP"
			(at 2.8321 -1.7399 270)
			(unlocked yes)
			(layer "B.Fab")
			(hide yes)
			(effects
				(font
					(size 1.016 1.016)
					(thickness 0.1524)
				)
				(justify mirror)
			)
		)
		(property "Device Type" "C0201H13"
			(at 2.8321 -3.2639 270)
			(unlocked yes)
			(layer "B.Fab")
			(hide yes)
			(effects
				(font
					(size 1.016 1.016)
					(thickness 0.1524)
				)
				(justify mirror)
			)
		)
		(duplicate_pad_numbers_are_jumpers no)
		(fp_rect
			(start 0.2794 0.6477)
			(end -0.2794 -0.6477)
			(stroke
				(width 0)
				(type default)
			)
			(fill no)
			(layer "B.CrtYd")
		)
		(fp_rect
			(start 0.2794 0.6477)
			(end -0.2794 -0.6477)
			(stroke
				(width 0)
				(type default)
			)
			(fill no)
			(layer "B.Fab")
		)
		(pad "1" smd custom
			(at 0 -0.2794 90)
			(size 0.0762 0.0762)
			(layers "B.Cu" "B.Mask" "B.Paste")
			(net "PCE_AVDD")
			(options
				(clearance outline)
				(anchor circle)
			)
			(primitives
				(gr_poly
					(pts
						(arc
							(start 0.1524 0.127)
							(mid 0.137521 0.162921)
							(end 0.1016 0.1778)
						)
						(arc
							(start -0.1016 0.1778)
							(mid -0.137521 0.162921)
							(end -0.1524 0.127)
						)
						(arc
							(start -0.1524 -0.127)
							(mid -0.137521 -0.162921)
							(end -0.1016 -0.1778)
						)
						(arc
							(start 0.1016 -0.1778)
							(mid 0.137521 -0.162921)
							(end 0.1524 -0.127)
						)
					)
					(width 0)
					(fill yes)
				)
			)
		)
		(pad "2" smd custom
			(at 0 0.2794 90)
			(size 0.0762 0.0762)
			(layers "B.Cu" "B.Mask" "B.Paste")
			(net "GND")
			(options
				(clearance outline)
				(anchor circle)
			)
			(primitives
				(gr_poly
					(pts
						(arc
							(start 0.1524 0.127)
							(mid 0.137521 0.162921)
							(end 0.1016 0.1778)
						)
						(arc
							(start -0.1016 0.1778)
							(mid -0.137521 0.162921)
							(end -0.1524 0.127)
						)
						(arc
							(start -0.1524 -0.127)
							(mid -0.137521 -0.162921)
							(end -0.1016 -0.1778)
						)
						(arc
							(start 0.1016 -0.1778)
							(mid 0.137521 -0.162921)
							(end 0.1524 -0.127)
						)
					)
					(width 0)
					(fill yes)
				)
			)
		)
	)
	(footprint ""
		(layer "B.Cu")
		(at 274.193 -182.753 90)
		(property "Reference" "R355"
			(at 0 0 90)
			(layer "B.SilkS")
			(hide yes)
			(effects
				(font
					(size 1.27 1.27)
				)
				(justify mirror)
			)
		)
		(property "Value" "3K3R2F-2-GP"
			(at -0.064008 -3.993896 90)
			(unlocked yes)
			(layer "B.Fab")
			(hide yes)
			(effects
				(font
					(size 1.016 1.016)
					(thickness 0.1524)
				)
				(justify mirror)
			)
		)
		(property "Device Type" "R402H16"
			(at -0.064008 -5.517896 90)
			(unlocked yes)
			(layer "B.Fab")
			(hide yes)
			(effects
				(font
					(size 1.016 1.016)
					(thickness 0.1524)
				)
				(justify mirror)
			)
		)
		(duplicate_pad_numbers_are_jumpers no)
		(fp_line
			(start 0.508 -0.9398)
			(end 0.508 0.9398)
			(stroke
				(width 0.1524)
				(type default)
			)
			(layer "B.SilkS")
		)
		(fp_line
			(start -0.508 -0.9398)
			(end 0.508 -0.9398)
			(stroke
				(width 0.1524)
				(type default)
			)
			(layer "B.SilkS")
		)
		(fp_rect
			(start 0.508 0.9398)
			(end -0.508 -0.9398)
			(stroke
				(width 0)
				(type default)
			)
			(fill no)
			(layer "B.CrtYd")
		)
		(fp_rect
			(start 0.508 0.9398)
			(end -0.508 -0.9398)
			(stroke
				(width 0)
				(type default)
			)
			(fill no)
			(layer "B.Fab")
		)
		(pad "1" smd custom
			(at 0 -0.4445 270)
			(size 0.1397 0.1397)
			(layers "B.Cu" "B.Mask" "B.Paste")
			(net "P3V3_STBY")
			(options
				(clearance outline)
				(anchor circle)
			)
			(primitives
				(gr_poly
					(pts
						(arc
							(start -0.1778 0.2794)
							(mid -0.249642 0.249642)
							(end -0.2794 0.1778)
						)
						(arc
							(start -0.2794 -0.1778)
							(mid -0.249642 -0.249642)
							(end -0.1778 -0.2794)
						)
						(arc
							(start 0.1778 -0.2794)
							(mid 0.249642 -0.249642)
							(end 0.2794 -0.1778)
						)
						(arc
							(start 0.2794 0.1778)
							(mid 0.249642 0.249642)
							(end 0.1778 0.2794)
						)
					)
					(width 0)
					(fill yes)
				)
			)
		)
		(pad "2" smd custom
			(at 0 0.4445 270)
			(size 0.1397 0.1397)
			(layers "B.Cu" "B.Mask" "B.Paste")
			(net "ROMA4")
			(options
				(clearance outline)
				(anchor circle)
			)
			(primitives
				(gr_poly
					(pts
						(arc
							(start -0.1778 0.2794)
							(mid -0.249642 0.249642)
							(end -0.2794 0.1778)
						)
						(arc
							(start -0.2794 -0.1778)
							(mid -0.249642 -0.249642)
							(end -0.1778 -0.2794)
						)
						(arc
							(start 0.1778 -0.2794)
							(mid 0.249642 -0.249642)
							(end 0.2794 -0.1778)
						)
						(arc
							(start 0.2794 0.1778)
							(mid 0.249642 0.249642)
							(end 0.1778 0.2794)
						)
					)
					(width 0)
					(fill yes)
				)
			)
		)
	)
	(footprint ""
		(layer "B.Cu")
		(at 49.73193 -79.682086)
		(property "Reference" "TP187"
			(at 0 0 0)
			(layer "B.SilkS")
			(hide yes)
			(effects
				(font
					(size 1.27 1.27)
				)
				(justify mirror)
			)
		)
		(property "Value" "TPAD32-GP"
			(at 0 -3.166364 0)
			(unlocked yes)
			(layer "B.Fab")
			(hide yes)
			(effects
				(font
					(size 1.016 1.016)
					(thickness 0.1524)
				)
				(justify mirror)
			)
		)
		(property "Device Type" "TPAD32"
			(at 0 -4.690618 0)
			(unlocked yes)
			(layer "B.Fab")
			(hide yes)
			(effects
				(font
					(size 1.016 1.016)
					(thickness 0.1524)
				)
				(justify mirror)
			)
		)
		(duplicate_pad_numbers_are_jumpers no)
		(fp_poly
			(pts
				(arc
					(start 0.4064 0)
					(mid -0.4064 0)
					(end 0.4064 0)
				)
			)
			(stroke
				(width 0)
				(type default)
			)
			(fill no)
			(layer "B.CrtYd")
		)
		(fp_poly
			(pts
				(arc
					(start 0.7112 0)
					(mid -0.7112 0)
					(end 0.7112 0)
				)
			)
			(stroke
				(width 0)
				(type default)
			)
			(fill no)
			(layer "B.Fab")
		)
		(pad "1" smd circle
			(at 0 0 180)
			(size 0.8128 0.8128)
			(layers "B.Cu" "B.Mask" "B.Paste")
			(net "INT_CONN_A_SB6")
		)
	)
	(footprint ""
		(layer "B.Cu")
		(at 199.898 -104.902)
		(property "Reference" "PR9018"
			(at 0 0 0)
			(layer "B.SilkS")
			(hide yes)
			(effects
				(font
					(size 1.27 1.27)
				)
				(justify mirror)
			)
		)
		(property "Value" "2KR2F-3-GP"
			(at -0.064008 -3.993896 0)
			(unlocked yes)
			(layer "B.Fab")
			(hide yes)
			(effects
				(font
					(size 1.016 1.016)
					(thickness 0.1524)
				)
				(justify mirror)
			)
		)
		(property "Device Type" "R402H16"
			(at -0.064008 -5.517896 0)
			(unlocked yes)
			(layer "B.Fab")
			(hide yes)
			(effects
				(font
					(size 1.016 1.016)
					(thickness 0.1524)
				)
				(justify mirror)
			)
		)
		(duplicate_pad_numbers_are_jumpers no)
		(fp_line
			(start -0.508 -0.9398)
			(end 0.508 -0.9398)
			(stroke
				(width 0.1524)
				(type default)
			)
			(layer "B.SilkS")
		)
		(fp_line
			(start 0.508 -0.9398)
			(end 0.508 0.9398)
			(stroke
				(width 0.1524)
				(type default)
			)
			(layer "B.SilkS")
		)
		(fp_rect
			(start 0.508 0.9398)
			(end -0.508 -0.9398)
			(stroke
				(width 0)
				(type default)
			)
			(fill no)
			(layer "B.CrtYd")
		)
		(fp_rect
			(start 0.508 0.9398)
			(end -0.508 -0.9398)
			(stroke
				(width 0)
				(type default)
			)
			(fill no)
			(layer "B.Fab")
		)
		(pad "1" smd custom
			(at 0 -0.4445 180)
			(size 0.1397 0.1397)
			(layers "B.Cu" "B.Mask" "B.Paste")
			(net "P1V5_E_SW")
			(options
				(clearance outline)
				(anchor circle)
			)
			(primitives
				(gr_poly
					(pts
						(arc
							(start -0.1778 0.2794)
							(mid -0.249642 0.249642)
							(end -0.2794 0.1778)
						)
						(arc
							(start -0.2794 -0.1778)
							(mid -0.249642 -0.249642)
							(end -0.1778 -0.2794)
						)
						(arc
							(start 0.1778 -0.2794)
							(mid 0.249642 -0.249642)
							(end 0.2794 -0.1778)
						)
						(arc
							(start 0.2794 0.1778)
							(mid 0.249642 0.249642)
							(end 0.1778 0.2794)
						)
					)
					(width 0)
					(fill yes)
				)
			)
		)
		(pad "2" smd custom
			(at 0 0.4445 180)
			(size 0.1397 0.1397)
			(layers "B.Cu" "B.Mask" "B.Paste")
			(net "P1V5_E_VFB_R")
			(options
				(clearance outline)
				(anchor circle)
			)
			(primitives
				(gr_poly
					(pts
						(arc
							(start -0.1778 0.2794)
							(mid -0.249642 0.249642)
							(end -0.2794 0.1778)
						)
						(arc
							(start -0.2794 -0.1778)
							(mid -0.249642 -0.249642)
							(end -0.1778 -0.2794)
						)
						(arc
							(start 0.1778 -0.2794)
							(mid 0.249642 -0.249642)
							(end 0.2794 -0.1778)
						)
						(arc
							(start 0.2794 0.1778)
							(mid 0.249642 0.249642)
							(end 0.1778 0.2794)
						)
					)
					(width 0)
					(fill yes)
				)
			)
		)
	)
	(footprint ""
		(layer "B.Cu")
		(at 120.015 -41.148 -90)
		(property "Reference" "SR623"
			(at 0 0 90)
			(layer "B.SilkS")
			(hide yes)
			(effects
				(font
					(size 1.27 1.27)
				)
				(justify mirror)
			)
		)
		(property "Value" "2K2R2F-GP"
			(at -0.064008 -3.993896 270)
			(unlocked yes)
			(layer "B.Fab")
			(hide yes)
			(effects
				(font
					(size 1.016 1.016)
					(thickness 0.1524)
				)
				(justify mirror)
			)
		)
		(property "Device Type" "R402H16"
			(at -0.064008 -5.517896 270)
			(unlocked yes)
			(layer "B.Fab")
			(hide yes)
			(effects
				(font
					(size 1.016 1.016)
					(thickness 0.1524)
				)
				(justify mirror)
			)
		)
		(duplicate_pad_numbers_are_jumpers no)
		(fp_line
			(start -0.508 -0.9398)
			(end 0.508 -0.9398)
			(stroke
				(width 0.1524)
				(type default)
			)
			(layer "B.SilkS")
		)
		(fp_line
			(start 0.508 -0.9398)
			(end 0.508 0.9398)
			(stroke
				(width 0.1524)
				(type default)
			)
			(layer "B.SilkS")
		)
		(fp_rect
			(start 0.508 0.9398)
			(end -0.508 -0.9398)
			(stroke
				(width 0)
				(type default)
			)
			(fill no)
			(layer "B.CrtYd")
		)
		(fp_rect
			(start 0.508 0.9398)
			(end -0.508 -0.9398)
			(stroke
				(width 0)
				(type default)
			)
			(fill no)
			(layer "B.Fab")
		)
		(pad "1" smd custom
			(at 0 -0.4445 90)
			(size 0.1397 0.1397)
			(layers "B.Cu" "B.Mask" "B.Paste")
			(net "P1V8_C")
			(options
				(clearance outline)
				(anchor circle)
			)
			(primitives
				(gr_poly
					(pts
						(arc
							(start -0.1778 0.2794)
							(mid -0.249642 0.249642)
							(end -0.2794 0.1778)
						)
						(arc
							(start -0.2794 -0.1778)
							(mid -0.249642 -0.249642)
							(end -0.1778 -0.2794)
						)
						(arc
							(start 0.1778 -0.2794)
							(mid 0.249642 -0.249642)
							(end 0.2794 -0.1778)
						)
						(arc
							(start 0.2794 0.1778)
							(mid 0.249642 0.249642)
							(end 0.1778 0.2794)
						)
					)
					(width 0)
					(fill yes)
				)
			)
		)
		(pad "2" smd custom
			(at 0 0.4445 90)
			(size 0.1397 0.1397)
			(layers "B.Cu" "B.Mask" "B.Paste")
			(net "IOC_SDA_3")
			(options
				(clearance outline)
				(anchor circle)
			)
			(primitives
				(gr_poly
					(pts
						(arc
							(start -0.1778 0.2794)
							(mid -0.249642 0.249642)
							(end -0.2794 0.1778)
						)
						(arc
							(start -0.2794 -0.1778)
							(mid -0.249642 -0.249642)
							(end -0.1778 -0.2794)
						)
						(arc
							(start 0.1778 -0.2794)
							(mid 0.249642 -0.249642)
							(end 0.2794 -0.1778)
						)
						(arc
							(start 0.2794 0.1778)
							(mid 0.249642 0.249642)
							(end 0.1778 0.2794)
						)
					)
					(width 0)
					(fill yes)
				)
			)
		)
	)
	(footprint ""
		(layer "B.Cu")
		(at 88.52916 -53.086)
		(property "Reference" "SR631"
			(at 0 0 0)
			(layer "B.SilkS")
			(hide yes)
			(effects
				(font
					(size 1.27 1.27)
				)
				(justify mirror)
			)
		)
		(property "Value" "2K2R2F-GP"
			(at -0.064008 -3.993896 0)
			(unlocked yes)
			(layer "B.Fab")
			(hide yes)
			(effects
				(font
					(size 1.016 1.016)
					(thickness 0.1524)
				)
				(justify mirror)
			)
		)
		(property "Device Type" "R402H16"
			(at -0.064008 -5.517896 0)
			(unlocked yes)
			(layer "B.Fab")
			(hide yes)
			(effects
				(font
					(size 1.016 1.016)
					(thickness 0.1524)
				)
				(justify mirror)
			)
		)
		(duplicate_pad_numbers_are_jumpers no)
		(fp_line
			(start -0.508 -0.9398)
			(end 0.508 -0.9398)
			(stroke
				(width 0.1524)
				(type default)
			)
			(layer "B.SilkS")
		)
		(fp_line
			(start 0.508 -0.9398)
			(end 0.508 0.9398)
			(stroke
				(width 0.1524)
				(type default)
			)
			(layer "B.SilkS")
		)
		(fp_rect
			(start 0.508 0.9398)
			(end -0.508 -0.9398)
			(stroke
				(width 0)
				(type default)
			)
			(fill no)
			(layer "B.CrtYd")
		)
		(fp_rect
			(start 0.508 0.9398)
			(end -0.508 -0.9398)
			(stroke
				(width 0)
				(type default)
			)
			(fill no)
			(layer "B.Fab")
		)
		(pad "1" smd custom
			(at 0 -0.4445 180)
			(size 0.1397 0.1397)
			(layers "B.Cu" "B.Mask" "B.Paste")
			(net "P1V8_C")
			(options
				(clearance outline)
				(anchor circle)
			)
			(primitives
				(gr_poly
					(pts
						(arc
							(start -0.1778 0.2794)
							(mid -0.249642 0.249642)
							(end -0.2794 0.1778)
						)
						(arc
							(start -0.2794 -0.1778)
							(mid -0.249642 -0.249642)
							(end -0.1778 -0.2794)
						)
						(arc
							(start 0.1778 -0.2794)
							(mid 0.249642 -0.249642)
							(end 0.2794 -0.1778)
						)
						(arc
							(start 0.2794 0.1778)
							(mid 0.249642 0.249642)
							(end 0.1778 0.2794)
						)
					)
					(width 0)
					(fill yes)
				)
			)
		)
		(pad "2" smd custom
			(at 0 0.4445 180)
			(size 0.1397 0.1397)
			(layers "B.Cu" "B.Mask" "B.Paste")
			(net "SIO_DIN_1")
			(options
				(clearance outline)
				(anchor circle)
			)
			(primitives
				(gr_poly
					(pts
						(arc
							(start -0.1778 0.2794)
							(mid -0.249642 0.249642)
							(end -0.2794 0.1778)
						)
						(arc
							(start -0.2794 -0.1778)
							(mid -0.249642 -0.249642)
							(end -0.1778 -0.2794)
						)
						(arc
							(start 0.1778 -0.2794)
							(mid 0.249642 -0.249642)
							(end 0.2794 -0.1778)
						)
						(arc
							(start 0.2794 0.1778)
							(mid 0.249642 0.249642)
							(end 0.1778 0.2794)
						)
					)
					(width 0)
					(fill yes)
				)
			)
		)
	)
	(footprint ""
		(layer "B.Cu")
		(at 340.995 -101.473 -90)
		(property "Reference" "PR14"
			(at 0 0 90)
			(layer "B.SilkS")
			(hide yes)
			(effects
				(font
					(size 1.27 1.27)
				)
				(justify mirror)
			)
		)
		(property "Value" "2KR2F-3-GP"
			(at -0.064008 -3.993896 270)
			(unlocked yes)
			(layer "B.Fab")
			(hide yes)
			(effects
				(font
					(size 1.016 1.016)
					(thickness 0.1524)
				)
				(justify mirror)
			)
		)
		(property "Device Type" "R402H16"
			(at -0.064008 -5.517896 270)
			(unlocked yes)
			(layer "B.Fab")
			(hide yes)
			(effects
				(font
					(size 1.016 1.016)
					(thickness 0.1524)
				)
				(justify mirror)
			)
		)
		(duplicate_pad_numbers_are_jumpers no)
		(fp_line
			(start -0.508 -0.9398)
			(end 0.508 -0.9398)
			(stroke
				(width 0.1524)
				(type default)
			)
			(layer "B.SilkS")
		)
		(fp_line
			(start 0.508 -0.9398)
			(end 0.508 0.9398)
			(stroke
				(width 0.1524)
				(type default)
			)
			(layer "B.SilkS")
		)
		(fp_rect
			(start 0.508 0.9398)
			(end -0.508 -0.9398)
			(stroke
				(width 0)
				(type default)
			)
			(fill no)
			(layer "B.CrtYd")
		)
		(fp_rect
			(start 0.508 0.9398)
			(end -0.508 -0.9398)
			(stroke
				(width 0)
				(type default)
			)
			(fill no)
			(layer "B.Fab")
		)
		(pad "1" smd custom
			(at 0 -0.4445 90)
			(size 0.1397 0.1397)
			(layers "B.Cu" "B.Mask" "B.Paste")
			(net "P5V_STBY_SW")
			(options
				(clearance outline)
				(anchor circle)
			)
			(primitives
				(gr_poly
					(pts
						(arc
							(start -0.1778 0.2794)
							(mid -0.249642 0.249642)
							(end -0.2794 0.1778)
						)
						(arc
							(start -0.2794 -0.1778)
							(mid -0.249642 -0.249642)
							(end -0.1778 -0.2794)
						)
						(arc
							(start 0.1778 -0.2794)
							(mid 0.249642 -0.249642)
							(end 0.2794 -0.1778)
						)
						(arc
							(start 0.2794 0.1778)
							(mid 0.249642 0.249642)
							(end 0.1778 0.2794)
						)
					)
					(width 0)
					(fill yes)
				)
			)
		)
		(pad "2" smd custom
			(at 0 0.4445 90)
			(size 0.1397 0.1397)
			(layers "B.Cu" "B.Mask" "B.Paste")
			(net "P5V_STBY_VFB_R")
			(options
				(clearance outline)
				(anchor circle)
			)
			(primitives
				(gr_poly
					(pts
						(arc
							(start -0.1778 0.2794)
							(mid -0.249642 0.249642)
							(end -0.2794 0.1778)
						)
						(arc
							(start -0.2794 -0.1778)
							(mid -0.249642 -0.249642)
							(end -0.1778 -0.2794)
						)
						(arc
							(start 0.1778 -0.2794)
							(mid 0.249642 -0.249642)
							(end 0.2794 -0.1778)
						)
						(arc
							(start 0.2794 0.1778)
							(mid 0.249642 0.249642)
							(end 0.1778 0.2794)
						)
					)
					(width 0)
					(fill yes)
				)
			)
		)
	)
	(footprint ""
		(layer "B.Cu")
		(at 318.008 -173.609 90)
		(property "Reference" "R469"
			(at 0 0 90)
			(layer "B.SilkS")
			(hide yes)
			(effects
				(font
					(size 1.27 1.27)
				)
				(justify mirror)
			)
		)
		(property "Value" "0R2J-2-GP"
			(at -0.064008 -3.993896 90)
			(unlocked yes)
			(layer "B.Fab")
			(hide yes)
			(effects
				(font
					(size 1.016 1.016)
					(thickness 0.1524)
				)
				(justify mirror)
			)
		)
		(property "Device Type" "R402H16"
			(at -0.064008 -5.517896 90)
			(unlocked yes)
			(layer "B.Fab")
			(hide yes)
			(effects
				(font
					(size 1.016 1.016)
					(thickness 0.1524)
				)
				(justify mirror)
			)
		)
		(duplicate_pad_numbers_are_jumpers no)
		(fp_line
			(start 0.508 -0.9398)
			(end 0.508 0.9398)
			(stroke
				(width 0.1524)
				(type default)
			)
			(layer "B.SilkS")
		)
		(fp_line
			(start -0.508 -0.9398)
			(end 0.508 -0.9398)
			(stroke
				(width 0.1524)
				(type default)
			)
			(layer "B.SilkS")
		)
		(fp_rect
			(start 0.508 0.9398)
			(end -0.508 -0.9398)
			(stroke
				(width 0)
				(type default)
			)
			(fill no)
			(layer "B.CrtYd")
		)
		(fp_rect
			(start 0.508 0.9398)
			(end -0.508 -0.9398)
			(stroke
				(width 0)
				(type default)
			)
			(fill no)
			(layer "B.Fab")
		)
		(pad "1" smd custom
			(at 0 -0.4445 270)
			(size 0.1397 0.1397)
			(layers "B.Cu" "B.Mask" "B.Paste")
			(net "BMC0_SMB14_SDA")
			(options
				(clearance outline)
				(anchor circle)
			)
			(primitives
				(gr_poly
					(pts
						(arc
							(start -0.1778 0.2794)
							(mid -0.249642 0.249642)
							(end -0.2794 0.1778)
						)
						(arc
							(start -0.2794 -0.1778)
							(mid -0.249642 -0.249642)
							(end -0.1778 -0.2794)
						)
						(arc
							(start 0.1778 -0.2794)
							(mid 0.249642 -0.249642)
							(end 0.2794 -0.1778)
						)
						(arc
							(start 0.2794 0.1778)
							(mid 0.249642 0.249642)
							(end 0.1778 0.2794)
						)
					)
					(width 0)
					(fill yes)
				)
			)
		)
		(pad "2" smd custom
			(at 0 0.4445 270)
			(size 0.1397 0.1397)
			(layers "B.Cu" "B.Mask" "B.Paste")
			(net "EXP_IOC_BMC_SDA_14")
			(options
				(clearance outline)
				(anchor circle)
			)
			(primitives
				(gr_poly
					(pts
						(arc
							(start -0.1778 0.2794)
							(mid -0.249642 0.249642)
							(end -0.2794 0.1778)
						)
						(arc
							(start -0.2794 -0.1778)
							(mid -0.249642 -0.249642)
							(end -0.1778 -0.2794)
						)
						(arc
							(start 0.1778 -0.2794)
							(mid 0.249642 -0.249642)
							(end 0.2794 -0.1778)
						)
						(arc
							(start 0.2794 0.1778)
							(mid 0.249642 0.249642)
							(end 0.1778 0.2794)
						)
					)
					(width 0)
					(fill yes)
				)
			)
		)
	)
	(footprint ""
		(layer "B.Cu")
		(at 90.68816 -41.148 90)
		(property "Reference" "SC940"
			(at 0 0 90)
			(layer "B.SilkS")
			(hide yes)
			(effects
				(font
					(size 1.27 1.27)
				)
				(justify mirror)
			)
		)
		(property "Value" "SCD1U6D3V1KX-GP"
			(at 2.8321 -1.7399 90)
			(unlocked yes)
			(layer "B.Fab")
			(hide yes)
			(effects
				(font
					(size 1.016 1.016)
					(thickness 0.1524)
				)
				(justify mirror)
			)
		)
		(property "Device Type" "C0201H13"
			(at 2.8321 -3.2639 90)
			(unlocked yes)
			(layer "B.Fab")
			(hide yes)
			(effects
				(font
					(size 1.016 1.016)
					(thickness 0.1524)
				)
				(justify mirror)
			)
		)
		(duplicate_pad_numbers_are_jumpers no)
		(fp_rect
			(start 0.2794 0.6477)
			(end -0.2794 -0.6477)
			(stroke
				(width 0)
				(type default)
			)
			(fill no)
			(layer "B.CrtYd")
		)
		(fp_rect
			(start 0.2794 0.6477)
			(end -0.2794 -0.6477)
			(stroke
				(width 0)
				(type default)
			)
			(fill no)
			(layer "B.Fab")
		)
		(pad "1" smd custom
			(at 0 -0.2794 270)
			(size 0.0762 0.0762)
			(layers "B.Cu" "B.Mask" "B.Paste")
			(net "SAS0_VDDH")
			(options
				(clearance outline)
				(anchor circle)
			)
			(primitives
				(gr_poly
					(pts
						(arc
							(start 0.1524 0.127)
							(mid 0.137521 0.162921)
							(end 0.1016 0.1778)
						)
						(arc
							(start -0.1016 0.1778)
							(mid -0.137521 0.162921)
							(end -0.1524 0.127)
						)
						(arc
							(start -0.1524 -0.127)
							(mid -0.137521 -0.162921)
							(end -0.1016 -0.1778)
						)
						(arc
							(start 0.1016 -0.1778)
							(mid 0.137521 -0.162921)
							(end 0.1524 -0.127)
						)
					)
					(width 0)
					(fill yes)
				)
			)
		)
		(pad "2" smd custom
			(at 0 0.2794 270)
			(size 0.0762 0.0762)
			(layers "B.Cu" "B.Mask" "B.Paste")
			(net "GND")
			(options
				(clearance outline)
				(anchor circle)
			)
			(primitives
				(gr_poly
					(pts
						(arc
							(start 0.1524 0.127)
							(mid 0.137521 0.162921)
							(end 0.1016 0.1778)
						)
						(arc
							(start -0.1016 0.1778)
							(mid -0.137521 0.162921)
							(end -0.1524 0.127)
						)
						(arc
							(start -0.1524 -0.127)
							(mid -0.137521 -0.162921)
							(end -0.1016 -0.1778)
						)
						(arc
							(start 0.1016 -0.1778)
							(mid 0.137521 -0.162921)
							(end 0.1524 -0.127)
						)
					)
					(width 0)
					(fill yes)
				)
			)
		)
	)
	(footprint ""
		(layer "B.Cu")
		(at 265.811 -16.891 180)
		(property "Reference" "C337"
			(at 0 0 0)
			(layer "B.SilkS")
			(hide yes)
			(effects
				(font
					(size 1.27 1.27)
				)
				(justify mirror)
			)
		)
		(property "Value" "SC1U10V3KX-4GP-U"
			(at 0 -2.8194 180)
			(unlocked yes)
			(layer "B.Fab")
			(hide yes)
			(effects
				(font
					(size 1.016 1.016)
					(thickness 0.1524)
				)
				(justify mirror)
			)
		)
		(property "Device Type" "C603H36"
			(at 0 -4.3434 180)
			(unlocked yes)
			(layer "B.Fab")
			(hide yes)
			(effects
				(font
					(size 1.016 1.016)
					(thickness 0.1524)
				)
				(justify mirror)
			)
		)
		(duplicate_pad_numbers_are_jumpers no)
		(fp_line
			(start -0.508 0)
			(end 0.508 0)
			(stroke
				(width 0.2032)
				(type default)
			)
			(layer "B.SilkS")
		)
		(fp_rect
			(start 0.5842 1.3335)
			(end -0.5842 -1.3335)
			(stroke
				(width 0)
				(type default)
			)
			(fill no)
			(layer "B.CrtYd")
		)
		(fp_rect
			(start 0.5842 1.3335)
			(end -0.5842 -1.3335)
			(stroke
				(width 0)
				(type default)
			)
			(fill no)
			(layer "B.Fab")
		)
		(pad "1" smd custom
			(at 0 -0.762)
			(size 0.2159 0.2159)
			(layers "B.Cu" "B.Mask" "B.Paste")
			(net "P5V_USB")
			(options
				(clearance outline)
				(anchor circle)
			)
			(primitives
				(gr_poly
					(pts
						(arc
							(start -0.3302 0.4318)
							(mid -0.402042 0.402042)
							(end -0.4318 0.3302)
						)
						(arc
							(start -0.4318 -0.3302)
							(mid -0.402042 -0.402042)
							(end -0.3302 -0.4318)
						)
						(arc
							(start 0.3302 -0.4318)
							(mid 0.402042 -0.402042)
							(end 0.4318 -0.3302)
						)
						(arc
							(start 0.4318 0.3302)
							(mid 0.402042 0.402042)
							(end 0.3302 0.4318)
						)
					)
					(width 0)
					(fill yes)
				)
			)
		)
		(pad "2" smd custom
			(at 0 0.762)
			(size 0.2159 0.2159)
			(layers "B.Cu" "B.Mask" "B.Paste")
			(net "GND")
			(options
				(clearance outline)
				(anchor circle)
			)
			(primitives
				(gr_poly
					(pts
						(arc
							(start -0.3302 0.4318)
							(mid -0.402042 0.402042)
							(end -0.4318 0.3302)
						)
						(arc
							(start -0.4318 -0.3302)
							(mid -0.402042 -0.402042)
							(end -0.3302 -0.4318)
						)
						(arc
							(start 0.3302 -0.4318)
							(mid 0.402042 -0.402042)
							(end 0.4318 -0.3302)
						)
						(arc
							(start 0.4318 0.3302)
							(mid 0.402042 0.402042)
							(end 0.3302 0.4318)
						)
					)
					(width 0)
					(fill yes)
				)
			)
		)
	)
	(footprint ""
		(layer "B.Cu")
		(at 290.068 -203.835 180)
		(property "Reference" "C197"
			(at 0 0 0)
			(layer "B.SilkS")
			(hide yes)
			(effects
				(font
					(size 1.27 1.27)
				)
				(justify mirror)
			)
		)
		(property "Value" "SC1U10V3KX-4GP-U"
			(at 0 -2.8194 180)
			(unlocked yes)
			(layer "B.Fab")
			(hide yes)
			(effects
				(font
					(size 1.016 1.016)
					(thickness 0.1524)
				)
				(justify mirror)
			)
		)
		(property "Device Type" "C603H36"
			(at 0 -4.3434 180)
			(unlocked yes)
			(layer "B.Fab")
			(hide yes)
			(effects
				(font
					(size 1.016 1.016)
					(thickness 0.1524)
				)
				(justify mirror)
			)
		)
		(duplicate_pad_numbers_are_jumpers no)
		(fp_line
			(start -0.508 0)
			(end 0.508 0)
			(stroke
				(width 0.2032)
				(type default)
			)
			(layer "B.SilkS")
		)
		(fp_rect
			(start 0.5842 1.3335)
			(end -0.5842 -1.3335)
			(stroke
				(width 0)
				(type default)
			)
			(fill no)
			(layer "B.CrtYd")
		)
		(fp_rect
			(start 0.5842 1.3335)
			(end -0.5842 -1.3335)
			(stroke
				(width 0)
				(type default)
			)
			(fill no)
			(layer "B.Fab")
		)
		(pad "1" smd custom
			(at 0 -0.762)
			(size 0.2159 0.2159)
			(layers "B.Cu" "B.Mask" "B.Paste")
			(net "P1V53_STBY")
			(options
				(clearance outline)
				(anchor circle)
			)
			(primitives
				(gr_poly
					(pts
						(arc
							(start -0.3302 0.4318)
							(mid -0.402042 0.402042)
							(end -0.4318 0.3302)
						)
						(arc
							(start -0.4318 -0.3302)
							(mid -0.402042 -0.402042)
							(end -0.3302 -0.4318)
						)
						(arc
							(start 0.3302 -0.4318)
							(mid 0.402042 -0.402042)
							(end 0.4318 -0.3302)
						)
						(arc
							(start 0.4318 0.3302)
							(mid 0.402042 0.402042)
							(end 0.3302 0.4318)
						)
					)
					(width 0)
					(fill yes)
				)
			)
		)
		(pad "2" smd custom
			(at 0 0.762)
			(size 0.2159 0.2159)
			(layers "B.Cu" "B.Mask" "B.Paste")
			(net "GND")
			(options
				(clearance outline)
				(anchor circle)
			)
			(primitives
				(gr_poly
					(pts
						(arc
							(start -0.3302 0.4318)
							(mid -0.402042 0.402042)
							(end -0.4318 0.3302)
						)
						(arc
							(start -0.4318 -0.3302)
							(mid -0.402042 -0.402042)
							(end -0.3302 -0.4318)
						)
						(arc
							(start 0.3302 -0.4318)
							(mid 0.402042 -0.402042)
							(end 0.4318 -0.3302)
						)
						(arc
							(start 0.4318 0.3302)
							(mid 0.402042 0.402042)
							(end 0.3302 0.4318)
						)
					)
					(width 0)
					(fill yes)
				)
			)
		)
	)
	(footprint ""
		(layer "B.Cu")
		(at 107.169966 -48.26 90)
		(property "Reference" "SC1053"
			(at 0 0 90)
			(layer "B.SilkS")
			(hide yes)
			(effects
				(font
					(size 1.27 1.27)
				)
				(justify mirror)
			)
		)
		(property "Value" "SCD1U16V2KX-3GP"
			(at -1.1811 -2.7051 90)
			(unlocked yes)
			(layer "B.Fab")
			(hide yes)
			(effects
				(font
					(size 1.016 1.016)
					(thickness 0.1524)
				)
				(justify mirror)
			)
		)
		(property "Device Type" "C402H22"
			(at -1.1811 -4.2291 90)
			(unlocked yes)
			(layer "B.Fab")
			(hide yes)
			(effects
				(font
					(size 1.016 1.016)
					(thickness 0.1524)
				)
				(justify mirror)
			)
		)
		(duplicate_pad_numbers_are_jumpers no)
		(fp_rect
			(start 0.4318 0.9525)
			(end -0.4318 -0.9525)
			(stroke
				(width 0)
				(type default)
			)
			(fill no)
			(layer "B.CrtYd")
		)
		(fp_rect
			(start 0.4318 0.9525)
			(end -0.4318 -0.9525)
			(stroke
				(width 0)
				(type default)
			)
			(fill no)
			(layer "B.Fab")
		)
		(pad "1" smd custom
			(at 0 -0.4445 270)
			(size 0.1524 0.1524)
			(layers "B.Cu" "B.Mask" "B.Paste")
			(net "P0V955_C")
			(options
				(clearance outline)
				(anchor circle)
			)
			(primitives
				(gr_poly
					(pts
						(arc
							(start 0.3048 0.2032)
							(mid 0.275042 0.275042)
							(end 0.2032 0.3048)
						)
						(arc
							(start -0.2032 0.3048)
							(mid -0.275042 0.275042)
							(end -0.3048 0.2032)
						)
						(arc
							(start -0.3048 -0.2032)
							(mid -0.275042 -0.275042)
							(end -0.2032 -0.3048)
						)
						(arc
							(start 0.2032 -0.3048)
							(mid 0.275042 -0.275042)
							(end 0.3048 -0.2032)
						)
					)
					(width 0)
					(fill yes)
				)
			)
		)
		(pad "2" smd custom
			(at 0 0.4445 270)
			(size 0.1524 0.1524)
			(layers "B.Cu" "B.Mask" "B.Paste")
			(net "GND")
			(options
				(clearance outline)
				(anchor circle)
			)
			(primitives
				(gr_poly
					(pts
						(arc
							(start 0.3048 0.2032)
							(mid 0.275042 0.275042)
							(end 0.2032 0.3048)
						)
						(arc
							(start -0.2032 0.3048)
							(mid -0.275042 0.275042)
							(end -0.3048 0.2032)
						)
						(arc
							(start -0.3048 -0.2032)
							(mid -0.275042 -0.275042)
							(end -0.2032 -0.3048)
						)
						(arc
							(start 0.2032 -0.3048)
							(mid 0.275042 -0.275042)
							(end 0.3048 -0.2032)
						)
					)
					(width 0)
					(fill yes)
				)
			)
		)
	)
	(footprint ""
		(layer "B.Cu")
		(at 112.532668 -35.32251)
		(property "Reference" "STP2"
			(at 0 0 0)
			(layer "B.SilkS")
			(hide yes)
			(effects
				(font
					(size 1.27 1.27)
				)
				(justify mirror)
			)
		)
		(property "Value" "TPAD28"
			(at -0.0127 -1.8034 0)
			(unlocked yes)
			(layer "B.Fab")
			(hide yes)
			(effects
				(font
					(size 1.016 1.016)
					(thickness 0.1524)
				)
				(justify mirror)
			)
		)
		(property "Device Type" "TPAD28"
			(at -0.0127 -3.3274 0)
			(unlocked yes)
			(layer "B.Fab")
			(hide yes)
			(effects
				(font
					(size 1.016 1.016)
					(thickness 0.1524)
				)
				(justify mirror)
			)
		)
		(duplicate_pad_numbers_are_jumpers no)
		(fp_poly
			(pts
				(arc
					(start 0.3556 0)
					(mid -0.3556 0)
					(end 0.3556 0)
				)
			)
			(stroke
				(width 0)
				(type default)
			)
			(fill no)
			(layer "B.CrtYd")
		)
		(fp_poly
			(pts
				(arc
					(start 0.6096 0)
					(mid -0.6096 0)
					(end 0.6096 0)
				)
			)
			(stroke
				(width 0)
				(type default)
			)
			(fill no)
			(layer "B.Fab")
		)
		(pad "1" smd circle
			(at 0 0 180)
			(size 0.7112 0.7112)
			(layers "B.Cu" "B.Mask" "B.Paste")
			(net "IOC_GPIO_25")
		)
	)
	(footprint ""
		(layer "B.Cu")
		(at 96.40316 -31.623)
		(property "Reference" "SC865"
			(at 0 0 0)
			(layer "B.SilkS")
			(hide yes)
			(effects
				(font
					(size 1.27 1.27)
				)
				(justify mirror)
			)
		)
		(property "Value" "SCD22U6D3V1MX-1-GP"
			(at 2.8321 -1.7399 0)
			(unlocked yes)
			(layer "B.Fab")
			(hide yes)
			(effects
				(font
					(size 1.016 1.016)
					(thickness 0.1524)
				)
				(justify mirror)
			)
		)
		(property "Device Type" "C0201H13"
			(at 2.8321 -3.2639 0)
			(unlocked yes)
			(layer "B.Fab")
			(hide yes)
			(effects
				(font
					(size 1.016 1.016)
					(thickness 0.1524)
				)
				(justify mirror)
			)
		)
		(duplicate_pad_numbers_are_jumpers no)
		(fp_rect
			(start 0.2794 0.6477)
			(end -0.2794 -0.6477)
			(stroke
				(width 0)
				(type default)
			)
			(fill no)
			(layer "B.CrtYd")
		)
		(fp_rect
			(start 0.2794 0.6477)
			(end -0.2794 -0.6477)
			(stroke
				(width 0)
				(type default)
			)
			(fill no)
			(layer "B.Fab")
		)
		(pad "1" smd custom
			(at 0 -0.2794 180)
			(size 0.0762 0.0762)
			(layers "B.Cu" "B.Mask" "B.Paste")
			(net "PCIE_SAS_C_CPU_RX_P2")
			(options
				(clearance outline)
				(anchor circle)
			)
			(primitives
				(gr_poly
					(pts
						(arc
							(start 0.1524 0.127)
							(mid 0.137521 0.162921)
							(end 0.1016 0.1778)
						)
						(arc
							(start -0.1016 0.1778)
							(mid -0.137521 0.162921)
							(end -0.1524 0.127)
						)
						(arc
							(start -0.1524 -0.127)
							(mid -0.137521 -0.162921)
							(end -0.1016 -0.1778)
						)
						(arc
							(start 0.1016 -0.1778)
							(mid 0.137521 -0.162921)
							(end 0.1524 -0.127)
						)
					)
					(width 0)
					(fill yes)
				)
			)
		)
		(pad "2" smd custom
			(at 0 0.2794 180)
			(size 0.0762 0.0762)
			(layers "B.Cu" "B.Mask" "B.Paste")
			(net "PCIE_SAS_CPU_RX_P2")
			(options
				(clearance outline)
				(anchor circle)
			)
			(primitives
				(gr_poly
					(pts
						(arc
							(start 0.1524 0.127)
							(mid 0.137521 0.162921)
							(end 0.1016 0.1778)
						)
						(arc
							(start -0.1016 0.1778)
							(mid -0.137521 0.162921)
							(end -0.1524 0.127)
						)
						(arc
							(start -0.1524 -0.127)
							(mid -0.137521 -0.162921)
							(end -0.1016 -0.1778)
						)
						(arc
							(start 0.1016 -0.1778)
							(mid 0.137521 -0.162921)
							(end 0.1524 -0.127)
						)
					)
					(width 0)
					(fill yes)
				)
			)
		)
	)
	(footprint ""
		(layer "B.Cu")
		(at 117.037612 -222.885 180)
		(property "Reference" "SR891"
			(at 0 0 0)
			(layer "B.SilkS")
			(hide yes)
			(effects
				(font
					(size 1.27 1.27)
				)
				(justify mirror)
			)
		)
		(property "Value" "0R2J-2-GP"
			(at -0.064008 -3.993896 180)
			(unlocked yes)
			(layer "B.Fab")
			(hide yes)
			(effects
				(font
					(size 1.016 1.016)
					(thickness 0.1524)
				)
				(justify mirror)
			)
		)
		(property "Device Type" "R402H16"
			(at -0.064008 -5.517896 180)
			(unlocked yes)
			(layer "B.Fab")
			(hide yes)
			(effects
				(font
					(size 1.016 1.016)
					(thickness 0.1524)
				)
				(justify mirror)
			)
		)
		(duplicate_pad_numbers_are_jumpers no)
		(fp_line
			(start 0.508 -0.9398)
			(end 0.508 0.9398)
			(stroke
				(width 0.1524)
				(type default)
			)
			(layer "B.SilkS")
		)
		(fp_line
			(start -0.508 -0.9398)
			(end 0.508 -0.9398)
			(stroke
				(width 0.1524)
				(type default)
			)
			(layer "B.SilkS")
		)
		(fp_rect
			(start 0.508 0.9398)
			(end -0.508 -0.9398)
			(stroke
				(width 0)
				(type default)
			)
			(fill no)
			(layer "B.CrtYd")
		)
		(fp_rect
			(start 0.508 0.9398)
			(end -0.508 -0.9398)
			(stroke
				(width 0)
				(type default)
			)
			(fill no)
			(layer "B.Fab")
		)
		(pad "1" smd custom
			(at 0 -0.4445)
			(size 0.1397 0.1397)
			(layers "B.Cu" "B.Mask" "B.Paste")
			(net "SAS_GF_EXP_RX_DN7")
			(options
				(clearance outline)
				(anchor circle)
			)
			(primitives
				(gr_poly
					(pts
						(arc
							(start -0.1778 0.2794)
							(mid -0.249642 0.249642)
							(end -0.2794 0.1778)
						)
						(arc
							(start -0.2794 -0.1778)
							(mid -0.249642 -0.249642)
							(end -0.1778 -0.2794)
						)
						(arc
							(start 0.1778 -0.2794)
							(mid 0.249642 -0.249642)
							(end 0.2794 -0.1778)
						)
						(arc
							(start 0.2794 0.1778)
							(mid 0.249642 0.249642)
							(end 0.1778 0.2794)
						)
					)
					(width 0)
					(fill yes)
				)
			)
		)
		(pad "2" smd custom
			(at 0 0.4445)
			(size 0.1397 0.1397)
			(layers "B.Cu" "B.Mask" "B.Paste")
			(net "REDV_RX7_N")
			(options
				(clearance outline)
				(anchor circle)
			)
			(primitives
				(gr_poly
					(pts
						(arc
							(start -0.1778 0.2794)
							(mid -0.249642 0.249642)
							(end -0.2794 0.1778)
						)
						(arc
							(start -0.2794 -0.1778)
							(mid -0.249642 -0.249642)
							(end -0.1778 -0.2794)
						)
						(arc
							(start 0.1778 -0.2794)
							(mid 0.249642 -0.249642)
							(end 0.2794 -0.1778)
						)
						(arc
							(start 0.2794 0.1778)
							(mid 0.249642 0.249642)
							(end 0.1778 0.2794)
						)
					)
					(width 0)
					(fill yes)
				)
			)
		)
	)
	(footprint ""
		(layer "B.Cu")
		(at 325.374 -182.372 180)
		(property "Reference" "R3029"
			(at 0 0 0)
			(layer "B.SilkS")
			(hide yes)
			(effects
				(font
					(size 1.27 1.27)
				)
				(justify mirror)
			)
		)
		(property "Value" "1KR2F-3-GP"
			(at -0.064008 -3.993896 180)
			(unlocked yes)
			(layer "B.Fab")
			(hide yes)
			(effects
				(font
					(size 1.016 1.016)
					(thickness 0.1524)
				)
				(justify mirror)
			)
		)
		(property "Device Type" "R402H16"
			(at -0.064008 -5.517896 180)
			(unlocked yes)
			(layer "B.Fab")
			(hide yes)
			(effects
				(font
					(size 1.016 1.016)
					(thickness 0.1524)
				)
				(justify mirror)
			)
		)
		(duplicate_pad_numbers_are_jumpers no)
		(fp_line
			(start 0.508 -0.9398)
			(end 0.508 0.9398)
			(stroke
				(width 0.1524)
				(type default)
			)
			(layer "B.SilkS")
		)
		(fp_line
			(start -0.508 -0.9398)
			(end 0.508 -0.9398)
			(stroke
				(width 0.1524)
				(type default)
			)
			(layer "B.SilkS")
		)
		(fp_rect
			(start 0.508 0.9398)
			(end -0.508 -0.9398)
			(stroke
				(width 0)
				(type default)
			)
			(fill no)
			(layer "B.CrtYd")
		)
		(fp_rect
			(start 0.508 0.9398)
			(end -0.508 -0.9398)
			(stroke
				(width 0)
				(type default)
			)
			(fill no)
			(layer "B.Fab")
		)
		(pad "1" smd custom
			(at 0 -0.4445)
			(size 0.1397 0.1397)
			(layers "B.Cu" "B.Mask" "B.Paste")
			(net "P0V955_C")
			(options
				(clearance outline)
				(anchor circle)
			)
			(primitives
				(gr_poly
					(pts
						(arc
							(start -0.1778 0.2794)
							(mid -0.249642 0.249642)
							(end -0.2794 0.1778)
						)
						(arc
							(start -0.2794 -0.1778)
							(mid -0.249642 -0.249642)
							(end -0.1778 -0.2794)
						)
						(arc
							(start 0.1778 -0.2794)
							(mid 0.249642 -0.249642)
							(end 0.2794 -0.1778)
						)
						(arc
							(start 0.2794 0.1778)
							(mid 0.249642 0.249642)
							(end 0.1778 0.2794)
						)
					)
					(width 0)
					(fill yes)
				)
			)
		)
		(pad "2" smd custom
			(at 0 0.4445)
			(size 0.1397 0.1397)
			(layers "B.Cu" "B.Mask" "B.Paste")
			(net "ADC_P0V955_C")
			(options
				(clearance outline)
				(anchor circle)
			)
			(primitives
				(gr_poly
					(pts
						(arc
							(start -0.1778 0.2794)
							(mid -0.249642 0.249642)
							(end -0.2794 0.1778)
						)
						(arc
							(start -0.2794 -0.1778)
							(mid -0.249642 -0.249642)
							(end -0.1778 -0.2794)
						)
						(arc
							(start 0.1778 -0.2794)
							(mid 0.249642 -0.249642)
							(end 0.2794 -0.1778)
						)
						(arc
							(start 0.2794 0.1778)
							(mid 0.249642 0.249642)
							(end 0.1778 0.2794)
						)
					)
					(width 0)
					(fill yes)
				)
			)
		)
	)
	(footprint ""
		(layer "B.Cu")
		(at 108.020612 -209.423 -90)
		(property "Reference" "SC1289"
			(at 0 0 90)
			(layer "B.SilkS")
			(hide yes)
			(effects
				(font
					(size 1.27 1.27)
				)
				(justify mirror)
			)
		)
		(property "Value" "SC1U10V2KX-4-GP"
			(at -1.1811 -2.7051 270)
			(unlocked yes)
			(layer "B.Fab")
			(hide yes)
			(effects
				(font
					(size 1.016 1.016)
					(thickness 0.1524)
				)
				(justify mirror)
			)
		)
		(property "Device Type" "C402H22"
			(at -1.1811 -4.2291 270)
			(unlocked yes)
			(layer "B.Fab")
			(hide yes)
			(effects
				(font
					(size 1.016 1.016)
					(thickness 0.1524)
				)
				(justify mirror)
			)
		)
		(duplicate_pad_numbers_are_jumpers no)
		(fp_rect
			(start 0.4318 0.9525)
			(end -0.4318 -0.9525)
			(stroke
				(width 0)
				(type default)
			)
			(fill no)
			(layer "B.CrtYd")
		)
		(fp_rect
			(start 0.4318 0.9525)
			(end -0.4318 -0.9525)
			(stroke
				(width 0)
				(type default)
			)
			(fill no)
			(layer "B.Fab")
		)
		(pad "1" smd custom
			(at 0 -0.4445 90)
			(size 0.1524 0.1524)
			(layers "B.Cu" "B.Mask" "B.Paste")
			(net "1.2V_REDV")
			(options
				(clearance outline)
				(anchor circle)
			)
			(primitives
				(gr_poly
					(pts
						(arc
							(start 0.3048 0.2032)
							(mid 0.275042 0.275042)
							(end 0.2032 0.3048)
						)
						(arc
							(start -0.2032 0.3048)
							(mid -0.275042 0.275042)
							(end -0.3048 0.2032)
						)
						(arc
							(start -0.3048 -0.2032)
							(mid -0.275042 -0.275042)
							(end -0.2032 -0.3048)
						)
						(arc
							(start 0.2032 -0.3048)
							(mid 0.275042 -0.275042)
							(end 0.3048 -0.2032)
						)
					)
					(width 0)
					(fill yes)
				)
			)
		)
		(pad "2" smd custom
			(at 0 0.4445 90)
			(size 0.1524 0.1524)
			(layers "B.Cu" "B.Mask" "B.Paste")
			(net "GND")
			(options
				(clearance outline)
				(anchor circle)
			)
			(primitives
				(gr_poly
					(pts
						(arc
							(start 0.3048 0.2032)
							(mid 0.275042 0.275042)
							(end 0.2032 0.3048)
						)
						(arc
							(start -0.2032 0.3048)
							(mid -0.275042 0.275042)
							(end -0.3048 0.2032)
						)
						(arc
							(start -0.3048 -0.2032)
							(mid -0.275042 -0.275042)
							(end -0.2032 -0.3048)
						)
						(arc
							(start 0.2032 -0.3048)
							(mid 0.275042 -0.275042)
							(end 0.3048 -0.2032)
						)
					)
					(width 0)
					(fill yes)
				)
			)
		)
	)
	(footprint ""
		(layer "B.Cu")
		(at 11.938 -221.615 90)
		(property "Reference" "SR315"
			(at 0 0 90)
			(layer "B.SilkS")
			(hide yes)
			(effects
				(font
					(size 1.27 1.27)
				)
				(justify mirror)
			)
		)
		(property "Value" "0R2J-2-GP"
			(at -0.064008 -3.993896 90)
			(unlocked yes)
			(layer "B.Fab")
			(hide yes)
			(effects
				(font
					(size 1.016 1.016)
					(thickness 0.1524)
				)
				(justify mirror)
			)
		)
		(property "Device Type" "R402H16"
			(at -0.064008 -5.517896 90)
			(unlocked yes)
			(layer "B.Fab")
			(hide yes)
			(effects
				(font
					(size 1.016 1.016)
					(thickness 0.1524)
				)
				(justify mirror)
			)
		)
		(duplicate_pad_numbers_are_jumpers no)
		(fp_line
			(start 0.508 -0.9398)
			(end 0.508 0.9398)
			(stroke
				(width 0.1524)
				(type default)
			)
			(layer "B.SilkS")
		)
		(fp_line
			(start -0.508 -0.9398)
			(end 0.508 -0.9398)
			(stroke
				(width 0.1524)
				(type default)
			)
			(layer "B.SilkS")
		)
		(fp_rect
			(start 0.508 0.9398)
			(end -0.508 -0.9398)
			(stroke
				(width 0)
				(type default)
			)
			(fill no)
			(layer "B.CrtYd")
		)
		(fp_rect
			(start 0.508 0.9398)
			(end -0.508 -0.9398)
			(stroke
				(width 0)
				(type default)
			)
			(fill no)
			(layer "B.Fab")
		)
		(pad "1" smd custom
			(at 0 -0.4445 270)
			(size 0.1397 0.1397)
			(layers "B.Cu" "B.Mask" "B.Paste")
			(net "EXP_SCL_0")
			(options
				(clearance outline)
				(anchor circle)
			)
			(primitives
				(gr_poly
					(pts
						(arc
							(start -0.1778 0.2794)
							(mid -0.249642 0.249642)
							(end -0.2794 0.1778)
						)
						(arc
							(start -0.2794 -0.1778)
							(mid -0.249642 -0.249642)
							(end -0.1778 -0.2794)
						)
						(arc
							(start 0.1778 -0.2794)
							(mid 0.249642 -0.249642)
							(end 0.2794 -0.1778)
						)
						(arc
							(start 0.2794 0.1778)
							(mid 0.249642 0.249642)
							(end 0.1778 0.2794)
						)
					)
					(width 0)
					(fill yes)
				)
			)
		)
		(pad "2" smd custom
			(at 0 0.4445 270)
			(size 0.1397 0.1397)
			(layers "B.Cu" "B.Mask" "B.Paste")
			(net "BMC_IOEXP_SCL_10")
			(options
				(clearance outline)
				(anchor circle)
			)
			(primitives
				(gr_poly
					(pts
						(arc
							(start -0.1778 0.2794)
							(mid -0.249642 0.249642)
							(end -0.2794 0.1778)
						)
						(arc
							(start -0.2794 -0.1778)
							(mid -0.249642 -0.249642)
							(end -0.1778 -0.2794)
						)
						(arc
							(start 0.1778 -0.2794)
							(mid 0.249642 -0.249642)
							(end 0.2794 -0.1778)
						)
						(arc
							(start 0.2794 0.1778)
							(mid 0.249642 0.249642)
							(end 0.1778 0.2794)
						)
					)
					(width 0)
					(fill yes)
				)
			)
		)
	)
	(footprint ""
		(layer "B.Cu")
		(at 45.54093 -77.650086)
		(property "Reference" "SC1277"
			(at 0 0 0)
			(layer "B.SilkS")
			(hide yes)
			(effects
				(font
					(size 1.27 1.27)
				)
				(justify mirror)
			)
		)
		(property "Value" "SCD01U50V2KX-1GP"
			(at -1.1811 -2.7051 0)
			(unlocked yes)
			(layer "B.Fab")
			(hide yes)
			(effects
				(font
					(size 1.016 1.016)
					(thickness 0.1524)
				)
				(justify mirror)
			)
		)
		(property "Device Type" "C402H22"
			(at -1.1811 -4.2291 0)
			(unlocked yes)
			(layer "B.Fab")
			(hide yes)
			(effects
				(font
					(size 1.016 1.016)
					(thickness 0.1524)
				)
				(justify mirror)
			)
		)
		(duplicate_pad_numbers_are_jumpers no)
		(fp_rect
			(start 0.4318 0.9525)
			(end -0.4318 -0.9525)
			(stroke
				(width 0)
				(type default)
			)
			(fill no)
			(layer "B.CrtYd")
		)
		(fp_rect
			(start 0.4318 0.9525)
			(end -0.4318 -0.9525)
			(stroke
				(width 0)
				(type default)
			)
			(fill no)
			(layer "B.Fab")
		)
		(pad "1" smd custom
			(at 0 -0.4445 180)
			(size 0.1524 0.1524)
			(layers "B.Cu" "B.Mask" "B.Paste")
			(net "SAS_EXP2CONN_RX_N_21")
			(options
				(clearance outline)
				(anchor circle)
			)
			(primitives
				(gr_poly
					(pts
						(arc
							(start 0.3048 0.2032)
							(mid 0.275042 0.275042)
							(end 0.2032 0.3048)
						)
						(arc
							(start -0.2032 0.3048)
							(mid -0.275042 0.275042)
							(end -0.3048 0.2032)
						)
						(arc
							(start -0.3048 -0.2032)
							(mid -0.275042 -0.275042)
							(end -0.2032 -0.3048)
						)
						(arc
							(start 0.2032 -0.3048)
							(mid 0.275042 -0.275042)
							(end 0.3048 -0.2032)
						)
					)
					(width 0)
					(fill yes)
				)
			)
		)
		(pad "2" smd custom
			(at 0 0.4445 180)
			(size 0.1524 0.1524)
			(layers "B.Cu" "B.Mask" "B.Paste")
			(net "MINI_RX_N_21")
			(options
				(clearance outline)
				(anchor circle)
			)
			(primitives
				(gr_poly
					(pts
						(arc
							(start 0.3048 0.2032)
							(mid 0.275042 0.275042)
							(end 0.2032 0.3048)
						)
						(arc
							(start -0.2032 0.3048)
							(mid -0.275042 0.275042)
							(end -0.3048 0.2032)
						)
						(arc
							(start -0.3048 -0.2032)
							(mid -0.275042 -0.275042)
							(end -0.2032 -0.3048)
						)
						(arc
							(start 0.2032 -0.3048)
							(mid 0.275042 -0.275042)
							(end 0.3048 -0.2032)
						)
					)
					(width 0)
					(fill yes)
				)
			)
		)
	)
	(footprint ""
		(layer "B.Cu")
		(at 108.020612 -217.297 -90)
		(property "Reference" "SR913"
			(at 0 0 90)
			(layer "B.SilkS")
			(hide yes)
			(effects
				(font
					(size 1.27 1.27)
				)
				(justify mirror)
			)
		)
		(property "Value" "4K7R2F-GP"
			(at -0.064008 -3.993896 270)
			(unlocked yes)
			(layer "B.Fab")
			(hide yes)
			(effects
				(font
					(size 1.016 1.016)
					(thickness 0.1524)
				)
				(justify mirror)
			)
		)
		(property "Device Type" "R402H16"
			(at -0.064008 -5.517896 270)
			(unlocked yes)
			(layer "B.Fab")
			(hide yes)
			(effects
				(font
					(size 1.016 1.016)
					(thickness 0.1524)
				)
				(justify mirror)
			)
		)
		(duplicate_pad_numbers_are_jumpers no)
		(fp_line
			(start -0.508 -0.9398)
			(end 0.508 -0.9398)
			(stroke
				(width 0.1524)
				(type default)
			)
			(layer "B.SilkS")
		)
		(fp_line
			(start 0.508 -0.9398)
			(end 0.508 0.9398)
			(stroke
				(width 0.1524)
				(type default)
			)
			(layer "B.SilkS")
		)
		(fp_rect
			(start 0.508 0.9398)
			(end -0.508 -0.9398)
			(stroke
				(width 0)
				(type default)
			)
			(fill no)
			(layer "B.CrtYd")
		)
		(fp_rect
			(start 0.508 0.9398)
			(end -0.508 -0.9398)
			(stroke
				(width 0)
				(type default)
			)
			(fill no)
			(layer "B.Fab")
		)
		(pad "1" smd custom
			(at 0 -0.4445 90)
			(size 0.1397 0.1397)
			(layers "B.Cu" "B.Mask" "B.Paste")
			(net "REDV_I2C_SEL2B")
			(options
				(clearance outline)
				(anchor circle)
			)
			(primitives
				(gr_poly
					(pts
						(arc
							(start -0.1778 0.2794)
							(mid -0.249642 0.249642)
							(end -0.2794 0.1778)
						)
						(arc
							(start -0.2794 -0.1778)
							(mid -0.249642 -0.249642)
							(end -0.1778 -0.2794)
						)
						(arc
							(start 0.1778 -0.2794)
							(mid 0.249642 -0.249642)
							(end 0.2794 -0.1778)
						)
						(arc
							(start 0.2794 0.1778)
							(mid 0.249642 0.249642)
							(end 0.1778 0.2794)
						)
					)
					(width 0)
					(fill yes)
				)
			)
		)
		(pad "2" smd custom
			(at 0 0.4445 90)
			(size 0.1397 0.1397)
			(layers "B.Cu" "B.Mask" "B.Paste")
			(net "GND")
			(options
				(clearance outline)
				(anchor circle)
			)
			(primitives
				(gr_poly
					(pts
						(arc
							(start -0.1778 0.2794)
							(mid -0.249642 0.249642)
							(end -0.2794 0.1778)
						)
						(arc
							(start -0.2794 -0.1778)
							(mid -0.249642 -0.249642)
							(end -0.1778 -0.2794)
						)
						(arc
							(start 0.1778 -0.2794)
							(mid 0.249642 -0.249642)
							(end 0.2794 -0.1778)
						)
						(arc
							(start 0.2794 0.1778)
							(mid 0.249642 0.249642)
							(end 0.1778 0.2794)
						)
					)
					(width 0)
					(fill yes)
				)
			)
		)
	)
	(footprint ""
		(layer "B.Cu")
		(at 117.48897 -87.884)
		(property "Reference" "STP108"
			(at 0 0 0)
			(layer "B.SilkS")
			(hide yes)
			(effects
				(font
					(size 1.27 1.27)
				)
				(justify mirror)
			)
		)
		(property "Value" "TPAD28"
			(at -0.0127 -1.8034 0)
			(unlocked yes)
			(layer "B.Fab")
			(hide yes)
			(effects
				(font
					(size 1.016 1.016)
					(thickness 0.1524)
				)
				(justify mirror)
			)
		)
		(property "Device Type" "TPAD28"
			(at -0.0127 -3.3274 0)
			(unlocked yes)
			(layer "B.Fab")
			(hide yes)
			(effects
				(font
					(size 1.016 1.016)
					(thickness 0.1524)
				)
				(justify mirror)
			)
		)
		(duplicate_pad_numbers_are_jumpers no)
		(fp_poly
			(pts
				(arc
					(start 0.3556 0)
					(mid -0.3556 0)
					(end 0.3556 0)
				)
			)
			(stroke
				(width 0)
				(type default)
			)
			(fill no)
			(layer "B.CrtYd")
		)
		(fp_poly
			(pts
				(arc
					(start 0.6096 0)
					(mid -0.6096 0)
					(end 0.6096 0)
				)
			)
			(stroke
				(width 0)
				(type default)
			)
			(fill no)
			(layer "B.Fab")
		)
		(pad "1" smd circle
			(at 0 0 180)
			(size 0.7112 0.7112)
			(layers "B.Cu" "B.Mask" "B.Paste")
			(net "TEST_MUX_41")
		)
	)
	(footprint ""
		(layer "B.Cu")
		(at 331.499464 -22.237192)
		(property "Reference" ""
			(at 0 0 0)
			(layer "B.SilkS")
			(hide yes)
			(effects
				(font
					(size 1.27 1.27)
				)
				(justify mirror)
			)
		)
		(property "Value" "*"
			(at 5.5753 -0.4572 0)
			(unlocked yes)
			(layer "B.Fab")
			(hide yes)
			(effects
				(font
					(size 1.016 1.016)
					(thickness 0.1524)
				)
				(justify mirror)
			)
		)
		(duplicate_pad_numbers_are_jumpers no)
		(fp_poly
			(pts
				(arc
					(start 4.3053 0)
					(mid -4.3053 0)
					(end 4.3053 0)
				)
			)
			(stroke
				(width 0)
				(type default)
			)
			(fill no)
			(layer "B.CrtYd")
		)
		(fp_poly
			(pts
				(arc
					(start 4.3053 0)
					(mid -4.3053 0)
					(end 4.3053 0)
				)
			)
			(stroke
				(width 0)
				(type default)
			)
			(fill no)
			(layer "B.Fab")
		)
		(pad "1" smd custom
			(at 2.95275 0 180)
			(size 2.000013 2.000013)
			(layers "B.Cu" "B.Mask" "B.Paste")
			(net "Net_53")
			(options
				(clearance outline)
				(anchor circle)
			)
			(primitives
				(gr_poly
					(pts
						(arc
							(start 4.0005 -0.00254)
							(mid -4.000501 0)
							(end 4.0005 0.00254)
						)
						(arc
							(start 1.905 0.00254)
							(mid -1.905002 0)
							(end 1.905 -0.00254)
						)
					)
					(width 0)
					(fill yes)
				)
			)
		)
	)
	(footprint ""
		(layer "B.Cu")
		(at 160.147 -89.154)
		(property "Reference" "PC178"
			(at 0 0 0)
			(layer "B.SilkS")
			(hide yes)
			(effects
				(font
					(size 1.27 1.27)
				)
				(justify mirror)
			)
		)
		(property "Value" "SC22U6D3V3MX-1-GP"
			(at 0 -2.8194 0)
			(unlocked yes)
			(layer "B.Fab")
			(hide yes)
			(effects
				(font
					(size 1.016 1.016)
					(thickness 0.1524)
				)
				(justify mirror)
			)
		)
		(property "Device Type" "C603H40"
			(at 0 -4.3434 0)
			(unlocked yes)
			(layer "B.Fab")
			(hide yes)
			(effects
				(font
					(size 1.016 1.016)
					(thickness 0.1524)
				)
				(justify mirror)
			)
		)
		(duplicate_pad_numbers_are_jumpers no)
		(fp_line
			(start -0.508 0)
			(end 0.508 0)
			(stroke
				(width 0.2032)
				(type default)
			)
			(layer "B.SilkS")
		)
		(fp_rect
			(start 0.5842 1.3335)
			(end -0.5842 -1.3335)
			(stroke
				(width 0)
				(type default)
			)
			(fill no)
			(layer "B.CrtYd")
		)
		(fp_rect
			(start 0.5842 1.3335)
			(end -0.5842 -1.3335)
			(stroke
				(width 0)
				(type default)
			)
			(fill no)
			(layer "B.Fab")
		)
		(pad "1" smd custom
			(at 0 -0.762 180)
			(size 0.2159 0.2159)
			(layers "B.Cu" "B.Mask" "B.Paste")
			(net "P0V9_E")
			(options
				(clearance outline)
				(anchor circle)
			)
			(primitives
				(gr_poly
					(pts
						(arc
							(start -0.3302 0.4318)
							(mid -0.402042 0.402042)
							(end -0.4318 0.3302)
						)
						(arc
							(start -0.4318 -0.3302)
							(mid -0.402042 -0.402042)
							(end -0.3302 -0.4318)
						)
						(arc
							(start 0.3302 -0.4318)
							(mid 0.402042 -0.402042)
							(end 0.4318 -0.3302)
						)
						(arc
							(start 0.4318 0.3302)
							(mid 0.402042 0.402042)
							(end 0.3302 0.4318)
						)
					)
					(width 0)
					(fill yes)
				)
			)
		)
		(pad "2" smd custom
			(at 0 0.762 180)
			(size 0.2159 0.2159)
			(layers "B.Cu" "B.Mask" "B.Paste")
			(net "GND")
			(options
				(clearance outline)
				(anchor circle)
			)
			(primitives
				(gr_poly
					(pts
						(arc
							(start -0.3302 0.4318)
							(mid -0.402042 0.402042)
							(end -0.4318 0.3302)
						)
						(arc
							(start -0.4318 -0.3302)
							(mid -0.402042 -0.402042)
							(end -0.3302 -0.4318)
						)
						(arc
							(start 0.3302 -0.4318)
							(mid 0.402042 -0.402042)
							(end 0.4318 -0.3302)
						)
						(arc
							(start 0.4318 0.3302)
							(mid 0.402042 0.402042)
							(end 0.3302 0.4318)
						)
					)
					(width 0)
					(fill yes)
				)
			)
		)
	)
	(footprint ""
		(layer "B.Cu")
		(at 263.271 -16.891 180)
		(property "Reference" "C335"
			(at 0 0 0)
			(layer "B.SilkS")
			(hide yes)
			(effects
				(font
					(size 1.27 1.27)
				)
				(justify mirror)
			)
		)
		(property "Value" "SC1U10V3KX-4GP-U"
			(at 0 -2.8194 180)
			(unlocked yes)
			(layer "B.Fab")
			(hide yes)
			(effects
				(font
					(size 1.016 1.016)
					(thickness 0.1524)
				)
				(justify mirror)
			)
		)
		(property "Device Type" "C603H36"
			(at 0 -4.3434 180)
			(unlocked yes)
			(layer "B.Fab")
			(hide yes)
			(effects
				(font
					(size 1.016 1.016)
					(thickness 0.1524)
				)
				(justify mirror)
			)
		)
		(duplicate_pad_numbers_are_jumpers no)
		(fp_line
			(start -0.508 0)
			(end 0.508 0)
			(stroke
				(width 0.2032)
				(type default)
			)
			(layer "B.SilkS")
		)
		(fp_rect
			(start 0.5842 1.3335)
			(end -0.5842 -1.3335)
			(stroke
				(width 0)
				(type default)
			)
			(fill no)
			(layer "B.CrtYd")
		)
		(fp_rect
			(start 0.5842 1.3335)
			(end -0.5842 -1.3335)
			(stroke
				(width 0)
				(type default)
			)
			(fill no)
			(layer "B.Fab")
		)
		(pad "1" smd custom
			(at 0 -0.762)
			(size 0.2159 0.2159)
			(layers "B.Cu" "B.Mask" "B.Paste")
			(net "P5V_USB")
			(options
				(clearance outline)
				(anchor circle)
			)
			(primitives
				(gr_poly
					(pts
						(arc
							(start -0.3302 0.4318)
							(mid -0.402042 0.402042)
							(end -0.4318 0.3302)
						)
						(arc
							(start -0.4318 -0.3302)
							(mid -0.402042 -0.402042)
							(end -0.3302 -0.4318)
						)
						(arc
							(start 0.3302 -0.4318)
							(mid 0.402042 -0.402042)
							(end 0.4318 -0.3302)
						)
						(arc
							(start 0.4318 0.3302)
							(mid 0.402042 0.402042)
							(end 0.3302 0.4318)
						)
					)
					(width 0)
					(fill yes)
				)
			)
		)
		(pad "2" smd custom
			(at 0 0.762)
			(size 0.2159 0.2159)
			(layers "B.Cu" "B.Mask" "B.Paste")
			(net "GND")
			(options
				(clearance outline)
				(anchor circle)
			)
			(primitives
				(gr_poly
					(pts
						(arc
							(start -0.3302 0.4318)
							(mid -0.402042 0.402042)
							(end -0.4318 0.3302)
						)
						(arc
							(start -0.4318 -0.3302)
							(mid -0.402042 -0.402042)
							(end -0.3302 -0.4318)
						)
						(arc
							(start 0.3302 -0.4318)
							(mid 0.402042 -0.402042)
							(end 0.4318 -0.3302)
						)
						(arc
							(start 0.4318 0.3302)
							(mid 0.402042 0.402042)
							(end 0.3302 0.4318)
						)
					)
					(width 0)
					(fill yes)
				)
			)
		)
	)
	(footprint ""
		(layer "B.Cu")
		(at 105.489756 -40.3479)
		(property "Reference" "SC1042"
			(at 0 0 0)
			(layer "B.SilkS")
			(hide yes)
			(effects
				(font
					(size 1.27 1.27)
				)
				(justify mirror)
			)
		)
		(property "Value" "SCD1U16V2KX-3GP"
			(at -1.1811 -2.7051 0)
			(unlocked yes)
			(layer "B.Fab")
			(hide yes)
			(effects
				(font
					(size 1.016 1.016)
					(thickness 0.1524)
				)
				(justify mirror)
			)
		)
		(property "Device Type" "C402H22"
			(at -1.1811 -4.2291 0)
			(unlocked yes)
			(layer "B.Fab")
			(hide yes)
			(effects
				(font
					(size 1.016 1.016)
					(thickness 0.1524)
				)
				(justify mirror)
			)
		)
		(duplicate_pad_numbers_are_jumpers no)
		(fp_rect
			(start 0.4318 0.9525)
			(end -0.4318 -0.9525)
			(stroke
				(width 0)
				(type default)
			)
			(fill no)
			(layer "B.CrtYd")
		)
		(fp_rect
			(start 0.4318 0.9525)
			(end -0.4318 -0.9525)
			(stroke
				(width 0)
				(type default)
			)
			(fill no)
			(layer "B.Fab")
		)
		(pad "1" smd custom
			(at 0 -0.4445 180)
			(size 0.1524 0.1524)
			(layers "B.Cu" "B.Mask" "B.Paste")
			(net "P0V955_C")
			(options
				(clearance outline)
				(anchor circle)
			)
			(primitives
				(gr_poly
					(pts
						(arc
							(start 0.3048 0.2032)
							(mid 0.275042 0.275042)
							(end 0.2032 0.3048)
						)
						(arc
							(start -0.2032 0.3048)
							(mid -0.275042 0.275042)
							(end -0.3048 0.2032)
						)
						(arc
							(start -0.3048 -0.2032)
							(mid -0.275042 -0.275042)
							(end -0.2032 -0.3048)
						)
						(arc
							(start 0.2032 -0.3048)
							(mid 0.275042 -0.275042)
							(end 0.3048 -0.2032)
						)
					)
					(width 0)
					(fill yes)
				)
			)
		)
		(pad "2" smd custom
			(at 0 0.4445 180)
			(size 0.1524 0.1524)
			(layers "B.Cu" "B.Mask" "B.Paste")
			(net "GND")
			(options
				(clearance outline)
				(anchor circle)
			)
			(primitives
				(gr_poly
					(pts
						(arc
							(start 0.3048 0.2032)
							(mid 0.275042 0.275042)
							(end 0.2032 0.3048)
						)
						(arc
							(start -0.2032 0.3048)
							(mid -0.275042 0.275042)
							(end -0.3048 0.2032)
						)
						(arc
							(start -0.3048 -0.2032)
							(mid -0.275042 -0.275042)
							(end -0.2032 -0.3048)
						)
						(arc
							(start 0.2032 -0.3048)
							(mid 0.275042 -0.275042)
							(end 0.3048 -0.2032)
						)
					)
					(width 0)
					(fill yes)
				)
			)
		)
	)
	(footprint ""
		(layer "B.Cu")
		(at 118.68277 -87.0204)
		(property "Reference" "STP64"
			(at 0 0 0)
			(layer "B.SilkS")
			(hide yes)
			(effects
				(font
					(size 1.27 1.27)
				)
				(justify mirror)
			)
		)
		(property "Value" "TPAD28"
			(at -0.0127 -1.8034 0)
			(unlocked yes)
			(layer "B.Fab")
			(hide yes)
			(effects
				(font
					(size 1.016 1.016)
					(thickness 0.1524)
				)
				(justify mirror)
			)
		)
		(property "Device Type" "TPAD28"
			(at -0.0127 -3.3274 0)
			(unlocked yes)
			(layer "B.Fab")
			(hide yes)
			(effects
				(font
					(size 1.016 1.016)
					(thickness 0.1524)
				)
				(justify mirror)
			)
		)
		(duplicate_pad_numbers_are_jumpers no)
		(fp_poly
			(pts
				(arc
					(start 0.3556 0)
					(mid -0.3556 0)
					(end 0.3556 0)
				)
			)
			(stroke
				(width 0)
				(type default)
			)
			(fill no)
			(layer "B.CrtYd")
		)
		(fp_poly
			(pts
				(arc
					(start 0.6096 0)
					(mid -0.6096 0)
					(end 0.6096 0)
				)
			)
			(stroke
				(width 0)
				(type default)
			)
			(fill no)
			(layer "B.Fab")
		)
		(pad "1" smd circle
			(at 0 0 180)
			(size 0.7112 0.7112)
			(layers "B.Cu" "B.Mask" "B.Paste")
			(net "EXP_TEST_MUX26")
		)
	)
	(footprint ""
		(layer "B.Cu")
		(at 325.374 -177.8)
		(property "Reference" "R434"
			(at 0 0 0)
			(layer "B.SilkS")
			(hide yes)
			(effects
				(font
					(size 1.27 1.27)
				)
				(justify mirror)
			)
		)
		(property "Value" "3K3R2F-2-GP"
			(at -0.064008 -3.993896 0)
			(unlocked yes)
			(layer "B.Fab")
			(hide yes)
			(effects
				(font
					(size 1.016 1.016)
					(thickness 0.1524)
				)
				(justify mirror)
			)
		)
		(property "Device Type" "R402H16"
			(at -0.064008 -5.517896 0)
			(unlocked yes)
			(layer "B.Fab")
			(hide yes)
			(effects
				(font
					(size 1.016 1.016)
					(thickness 0.1524)
				)
				(justify mirror)
			)
		)
		(duplicate_pad_numbers_are_jumpers no)
		(fp_line
			(start -0.508 -0.9398)
			(end 0.508 -0.9398)
			(stroke
				(width 0.1524)
				(type default)
			)
			(layer "B.SilkS")
		)
		(fp_line
			(start 0.508 -0.9398)
			(end 0.508 0.9398)
			(stroke
				(width 0.1524)
				(type default)
			)
			(layer "B.SilkS")
		)
		(fp_rect
			(start 0.508 0.9398)
			(end -0.508 -0.9398)
			(stroke
				(width 0)
				(type default)
			)
			(fill no)
			(layer "B.CrtYd")
		)
		(fp_rect
			(start 0.508 0.9398)
			(end -0.508 -0.9398)
			(stroke
				(width 0)
				(type default)
			)
			(fill no)
			(layer "B.Fab")
		)
		(pad "1" smd custom
			(at 0 -0.4445 180)
			(size 0.1397 0.1397)
			(layers "B.Cu" "B.Mask" "B.Paste")
			(net "ADC_P5V_STBY")
			(options
				(clearance outline)
				(anchor circle)
			)
			(primitives
				(gr_poly
					(pts
						(arc
							(start -0.1778 0.2794)
							(mid -0.249642 0.249642)
							(end -0.2794 0.1778)
						)
						(arc
							(start -0.2794 -0.1778)
							(mid -0.249642 -0.249642)
							(end -0.1778 -0.2794)
						)
						(arc
							(start 0.1778 -0.2794)
							(mid 0.249642 -0.249642)
							(end 0.2794 -0.1778)
						)
						(arc
							(start 0.2794 0.1778)
							(mid 0.249642 0.249642)
							(end 0.1778 0.2794)
						)
					)
					(width 0)
					(fill yes)
				)
			)
		)
		(pad "2" smd custom
			(at 0 0.4445 180)
			(size 0.1397 0.1397)
			(layers "B.Cu" "B.Mask" "B.Paste")
			(net "P5V_STBY")
			(options
				(clearance outline)
				(anchor circle)
			)
			(primitives
				(gr_poly
					(pts
						(arc
							(start -0.1778 0.2794)
							(mid -0.249642 0.249642)
							(end -0.2794 0.1778)
						)
						(arc
							(start -0.2794 -0.1778)
							(mid -0.249642 -0.249642)
							(end -0.1778 -0.2794)
						)
						(arc
							(start 0.1778 -0.2794)
							(mid 0.249642 -0.249642)
							(end 0.2794 -0.1778)
						)
						(arc
							(start 0.2794 0.1778)
							(mid 0.249642 0.249642)
							(end 0.1778 0.2794)
						)
					)
					(width 0)
					(fill yes)
				)
			)
		)
	)
	(footprint ""
		(layer "B.Cu")
		(at 274.193 -181.737 90)
		(property "Reference" "R359"
			(at 0 0 90)
			(layer "B.SilkS")
			(hide yes)
			(effects
				(font
					(size 1.27 1.27)
				)
				(justify mirror)
			)
		)
		(property "Value" "3K3R2F-2-GP"
			(at -0.064008 -3.993896 90)
			(unlocked yes)
			(layer "B.Fab")
			(hide yes)
			(effects
				(font
					(size 1.016 1.016)
					(thickness 0.1524)
				)
				(justify mirror)
			)
		)
		(property "Device Type" "R402H16"
			(at -0.064008 -5.517896 90)
			(unlocked yes)
			(layer "B.Fab")
			(hide yes)
			(effects
				(font
					(size 1.016 1.016)
					(thickness 0.1524)
				)
				(justify mirror)
			)
		)
		(duplicate_pad_numbers_are_jumpers no)
		(fp_line
			(start 0.508 -0.9398)
			(end 0.508 0.9398)
			(stroke
				(width 0.1524)
				(type default)
			)
			(layer "B.SilkS")
		)
		(fp_line
			(start -0.508 -0.9398)
			(end 0.508 -0.9398)
			(stroke
				(width 0.1524)
				(type default)
			)
			(layer "B.SilkS")
		)
		(fp_rect
			(start 0.508 0.9398)
			(end -0.508 -0.9398)
			(stroke
				(width 0)
				(type default)
			)
			(fill no)
			(layer "B.CrtYd")
		)
		(fp_rect
			(start 0.508 0.9398)
			(end -0.508 -0.9398)
			(stroke
				(width 0)
				(type default)
			)
			(fill no)
			(layer "B.Fab")
		)
		(pad "1" smd custom
			(at 0 -0.4445 270)
			(size 0.1397 0.1397)
			(layers "B.Cu" "B.Mask" "B.Paste")
			(net "P3V3_STBY")
			(options
				(clearance outline)
				(anchor circle)
			)
			(primitives
				(gr_poly
					(pts
						(arc
							(start -0.1778 0.2794)
							(mid -0.249642 0.249642)
							(end -0.2794 0.1778)
						)
						(arc
							(start -0.2794 -0.1778)
							(mid -0.249642 -0.249642)
							(end -0.1778 -0.2794)
						)
						(arc
							(start 0.1778 -0.2794)
							(mid 0.249642 -0.249642)
							(end 0.2794 -0.1778)
						)
						(arc
							(start 0.2794 0.1778)
							(mid 0.249642 0.249642)
							(end 0.1778 0.2794)
						)
					)
					(width 0)
					(fill yes)
				)
			)
		)
		(pad "2" smd custom
			(at 0 0.4445 270)
			(size 0.1397 0.1397)
			(layers "B.Cu" "B.Mask" "B.Paste")
			(net "ROMA5")
			(options
				(clearance outline)
				(anchor circle)
			)
			(primitives
				(gr_poly
					(pts
						(arc
							(start -0.1778 0.2794)
							(mid -0.249642 0.249642)
							(end -0.2794 0.1778)
						)
						(arc
							(start -0.2794 -0.1778)
							(mid -0.249642 -0.249642)
							(end -0.1778 -0.2794)
						)
						(arc
							(start 0.1778 -0.2794)
							(mid 0.249642 -0.249642)
							(end 0.2794 -0.1778)
						)
						(arc
							(start 0.2794 0.1778)
							(mid 0.249642 0.249642)
							(end 0.1778 0.2794)
						)
					)
					(width 0)
					(fill yes)
				)
			)
		)
	)
	(footprint ""
		(layer "B.Cu")
		(at 110.748826 -41.8719 -90)
		(property "Reference" "SC989"
			(at 0 0 90)
			(layer "B.SilkS")
			(hide yes)
			(effects
				(font
					(size 1.27 1.27)
				)
				(justify mirror)
			)
		)
		(property "Value" "SCD1U16V2KX-3GP"
			(at -1.1811 -2.7051 270)
			(unlocked yes)
			(layer "B.Fab")
			(hide yes)
			(effects
				(font
					(size 1.016 1.016)
					(thickness 0.1524)
				)
				(justify mirror)
			)
		)
		(property "Device Type" "C402H22"
			(at -1.1811 -4.2291 270)
			(unlocked yes)
			(layer "B.Fab")
			(hide yes)
			(effects
				(font
					(size 1.016 1.016)
					(thickness 0.1524)
				)
				(justify mirror)
			)
		)
		(duplicate_pad_numbers_are_jumpers no)
		(fp_rect
			(start 0.4318 0.9525)
			(end -0.4318 -0.9525)
			(stroke
				(width 0)
				(type default)
			)
			(fill no)
			(layer "B.CrtYd")
		)
		(fp_rect
			(start 0.4318 0.9525)
			(end -0.4318 -0.9525)
			(stroke
				(width 0)
				(type default)
			)
			(fill no)
			(layer "B.Fab")
		)
		(pad "1" smd custom
			(at 0 -0.4445 90)
			(size 0.1524 0.1524)
			(layers "B.Cu" "B.Mask" "B.Paste")
			(net "P1V8_C")
			(options
				(clearance outline)
				(anchor circle)
			)
			(primitives
				(gr_poly
					(pts
						(arc
							(start 0.3048 0.2032)
							(mid 0.275042 0.275042)
							(end 0.2032 0.3048)
						)
						(arc
							(start -0.2032 0.3048)
							(mid -0.275042 0.275042)
							(end -0.3048 0.2032)
						)
						(arc
							(start -0.3048 -0.2032)
							(mid -0.275042 -0.275042)
							(end -0.2032 -0.3048)
						)
						(arc
							(start 0.2032 -0.3048)
							(mid 0.275042 -0.275042)
							(end 0.3048 -0.2032)
						)
					)
					(width 0)
					(fill yes)
				)
			)
		)
		(pad "2" smd custom
			(at 0 0.4445 90)
			(size 0.1524 0.1524)
			(layers "B.Cu" "B.Mask" "B.Paste")
			(net "GND")
			(options
				(clearance outline)
				(anchor circle)
			)
			(primitives
				(gr_poly
					(pts
						(arc
							(start 0.3048 0.2032)
							(mid 0.275042 0.275042)
							(end 0.2032 0.3048)
						)
						(arc
							(start -0.2032 0.3048)
							(mid -0.275042 0.275042)
							(end -0.3048 0.2032)
						)
						(arc
							(start -0.3048 -0.2032)
							(mid -0.275042 -0.275042)
							(end -0.2032 -0.3048)
						)
						(arc
							(start 0.2032 -0.3048)
							(mid 0.275042 -0.275042)
							(end 0.3048 -0.2032)
						)
					)
					(width 0)
					(fill yes)
				)
			)
		)
	)
	(footprint ""
		(layer "B.Cu")
		(at 294.33012 -170.28922)
		(property "Reference" "TP153"
			(at 0 0 0)
			(layer "B.SilkS")
			(hide yes)
			(effects
				(font
					(size 1.27 1.27)
				)
				(justify mirror)
			)
		)
		(property "Value" "TPAD28"
			(at -0.0127 -1.8034 0)
			(unlocked yes)
			(layer "B.Fab")
			(hide yes)
			(effects
				(font
					(size 1.016 1.016)
					(thickness 0.1524)
				)
				(justify mirror)
			)
		)
		(property "Device Type" "TPAD28"
			(at -0.0127 -3.3274 0)
			(unlocked yes)
			(layer "B.Fab")
			(hide yes)
			(effects
				(font
					(size 1.016 1.016)
					(thickness 0.1524)
				)
				(justify mirror)
			)
		)
		(duplicate_pad_numbers_are_jumpers no)
		(fp_poly
			(pts
				(arc
					(start 0.3556 0)
					(mid -0.3556 0)
					(end 0.3556 0)
				)
			)
			(stroke
				(width 0)
				(type default)
			)
			(fill no)
			(layer "B.CrtYd")
		)
		(fp_poly
			(pts
				(arc
					(start 0.6096 0)
					(mid -0.6096 0)
					(end 0.6096 0)
				)
			)
			(stroke
				(width 0)
				(type default)
			)
			(fill no)
			(layer "B.Fab")
		)
		(pad "1" smd circle
			(at 0 0 180)
			(size 0.7112 0.7112)
			(layers "B.Cu" "B.Mask" "B.Paste")
			(net "TP_BMC_GPIOU3")
		)
	)
	(footprint ""
		(layer "B.Cu")
		(at 128.79197 -104.267)
		(property "Reference" "SC1172"
			(at 0 0 0)
			(layer "B.SilkS")
			(hide yes)
			(effects
				(font
					(size 1.27 1.27)
				)
				(justify mirror)
			)
		)
		(property "Value" "SC1U10V2KX-4-GP"
			(at -1.1811 -2.7051 0)
			(unlocked yes)
			(layer "B.Fab")
			(hide yes)
			(effects
				(font
					(size 1.016 1.016)
					(thickness 0.1524)
				)
				(justify mirror)
			)
		)
		(property "Device Type" "C402H22"
			(at -1.1811 -4.2291 0)
			(unlocked yes)
			(layer "B.Fab")
			(hide yes)
			(effects
				(font
					(size 1.016 1.016)
					(thickness 0.1524)
				)
				(justify mirror)
			)
		)
		(duplicate_pad_numbers_are_jumpers no)
		(fp_rect
			(start 0.4318 0.9525)
			(end -0.4318 -0.9525)
			(stroke
				(width 0)
				(type default)
			)
			(fill no)
			(layer "B.CrtYd")
		)
		(fp_rect
			(start 0.4318 0.9525)
			(end -0.4318 -0.9525)
			(stroke
				(width 0)
				(type default)
			)
			(fill no)
			(layer "B.Fab")
		)
		(pad "1" smd custom
			(at 0 -0.4445 180)
			(size 0.1524 0.1524)
			(layers "B.Cu" "B.Mask" "B.Paste")
			(net "GB_VDDA")
			(options
				(clearance outline)
				(anchor circle)
			)
			(primitives
				(gr_poly
					(pts
						(arc
							(start 0.3048 0.2032)
							(mid 0.275042 0.275042)
							(end 0.2032 0.3048)
						)
						(arc
							(start -0.2032 0.3048)
							(mid -0.275042 0.275042)
							(end -0.3048 0.2032)
						)
						(arc
							(start -0.3048 -0.2032)
							(mid -0.275042 -0.275042)
							(end -0.2032 -0.3048)
						)
						(arc
							(start 0.2032 -0.3048)
							(mid 0.275042 -0.275042)
							(end 0.3048 -0.2032)
						)
					)
					(width 0)
					(fill yes)
				)
			)
		)
		(pad "2" smd custom
			(at 0 0.4445 180)
			(size 0.1524 0.1524)
			(layers "B.Cu" "B.Mask" "B.Paste")
			(net "GND")
			(options
				(clearance outline)
				(anchor circle)
			)
			(primitives
				(gr_poly
					(pts
						(arc
							(start 0.3048 0.2032)
							(mid 0.275042 0.275042)
							(end 0.2032 0.3048)
						)
						(arc
							(start -0.2032 0.3048)
							(mid -0.275042 0.275042)
							(end -0.3048 0.2032)
						)
						(arc
							(start -0.3048 -0.2032)
							(mid -0.275042 -0.275042)
							(end -0.2032 -0.3048)
						)
						(arc
							(start 0.2032 -0.3048)
							(mid 0.275042 -0.275042)
							(end 0.3048 -0.2032)
						)
					)
					(width 0)
					(fill yes)
				)
			)
		)
	)
	(footprint ""
		(layer "B.Cu")
		(at 319.405 -182.753 90)
		(property "Reference" "C8089"
			(at 0 0 90)
			(layer "B.SilkS")
			(hide yes)
			(effects
				(font
					(size 1.27 1.27)
				)
				(justify mirror)
			)
		)
		(property "Value" "SCD1U25V2KX-2-GP"
			(at -1.1811 -2.7051 90)
			(unlocked yes)
			(layer "B.Fab")
			(hide yes)
			(effects
				(font
					(size 1.016 1.016)
					(thickness 0.1524)
				)
				(justify mirror)
			)
		)
		(property "Device Type" "C402H22"
			(at -1.1811 -4.2291 90)
			(unlocked yes)
			(layer "B.Fab")
			(hide yes)
			(effects
				(font
					(size 1.016 1.016)
					(thickness 0.1524)
				)
				(justify mirror)
			)
		)
		(duplicate_pad_numbers_are_jumpers no)
		(fp_rect
			(start 0.4318 0.9525)
			(end -0.4318 -0.9525)
			(stroke
				(width 0)
				(type default)
			)
			(fill no)
			(layer "B.CrtYd")
		)
		(fp_rect
			(start 0.4318 0.9525)
			(end -0.4318 -0.9525)
			(stroke
				(width 0)
				(type default)
			)
			(fill no)
			(layer "B.Fab")
		)
		(pad "1" smd custom
			(at 0 -0.4445 270)
			(size 0.1524 0.1524)
			(layers "B.Cu" "B.Mask" "B.Paste")
			(net "ADC_P1V5_E")
			(options
				(clearance outline)
				(anchor circle)
			)
			(primitives
				(gr_poly
					(pts
						(arc
							(start 0.3048 0.2032)
							(mid 0.275042 0.275042)
							(end 0.2032 0.3048)
						)
						(arc
							(start -0.2032 0.3048)
							(mid -0.275042 0.275042)
							(end -0.3048 0.2032)
						)
						(arc
							(start -0.3048 -0.2032)
							(mid -0.275042 -0.275042)
							(end -0.2032 -0.3048)
						)
						(arc
							(start 0.2032 -0.3048)
							(mid 0.275042 -0.275042)
							(end 0.3048 -0.2032)
						)
					)
					(width 0)
					(fill yes)
				)
			)
		)
		(pad "2" smd custom
			(at 0 0.4445 270)
			(size 0.1524 0.1524)
			(layers "B.Cu" "B.Mask" "B.Paste")
			(net "GND")
			(options
				(clearance outline)
				(anchor circle)
			)
			(primitives
				(gr_poly
					(pts
						(arc
							(start 0.3048 0.2032)
							(mid 0.275042 0.275042)
							(end 0.2032 0.3048)
						)
						(arc
							(start -0.2032 0.3048)
							(mid -0.275042 0.275042)
							(end -0.3048 0.2032)
						)
						(arc
							(start -0.3048 -0.2032)
							(mid -0.275042 -0.275042)
							(end -0.2032 -0.3048)
						)
						(arc
							(start 0.2032 -0.3048)
							(mid 0.275042 -0.275042)
							(end 0.3048 -0.2032)
						)
					)
					(width 0)
					(fill yes)
				)
			)
		)
	)
	(footprint ""
		(layer "B.Cu")
		(at 171.704 -118.364 -90)
		(property "Reference" "PR150"
			(at 0 0 90)
			(layer "B.SilkS")
			(hide yes)
			(effects
				(font
					(size 1.27 1.27)
				)
				(justify mirror)
			)
		)
		(property "Value" "0R3J-0-U-GP"
			(at 0.0254 -2.5146 270)
			(unlocked yes)
			(layer "B.Fab")
			(hide yes)
			(effects
				(font
					(size 1.016 1.016)
					(thickness 0.1524)
				)
				(justify mirror)
			)
		)
		(property "Device Type" "R603H22"
			(at 0.0254 -4.0386 270)
			(unlocked yes)
			(layer "B.Fab")
			(hide yes)
			(effects
				(font
					(size 1.016 1.016)
					(thickness 0.1524)
				)
				(justify mirror)
			)
		)
		(duplicate_pad_numbers_are_jumpers no)
		(fp_line
			(start -0.2032 0)
			(end -0.4826 0)
			(stroke
				(width 0.2032)
				(type default)
			)
			(layer "B.SilkS")
		)
		(fp_line
			(start 0.4826 0)
			(end 0.2032 0)
			(stroke
				(width 0.2032)
				(type default)
			)
			(layer "B.SilkS")
		)
		(fp_rect
			(start 0.5842 1.3335)
			(end -0.5842 -1.3335)
			(stroke
				(width 0)
				(type default)
			)
			(fill no)
			(layer "B.CrtYd")
		)
		(fp_rect
			(start 0.5842 1.3335)
			(end -0.5842 -1.3335)
			(stroke
				(width 0)
				(type default)
			)
			(fill no)
			(layer "B.Fab")
		)
		(pad "1" smd custom
			(at 0 -0.762 90)
			(size 0.2159 0.2159)
			(layers "B.Cu" "B.Mask" "B.Paste")
			(net "P0V9_E_VIN")
			(options
				(clearance outline)
				(anchor circle)
			)
			(primitives
				(gr_poly
					(pts
						(arc
							(start -0.3302 0.4318)
							(mid -0.402042 0.402042)
							(end -0.4318 0.3302)
						)
						(arc
							(start -0.4318 -0.3302)
							(mid -0.402042 -0.402042)
							(end -0.3302 -0.4318)
						)
						(arc
							(start 0.3302 -0.4318)
							(mid 0.402042 -0.402042)
							(end 0.4318 -0.3302)
						)
						(arc
							(start 0.4318 0.3302)
							(mid 0.402042 0.402042)
							(end 0.3302 0.4318)
						)
					)
					(width 0)
					(fill yes)
				)
			)
		)
		(pad "2" smd custom
			(at 0 0.762 90)
			(size 0.2159 0.2159)
			(layers "B.Cu" "B.Mask" "B.Paste")
			(net "P0V9_E_VDD")
			(options
				(clearance outline)
				(anchor circle)
			)
			(primitives
				(gr_poly
					(pts
						(arc
							(start -0.3302 0.4318)
							(mid -0.402042 0.402042)
							(end -0.4318 0.3302)
						)
						(arc
							(start -0.4318 -0.3302)
							(mid -0.402042 -0.402042)
							(end -0.3302 -0.4318)
						)
						(arc
							(start 0.3302 -0.4318)
							(mid 0.402042 -0.402042)
							(end 0.4318 -0.3302)
						)
						(arc
							(start 0.4318 0.3302)
							(mid 0.402042 0.402042)
							(end 0.3302 0.4318)
						)
					)
					(width 0)
					(fill yes)
				)
			)
		)
	)
	(footprint ""
		(layer "B.Cu")
		(at 107.58297 -94.615 -90)
		(property "Reference" "SC1213"
			(at 0 0 90)
			(layer "B.SilkS")
			(hide yes)
			(effects
				(font
					(size 1.27 1.27)
				)
				(justify mirror)
			)
		)
		(property "Value" "SC1KP50V2KX-1GP"
			(at -1.1811 -2.7051 270)
			(unlocked yes)
			(layer "B.Fab")
			(hide yes)
			(effects
				(font
					(size 1.016 1.016)
					(thickness 0.1524)
				)
				(justify mirror)
			)
		)
		(property "Device Type" "C402H22"
			(at -1.1811 -4.2291 270)
			(unlocked yes)
			(layer "B.Fab")
			(hide yes)
			(effects
				(font
					(size 1.016 1.016)
					(thickness 0.1524)
				)
				(justify mirror)
			)
		)
		(duplicate_pad_numbers_are_jumpers no)
		(fp_rect
			(start 0.4318 0.9525)
			(end -0.4318 -0.9525)
			(stroke
				(width 0)
				(type default)
			)
			(fill no)
			(layer "B.CrtYd")
		)
		(fp_rect
			(start 0.4318 0.9525)
			(end -0.4318 -0.9525)
			(stroke
				(width 0)
				(type default)
			)
			(fill no)
			(layer "B.Fab")
		)
		(pad "1" smd custom
			(at 0 -0.4445 90)
			(size 0.1524 0.1524)
			(layers "B.Cu" "B.Mask" "B.Paste")
			(net "P1V8_E")
			(options
				(clearance outline)
				(anchor circle)
			)
			(primitives
				(gr_poly
					(pts
						(arc
							(start 0.3048 0.2032)
							(mid 0.275042 0.275042)
							(end 0.2032 0.3048)
						)
						(arc
							(start -0.2032 0.3048)
							(mid -0.275042 0.275042)
							(end -0.3048 0.2032)
						)
						(arc
							(start -0.3048 -0.2032)
							(mid -0.275042 -0.275042)
							(end -0.2032 -0.3048)
						)
						(arc
							(start 0.2032 -0.3048)
							(mid 0.275042 -0.275042)
							(end 0.3048 -0.2032)
						)
					)
					(width 0)
					(fill yes)
				)
			)
		)
		(pad "2" smd custom
			(at 0 0.4445 90)
			(size 0.1524 0.1524)
			(layers "B.Cu" "B.Mask" "B.Paste")
			(net "GND")
			(options
				(clearance outline)
				(anchor circle)
			)
			(primitives
				(gr_poly
					(pts
						(arc
							(start 0.3048 0.2032)
							(mid 0.275042 0.275042)
							(end 0.2032 0.3048)
						)
						(arc
							(start -0.2032 0.3048)
							(mid -0.275042 0.275042)
							(end -0.3048 0.2032)
						)
						(arc
							(start -0.3048 -0.2032)
							(mid -0.275042 -0.275042)
							(end -0.2032 -0.3048)
						)
						(arc
							(start 0.2032 -0.3048)
							(mid 0.275042 -0.275042)
							(end 0.3048 -0.2032)
						)
					)
					(width 0)
					(fill yes)
				)
			)
		)
	)
	(gr_poly
		(pts
			(xy 10.450322 -106.369612) (xy 6.13029 -106.369612) (xy 6.13029 -95.892112)
			(arc
				(start 5.626862 -95.892112)
				(mid 4.272266 -94.799912)
				(end 5.626862 -93.707712)
			)
			(xy 6.13029 -93.707712) (xy 6.13029 -82.199988) (xy 23.86965 -82.199988) (xy 23.86965 -93.707712)
			(arc
				(start 24.372824 -93.707712)
				(mid 25.727728 -94.799912)
				(end 24.372824 -95.892112)
			)
			(xy 23.86965 -95.892112) (xy 23.86965 -106.369612) (xy 19.149822 -106.369612) (xy 19.149822 -108.479844)
			(xy 26.469594 -108.479844) (xy 26.469594 -77.999844) (xy 3.530346 -77.999844) (xy 3.530346 -108.479844)
			(xy 10.450322 -108.479844)
		)
		(stroke
			(width 0)
			(type solid)
		)
		(fill yes)
		(layer "F.Cu")
		(net "GND")
	)
	(gr_arc
		(start 10.80008 -104.078532)
		(mid 10.830648 -104.232208)
		(end 10.917682 -104.362504)
		(stroke
			(width 0.0508)
			(type default)
		)
		(layer "F.Cu")
	)
	(gr_line
		(start 10.80008 -102.489762)
		(end 10.80008 -104.078532)
		(stroke
			(width 0.0508)
			(type default)
		)
		(layer "F.Cu")
	)
	(gr_arc
		(start 10.99058 -104.538526)
		(mid 10.971638 -104.443265)
		(end 10.917682 -104.362504)
		(stroke
			(width 0.0508)
			(type default)
		)
		(layer "F.Cu")
	)
	(gr_arc
		(start 11.20013 -98.623374)
		(mid 11.186132 -98.553)
		(end 11.146282 -98.493326)
		(stroke
			(width 0.0508)
			(type default)
		)
		(layer "F.Cu")
	)
	(gr_line
		(start 11.20013 -98.623374)
		(end 11.20013 -99.980242)
		(stroke
			(width 0.0508)
			(type default)
		)
		(layer "F.Cu")
	)
	(gr_arc
		(start 11.451082 -104.260904)
		(mid 11.364027 -104.391191)
		(end 11.33348 -104.544876)
		(stroke
			(width 0.0508)
			(type default)
		)
		(layer "F.Cu")
	)
	(gr_arc
		(start 11.451082 -104.260904)
		(mid 11.561444 -104.095779)
		(end 11.60018 -103.900986)
		(stroke
			(width 0.0508)
			(type default)
		)
		(layer "F.Cu")
	)
	(gr_line
		(start 11.60018 -102.489762)
		(end 11.60018 -103.900986)
		(stroke
			(width 0.0508)
			(type default)
		)
		(layer "F.Cu")
	)
	(gr_line
		(start 12.00023 -98.641154)
		(end 12.00023 -99.980242)
		(stroke
			(width 0.0508)
			(type default)
		)
		(layer "F.Cu")
	)
	(gr_arc
		(start 12.060682 -98.495104)
		(mid 12.01595 -98.562125)
		(end 12.00023 -98.641154)
		(stroke
			(width 0.0508)
			(type default)
		)
		(layer "F.Cu")
	)
	(gr_arc
		(start 13.20038 -103.946452)
		(mid 13.234235 -104.116652)
		(end 13.330682 -104.260904)
		(stroke
			(width 0.0508)
			(type default)
		)
		(layer "F.Cu")
	)
	(gr_line
		(start 13.20038 -102.489762)
		(end 13.20038 -103.946452)
		(stroke
			(width 0.0508)
			(type default)
		)
		(layer "F.Cu")
	)
	(gr_arc
		(start 13.42771 -104.495092)
		(mid 13.402468 -104.368359)
		(end 13.330682 -104.260904)
		(stroke
			(width 0.0508)
			(type default)
		)
		(layer "F.Cu")
	)
	(gr_arc
		(start 13.42898 -104.953816)
		(mid 13.428653 -104.938436)
		(end 13.42771 -104.923082)
		(stroke
			(width 0.0508)
			(type default)
		)
		(layer "F.Cu")
	)
	(gr_arc
		(start 13.60043 -98.6917)
		(mid 13.576532 -98.571559)
		(end 13.508482 -98.469704)
		(stroke
			(width 0.0508)
			(type default)
		)
		(layer "F.Cu")
	)
	(gr_line
		(start 13.60043 -98.6917)
		(end 13.60043 -99.980242)
		(stroke
			(width 0.0508)
			(type default)
		)
		(layer "F.Cu")
	)
	(gr_arc
		(start 13.899642 -104.160066)
		(mid 13.804599 -104.345338)
		(end 13.77188 -104.550972)
		(stroke
			(width 0.0508)
			(type default)
		)
		(layer "F.Cu")
	)
	(gr_arc
		(start 13.899642 -104.160066)
		(mid 13.974278 -104.048437)
		(end 14.00048 -103.916734)
		(stroke
			(width 0.0508)
			(type default)
		)
		(layer "F.Cu")
	)
	(gr_line
		(start 14.00048 -102.489762)
		(end 14.00048 -103.916734)
		(stroke
			(width 0.0508)
			(type default)
		)
		(layer "F.Cu")
	)
	(gr_line
		(start 14.40053 -98.63582)
		(end 14.40053 -99.980242)
		(stroke
			(width 0.0508)
			(type default)
		)
		(layer "F.Cu")
	)
	(gr_arc
		(start 14.448282 -98.520504)
		(mid 14.412958 -98.573418)
		(end 14.40053 -98.63582)
		(stroke
			(width 0.0508)
			(type default)
		)
		(layer "F.Cu")
	)
	(gr_arc
		(start 15.59941 -103.825802)
		(mid 15.642584 -104.042853)
		(end 15.765526 -104.226868)
		(stroke
			(width 0.0508)
			(type default)
		)
		(layer "F.Cu")
	)
	(gr_line
		(start 15.59941 -102.489762)
		(end 15.59941 -103.825802)
		(stroke
			(width 0.0508)
			(type default)
		)
		(layer "F.Cu")
	)
	(gr_arc
		(start 15.82801 -104.458516)
		(mid 15.812142 -104.338545)
		(end 15.765526 -104.226868)
		(stroke
			(width 0.0508)
			(type default)
		)
		(layer "F.Cu")
	)
	(gr_arc
		(start 15.99946 -98.622104)
		(mid 15.98579 -98.553382)
		(end 15.946882 -98.495104)
		(stroke
			(width 0.0508)
			(type default)
		)
		(layer "F.Cu")
	)
	(gr_line
		(start 15.99946 -98.622104)
		(end 15.99946 -99.980242)
		(stroke
			(width 0.0508)
			(type default)
		)
		(layer "F.Cu")
	)
	(gr_arc
		(start 16.278352 -104.160574)
		(mid 16.19885 -104.279557)
		(end 16.17091 -104.419908)
		(stroke
			(width 0.0508)
			(type default)
		)
		(layer "F.Cu")
	)
	(gr_arc
		(start 16.278352 -104.160574)
		(mid 16.368025 -104.026315)
		(end 16.39951 -103.867966)
		(stroke
			(width 0.0508)
			(type default)
		)
		(layer "F.Cu")
	)
	(gr_line
		(start 16.39951 -102.489762)
		(end 16.39951 -103.867966)
		(stroke
			(width 0.0508)
			(type default)
		)
		(layer "F.Cu")
	)
	(gr_line
		(start 16.79956 -98.730816)
		(end 16.79956 -99.980242)
		(stroke
			(width 0.0508)
			(type default)
		)
		(layer "F.Cu")
	)
	(gr_arc
		(start 16.886682 -98.520504)
		(mid 16.822193 -98.616992)
		(end 16.79956 -98.730816)
		(stroke
			(width 0.0508)
			(type default)
		)
		(layer "F.Cu")
	)
	(gr_arc
		(start 17.99971 -104.14635)
		(mid 18.033913 -104.3183)
		(end 18.131282 -104.464104)
		(stroke
			(width 0.0508)
			(type default)
		)
		(layer "F.Cu")
	)
	(gr_line
		(start 17.99971 -102.489762)
		(end 17.99971 -104.14635)
		(stroke
			(width 0.0508)
			(type default)
		)
		(layer "F.Cu")
	)
	(gr_arc
		(start 18.22831 -104.698292)
		(mid 18.203068 -104.571559)
		(end 18.131282 -104.464104)
		(stroke
			(width 0.0508)
			(type default)
		)
		(layer "F.Cu")
	)
	(gr_arc
		(start 18.39976 -98.887534)
		(mid 18.362986 -98.702657)
		(end 18.258282 -98.545904)
		(stroke
			(width 0.0508)
			(type default)
		)
		(layer "F.Cu")
	)
	(gr_line
		(start 18.39976 -98.887534)
		(end 18.39976 -99.980242)
		(stroke
			(width 0.0508)
			(type default)
		)
		(layer "F.Cu")
	)
	(gr_arc
		(start 18.715482 -104.108504)
		(mid 18.608726 -104.268275)
		(end 18.57121 -104.456738)
		(stroke
			(width 0.0508)
			(type default)
		)
		(layer "F.Cu")
	)
	(gr_arc
		(start 18.715482 -104.108504)
		(mid 18.777884 -104.015027)
		(end 18.79981 -103.904796)
		(stroke
			(width 0.0508)
			(type default)
		)
		(layer "F.Cu")
	)
	(gr_line
		(start 18.79981 -102.489762)
		(end 18.79981 -103.904796)
		(stroke
			(width 0.0508)
			(type default)
		)
		(layer "F.Cu")
	)
	(gr_line
		(start 19.19986 -98.848164)
		(end 19.19986 -99.980242)
		(stroke
			(width 0.0508)
			(type default)
		)
		(layer "F.Cu")
	)
	(gr_arc
		(start 19.325082 -98.545904)
		(mid 19.232411 -98.684578)
		(end 19.19986 -98.848164)
		(stroke
			(width 0.0508)
			(type default)
		)
		(layer "F.Cu")
	)
	(gr_line
		(start 32.334454 -90.096086)
		(end 32.657288 -89.773252)
		(stroke
			(width 0.0508)
			(type default)
		)
		(layer "F.Cu")
	)
	(gr_arc
		(start 32.657288 -89.773252)
		(mid 32.714053 -89.688297)
		(end 32.733996 -89.588086)
		(stroke
			(width 0.0508)
			(type default)
		)
		(layer "F.Cu")
	)
	(gr_arc
		(start 33.076896 -89.588086)
		(mid 33.127226 -89.840771)
		(end 33.270444 -90.054938)
		(stroke
			(width 0.0508)
			(type default)
		)
		(layer "F.Cu")
	)
	(gr_line
		(start 33.270444 -90.054938)
		(end 33.311338 -90.096086)
		(stroke
			(width 0.0508)
			(type default)
		)
		(layer "F.Cu")
	)
	(gr_line
		(start 35.382454 -90.096086)
		(end 35.517582 -89.960958)
		(stroke
			(width 0.0508)
			(type default)
		)
		(layer "F.Cu")
	)
	(gr_arc
		(start 35.517582 -89.960958)
		(mid 35.647464 -89.766576)
		(end 35.693096 -89.537286)
		(stroke
			(width 0.0508)
			(type default)
		)
		(layer "F.Cu")
	)
	(gr_arc
		(start 36.035996 -89.537286)
		(mid 36.079194 -89.754871)
		(end 36.202366 -89.939368)
		(stroke
			(width 0.0508)
			(type default)
		)
		(layer "F.Cu")
	)
	(gr_line
		(start 36.202366 -89.939368)
		(end 36.359338 -90.096086)
		(stroke
			(width 0.0508)
			(type default)
		)
		(layer "F.Cu")
	)
	(gr_line
		(start 38.430454 -90.096086)
		(end 38.554406 -89.972134)
		(stroke
			(width 0.0508)
			(type default)
		)
		(layer "F.Cu")
	)
	(gr_arc
		(start 38.554406 -89.972134)
		(mid 38.664401 -89.807598)
		(end 38.702996 -89.613486)
		(stroke
			(width 0.0508)
			(type default)
		)
		(layer "F.Cu")
	)
	(gr_arc
		(start 39.045896 -89.899744)
		(mid 39.056323 -89.952125)
		(end 39.086028 -89.996518)
		(stroke
			(width 0.0508)
			(type default)
		)
		(layer "F.Cu")
	)
	(gr_line
		(start 39.086028 -89.996518)
		(end 39.115746 -90.026236)
		(stroke
			(width 0.0508)
			(type default)
		)
		(layer "F.Cu")
	)
	(gr_arc
		(start 39.115746 -90.026236)
		(mid 39.193131 -90.077922)
		(end 39.284402 -90.096086)
		(stroke
			(width 0.0508)
			(type default)
		)
		(layer "F.Cu")
	)
	(gr_line
		(start 39.238428 -80.099662)
		(end 39.591996 -79.746094)
		(stroke
			(width 0.0508)
			(type default)
		)
		(layer "F.Cu")
	)
	(gr_line
		(start 39.284402 -90.096086)
		(end 39.407338 -90.096086)
		(stroke
			(width 0.0508)
			(type default)
		)
		(layer "F.Cu")
	)
	(gr_line
		(start 39.347902 -82.802984)
		(end 39.591996 -83.047078)
		(stroke
			(width 0.0508)
			(type default)
		)
		(layer "F.Cu")
	)
	(gr_line
		(start 39.347902 -82.314288)
		(end 39.591996 -82.070194)
		(stroke
			(width 0.0508)
			(type default)
		)
		(layer "F.Cu")
	)
	(gr_arc
		(start 39.385494 -80.516222)
		(mid 39.305428 -80.46278)
		(end 39.210996 -80.444086)
		(stroke
			(width 0.0508)
			(type default)
		)
		(layer "F.Cu")
	)
	(gr_line
		(start 39.385494 -80.516222)
		(end 39.591996 -80.722978)
		(stroke
			(width 0.0508)
			(type default)
		)
		(layer "F.Cu")
	)
	(gr_line
		(start 41.351454 -90.096086)
		(end 41.592246 -89.855294)
		(stroke
			(width 0.0508)
			(type default)
		)
		(layer "F.Cu")
	)
	(gr_arc
		(start 41.592246 -89.855294)
		(mid 41.648622 -89.770922)
		(end 41.668446 -89.671398)
		(stroke
			(width 0.0508)
			(type default)
		)
		(layer "F.Cu")
	)
	(gr_line
		(start 41.693338 -83.489546)
		(end 41.907968 -83.27517)
		(stroke
			(width 0.0508)
			(type default)
		)
		(layer "F.Cu")
	)
	(gr_arc
		(start 41.800018 -80.618838)
		(mid 41.829776 -80.69068)
		(end 41.901618 -80.720438)
		(stroke
			(width 0.0508)
			(type default)
		)
		(layer "F.Cu")
	)
	(gr_line
		(start 41.800018 -79.590138)
		(end 41.800018 -80.618838)
		(stroke
			(width 0.0508)
			(type default)
		)
		(layer "F.Cu")
	)
	(gr_line
		(start 41.901618 -80.720438)
		(end 41.926764 -80.720438)
		(stroke
			(width 0.0508)
			(type default)
		)
		(layer "F.Cu")
	)
	(gr_arc
		(start 41.907968 -83.27517)
		(mid 41.997137 -83.141608)
		(end 42.028364 -82.984086)
		(stroke
			(width 0.0508)
			(type default)
		)
		(layer "F.Cu")
	)
	(gr_arc
		(start 42.011346 -89.83599)
		(mid 42.031165 -89.935514)
		(end 42.087546 -90.019886)
		(stroke
			(width 0.0508)
			(type default)
		)
		(layer "F.Cu")
	)
	(gr_arc
		(start 42.028364 -80.822038)
		(mid 41.998617 -80.750184)
		(end 41.926764 -80.720438)
		(stroke
			(width 0.0508)
			(type default)
		)
		(layer "F.Cu")
	)
	(gr_arc
		(start 42.087546 -90.019886)
		(mid 42.171909 -90.076292)
		(end 42.271442 -90.096086)
		(stroke
			(width 0.0508)
			(type default)
		)
		(layer "F.Cu")
	)
	(gr_line
		(start 42.111422 -74.754486)
		(end 42.398696 -75.04176)
		(stroke
			(width 0.0508)
			(type default)
		)
		(layer "F.Cu")
	)
	(gr_line
		(start 42.199814 -76.05141)
		(end 42.199814 -77.08011)
		(stroke
			(width 0.0508)
			(type default)
		)
		(layer "F.Cu")
	)
	(gr_line
		(start 42.271442 -90.096086)
		(end 42.328338 -90.096086)
		(stroke
			(width 0.0508)
			(type default)
		)
		(layer "F.Cu")
	)
	(gr_arc
		(start 42.301414 -75.94981)
		(mid 42.229566 -75.979564)
		(end 42.199814 -76.05141)
		(stroke
			(width 0.0508)
			(type default)
		)
		(layer "F.Cu")
	)
	(gr_line
		(start 42.301414 -75.94981)
		(end 42.326814 -75.94981)
		(stroke
			(width 0.0508)
			(type default)
		)
		(layer "F.Cu")
	)
	(gr_arc
		(start 42.326814 -75.94981)
		(mid 42.398656 -75.920052)
		(end 42.428414 -75.84821)
		(stroke
			(width 0.0508)
			(type default)
		)
		(layer "F.Cu")
	)
	(gr_arc
		(start 42.371264 -82.984086)
		(mid 42.409218 -83.174893)
		(end 42.517314 -83.336638)
		(stroke
			(width 0.0508)
			(type default)
		)
		(layer "F.Cu")
	)
	(gr_arc
		(start 42.428414 -75.113642)
		(mid 42.420695 -75.074747)
		(end 42.398696 -75.04176)
		(stroke
			(width 0.0508)
			(type default)
		)
		(layer "F.Cu")
	)
	(gr_arc
		(start 42.472864 -80.720438)
		(mid 42.401022 -80.750196)
		(end 42.371264 -80.822038)
		(stroke
			(width 0.0508)
			(type default)
		)
		(layer "F.Cu")
	)
	(gr_line
		(start 42.472864 -80.720438)
		(end 42.498264 -80.720438)
		(stroke
			(width 0.0508)
			(type default)
		)
		(layer "F.Cu")
	)
	(gr_arc
		(start 42.498264 -80.720438)
		(mid 42.570143 -80.690695)
		(end 42.599864 -80.618838)
		(stroke
			(width 0.0508)
			(type default)
		)
		(layer "F.Cu")
	)
	(gr_line
		(start 42.517314 -83.336638)
		(end 42.670222 -83.489546)
		(stroke
			(width 0.0508)
			(type default)
		)
		(layer "F.Cu")
	)
	(gr_line
		(start 42.599864 -79.590138)
		(end 42.599864 -80.618838)
		(stroke
			(width 0.0508)
			(type default)
		)
		(layer "F.Cu")
	)
	(gr_arc
		(start 42.771314 -75.84821)
		(mid 42.801076 -75.920041)
		(end 42.872914 -75.94981)
		(stroke
			(width 0.0508)
			(type default)
		)
		(layer "F.Cu")
	)
	(gr_arc
		(start 42.801032 -75.04176)
		(mid 42.779049 -75.074753)
		(end 42.771314 -75.113642)
		(stroke
			(width 0.0508)
			(type default)
		)
		(layer "F.Cu")
	)
	(gr_line
		(start 42.801032 -75.04176)
		(end 43.088306 -74.754486)
		(stroke
			(width 0.0508)
			(type default)
		)
		(layer "F.Cu")
	)
	(gr_line
		(start 42.872914 -75.94981)
		(end 42.898314 -75.94981)
		(stroke
			(width 0.0508)
			(type default)
		)
		(layer "F.Cu")
	)
	(gr_arc
		(start 42.999914 -76.05141)
		(mid 42.970156 -75.979568)
		(end 42.898314 -75.94981)
		(stroke
			(width 0.0508)
			(type default)
		)
		(layer "F.Cu")
	)
	(gr_line
		(start 42.999914 -76.05141)
		(end 42.999914 -77.08011)
		(stroke
			(width 0.0508)
			(type default)
		)
		(layer "F.Cu")
	)
	(gr_arc
		(start 44.19981 -80.618838)
		(mid 44.229568 -80.69068)
		(end 44.30141 -80.720438)
		(stroke
			(width 0.0508)
			(type default)
		)
		(layer "F.Cu")
	)
	(gr_line
		(start 44.19981 -79.590138)
		(end 44.19981 -80.618838)
		(stroke
			(width 0.0508)
			(type default)
		)
		(layer "F.Cu")
	)
	(gr_line
		(start 44.30141 -80.720438)
		(end 44.32681 -80.720438)
		(stroke
			(width 0.0508)
			(type default)
		)
		(layer "F.Cu")
	)
	(gr_arc
		(start 44.42841 -80.822038)
		(mid 44.398666 -80.750168)
		(end 44.32681 -80.720438)
		(stroke
			(width 0.0508)
			(type default)
		)
		(layer "F.Cu")
	)
	(gr_line
		(start 44.511468 -74.906886)
		(end 44.798742 -75.19416)
		(stroke
			(width 0.0508)
			(type default)
		)
		(layer "F.Cu")
	)
	(gr_line
		(start 44.59986 -76.05141)
		(end 44.59986 -77.08011)
		(stroke
			(width 0.0508)
			(type default)
		)
		(layer "F.Cu")
	)
	(gr_line
		(start 44.647104 -83.502246)
		(end 44.821856 -83.327494)
		(stroke
			(width 0.0508)
			(type default)
		)
		(layer "F.Cu")
	)
	(gr_arc
		(start 44.70146 -75.94981)
		(mid 44.629647 -75.979583)
		(end 44.59986 -76.05141)
		(stroke
			(width 0.0508)
			(type default)
		)
		(layer "F.Cu")
	)
	(gr_line
		(start 44.70146 -75.94981)
		(end 44.72686 -75.94981)
		(stroke
			(width 0.0508)
			(type default)
		)
		(layer "F.Cu")
	)
	(gr_arc
		(start 44.72686 -75.94981)
		(mid 44.798702 -75.920052)
		(end 44.82846 -75.84821)
		(stroke
			(width 0.0508)
			(type default)
		)
		(layer "F.Cu")
	)
	(gr_arc
		(start 44.821856 -83.327494)
		(mid 44.927117 -83.169934)
		(end 44.964096 -82.984086)
		(stroke
			(width 0.0508)
			(type default)
		)
		(layer "F.Cu")
	)
	(gr_arc
		(start 44.82846 -75.266042)
		(mid 44.820741 -75.227147)
		(end 44.798742 -75.19416)
		(stroke
			(width 0.0508)
			(type default)
		)
		(layer "F.Cu")
	)
	(gr_arc
		(start 44.87291 -80.720438)
		(mid 44.801068 -80.750196)
		(end 44.77131 -80.822038)
		(stroke
			(width 0.0508)
			(type default)
		)
		(layer "F.Cu")
	)
	(gr_line
		(start 44.87291 -80.720438)
		(end 44.89831 -80.720438)
		(stroke
			(width 0.0508)
			(type default)
		)
		(layer "F.Cu")
	)
	(gr_arc
		(start 44.89831 -80.720438)
		(mid 44.970159 -80.690679)
		(end 44.99991 -80.618838)
		(stroke
			(width 0.0508)
			(type default)
		)
		(layer "F.Cu")
	)
	(gr_line
		(start 44.99991 -79.590138)
		(end 44.99991 -80.618838)
		(stroke
			(width 0.0508)
			(type default)
		)
		(layer "F.Cu")
	)
	(gr_arc
		(start 45.17136 -75.84821)
		(mid 45.201119 -75.92006)
		(end 45.27296 -75.94981)
		(stroke
			(width 0.0508)
			(type default)
		)
		(layer "F.Cu")
	)
	(gr_arc
		(start 45.201078 -75.19416)
		(mid 45.179085 -75.22715)
		(end 45.17136 -75.266042)
		(stroke
			(width 0.0508)
			(type default)
		)
		(layer "F.Cu")
	)
	(gr_line
		(start 45.201078 -75.19416)
		(end 45.488352 -74.906886)
		(stroke
			(width 0.0508)
			(type default)
		)
		(layer "F.Cu")
	)
	(gr_line
		(start 45.27296 -75.94981)
		(end 45.29836 -75.94981)
		(stroke
			(width 0.0508)
			(type default)
		)
		(layer "F.Cu")
	)
	(gr_arc
		(start 45.306996 -82.984086)
		(mid 45.343964 -83.169935)
		(end 45.449236 -83.327494)
		(stroke
			(width 0.0508)
			(type default)
		)
		(layer "F.Cu")
	)
	(gr_arc
		(start 45.39996 -76.05141)
		(mid 45.370202 -75.979568)
		(end 45.29836 -75.94981)
		(stroke
			(width 0.0508)
			(type default)
		)
		(layer "F.Cu")
	)
	(gr_line
		(start 45.39996 -76.05141)
		(end 45.39996 -77.08011)
		(stroke
			(width 0.0508)
			(type default)
		)
		(layer "F.Cu")
	)
	(gr_line
		(start 45.449236 -83.327494)
		(end 45.623988 -83.502246)
		(stroke
			(width 0.0508)
			(type default)
		)
		(layer "F.Cu")
	)
	(gr_arc
		(start 48.227996 -87.086186)
		(mid 48.639159 -87.004401)
		(end 48.98771 -86.77148)
		(stroke
			(width 0.0508)
			(type default)
		)
		(layer "F.Cu")
	)
	(gr_arc
		(start 48.227996 -84.254086)
		(mid 48.639148 -84.172279)
		(end 48.98771 -83.93938)
		(stroke
			(width 0.0508)
			(type default)
		)
		(layer "F.Cu")
	)
	(gr_arc
		(start 48.98771 -87.743792)
		(mid 48.639156 -87.510871)
		(end 48.227996 -87.429086)
		(stroke
			(width 0.0508)
			(type default)
		)
		(layer "F.Cu")
	)
	(gr_line
		(start 48.98771 -87.743792)
		(end 48.989996 -87.746078)
		(stroke
			(width 0.0508)
			(type default)
		)
		(layer "F.Cu")
	)
	(gr_line
		(start 48.98771 -86.77148)
		(end 48.989996 -86.769194)
		(stroke
			(width 0.0508)
			(type default)
		)
		(layer "F.Cu")
	)
	(gr_arc
		(start 48.98771 -84.911692)
		(mid 48.639156 -84.678771)
		(end 48.227996 -84.596986)
		(stroke
			(width 0.0508)
			(type default)
		)
		(layer "F.Cu")
	)
	(gr_line
		(start 48.98771 -84.911692)
		(end 48.989996 -84.913978)
		(stroke
			(width 0.0508)
			(type default)
		)
		(layer "F.Cu")
	)
	(gr_line
		(start 48.98771 -83.93938)
		(end 48.989996 -83.937094)
		(stroke
			(width 0.0508)
			(type default)
		)
		(layer "F.Cu")
	)
	(gr_line
		(start 50.511456 -82.117438)
		(end 50.79873 -81.830164)
		(stroke
			(width 0.0508)
			(type default)
		)
		(layer "F.Cu")
	)
	(gr_arc
		(start 50.599848 -80.618838)
		(mid 50.629606 -80.69068)
		(end 50.701448 -80.720438)
		(stroke
			(width 0.0508)
			(type default)
		)
		(layer "F.Cu")
	)
	(gr_line
		(start 50.599848 -79.590138)
		(end 50.599848 -80.618838)
		(stroke
			(width 0.0508)
			(type default)
		)
		(layer "F.Cu")
	)
	(gr_line
		(start 50.701448 -80.720438)
		(end 50.726848 -80.720438)
		(stroke
			(width 0.0508)
			(type default)
		)
		(layer "F.Cu")
	)
	(gr_arc
		(start 50.79873 -81.830164)
		(mid 50.820729 -81.797175)
		(end 50.828448 -81.758282)
		(stroke
			(width 0.0508)
			(type default)
		)
		(layer "F.Cu")
	)
	(gr_arc
		(start 50.828448 -80.822038)
		(mid 50.798706 -80.750154)
		(end 50.726848 -80.720438)
		(stroke
			(width 0.0508)
			(type default)
		)
		(layer "F.Cu")
	)
	(gr_line
		(start 50.911506 -74.906886)
		(end 51.19878 -75.19416)
		(stroke
			(width 0.0508)
			(type default)
		)
		(layer "F.Cu")
	)
	(gr_line
		(start 50.999898 -76.05141)
		(end 50.999898 -77.08011)
		(stroke
			(width 0.0508)
			(type default)
		)
		(layer "F.Cu")
	)
	(gr_arc
		(start 51.101498 -75.94981)
		(mid 51.029661 -75.979569)
		(end 50.999898 -76.05141)
		(stroke
			(width 0.0508)
			(type default)
		)
		(layer "F.Cu")
	)
	(gr_line
		(start 51.101498 -75.94981)
		(end 51.126898 -75.94981)
		(stroke
			(width 0.0508)
			(type default)
		)
		(layer "F.Cu")
	)
	(gr_arc
		(start 51.126898 -75.94981)
		(mid 51.19874 -75.920052)
		(end 51.228498 -75.84821)
		(stroke
			(width 0.0508)
			(type default)
		)
		(layer "F.Cu")
	)
	(gr_arc
		(start 51.171348 -81.758282)
		(mid 51.179067 -81.797177)
		(end 51.201066 -81.830164)
		(stroke
			(width 0.0508)
			(type default)
		)
		(layer "F.Cu")
	)
	(gr_line
		(start 51.201066 -81.830164)
		(end 51.48834 -82.117438)
		(stroke
			(width 0.0508)
			(type default)
		)
		(layer "F.Cu")
	)
	(gr_arc
		(start 51.228498 -75.266042)
		(mid 51.220779 -75.227147)
		(end 51.19878 -75.19416)
		(stroke
			(width 0.0508)
			(type default)
		)
		(layer "F.Cu")
	)
	(gr_arc
		(start 51.272948 -80.720438)
		(mid 51.201106 -80.750196)
		(end 51.171348 -80.822038)
		(stroke
			(width 0.0508)
			(type default)
		)
		(layer "F.Cu")
	)
	(gr_line
		(start 51.272948 -80.720438)
		(end 51.298348 -80.720438)
		(stroke
			(width 0.0508)
			(type default)
		)
		(layer "F.Cu")
	)
	(gr_arc
		(start 51.298348 -80.720438)
		(mid 51.370172 -80.690665)
		(end 51.399948 -80.618838)
		(stroke
			(width 0.0508)
			(type default)
		)
		(layer "F.Cu")
	)
	(gr_line
		(start 51.399948 -79.590138)
		(end 51.399948 -80.618838)
		(stroke
			(width 0.0508)
			(type default)
		)
		(layer "F.Cu")
	)
	(gr_arc
		(start 51.571398 -75.84821)
		(mid 51.601159 -75.920046)
		(end 51.672998 -75.94981)
		(stroke
			(width 0.0508)
			(type default)
		)
		(layer "F.Cu")
	)
	(gr_arc
		(start 51.601116 -75.19416)
		(mid 51.579115 -75.227148)
		(end 51.571398 -75.266042)
		(stroke
			(width 0.0508)
			(type default)
		)
		(layer "F.Cu")
	)
	(gr_line
		(start 51.601116 -75.19416)
		(end 51.88839 -74.906886)
		(stroke
			(width 0.0508)
			(type default)
		)
		(layer "F.Cu")
	)
	(gr_line
		(start 51.672998 -75.94981)
		(end 51.698398 -75.94981)
		(stroke
			(width 0.0508)
			(type default)
		)
		(layer "F.Cu")
	)
	(gr_arc
		(start 51.799998 -76.05141)
		(mid 51.77024 -75.979568)
		(end 51.698398 -75.94981)
		(stroke
			(width 0.0508)
			(type default)
		)
		(layer "F.Cu")
	)
	(gr_line
		(start 51.799998 -76.05141)
		(end 51.799998 -77.08011)
		(stroke
			(width 0.0508)
			(type default)
		)
		(layer "F.Cu")
	)
	(gr_line
		(start 52.917852 -82.117438)
		(end 53.198776 -81.836514)
		(stroke
			(width 0.0508)
			(type default)
		)
		(layer "F.Cu")
	)
	(gr_arc
		(start 52.999894 -80.618838)
		(mid 53.029652 -80.69068)
		(end 53.101494 -80.720438)
		(stroke
			(width 0.0508)
			(type default)
		)
		(layer "F.Cu")
	)
	(gr_line
		(start 52.999894 -79.590138)
		(end 52.999894 -80.618838)
		(stroke
			(width 0.0508)
			(type default)
		)
		(layer "F.Cu")
	)
	(gr_line
		(start 53.101494 -80.720438)
		(end 53.126894 -80.720438)
		(stroke
			(width 0.0508)
			(type default)
		)
		(layer "F.Cu")
	)
	(gr_arc
		(start 53.198776 -81.836514)
		(mid 53.22077 -81.803525)
		(end 53.228494 -81.764632)
		(stroke
			(width 0.0508)
			(type default)
		)
		(layer "F.Cu")
	)
	(gr_arc
		(start 53.228494 -80.822038)
		(mid 53.198749 -80.750174)
		(end 53.126894 -80.720438)
		(stroke
			(width 0.0508)
			(type default)
		)
		(layer "F.Cu")
	)
	(gr_line
		(start 53.311298 -74.906886)
		(end 53.598572 -75.19416)
		(stroke
			(width 0.0508)
			(type default)
		)
		(layer "F.Cu")
	)
	(gr_line
		(start 53.399944 -76.05141)
		(end 53.399944 -77.08011)
		(stroke
			(width 0.0508)
			(type default)
		)
		(layer "F.Cu")
	)
	(gr_arc
		(start 53.501544 -75.94981)
		(mid 53.429677 -75.979553)
		(end 53.399944 -76.05141)
		(stroke
			(width 0.0508)
			(type default)
		)
		(layer "F.Cu")
	)
	(gr_line
		(start 53.501544 -75.94981)
		(end 53.52669 -75.94981)
		(stroke
			(width 0.0508)
			(type default)
		)
		(layer "F.Cu")
	)
	(gr_arc
		(start 53.52669 -75.94981)
		(mid 53.598532 -75.920052)
		(end 53.62829 -75.84821)
		(stroke
			(width 0.0508)
			(type default)
		)
		(layer "F.Cu")
	)
	(gr_arc
		(start 53.571394 -81.764632)
		(mid 53.579113 -81.803527)
		(end 53.601112 -81.836514)
		(stroke
			(width 0.0508)
			(type default)
		)
		(layer "F.Cu")
	)
	(gr_line
		(start 53.601112 -81.836514)
		(end 53.882036 -82.117438)
		(stroke
			(width 0.0508)
			(type default)
		)
		(layer "F.Cu")
	)
	(gr_arc
		(start 53.62829 -75.266042)
		(mid 53.620571 -75.227147)
		(end 53.598572 -75.19416)
		(stroke
			(width 0.0508)
			(type default)
		)
		(layer "F.Cu")
	)
	(gr_arc
		(start 53.672994 -80.720438)
		(mid 53.601152 -80.750196)
		(end 53.571394 -80.822038)
		(stroke
			(width 0.0508)
			(type default)
		)
		(layer "F.Cu")
	)
	(gr_line
		(start 53.672994 -80.720438)
		(end 53.698394 -80.720438)
		(stroke
			(width 0.0508)
			(type default)
		)
		(layer "F.Cu")
	)
	(gr_arc
		(start 53.698394 -80.720438)
		(mid 53.770253 -80.690684)
		(end 53.799994 -80.618838)
		(stroke
			(width 0.0508)
			(type default)
		)
		(layer "F.Cu")
	)
	(gr_line
		(start 53.799994 -79.590138)
		(end 53.799994 -80.618838)
		(stroke
			(width 0.0508)
			(type default)
		)
		(layer "F.Cu")
	)
	(gr_arc
		(start 53.97119 -75.84821)
		(mid 54.000951 -75.920049)
		(end 54.07279 -75.94981)
		(stroke
			(width 0.0508)
			(type default)
		)
		(layer "F.Cu")
	)
	(gr_arc
		(start 54.000908 -75.19416)
		(mid 53.978909 -75.227148)
		(end 53.97119 -75.266042)
		(stroke
			(width 0.0508)
			(type default)
		)
		(layer "F.Cu")
	)
	(gr_line
		(start 54.000908 -75.19416)
		(end 54.288182 -74.906886)
		(stroke
			(width 0.0508)
			(type default)
		)
		(layer "F.Cu")
	)
	(gr_line
		(start 54.07279 -75.94981)
		(end 54.09819 -75.94981)
		(stroke
			(width 0.0508)
			(type default)
		)
		(layer "F.Cu")
	)
	(gr_arc
		(start 54.19979 -76.05141)
		(mid 54.170032 -75.979568)
		(end 54.09819 -75.94981)
		(stroke
			(width 0.0508)
			(type default)
		)
		(layer "F.Cu")
	)
	(gr_line
		(start 54.19979 -76.05141)
		(end 54.19979 -77.08011)
		(stroke
			(width 0.0508)
			(type default)
		)
		(layer "F.Cu")
	)
	(gr_line
		(start 71.000112 -254.28194)
		(end 71.000112 -256.25044)
		(stroke
			(width 0.0508)
			(type default)
		)
		(layer "F.Cu")
	)
	(gr_arc
		(start 71.101712 -254.18034)
		(mid 71.029876 -254.210096)
		(end 71.000112 -254.28194)
		(stroke
			(width 0.0508)
			(type default)
		)
		(layer "F.Cu")
	)
	(gr_line
		(start 71.101712 -254.18034)
		(end 71.226934 -254.18034)
		(stroke
			(width 0.0508)
			(type default)
		)
		(layer "F.Cu")
	)
	(gr_arc
		(start 71.226934 -254.18034)
		(mid 71.298776 -254.150582)
		(end 71.328534 -254.07874)
		(stroke
			(width 0.0508)
			(type default)
		)
		(layer "F.Cu")
	)
	(gr_arc
		(start 71.671434 -254.07874)
		(mid 71.701208 -254.150544)
		(end 71.773034 -254.18034)
		(stroke
			(width 0.0508)
			(type default)
		)
		(layer "F.Cu")
	)
	(gr_line
		(start 71.773034 -254.18034)
		(end 71.898002 -254.18034)
		(stroke
			(width 0.0508)
			(type default)
		)
		(layer "F.Cu")
	)
	(gr_arc
		(start 71.999602 -254.28194)
		(mid 71.969844 -254.210098)
		(end 71.898002 -254.18034)
		(stroke
			(width 0.0508)
			(type default)
		)
		(layer "F.Cu")
	)
	(gr_line
		(start 71.999602 -254.28194)
		(end 71.999602 -256.25044)
		(stroke
			(width 0.0508)
			(type default)
		)
		(layer "F.Cu")
	)
	(gr_line
		(start 72.064626 -54.971442)
		(end 72.064626 -55.540402)
		(stroke
			(width 0.0508)
			(type default)
		)
		(layer "F.Cu")
	)
	(gr_arc
		(start 72.407526 -54.626002)
		(mid 72.43809 -54.759952)
		(end 72.526906 -54.864762)
		(stroke
			(width 0.0508)
			(type default)
		)
		(layer "F.Cu")
	)
	(gr_arc
		(start 72.526906 -55.647082)
		(mid 72.437993 -55.751856)
		(end 72.407526 -55.885842)
		(stroke
			(width 0.0508)
			(type default)
		)
		(layer "F.Cu")
	)
	(gr_arc
		(start 72.526906 -55.647082)
		(mid 72.6157 -55.542268)
		(end 72.646286 -55.408322)
		(stroke
			(width 0.0508)
			(type default)
		)
		(layer "F.Cu")
	)
	(gr_arc
		(start 72.646286 -55.103522)
		(mid 72.615794 -54.969529)
		(end 72.526906 -54.864762)
		(stroke
			(width 0.0508)
			(type default)
		)
		(layer "F.Cu")
	)
	(gr_line
		(start 72.646286 -55.103522)
		(end 72.646286 -55.408322)
		(stroke
			(width 0.0508)
			(type default)
		)
		(layer "F.Cu")
	)
	(gr_line
		(start 74.111866 -58.133742)
		(end 74.111866 -58.702702)
		(stroke
			(width 0.0508)
			(type default)
		)
		(layer "F.Cu")
	)
	(gr_line
		(start 74.111866 -56.569102)
		(end 74.111866 -57.138062)
		(stroke
			(width 0.0508)
			(type default)
		)
		(layer "F.Cu")
	)
	(gr_arc
		(start 74.454766 -57.788302)
		(mid 74.485332 -57.922248)
		(end 74.574146 -58.027062)
		(stroke
			(width 0.0508)
			(type default)
		)
		(layer "F.Cu")
	)
	(gr_arc
		(start 74.454766 -57.467754)
		(mid 74.45466 -57.475628)
		(end 74.454766 -57.483502)
		(stroke
			(width 0.0508)
			(type default)
		)
		(layer "F.Cu")
	)
	(gr_arc
		(start 74.454766 -56.223662)
		(mid 74.485355 -56.35759)
		(end 74.574146 -56.462422)
		(stroke
			(width 0.0508)
			(type default)
		)
		(layer "F.Cu")
	)
	(gr_arc
		(start 74.574146 -58.809382)
		(mid 74.485251 -58.914161)
		(end 74.454766 -59.048142)
		(stroke
			(width 0.0508)
			(type default)
		)
		(layer "F.Cu")
	)
	(gr_arc
		(start 74.574146 -58.809382)
		(mid 74.66294 -58.704568)
		(end 74.693526 -58.570622)
		(stroke
			(width 0.0508)
			(type default)
		)
		(layer "F.Cu")
	)
	(gr_arc
		(start 74.574146 -57.244742)
		(mid 74.488809 -57.342521)
		(end 74.454766 -57.467754)
		(stroke
			(width 0.0508)
			(type default)
		)
		(layer "F.Cu")
	)
	(gr_arc
		(start 74.574146 -57.244742)
		(mid 74.66294 -57.139928)
		(end 74.693526 -57.005982)
		(stroke
			(width 0.0508)
			(type default)
		)
		(layer "F.Cu")
	)
	(gr_arc
		(start 74.693526 -58.265822)
		(mid 74.663034 -58.131829)
		(end 74.574146 -58.027062)
		(stroke
			(width 0.0508)
			(type default)
		)
		(layer "F.Cu")
	)
	(gr_line
		(start 74.693526 -58.265822)
		(end 74.693526 -58.570622)
		(stroke
			(width 0.0508)
			(type default)
		)
		(layer "F.Cu")
	)
	(gr_arc
		(start 74.693526 -56.701182)
		(mid 74.663034 -56.567189)
		(end 74.574146 -56.462422)
		(stroke
			(width 0.0508)
			(type default)
		)
		(layer "F.Cu")
	)
	(gr_line
		(start 74.693526 -56.701182)
		(end 74.693526 -57.005982)
		(stroke
			(width 0.0508)
			(type default)
		)
		(layer "F.Cu")
	)
	(gr_line
		(start 74.999342 -254.689356)
		(end 74.999342 -256.25044)
		(stroke
			(width 0.0508)
			(type default)
		)
		(layer "F.Cu")
	)
	(gr_arc
		(start 75.180444 -254.252222)
		(mid 75.046394 -254.452769)
		(end 74.999342 -254.689356)
		(stroke
			(width 0.0508)
			(type default)
		)
		(layer "F.Cu")
	)
	(gr_arc
		(start 75.180444 -254.252222)
		(mid 75.319977 -254.043258)
		(end 75.368912 -253.7968)
		(stroke
			(width 0.0508)
			(type default)
		)
		(layer "F.Cu")
	)
	(gr_arc
		(start 75.711812 -253.897638)
		(mid 75.749336 -254.086093)
		(end 75.856084 -254.245872)
		(stroke
			(width 0.0508)
			(type default)
		)
		(layer "F.Cu")
	)
	(gr_arc
		(start 76.000102 -254.593598)
		(mid 75.96267 -254.405416)
		(end 75.856084 -254.245872)
		(stroke
			(width 0.0508)
			(type default)
		)
		(layer "F.Cu")
	)
	(gr_line
		(start 76.000102 -254.593598)
		(end 76.000102 -256.25044)
		(stroke
			(width 0.0508)
			(type default)
		)
		(layer "F.Cu")
	)
	(gr_line
		(start 77.890878 -52.088542)
		(end 78.29296 -51.68646)
		(stroke
			(width 0.0508)
			(type default)
		)
		(layer "F.Cu")
	)
	(gr_arc
		(start 78.142338 -52.491132)
		(mid 78.005437 -52.502411)
		(end 77.8891 -52.57546)
		(stroke
			(width 0.0508)
			(type default)
		)
		(layer "F.Cu")
	)
	(gr_arc
		(start 78.142338 -52.491132)
		(mid 78.279263 -52.479902)
		(end 78.395576 -52.406804)
		(stroke
			(width 0.0508)
			(type default)
		)
		(layer "F.Cu")
	)
	(gr_line
		(start 78.395576 -52.406804)
		(end 78.610968 -52.191158)
		(stroke
			(width 0.0508)
			(type default)
		)
		(layer "F.Cu")
	)
	(gr_line
		(start 78.45171 -43.85564)
		(end 78.853792 -43.453558)
		(stroke
			(width 0.0508)
			(type default)
		)
		(layer "F.Cu")
	)
	(gr_arc
		(start 78.610968 -52.191158)
		(mid 78.684191 -52.07487)
		(end 78.69555 -51.93792)
		(stroke
			(width 0.0508)
			(type default)
		)
		(layer "F.Cu")
	)
	(gr_arc
		(start 78.70317 -44.25823)
		(mid 78.566261 -44.269496)
		(end 78.449932 -44.342558)
		(stroke
			(width 0.0508)
			(type default)
		)
		(layer "F.Cu")
	)
	(gr_arc
		(start 78.70317 -44.25823)
		(mid 78.840095 -44.247)
		(end 78.956408 -44.173902)
		(stroke
			(width 0.0508)
			(type default)
		)
		(layer "F.Cu")
	)
	(gr_arc
		(start 78.779878 -51.684682)
		(mid 78.706802 -51.801002)
		(end 78.69555 -51.93792)
		(stroke
			(width 0.0508)
			(type default)
		)
		(layer "F.Cu")
	)
	(gr_line
		(start 78.956408 -44.173902)
		(end 79.1718 -43.958256)
		(stroke
			(width 0.0508)
			(type default)
		)
		(layer "F.Cu")
	)
	(gr_line
		(start 78.976982 -189.329568)
		(end 79.379318 -188.927232)
		(stroke
			(width 0.0508)
			(type default)
		)
		(layer "F.Cu")
	)
	(gr_line
		(start 78.997048 -50.982372)
		(end 79.399384 -50.580036)
		(stroke
			(width 0.0508)
			(type default)
		)
		(layer "F.Cu")
	)
	(gr_line
		(start 78.999842 -255.002538)
		(end 78.999842 -256.25044)
		(stroke
			(width 0.0508)
			(type default)
		)
		(layer "F.Cu")
	)
	(gr_arc
		(start 79.048102 -254.75946)
		(mid 79.011998 -254.878622)
		(end 78.999842 -255.002538)
		(stroke
			(width 0.0508)
			(type default)
		)
		(layer "F.Cu")
	)
	(gr_line
		(start 79.048102 -254.75946)
		(end 79.283052 -254.192786)
		(stroke
			(width 0.0508)
			(type default)
		)
		(layer "F.Cu")
	)
	(gr_arc
		(start 79.1718 -43.958256)
		(mid 79.245023 -43.841968)
		(end 79.256382 -43.705018)
		(stroke
			(width 0.0508)
			(type default)
		)
		(layer "F.Cu")
	)
	(gr_arc
		(start 79.228442 -189.731904)
		(mid 79.091487 -189.743256)
		(end 78.975204 -189.816486)
		(stroke
			(width 0.0508)
			(type default)
		)
		(layer "F.Cu")
	)
	(gr_arc
		(start 79.228442 -189.731904)
		(mid 79.365367 -189.720674)
		(end 79.48168 -189.647576)
		(stroke
			(width 0.0508)
			(type default)
		)
		(layer "F.Cu")
	)
	(gr_arc
		(start 79.248508 -51.384708)
		(mid 79.111562 -51.396074)
		(end 78.99527 -51.46929)
		(stroke
			(width 0.0508)
			(type default)
		)
		(layer "F.Cu")
	)
	(gr_arc
		(start 79.248508 -51.384708)
		(mid 79.385433 -51.373478)
		(end 79.501746 -51.30038)
		(stroke
			(width 0.0508)
			(type default)
		)
		(layer "F.Cu")
	)
	(gr_arc
		(start 79.283052 -254.192786)
		(mid 79.319132 -254.073749)
		(end 79.331312 -253.949962)
		(stroke
			(width 0.0508)
			(type default)
		)
		(layer "F.Cu")
	)
	(gr_line
		(start 79.331312 -252.382274)
		(end 79.331566 -252.382274)
		(stroke
			(width 0.0508)
			(type default)
		)
		(layer "F.Cu")
	)
	(gr_line
		(start 79.331566 -252.274832)
		(end 79.331566 -252.382274)
		(stroke
			(width 0.0508)
			(type default)
		)
		(layer "F.Cu")
	)
	(gr_arc
		(start 79.34071 -43.45178)
		(mid 79.267625 -43.568098)
		(end 79.256382 -43.705018)
		(stroke
			(width 0.0508)
			(type default)
		)
		(layer "F.Cu")
	)
	(gr_line
		(start 79.48168 -189.647576)
		(end 79.697326 -189.43193)
		(stroke
			(width 0.0508)
			(type default)
		)
		(layer "F.Cu")
	)
	(gr_line
		(start 79.501746 -51.30038)
		(end 79.717392 -51.084734)
		(stroke
			(width 0.0508)
			(type default)
		)
		(layer "F.Cu")
	)
	(gr_arc
		(start 79.674212 -253.892558)
		(mid 79.724813 -254.146717)
		(end 79.868776 -254.362204)
		(stroke
			(width 0.0508)
			(type default)
		)
		(layer "F.Cu")
	)
	(gr_line
		(start 79.674212 -252.603)
		(end 79.674212 -252.725174)
		(stroke
			(width 0.0508)
			(type default)
		)
		(layer "F.Cu")
	)
	(gr_line
		(start 79.674212 -252.603)
		(end 79.674466 -252.603)
		(stroke
			(width 0.0508)
			(type default)
		)
		(layer "F.Cu")
	)
	(gr_arc
		(start 79.697326 -189.43193)
		(mid 79.770386 -189.315605)
		(end 79.781654 -189.178692)
		(stroke
			(width 0.0508)
			(type default)
		)
		(layer "F.Cu")
	)
	(gr_arc
		(start 79.717392 -51.084734)
		(mid 79.790452 -50.968409)
		(end 79.80172 -50.831496)
		(stroke
			(width 0.0508)
			(type default)
		)
		(layer "F.Cu")
	)
	(gr_arc
		(start 79.866236 -188.925454)
		(mid 79.793015 -189.041744)
		(end 79.781654 -189.178692)
		(stroke
			(width 0.0508)
			(type default)
		)
		(layer "F.Cu")
	)
	(gr_arc
		(start 79.886302 -50.578258)
		(mid 79.813066 -50.694545)
		(end 79.80172 -50.831496)
		(stroke
			(width 0.0508)
			(type default)
		)
		(layer "F.Cu")
	)
	(gr_arc
		(start 79.999332 -254.677418)
		(mid 79.9654 -254.506829)
		(end 79.868776 -254.362204)
		(stroke
			(width 0.0508)
			(type default)
		)
		(layer "F.Cu")
	)
	(gr_line
		(start 79.999332 -254.677418)
		(end 79.999332 -256.25044)
		(stroke
			(width 0.0508)
			(type default)
		)
		(layer "F.Cu")
	)
	(gr_line
		(start 80.083406 -188.223144)
		(end 80.485488 -187.821062)
		(stroke
			(width 0.0508)
			(type default)
		)
		(layer "F.Cu")
	)
	(gr_line
		(start 80.103472 -49.875948)
		(end 80.505554 -49.473866)
		(stroke
			(width 0.0508)
			(type default)
		)
		(layer "F.Cu")
	)
	(gr_arc
		(start 80.334866 -188.625734)
		(mid 80.197959 -188.637001)
		(end 80.081628 -188.710062)
		(stroke
			(width 0.0508)
			(type default)
		)
		(layer "F.Cu")
	)
	(gr_arc
		(start 80.334866 -188.625734)
		(mid 80.471814 -188.61437)
		(end 80.588104 -188.541152)
		(stroke
			(width 0.0508)
			(type default)
		)
		(layer "F.Cu")
	)
	(gr_arc
		(start 80.354932 -50.278284)
		(mid 80.217979 -50.28964)
		(end 80.101694 -50.362866)
		(stroke
			(width 0.0508)
			(type default)
		)
		(layer "F.Cu")
	)
	(gr_arc
		(start 80.354932 -50.278284)
		(mid 80.491857 -50.267054)
		(end 80.60817 -50.193956)
		(stroke
			(width 0.0508)
			(type default)
		)
		(layer "F.Cu")
	)
	(gr_line
		(start 80.588104 -188.541152)
		(end 80.80375 -188.32576)
		(stroke
			(width 0.0508)
			(type default)
		)
		(layer "F.Cu")
	)
	(gr_line
		(start 80.60817 -50.193956)
		(end 80.823816 -49.978564)
		(stroke
			(width 0.0508)
			(type default)
		)
		(layer "F.Cu")
	)
	(gr_arc
		(start 80.80375 -188.32576)
		(mid 80.87681 -188.209435)
		(end 80.888078 -188.072522)
		(stroke
			(width 0.0508)
			(type default)
		)
		(layer "F.Cu")
	)
	(gr_arc
		(start 80.823816 -49.978564)
		(mid 80.896876 -49.862239)
		(end 80.908144 -49.725326)
		(stroke
			(width 0.0508)
			(type default)
		)
		(layer "F.Cu")
	)
	(gr_arc
		(start 80.972406 -187.819284)
		(mid 80.899323 -187.935603)
		(end 80.888078 -188.072522)
		(stroke
			(width 0.0508)
			(type default)
		)
		(layer "F.Cu")
	)
	(gr_arc
		(start 80.992472 -49.472088)
		(mid 80.9194 -49.588408)
		(end 80.908144 -49.725326)
		(stroke
			(width 0.0508)
			(type default)
		)
		(layer "F.Cu")
	)
	(gr_line
		(start 80.998822 -192.973198)
		(end 81.400904 -192.571116)
		(stroke
			(width 0.0508)
			(type default)
		)
		(layer "F.Cu")
	)
	(gr_line
		(start 81.18983 -187.11672)
		(end 81.591912 -186.714638)
		(stroke
			(width 0.0508)
			(type default)
		)
		(layer "F.Cu")
	)
	(gr_line
		(start 81.2292 -37.312092)
		(end 81.516474 -37.024818)
		(stroke
			(width 0.0508)
			(type default)
		)
		(layer "F.Cu")
	)
	(gr_line
		(start 81.2292 -36.335208)
		(end 81.516474 -36.622482)
		(stroke
			(width 0.0508)
			(type default)
		)
		(layer "F.Cu")
	)
	(gr_arc
		(start 81.250282 -193.375788)
		(mid 81.113373 -193.38705)
		(end 80.997044 -193.460116)
		(stroke
			(width 0.0508)
			(type default)
		)
		(layer "F.Cu")
	)
	(gr_arc
		(start 81.250282 -193.375788)
		(mid 81.38723 -193.364424)
		(end 81.50352 -193.291206)
		(stroke
			(width 0.0508)
			(type default)
		)
		(layer "F.Cu")
	)
	(gr_arc
		(start 81.44129 -187.51931)
		(mid 81.304375 -187.530567)
		(end 81.188052 -187.603638)
		(stroke
			(width 0.0508)
			(type default)
		)
		(layer "F.Cu")
	)
	(gr_arc
		(start 81.44129 -187.51931)
		(mid 81.578238 -187.507946)
		(end 81.694528 -187.434728)
		(stroke
			(width 0.0508)
			(type default)
		)
		(layer "F.Cu")
	)
	(gr_line
		(start 81.50352 -193.291206)
		(end 81.719166 -193.075814)
		(stroke
			(width 0.0508)
			(type default)
		)
		(layer "F.Cu")
	)
	(gr_arc
		(start 81.516474 -36.622482)
		(mid 81.549463 -36.644479)
		(end 81.588356 -36.6522)
		(stroke
			(width 0.0508)
			(type default)
		)
		(layer "F.Cu")
	)
	(gr_arc
		(start 81.588356 -36.9951)
		(mid 81.549461 -37.002819)
		(end 81.516474 -37.024818)
		(stroke
			(width 0.0508)
			(type default)
		)
		(layer "F.Cu")
	)
	(gr_line
		(start 81.694528 -187.434728)
		(end 81.90992 -187.219336)
		(stroke
			(width 0.0508)
			(type default)
		)
		(layer "F.Cu")
	)
	(gr_arc
		(start 81.719166 -193.075814)
		(mid 81.792226 -192.959489)
		(end 81.803494 -192.822576)
		(stroke
			(width 0.0508)
			(type default)
		)
		(layer "F.Cu")
	)
	(gr_line
		(start 81.852262 -189.258702)
		(end 82.254344 -188.85662)
		(stroke
			(width 0.0508)
			(type default)
		)
		(layer "F.Cu")
	)
	(gr_arc
		(start 81.887822 -192.569338)
		(mid 81.814716 -192.685655)
		(end 81.803494 -192.822576)
		(stroke
			(width 0.0508)
			(type default)
		)
		(layer "F.Cu")
	)
	(gr_arc
		(start 81.90992 -187.219336)
		(mid 81.983143 -187.103048)
		(end 81.994502 -186.966098)
		(stroke
			(width 0.0508)
			(type default)
		)
		(layer "F.Cu")
	)
	(gr_line
		(start 82.067908 -36.569396)
		(end 82.077052 -36.560252)
		(stroke
			(width 0.0508)
			(type default)
		)
		(layer "F.Cu")
	)
	(gr_arc
		(start 82.07883 -186.71286)
		(mid 82.005731 -186.829177)
		(end 81.994502 -186.966098)
		(stroke
			(width 0.0508)
			(type default)
		)
		(layer "F.Cu")
	)
	(gr_arc
		(start 82.084926 -36.9951)
		(mid 82.123701 -36.987374)
		(end 82.156554 -36.965382)
		(stroke
			(width 0.0508)
			(type default)
		)
		(layer "F.Cu")
	)
	(gr_arc
		(start 82.103722 -189.661292)
		(mid 81.966828 -189.672579)
		(end 81.850484 -189.74562)
		(stroke
			(width 0.0508)
			(type default)
		)
		(layer "F.Cu")
	)
	(gr_arc
		(start 82.103722 -189.661292)
		(mid 82.240647 -189.650062)
		(end 82.35696 -189.576964)
		(stroke
			(width 0.0508)
			(type default)
		)
		(layer "F.Cu")
	)
	(gr_line
		(start 82.105246 -191.866774)
		(end 82.507328 -191.464692)
		(stroke
			(width 0.0508)
			(type default)
		)
		(layer "F.Cu")
	)
	(gr_line
		(start 82.156554 -36.965382)
		(end 82.197448 -36.924488)
		(stroke
			(width 0.0508)
			(type default)
		)
		(layer "F.Cu")
	)
	(gr_arc
		(start 82.299302 -36.46805)
		(mid 82.178981 -36.492001)
		(end 82.077052 -36.560252)
		(stroke
			(width 0.0508)
			(type default)
		)
		(layer "F.Cu")
	)
	(gr_arc
		(start 82.353404 -36.81095)
		(mid 82.31466 -36.818732)
		(end 82.281776 -36.840668)
		(stroke
			(width 0.0508)
			(type default)
		)
		(layer "F.Cu")
	)
	(gr_arc
		(start 82.356706 -192.269364)
		(mid 82.21979 -192.280616)
		(end 82.103468 -192.353692)
		(stroke
			(width 0.0508)
			(type default)
		)
		(layer "F.Cu")
	)
	(gr_arc
		(start 82.356706 -192.269364)
		(mid 82.493654 -192.258)
		(end 82.609944 -192.184782)
		(stroke
			(width 0.0508)
			(type default)
		)
		(layer "F.Cu")
	)
	(gr_line
		(start 82.35696 -189.576964)
		(end 82.572352 -189.361318)
		(stroke
			(width 0.0508)
			(type default)
		)
		(layer "F.Cu")
	)
	(gr_line
		(start 82.428842 -183.034178)
		(end 82.830924 -182.632096)
		(stroke
			(width 0.0508)
			(type default)
		)
		(layer "F.Cu")
	)
	(gr_arc
		(start 82.572352 -189.361318)
		(mid 82.645575 -189.24503)
		(end 82.656934 -189.10808)
		(stroke
			(width 0.0508)
			(type default)
		)
		(layer "F.Cu")
	)
	(gr_line
		(start 82.609944 -192.184782)
		(end 82.825336 -191.96939)
		(stroke
			(width 0.0508)
			(type default)
		)
		(layer "F.Cu")
	)
	(gr_arc
		(start 82.680302 -183.436768)
		(mid 82.543387 -183.448021)
		(end 82.427064 -183.521096)
		(stroke
			(width 0.0508)
			(type default)
		)
		(layer "F.Cu")
	)
	(gr_arc
		(start 82.680302 -183.436768)
		(mid 82.817227 -183.425538)
		(end 82.93354 -183.35244)
		(stroke
			(width 0.0508)
			(type default)
		)
		(layer "F.Cu")
	)
	(gr_arc
		(start 82.741262 -188.854842)
		(mid 82.668173 -188.971162)
		(end 82.656934 -189.10808)
		(stroke
			(width 0.0508)
			(type default)
		)
		(layer "F.Cu")
	)
	(gr_arc
		(start 82.825336 -191.96939)
		(mid 82.898559 -191.853102)
		(end 82.909918 -191.716152)
		(stroke
			(width 0.0508)
			(type default)
		)
		(layer "F.Cu")
	)
	(gr_line
		(start 82.93354 -183.35244)
		(end 83.148932 -183.136794)
		(stroke
			(width 0.0508)
			(type default)
		)
		(layer "F.Cu")
	)
	(gr_line
		(start 82.958686 -188.152278)
		(end 83.360768 -187.750196)
		(stroke
			(width 0.0508)
			(type default)
		)
		(layer "F.Cu")
	)
	(gr_arc
		(start 82.994246 -191.462914)
		(mid 82.921124 -191.579229)
		(end 82.909918 -191.716152)
		(stroke
			(width 0.0508)
			(type default)
		)
		(layer "F.Cu")
	)
	(gr_line
		(start 83.000342 -254.28194)
		(end 83.000342 -256.25044)
		(stroke
			(width 0.0508)
			(type default)
		)
		(layer "F.Cu")
	)
	(gr_line
		(start 83.0834 -35.453574)
		(end 83.0834 -35.523678)
		(stroke
			(width 0.0508)
			(type default)
		)
		(layer "F.Cu")
	)
	(gr_arc
		(start 83.0834 -34.618676)
		(mid 83.303203 -34.765481)
		(end 83.562444 -34.81705)
		(stroke
			(width 0.0508)
			(type default)
		)
		(layer "F.Cu")
	)
	(gr_arc
		(start 83.101942 -254.18034)
		(mid 83.030087 -254.210086)
		(end 83.000342 -254.28194)
		(stroke
			(width 0.0508)
			(type default)
		)
		(layer "F.Cu")
	)
	(gr_line
		(start 83.101942 -254.18034)
		(end 83.227164 -254.18034)
		(stroke
			(width 0.0508)
			(type default)
		)
		(layer "F.Cu")
	)
	(gr_arc
		(start 83.148932 -183.136794)
		(mid 83.222155 -183.020506)
		(end 83.233514 -182.883556)
		(stroke
			(width 0.0508)
			(type default)
		)
		(layer "F.Cu")
	)
	(gr_arc
		(start 83.208876 -35.265614)
		(mid 83.117614 -35.340545)
		(end 83.0834 -35.453574)
		(stroke
			(width 0.0508)
			(type default)
		)
		(layer "F.Cu")
	)
	(gr_line
		(start 83.208876 -35.265614)
		(end 83.427062 -35.175444)
		(stroke
			(width 0.0508)
			(type default)
		)
		(layer "F.Cu")
	)
	(gr_arc
		(start 83.210146 -188.554868)
		(mid 83.073245 -188.566145)
		(end 82.956908 -188.639196)
		(stroke
			(width 0.0508)
			(type default)
		)
		(layer "F.Cu")
	)
	(gr_arc
		(start 83.210146 -188.554868)
		(mid 83.347071 -188.543638)
		(end 83.463384 -188.47054)
		(stroke
			(width 0.0508)
			(type default)
		)
		(layer "F.Cu")
	)
	(gr_line
		(start 83.21167 -190.76035)
		(end 83.613752 -190.358268)
		(stroke
			(width 0.0508)
			(type default)
		)
		(layer "F.Cu")
	)
	(gr_arc
		(start 83.227164 -254.18034)
		(mid 83.299006 -254.150582)
		(end 83.328764 -254.07874)
		(stroke
			(width 0.0508)
			(type default)
		)
		(layer "F.Cu")
	)
	(gr_arc
		(start 83.317842 -182.630318)
		(mid 83.244723 -182.746633)
		(end 83.233514 -182.883556)
		(stroke
			(width 0.0508)
			(type default)
		)
		(layer "F.Cu")
	)
	(gr_arc
		(start 83.46313 -191.16294)
		(mid 83.326232 -191.174223)
		(end 83.209892 -191.247268)
		(stroke
			(width 0.0508)
			(type default)
		)
		(layer "F.Cu")
	)
	(gr_arc
		(start 83.46313 -191.16294)
		(mid 83.600055 -191.15171)
		(end 83.716368 -191.078612)
		(stroke
			(width 0.0508)
			(type default)
		)
		(layer "F.Cu")
	)
	(gr_line
		(start 83.463384 -188.47054)
		(end 83.678776 -188.254894)
		(stroke
			(width 0.0508)
			(type default)
		)
		(layer "F.Cu")
	)
	(gr_arc
		(start 83.504786 -35.15995)
		(mid 83.465156 -35.163852)
		(end 83.427062 -35.175444)
		(stroke
			(width 0.0508)
			(type default)
		)
		(layer "F.Cu")
	)
	(gr_line
		(start 83.535266 -181.927754)
		(end 83.937348 -181.525672)
		(stroke
			(width 0.0508)
			(type default)
		)
		(layer "F.Cu")
	)
	(gr_arc
		(start 83.590892 -40.25138)
		(mid 83.486114 -40.162485)
		(end 83.352132 -40.132)
		(stroke
			(width 0.0508)
			(type default)
		)
		(layer "F.Cu")
	)
	(gr_arc
		(start 83.590892 -40.25138)
		(mid 83.695706 -40.340174)
		(end 83.829652 -40.37076)
		(stroke
			(width 0.0508)
			(type default)
		)
		(layer "F.Cu")
	)
	(gr_arc
		(start 83.671664 -254.07874)
		(mid 83.701434 -254.150569)
		(end 83.773264 -254.18034)
		(stroke
			(width 0.0508)
			(type default)
		)
		(layer "F.Cu")
	)
	(gr_arc
		(start 83.678776 -188.254894)
		(mid 83.751836 -188.138569)
		(end 83.763104 -188.001656)
		(stroke
			(width 0.0508)
			(type default)
		)
		(layer "F.Cu")
	)
	(gr_line
		(start 83.697572 -39.7891)
		(end 84.266532 -39.7891)
		(stroke
			(width 0.0508)
			(type default)
		)
		(layer "F.Cu")
	)
	(gr_line
		(start 83.716368 -191.078612)
		(end 83.93176 -190.862966)
		(stroke
			(width 0.0508)
			(type default)
		)
		(layer "F.Cu")
	)
	(gr_line
		(start 83.773264 -254.18034)
		(end 83.898232 -254.18034)
		(stroke
			(width 0.0508)
			(type default)
		)
		(layer "F.Cu")
	)
	(gr_arc
		(start 83.786726 -182.330344)
		(mid 83.649829 -182.341628)
		(end 83.533488 -182.414672)
		(stroke
			(width 0.0508)
			(type default)
		)
		(layer "F.Cu")
	)
	(gr_arc
		(start 83.786726 -182.330344)
		(mid 83.923651 -182.319114)
		(end 84.039964 -182.246016)
		(stroke
			(width 0.0508)
			(type default)
		)
		(layer "F.Cu")
	)
	(gr_line
		(start 83.829652 -40.37076)
		(end 84.134452 -40.37076)
		(stroke
			(width 0.0508)
			(type default)
		)
		(layer "F.Cu")
	)
	(gr_arc
		(start 83.847686 -187.748418)
		(mid 83.774479 -187.864707)
		(end 83.763104 -188.001656)
		(stroke
			(width 0.0508)
			(type default)
		)
		(layer "F.Cu")
	)
	(gr_arc
		(start 83.93176 -190.862966)
		(mid 84.004983 -190.746678)
		(end 84.016342 -190.609728)
		(stroke
			(width 0.0508)
			(type default)
		)
		(layer "F.Cu")
	)
	(gr_arc
		(start 83.999832 -254.28194)
		(mid 83.970074 -254.210098)
		(end 83.898232 -254.18034)
		(stroke
			(width 0.0508)
			(type default)
		)
		(layer "F.Cu")
	)
	(gr_line
		(start 83.999832 -254.28194)
		(end 83.999832 -256.25044)
		(stroke
			(width 0.0508)
			(type default)
		)
		(layer "F.Cu")
	)
	(gr_line
		(start 84.039964 -182.246016)
		(end 84.255356 -182.03037)
		(stroke
			(width 0.0508)
			(type default)
		)
		(layer "F.Cu")
	)
	(gr_line
		(start 84.055966 -37.7444)
		(end 84.246466 -37.9349)
		(stroke
			(width 0.0508)
			(type default)
		)
		(layer "F.Cu")
	)
	(gr_line
		(start 84.064856 -187.046108)
		(end 84.467192 -186.643772)
		(stroke
			(width 0.0508)
			(type default)
		)
		(layer "F.Cu")
	)
	(gr_line
		(start 84.08416 -38.760654)
		(end 84.272628 -38.571932)
		(stroke
			(width 0.0508)
			(type default)
		)
		(layer "F.Cu")
	)
	(gr_arc
		(start 84.10067 -190.35649)
		(mid 84.027599 -190.47281)
		(end 84.016342 -190.609728)
		(stroke
			(width 0.0508)
			(type default)
		)
		(layer "F.Cu")
	)
	(gr_line
		(start 84.129626 -41.3639)
		(end 85.077046 -41.3639)
		(stroke
			(width 0.0508)
			(type default)
		)
		(layer "F.Cu")
	)
	(gr_arc
		(start 84.134452 -40.37076)
		(mid 84.268445 -40.340268)
		(end 84.373212 -40.25138)
		(stroke
			(width 0.0508)
			(type default)
		)
		(layer "F.Cu")
	)
	(gr_arc
		(start 84.246466 -37.9349)
		(mid 84.450397 -38.071188)
		(end 84.690966 -38.11905)
		(stroke
			(width 0.0508)
			(type default)
		)
		(layer "F.Cu")
	)
	(gr_arc
		(start 84.255356 -182.03037)
		(mid 84.328416 -181.914045)
		(end 84.339684 -181.777132)
		(stroke
			(width 0.0508)
			(type default)
		)
		(layer "F.Cu")
	)
	(gr_arc
		(start 84.316316 -187.448444)
		(mid 84.179369 -187.459808)
		(end 84.063078 -187.533026)
		(stroke
			(width 0.0508)
			(type default)
		)
		(layer "F.Cu")
	)
	(gr_arc
		(start 84.316316 -187.448444)
		(mid 84.453241 -187.437214)
		(end 84.569554 -187.364116)
		(stroke
			(width 0.0508)
			(type default)
		)
		(layer "F.Cu")
	)
	(gr_line
		(start 84.389468 -41.814496)
		(end 84.401406 -41.82618)
		(stroke
			(width 0.0508)
			(type default)
		)
		(layer "F.Cu")
	)
	(gr_arc
		(start 84.401406 -41.82618)
		(mid 84.50622 -41.914974)
		(end 84.640166 -41.94556)
		(stroke
			(width 0.0508)
			(type default)
		)
		(layer "F.Cu")
	)
	(gr_arc
		(start 84.424266 -181.523894)
		(mid 84.351054 -181.640183)
		(end 84.339684 -181.777132)
		(stroke
			(width 0.0508)
			(type default)
		)
		(layer "F.Cu")
	)
	(gr_arc
		(start 84.538566 -38.46195)
		(mid 84.394654 -38.490482)
		(end 84.272628 -38.571932)
		(stroke
			(width 0.0508)
			(type default)
		)
		(layer "F.Cu")
	)
	(gr_line
		(start 84.569554 -187.364116)
		(end 84.7852 -187.148724)
		(stroke
			(width 0.0508)
			(type default)
		)
		(layer "F.Cu")
	)
	(gr_arc
		(start 84.611972 -40.132)
		(mid 84.478037 -40.162578)
		(end 84.373212 -40.25138)
		(stroke
			(width 0.0508)
			(type default)
		)
		(layer "F.Cu")
	)
	(gr_line
		(start 84.640166 -41.94556)
		(end 84.944966 -41.94556)
		(stroke
			(width 0.0508)
			(type default)
		)
		(layer "F.Cu")
	)
	(gr_arc
		(start 84.7852 -187.148724)
		(mid 84.8583 -187.03228)
		(end 84.869528 -186.895232)
		(stroke
			(width 0.0508)
			(type default)
		)
		(layer "F.Cu")
	)
	(gr_arc
		(start 84.944966 -41.94556)
		(mid 85.078959 -41.915068)
		(end 85.183726 -41.82618)
		(stroke
			(width 0.0508)
			(type default)
		)
		(layer "F.Cu")
	)
	(gr_arc
		(start 84.95411 -186.641994)
		(mid 84.880912 -186.758286)
		(end 84.869528 -186.895232)
		(stroke
			(width 0.0508)
			(type default)
		)
		(layer "F.Cu")
	)
	(gr_line
		(start 84.987384 -191.838072)
		(end 85.38972 -191.435736)
		(stroke
			(width 0.0508)
			(type default)
		)
		(layer "F.Cu")
	)
	(gr_line
		(start 84.9884 -33.789874)
		(end 85.23986 -33.538414)
		(stroke
			(width 0.0508)
			(type default)
		)
		(layer "F.Cu")
	)
	(gr_line
		(start 84.9884 -32.884872)
		(end 85.239606 -33.136078)
		(stroke
			(width 0.0508)
			(type default)
		)
		(layer "F.Cu")
	)
	(gr_arc
		(start 85.238844 -192.240408)
		(mid 85.101889 -192.251759)
		(end 84.985606 -192.32499)
		(stroke
			(width 0.0508)
			(type default)
		)
		(layer "F.Cu")
	)
	(gr_arc
		(start 85.238844 -192.240408)
		(mid 85.375769 -192.229178)
		(end 85.492082 -192.15608)
		(stroke
			(width 0.0508)
			(type default)
		)
		(layer "F.Cu")
	)
	(gr_arc
		(start 85.239606 -33.136078)
		(mid 85.27259 -33.158098)
		(end 85.311488 -33.165796)
		(stroke
			(width 0.0508)
			(type default)
		)
		(layer "F.Cu")
	)
	(gr_arc
		(start 85.311742 -33.508696)
		(mid 85.272847 -33.516415)
		(end 85.23986 -33.538414)
		(stroke
			(width 0.0508)
			(type default)
		)
		(layer "F.Cu")
	)
	(gr_line
		(start 85.32114 -33.508696)
		(end 85.521546 -33.508696)
		(stroke
			(width 0.0508)
			(type default)
		)
		(layer "F.Cu")
	)
	(gr_arc
		(start 85.422486 -41.7068)
		(mid 85.288546 -41.737373)
		(end 85.183726 -41.82618)
		(stroke
			(width 0.0508)
			(type default)
		)
		(layer "F.Cu")
	)
	(gr_line
		(start 85.492082 -192.15608)
		(end 85.707728 -191.940434)
		(stroke
			(width 0.0508)
			(type default)
		)
		(layer "F.Cu")
	)
	(gr_arc
		(start 85.65261 -34.81705)
		(mid 85.738812 -34.799882)
		(end 85.811868 -34.75101)
		(stroke
			(width 0.0508)
			(type default)
		)
		(layer "F.Cu")
	)
	(gr_line
		(start 85.66404 -33.16605)
		(end 85.703664 -33.16605)
		(stroke
			(width 0.0508)
			(type default)
		)
		(layer "F.Cu")
	)
	(gr_arc
		(start 85.703664 -36.46805)
		(mid 85.742551 -36.460316)
		(end 85.775546 -36.438332)
		(stroke
			(width 0.0508)
			(type default)
		)
		(layer "F.Cu")
	)
	(gr_arc
		(start 85.703664 -33.16605)
		(mid 85.742551 -33.158316)
		(end 85.775546 -33.136332)
		(stroke
			(width 0.0508)
			(type default)
		)
		(layer "F.Cu")
	)
	(gr_arc
		(start 85.707728 -191.940434)
		(mid 85.780788 -191.824109)
		(end 85.792056 -191.687196)
		(stroke
			(width 0.0508)
			(type default)
		)
		(layer "F.Cu")
	)
	(gr_arc
		(start 85.775546 -36.840668)
		(mid 85.742552 -36.818685)
		(end 85.703664 -36.81095)
		(stroke
			(width 0.0508)
			(type default)
		)
		(layer "F.Cu")
	)
	(gr_line
		(start 85.775546 -36.840668)
		(end 85.86216 -36.927282)
		(stroke
			(width 0.0508)
			(type default)
		)
		(layer "F.Cu")
	)
	(gr_line
		(start 85.775546 -36.438332)
		(end 85.86216 -36.351718)
		(stroke
			(width 0.0508)
			(type default)
		)
		(layer "F.Cu")
	)
	(gr_arc
		(start 85.775546 -33.538668)
		(mid 85.742552 -33.516685)
		(end 85.703664 -33.50895)
		(stroke
			(width 0.0508)
			(type default)
		)
		(layer "F.Cu")
	)
	(gr_line
		(start 85.775546 -33.538668)
		(end 85.86216 -33.625282)
		(stroke
			(width 0.0508)
			(type default)
		)
		(layer "F.Cu")
	)
	(gr_line
		(start 85.775546 -33.136332)
		(end 85.86216 -33.049718)
		(stroke
			(width 0.0508)
			(type default)
		)
		(layer "F.Cu")
	)
	(gr_arc
		(start 85.811868 -35.22599)
		(mid 85.738814 -35.177114)
		(end 85.65261 -35.15995)
		(stroke
			(width 0.0508)
			(type default)
		)
		(layer "F.Cu")
	)
	(gr_line
		(start 85.811868 -35.22599)
		(end 85.825838 -35.23996)
		(stroke
			(width 0.0508)
			(type default)
		)
		(layer "F.Cu")
	)
	(gr_line
		(start 85.811868 -34.75101)
		(end 85.825838 -34.73704)
		(stroke
			(width 0.0508)
			(type default)
		)
		(layer "F.Cu")
	)
	(gr_arc
		(start 85.819234 -39.7891)
		(mid 86.034924 -39.746197)
		(end 86.21776 -39.624)
		(stroke
			(width 0.0508)
			(type default)
		)
		(layer "F.Cu")
	)
	(gr_arc
		(start 85.825838 -35.23996)
		(mid 85.898895 -35.288826)
		(end 85.985096 -35.306)
		(stroke
			(width 0.0508)
			(type default)
		)
		(layer "F.Cu")
	)
	(gr_arc
		(start 85.849714 -43.0784)
		(mid 86.04888 -43.038783)
		(end 86.21776 -42.926)
		(stroke
			(width 0.0508)
			(type default)
		)
		(layer "F.Cu")
	)
	(gr_arc
		(start 85.86216 -36.927282)
		(mid 85.895148 -36.949284)
		(end 85.934042 -36.957)
		(stroke
			(width 0.0508)
			(type default)
		)
		(layer "F.Cu")
	)
	(gr_arc
		(start 85.86216 -33.625282)
		(mid 85.895148 -33.647284)
		(end 85.934042 -33.655)
		(stroke
			(width 0.0508)
			(type default)
		)
		(layer "F.Cu")
	)
	(gr_arc
		(start 85.865208 -38.11905)
		(mid 86.056 -38.08107)
		(end 86.21776 -37.973)
		(stroke
			(width 0.0508)
			(type default)
		)
		(layer "F.Cu")
	)
	(gr_arc
		(start 85.876638 -191.433958)
		(mid 85.803418 -191.550248)
		(end 85.792056 -191.687196)
		(stroke
			(width 0.0508)
			(type default)
		)
		(layer "F.Cu")
	)
	(gr_arc
		(start 85.911182 -44.704)
		(mid 86.077105 -44.670996)
		(end 86.21776 -44.577)
		(stroke
			(width 0.0508)
			(type default)
		)
		(layer "F.Cu")
	)
	(gr_line
		(start 85.934042 -36.957)
		(end 86.21776 -36.957)
		(stroke
			(width 0.0508)
			(type default)
		)
		(layer "F.Cu")
	)
	(gr_arc
		(start 85.934042 -36.322)
		(mid 85.895147 -36.329719)
		(end 85.86216 -36.351718)
		(stroke
			(width 0.0508)
			(type default)
		)
		(layer "F.Cu")
	)
	(gr_line
		(start 85.934042 -36.322)
		(end 86.21776 -36.322)
		(stroke
			(width 0.0508)
			(type default)
		)
		(layer "F.Cu")
	)
	(gr_line
		(start 85.934042 -33.655)
		(end 86.21776 -33.655)
		(stroke
			(width 0.0508)
			(type default)
		)
		(layer "F.Cu")
	)
	(gr_arc
		(start 85.934042 -33.02)
		(mid 85.895147 -33.027719)
		(end 85.86216 -33.049718)
		(stroke
			(width 0.0508)
			(type default)
		)
		(layer "F.Cu")
	)
	(gr_line
		(start 85.934042 -33.02)
		(end 86.21776 -33.02)
		(stroke
			(width 0.0508)
			(type default)
		)
		(layer "F.Cu")
	)
	(gr_line
		(start 85.985096 -35.306)
		(end 86.21776 -35.306)
		(stroke
			(width 0.0508)
			(type default)
		)
		(layer "F.Cu")
	)
	(gr_arc
		(start 85.985096 -34.671)
		(mid 85.898892 -34.688165)
		(end 85.825838 -34.73704)
		(stroke
			(width 0.0508)
			(type default)
		)
		(layer "F.Cu")
	)
	(gr_line
		(start 85.985096 -34.671)
		(end 86.21776 -34.671)
		(stroke
			(width 0.0508)
			(type default)
		)
		(layer "F.Cu")
	)
	(gr_arc
		(start 86.00313 -41.3639)
		(mid 86.119286 -41.340795)
		(end 86.21776 -41.275)
		(stroke
			(width 0.0508)
			(type default)
		)
		(layer "F.Cu")
	)
	(gr_line
		(start 86.093808 -190.731648)
		(end 86.49589 -190.329566)
		(stroke
			(width 0.0508)
			(type default)
		)
		(layer "F.Cu")
	)
	(gr_arc
		(start 86.21776 -43.561)
		(mid 86.062998 -43.457596)
		(end 85.880448 -43.4213)
		(stroke
			(width 0.0508)
			(type default)
		)
		(layer "F.Cu")
	)
	(gr_arc
		(start 86.21776 -41.91)
		(mid 85.992743 -41.759585)
		(end 85.727286 -41.7068)
		(stroke
			(width 0.0508)
			(type default)
		)
		(layer "F.Cu")
	)
	(gr_arc
		(start 86.21776 -40.259)
		(mid 86.077104 -40.165004)
		(end 85.911182 -40.132)
		(stroke
			(width 0.0508)
			(type default)
		)
		(layer "F.Cu")
	)
	(gr_arc
		(start 86.21776 -38.608)
		(mid 86.056008 -38.499921)
		(end 85.865208 -38.46195)
		(stroke
			(width 0.0508)
			(type default)
		)
		(layer "F.Cu")
	)
	(gr_arc
		(start 86.345268 -191.133984)
		(mid 86.208306 -191.145325)
		(end 86.09203 -191.218566)
		(stroke
			(width 0.0508)
			(type default)
		)
		(layer "F.Cu")
	)
	(gr_arc
		(start 86.345268 -191.133984)
		(mid 86.482193 -191.122754)
		(end 86.598506 -191.049656)
		(stroke
			(width 0.0508)
			(type default)
		)
		(layer "F.Cu")
	)
	(gr_line
		(start 86.598506 -191.049656)
		(end 86.814152 -190.834264)
		(stroke
			(width 0.0508)
			(type default)
		)
		(layer "F.Cu")
	)
	(gr_line
		(start 86.614 -28.64866)
		(end 87.14867 -29.18333)
		(stroke
			(width 0.06985)
			(type default)
		)
		(layer "F.Cu")
	)
	(gr_line
		(start 86.614 -27.63266)
		(end 86.614 -28.64866)
		(stroke
			(width 0.06985)
			(type default)
		)
		(layer "F.Cu")
	)
	(gr_arc
		(start 86.614 -26.74366)
		(mid 86.801971 -26.462342)
		(end 86.868 -26.130504)
		(stroke
			(width 0.06985)
			(type default)
		)
		(layer "F.Cu")
	)
	(gr_line
		(start 86.77656 -45.212)
		(end 86.796118 -45.192442)
		(stroke
			(width 0.0508)
			(type default)
		)
		(layer "F.Cu")
	)
	(gr_arc
		(start 86.77656 -44.577)
		(mid 86.945421 -44.689829)
		(end 87.144606 -44.7294)
		(stroke
			(width 0.0508)
			(type default)
		)
		(layer "F.Cu")
	)
	(gr_line
		(start 86.77656 -43.561)
		(end 86.994746 -43.342814)
		(stroke
			(width 0.0508)
			(type default)
		)
		(layer "F.Cu")
	)
	(gr_arc
		(start 86.77656 -42.926)
		(mid 86.804645 -42.944766)
		(end 86.837774 -42.9514)
		(stroke
			(width 0.0508)
			(type default)
		)
		(layer "F.Cu")
	)
	(gr_arc
		(start 86.77656 -41.275)
		(mid 86.804645 -41.293766)
		(end 86.837774 -41.3004)
		(stroke
			(width 0.0508)
			(type default)
		)
		(layer "F.Cu")
	)
	(gr_line
		(start 86.77656 -40.259)
		(end 86.842092 -40.193468)
		(stroke
			(width 0.0508)
			(type default)
		)
		(layer "F.Cu")
	)
	(gr_arc
		(start 86.77656 -39.624)
		(mid 86.804645 -39.642766)
		(end 86.837774 -39.6494)
		(stroke
			(width 0.0508)
			(type default)
		)
		(layer "F.Cu")
	)
	(gr_line
		(start 86.77656 -38.608)
		(end 86.856062 -38.528498)
		(stroke
			(width 0.0508)
			(type default)
		)
		(layer "F.Cu")
	)
	(gr_arc
		(start 86.77656 -37.973)
		(mid 86.875033 -38.038798)
		(end 86.99119 -38.0619)
		(stroke
			(width 0.0508)
			(type default)
		)
		(layer "F.Cu")
	)
	(gr_arc
		(start 86.77656 -36.322)
		(mid 86.945421 -36.434829)
		(end 87.144606 -36.4744)
		(stroke
			(width 0.0508)
			(type default)
		)
		(layer "F.Cu")
	)
	(gr_line
		(start 86.77656 -34.671)
		(end 87.11946 -34.671)
		(stroke
			(width 0.0508)
			(type default)
		)
		(layer "F.Cu")
	)
	(gr_line
		(start 86.77656 -33.02)
		(end 86.847172 -33.090612)
		(stroke
			(width 0.0508)
			(type default)
		)
		(layer "F.Cu")
	)
	(gr_arc
		(start 86.814152 -190.834264)
		(mid 86.887212 -190.717939)
		(end 86.89848 -190.581026)
		(stroke
			(width 0.0508)
			(type default)
		)
		(layer "F.Cu")
	)
	(gr_line
		(start 86.837774 -41.3004)
		(end 87.07501 -41.3004)
		(stroke
			(width 0.0508)
			(type default)
		)
		(layer "F.Cu")
	)
	(gr_line
		(start 86.837774 -39.6494)
		(end 86.982046 -39.6494)
		(stroke
			(width 0.0508)
			(type default)
		)
		(layer "F.Cu")
	)
	(gr_arc
		(start 86.847172 -33.090612)
		(mid 86.891885 -33.123727)
		(end 86.9442 -33.142682)
		(stroke
			(width 0.0508)
			(type default)
		)
		(layer "F.Cu")
	)
	(gr_line
		(start 86.868 -25.908)
		(end 86.868 -26.130504)
		(stroke
			(width 0.06985)
			(type default)
		)
		(layer "F.Cu")
	)
	(gr_line
		(start 86.9442 -33.142682)
		(end 86.944454 -33.142936)
		(stroke
			(width 0.0508)
			(type default)
		)
		(layer "F.Cu")
	)
	(gr_arc
		(start 86.944454 -33.142936)
		(mid 86.946231 -33.143198)
		(end 86.94801 -33.143444)
		(stroke
			(width 0.0508)
			(type default)
		)
		(layer "F.Cu")
	)
	(gr_arc
		(start 86.94801 -33.143444)
		(mid 86.965207 -33.145882)
		(end 86.982554 -33.146746)
		(stroke
			(width 0.0508)
			(type default)
		)
		(layer "F.Cu")
	)
	(gr_arc
		(start 86.982554 -33.146746)
		(mid 86.982935 -33.146873)
		(end 86.983316 -33.147)
		(stroke
			(width 0.0508)
			(type default)
		)
		(layer "F.Cu")
	)
	(gr_arc
		(start 86.982808 -190.327788)
		(mid 86.909727 -190.444107)
		(end 86.89848 -190.581026)
		(stroke
			(width 0.0508)
			(type default)
		)
		(layer "F.Cu")
	)
	(gr_line
		(start 86.999572 -254.28194)
		(end 86.999572 -256.25044)
		(stroke
			(width 0.0508)
			(type default)
		)
		(layer "F.Cu")
	)
	(gr_arc
		(start 87.086186 -45.0723)
		(mid 86.929209 -45.103531)
		(end 86.796118 -45.192442)
		(stroke
			(width 0.0508)
			(type default)
		)
		(layer "F.Cu")
	)
	(gr_arc
		(start 87.101172 -254.18034)
		(mid 87.029362 -254.21011)
		(end 86.999572 -254.28194)
		(stroke
			(width 0.0508)
			(type default)
		)
		(layer "F.Cu")
	)
	(gr_line
		(start 87.101172 -254.18034)
		(end 87.226902 -254.18034)
		(stroke
			(width 0.0508)
			(type default)
		)
		(layer "F.Cu")
	)
	(gr_arc
		(start 87.11184 -43.2943)
		(mid 87.048472 -43.30692)
		(end 86.994746 -43.342814)
		(stroke
			(width 0.0508)
			(type default)
		)
		(layer "F.Cu")
	)
	(gr_arc
		(start 87.113872 -36.8173)
		(mid 86.931318 -36.853593)
		(end 86.77656 -36.957)
		(stroke
			(width 0.0508)
			(type default)
		)
		(layer "F.Cu")
	)
	(gr_arc
		(start 87.154766 -38.4048)
		(mid 86.993117 -38.436944)
		(end 86.856062 -38.528498)
		(stroke
			(width 0.0508)
			(type default)
		)
		(layer "F.Cu")
	)
	(gr_arc
		(start 87.175086 -33.4899)
		(mid 86.95941 -33.53283)
		(end 86.77656 -33.655)
		(stroke
			(width 0.0508)
			(type default)
		)
		(layer "F.Cu")
	)
	(gr_arc
		(start 87.183214 -35.137598)
		(mid 86.96314 -35.181349)
		(end 86.77656 -35.306)
		(stroke
			(width 0.0508)
			(type default)
		)
		(layer "F.Cu")
	)
	(gr_line
		(start 87.183214 -35.137598)
		(end 87.326978 -35.137598)
		(stroke
			(width 0.0508)
			(type default)
		)
		(layer "F.Cu")
	)
	(gr_arc
		(start 87.226902 -254.18034)
		(mid 87.298744 -254.150582)
		(end 87.328502 -254.07874)
		(stroke
			(width 0.0508)
			(type default)
		)
		(layer "F.Cu")
	)
	(gr_arc
		(start 87.2871 -29.517594)
		(mid 87.251138 -29.336693)
		(end 87.14867 -29.18333)
		(stroke
			(width 0.06985)
			(type default)
		)
		(layer "F.Cu")
	)
	(gr_line
		(start 87.326978 -35.137598)
		(end 87.366602 -35.147504)
		(stroke
			(width 0.0508)
			(type default)
		)
		(layer "F.Cu")
	)
	(gr_arc
		(start 87.327486 -39.9923)
		(mid 87.064773 -40.044587)
		(end 86.842092 -40.193468)
		(stroke
			(width 0.0508)
			(type default)
		)
		(layer "F.Cu")
	)
	(gr_arc
		(start 87.400384 -35.170872)
		(mid 87.398747 -35.169333)
		(end 87.397082 -35.167824)
		(stroke
			(width 0.0508)
			(type default)
		)
		(layer "F.Cu")
	)
	(gr_arc
		(start 87.42045 -41.6433)
		(mid 87.071977 -41.712604)
		(end 86.77656 -41.91)
		(stroke
			(width 0.0508)
			(type default)
		)
		(layer "F.Cu")
	)
	(gr_arc
		(start 87.441786 -34.766504)
		(mid 87.287538 -34.695405)
		(end 87.11946 -34.671)
		(stroke
			(width 0.0508)
			(type default)
		)
		(layer "F.Cu")
	)
	(gr_arc
		(start 87.538306 -34.844482)
		(mid 87.492095 -34.802957)
		(end 87.441786 -34.766504)
		(stroke
			(width 0.0508)
			(type default)
		)
		(layer "F.Cu")
	)
	(gr_line
		(start 87.538306 -34.844482)
		(end 87.540592 -34.846006)
		(stroke
			(width 0.0508)
			(type default)
		)
		(layer "F.Cu")
	)
	(gr_line
		(start 87.540592 -34.846006)
		(end 87.542116 -34.847276)
		(stroke
			(width 0.0508)
			(type default)
		)
		(layer "F.Cu")
	)
	(gr_line
		(start 87.542116 -34.847276)
		(end 87.546688 -34.850832)
		(stroke
			(width 0.0508)
			(type default)
		)
		(layer "F.Cu")
	)
	(gr_arc
		(start 87.630762 -34.915856)
		(mid 87.624361 -34.909906)
		(end 87.617554 -34.904426)
		(stroke
			(width 0.0508)
			(type default)
		)
		(layer "F.Cu")
	)
	(gr_arc
		(start 87.671402 -254.07874)
		(mid 87.701174 -254.150555)
		(end 87.773002 -254.18034)
		(stroke
			(width 0.0508)
			(type default)
		)
		(layer "F.Cu")
	)
	(gr_arc
		(start 87.719154 -29.039566)
		(mid 87.653196 -29.138141)
		(end 87.63 -29.25445)
		(stroke
			(width 0.06985)
			(type default)
		)
		(layer "F.Cu")
	)
	(gr_line
		(start 87.719154 -29.039566)
		(end 88.138 -28.620466)
		(stroke
			(width 0.06985)
			(type default)
		)
		(layer "F.Cu")
	)
	(gr_line
		(start 87.773002 -254.18034)
		(end 87.898732 -254.18034)
		(stroke
			(width 0.0508)
			(type default)
		)
		(layer "F.Cu")
	)
	(gr_arc
		(start 87.884 -26.10231)
		(mid 87.950036 -26.434141)
		(end 88.138 -26.715466)
		(stroke
			(width 0.06985)
			(type default)
		)
		(layer "F.Cu")
	)
	(gr_line
		(start 87.884 -25.908)
		(end 87.884 -26.10231)
		(stroke
			(width 0.06985)
			(type default)
		)
		(layer "F.Cu")
	)
	(gr_arc
		(start 88.000332 -254.28194)
		(mid 87.970574 -254.210098)
		(end 87.898732 -254.18034)
		(stroke
			(width 0.0508)
			(type default)
		)
		(layer "F.Cu")
	)
	(gr_line
		(start 88.000332 -254.28194)
		(end 88.000332 -256.25044)
		(stroke
			(width 0.0508)
			(type default)
		)
		(layer "F.Cu")
	)
	(gr_line
		(start 88.138 -27.604466)
		(end 88.138 -28.620466)
		(stroke
			(width 0.06985)
			(type default)
		)
		(layer "F.Cu")
	)
	(gr_line
		(start 89.46134 -178.84521)
		(end 89.863676 -178.442874)
		(stroke
			(width 0.0508)
			(type default)
		)
		(layer "F.Cu")
	)
	(gr_arc
		(start 89.7128 -179.247546)
		(mid 89.575857 -179.258917)
		(end 89.459562 -179.332128)
		(stroke
			(width 0.0508)
			(type default)
		)
		(layer "F.Cu")
	)
	(gr_arc
		(start 89.7128 -179.247546)
		(mid 89.849725 -179.236316)
		(end 89.966038 -179.163218)
		(stroke
			(width 0.0508)
			(type default)
		)
		(layer "F.Cu")
	)
	(gr_line
		(start 89.966038 -179.163218)
		(end 90.181684 -178.947572)
		(stroke
			(width 0.0508)
			(type default)
		)
		(layer "F.Cu")
	)
	(gr_arc
		(start 90.181684 -178.947572)
		(mid 90.254744 -178.831247)
		(end 90.266012 -178.694334)
		(stroke
			(width 0.0508)
			(type default)
		)
		(layer "F.Cu")
	)
	(gr_line
		(start 90.197178 -175.265842)
		(end 90.59926 -174.86376)
		(stroke
			(width 0.0508)
			(type default)
		)
		(layer "F.Cu")
	)
	(gr_arc
		(start 90.350594 -178.441096)
		(mid 90.277376 -178.557384)
		(end 90.266012 -178.694334)
		(stroke
			(width 0.0508)
			(type default)
		)
		(layer "F.Cu")
	)
	(gr_arc
		(start 90.448638 -175.668432)
		(mid 90.311737 -175.679711)
		(end 90.1954 -175.75276)
		(stroke
			(width 0.0508)
			(type default)
		)
		(layer "F.Cu")
	)
	(gr_arc
		(start 90.448638 -175.668432)
		(mid 90.585586 -175.657068)
		(end 90.701876 -175.58385)
		(stroke
			(width 0.0508)
			(type default)
		)
		(layer "F.Cu")
	)
	(gr_line
		(start 90.567764 -177.738786)
		(end 90.969846 -177.336704)
		(stroke
			(width 0.0508)
			(type default)
		)
		(layer "F.Cu")
	)
	(gr_line
		(start 90.576908 -186.248548)
		(end 90.97899 -185.846466)
		(stroke
			(width 0.0508)
			(type default)
		)
		(layer "F.Cu")
	)
	(gr_line
		(start 90.592656 -40.254428)
		(end 90.602816 -40.244268)
		(stroke
			(width 0.0508)
			(type default)
		)
		(layer "F.Cu")
	)
	(gr_line
		(start 90.602816 -40.244268)
		(end 90.897456 -40.244268)
		(stroke
			(width 0.0508)
			(type default)
		)
		(layer "F.Cu")
	)
	(gr_arc
		(start 90.695018 -42.968164)
		(mid 90.679528 -42.965123)
		(end 90.663776 -42.9641)
		(stroke
			(width 0.0508)
			(type default)
		)
		(layer "F.Cu")
	)
	(gr_line
		(start 90.701876 -175.58385)
		(end 90.917268 -175.368458)
		(stroke
			(width 0.0508)
			(type default)
		)
		(layer "F.Cu")
	)
	(gr_line
		(start 90.714576 -34.96437)
		(end 90.750136 -34.99993)
		(stroke
			(width 0.0508)
			(type default)
		)
		(layer "F.Cu")
	)
	(gr_arc
		(start 90.721434 -42.978578)
		(mid 90.708531 -42.972599)
		(end 90.695018 -42.968164)
		(stroke
			(width 0.0508)
			(type default)
		)
		(layer "F.Cu")
	)
	(gr_arc
		(start 90.724736 -35.433)
		(mid 90.724743 -35.432365)
		(end 90.724736 -35.43173)
		(stroke
			(width 0.0508)
			(type default)
		)
		(layer "F.Cu")
	)
	(gr_line
		(start 90.727276 -42.176954)
		(end 90.750136 -42.199814)
		(stroke
			(width 0.0508)
			(type default)
		)
		(layer "F.Cu")
	)
	(gr_line
		(start 90.727276 -37.377116)
		(end 90.750136 -37.399976)
		(stroke
			(width 0.0508)
			(type default)
		)
		(layer "F.Cu")
	)
	(gr_arc
		(start 90.750136 -42.999914)
		(mid 90.736576 -42.988183)
		(end 90.721434 -42.978578)
		(stroke
			(width 0.0508)
			(type default)
		)
		(layer "F.Cu")
	)
	(gr_arc
		(start 90.750136 -38.199822)
		(mid 90.722054 -38.181041)
		(end 90.688922 -38.174422)
		(stroke
			(width 0.0508)
			(type default)
		)
		(layer "F.Cu")
	)
	(gr_arc
		(start 90.750136 -35.80003)
		(mid 90.722055 -35.781248)
		(end 90.688922 -35.77463)
		(stroke
			(width 0.0508)
			(type default)
		)
		(layer "F.Cu")
	)
	(gr_arc
		(start 90.819224 -178.141376)
		(mid 90.682329 -178.152662)
		(end 90.565986 -178.225704)
		(stroke
			(width 0.0508)
			(type default)
		)
		(layer "F.Cu")
	)
	(gr_arc
		(start 90.819224 -178.141376)
		(mid 90.956172 -178.130012)
		(end 91.072462 -178.056794)
		(stroke
			(width 0.0508)
			(type default)
		)
		(layer "F.Cu")
	)
	(gr_arc
		(start 90.828368 -186.651138)
		(mid 90.69146 -186.662405)
		(end 90.57513 -186.735466)
		(stroke
			(width 0.0508)
			(type default)
		)
		(layer "F.Cu")
	)
	(gr_arc
		(start 90.828368 -186.651138)
		(mid 90.965293 -186.639908)
		(end 91.081606 -186.56681)
		(stroke
			(width 0.0508)
			(type default)
		)
		(layer "F.Cu")
	)
	(gr_arc
		(start 90.887296 -37.851842)
		(mid 90.864807 -37.836809)
		(end 90.838274 -37.831522)
		(stroke
			(width 0.0508)
			(type default)
		)
		(layer "F.Cu")
	)
	(gr_line
		(start 90.887296 -37.851842)
		(end 90.907616 -37.872162)
		(stroke
			(width 0.0508)
			(type default)
		)
		(layer "F.Cu")
	)
	(gr_line
		(start 90.897456 -40.244268)
		(end 90.910156 -40.256968)
		(stroke
			(width 0.0508)
			(type default)
		)
		(layer "F.Cu")
	)
	(gr_arc
		(start 90.917268 -175.368458)
		(mid 90.990491 -175.25217)
		(end 91.00185 -175.11522)
		(stroke
			(width 0.0508)
			(type default)
		)
		(layer "F.Cu")
	)
	(gr_line
		(start 90.935048 -188.653928)
		(end 91.33713 -188.251846)
		(stroke
			(width 0.0508)
			(type default)
		)
		(layer "F.Cu")
	)
	(gr_arc
		(start 90.994992 -40.26027)
		(mid 90.961632 -40.257786)
		(end 90.92819 -40.256968)
		(stroke
			(width 0.0508)
			(type default)
		)
		(layer "F.Cu")
	)
	(gr_line
		(start 91.009216 -42.6212)
		(end 91.167966 -42.6212)
		(stroke
			(width 0.0508)
			(type default)
		)
		(layer "F.Cu")
	)
	(gr_arc
		(start 91.028012 -37.956744)
		(mid 90.97149 -37.909219)
		(end 90.907616 -37.872162)
		(stroke
			(width 0.0508)
			(type default)
		)
		(layer "F.Cu")
	)
	(gr_line
		(start 91.028012 -37.956744)
		(end 91.17965 -38.108382)
		(stroke
			(width 0.0508)
			(type default)
		)
		(layer "F.Cu")
	)
	(gr_arc
		(start 91.028012 -37.156898)
		(mid 90.889446 -37.064298)
		(end 90.726006 -37.031676)
		(stroke
			(width 0.0508)
			(type default)
		)
		(layer "F.Cu")
	)
	(gr_line
		(start 91.028012 -37.156898)
		(end 91.17965 -37.308536)
		(stroke
			(width 0.0508)
			(type default)
		)
		(layer "F.Cu")
	)
	(gr_arc
		(start 91.028012 -35.556952)
		(mid 90.889449 -35.464341)
		(end 90.726006 -35.43173)
		(stroke
			(width 0.0508)
			(type default)
		)
		(layer "F.Cu")
	)
	(gr_line
		(start 91.028012 -35.556952)
		(end 91.17965 -35.70859)
		(stroke
			(width 0.0508)
			(type default)
		)
		(layer "F.Cu")
	)
	(gr_line
		(start 91.072462 -178.056794)
		(end 91.288108 -177.841402)
		(stroke
			(width 0.0508)
			(type default)
		)
		(layer "F.Cu")
	)
	(gr_arc
		(start 91.075002 -34.767774)
		(mid 90.910091 -34.65764)
		(end 90.715592 -34.61893)
		(stroke
			(width 0.0508)
			(type default)
		)
		(layer "F.Cu")
	)
	(gr_line
		(start 91.075002 -34.767774)
		(end 91.228418 -34.92119)
		(stroke
			(width 0.0508)
			(type default)
		)
		(layer "F.Cu")
	)
	(gr_arc
		(start 91.079066 -39.5351)
		(mid 90.992716 -39.477392)
		(end 90.890852 -39.457122)
		(stroke
			(width 0.0508)
			(type default)
		)
		(layer "F.Cu")
	)
	(gr_line
		(start 91.079066 -39.5351)
		(end 91.282266 -39.7383)
		(stroke
			(width 0.0508)
			(type default)
		)
		(layer "F.Cu")
	)
	(gr_line
		(start 91.081606 -186.56681)
		(end 91.296998 -186.351164)
		(stroke
			(width 0.0508)
			(type default)
		)
		(layer "F.Cu")
	)
	(gr_arc
		(start 91.086178 -174.861982)
		(mid 91.013102 -174.978302)
		(end 91.00185 -175.11522)
		(stroke
			(width 0.0508)
			(type default)
		)
		(layer "F.Cu")
	)
	(gr_arc
		(start 91.17965 -38.108382)
		(mid 91.28092 -38.176048)
		(end 91.400376 -38.199822)
		(stroke
			(width 0.0508)
			(type default)
		)
		(layer "F.Cu")
	)
	(gr_arc
		(start 91.17965 -37.308536)
		(mid 91.28092 -37.376202)
		(end 91.400376 -37.399976)
		(stroke
			(width 0.0508)
			(type default)
		)
		(layer "F.Cu")
	)
	(gr_arc
		(start 91.17965 -35.70859)
		(mid 91.28092 -35.776256)
		(end 91.400376 -35.80003)
		(stroke
			(width 0.0508)
			(type default)
		)
		(layer "F.Cu")
	)
	(gr_arc
		(start 91.186508 -189.056518)
		(mid 91.049589 -189.067768)
		(end 90.93327 -189.140846)
		(stroke
			(width 0.0508)
			(type default)
		)
		(layer "F.Cu")
	)
	(gr_arc
		(start 91.186508 -189.056518)
		(mid 91.323456 -189.045154)
		(end 91.439746 -188.971936)
		(stroke
			(width 0.0508)
			(type default)
		)
		(layer "F.Cu")
	)
	(gr_arc
		(start 91.228418 -34.92119)
		(mid 91.315573 -34.979488)
		(end 91.41841 -34.99993)
		(stroke
			(width 0.0508)
			(type default)
		)
		(layer "F.Cu")
	)
	(gr_arc
		(start 91.282266 -39.7383)
		(mid 91.350673 -39.784008)
		(end 91.431364 -39.800022)
		(stroke
			(width 0.0508)
			(type default)
		)
		(layer "F.Cu")
	)
	(gr_arc
		(start 91.2876 -41.937686)
		(mid 91.17002 -41.859098)
		(end 91.031314 -41.831514)
		(stroke
			(width 0.0508)
			(type default)
		)
		(layer "F.Cu")
	)
	(gr_line
		(start 91.2876 -41.937686)
		(end 91.407488 -42.057574)
		(stroke
			(width 0.0508)
			(type default)
		)
		(layer "F.Cu")
	)
	(gr_arc
		(start 91.288108 -177.841402)
		(mid 91.361168 -177.725077)
		(end 91.372436 -177.588164)
		(stroke
			(width 0.0508)
			(type default)
		)
		(layer "F.Cu")
	)
	(gr_arc
		(start 91.296998 -186.351164)
		(mid 91.370221 -186.234876)
		(end 91.38158 -186.097926)
		(stroke
			(width 0.0508)
			(type default)
		)
		(layer "F.Cu")
	)
	(gr_line
		(start 91.303602 -174.159418)
		(end 91.705684 -173.757336)
		(stroke
			(width 0.0508)
			(type default)
		)
		(layer "F.Cu")
	)
	(gr_line
		(start 91.348814 -179.76215)
		(end 91.750896 -179.360068)
		(stroke
			(width 0.0508)
			(type default)
		)
		(layer "F.Cu")
	)
	(gr_line
		(start 91.400376 -38.199822)
		(end 91.549982 -38.199822)
		(stroke
			(width 0.0508)
			(type default)
		)
		(layer "F.Cu")
	)
	(gr_line
		(start 91.400376 -37.399976)
		(end 91.549982 -37.399976)
		(stroke
			(width 0.0508)
			(type default)
		)
		(layer "F.Cu")
	)
	(gr_line
		(start 91.400376 -35.80003)
		(end 91.549982 -35.80003)
		(stroke
			(width 0.0508)
			(type default)
		)
		(layer "F.Cu")
	)
	(gr_arc
		(start 91.40444 -40.454072)
		(mid 91.216505 -40.321702)
		(end 90.994992 -40.26027)
		(stroke
			(width 0.0508)
			(type default)
		)
		(layer "F.Cu")
	)
	(gr_line
		(start 91.40444 -40.454072)
		(end 91.549982 -40.599868)
		(stroke
			(width 0.0508)
			(type default)
		)
		(layer "F.Cu")
	)
	(gr_line
		(start 91.407488 -42.057574)
		(end 91.549982 -42.199814)
		(stroke
			(width 0.0508)
			(type default)
		)
		(layer "F.Cu")
	)
	(gr_line
		(start 91.41841 -34.99993)
		(end 91.549982 -34.99993)
		(stroke
			(width 0.0508)
			(type default)
		)
		(layer "F.Cu")
	)
	(gr_line
		(start 91.431364 -39.800022)
		(end 91.549982 -39.800022)
		(stroke
			(width 0.0508)
			(type default)
		)
		(layer "F.Cu")
	)
	(gr_arc
		(start 91.435682 -42.731944)
		(mid 91.312842 -42.649948)
		(end 91.167966 -42.6212)
		(stroke
			(width 0.0508)
			(type default)
		)
		(layer "F.Cu")
	)
	(gr_line
		(start 91.435682 -42.731944)
		(end 91.5162 -42.812716)
		(stroke
			(width 0.0508)
			(type default)
		)
		(layer "F.Cu")
	)
	(gr_line
		(start 91.439746 -188.971936)
		(end 91.655392 -188.756544)
		(stroke
			(width 0.0508)
			(type default)
		)
		(layer "F.Cu")
	)
	(gr_arc
		(start 91.456764 -177.334926)
		(mid 91.383668 -177.451245)
		(end 91.372436 -177.588164)
		(stroke
			(width 0.0508)
			(type default)
		)
		(layer "F.Cu")
	)
	(gr_arc
		(start 91.465908 -185.844688)
		(mid 91.392827 -185.961007)
		(end 91.38158 -186.097926)
		(stroke
			(width 0.0508)
			(type default)
		)
		(layer "F.Cu")
	)
	(gr_arc
		(start 91.549982 -42.981118)
		(mid 91.541427 -42.895245)
		(end 91.5162 -42.812716)
		(stroke
			(width 0.0508)
			(type default)
		)
		(layer "F.Cu")
	)
	(gr_line
		(start 91.549982 -42.981118)
		(end 91.549982 -42.999914)
		(stroke
			(width 0.0508)
			(type default)
		)
		(layer "F.Cu")
	)
	(gr_arc
		(start 91.555062 -174.562008)
		(mid 91.418154 -174.573276)
		(end 91.301824 -174.646336)
		(stroke
			(width 0.0508)
			(type default)
		)
		(layer "F.Cu")
	)
	(gr_arc
		(start 91.555062 -174.562008)
		(mid 91.691987 -174.550778)
		(end 91.8083 -174.47768)
		(stroke
			(width 0.0508)
			(type default)
		)
		(layer "F.Cu")
	)
	(gr_arc
		(start 91.600274 -180.16474)
		(mid 91.463365 -180.176004)
		(end 91.347036 -180.249068)
		(stroke
			(width 0.0508)
			(type default)
		)
		(layer "F.Cu")
	)
	(gr_arc
		(start 91.600274 -180.16474)
		(mid 91.737199 -180.15351)
		(end 91.853512 -180.080412)
		(stroke
			(width 0.0508)
			(type default)
		)
		(layer "F.Cu")
	)
	(gr_arc
		(start 91.655392 -188.756544)
		(mid 91.728452 -188.640219)
		(end 91.73972 -188.503306)
		(stroke
			(width 0.0508)
			(type default)
		)
		(layer "F.Cu")
	)
	(gr_line
		(start 91.674188 -176.632362)
		(end 92.07627 -176.23028)
		(stroke
			(width 0.0508)
			(type default)
		)
		(layer "F.Cu")
	)
	(gr_line
		(start 91.683078 -185.142378)
		(end 92.085414 -184.740042)
		(stroke
			(width 0.0508)
			(type default)
		)
		(layer "F.Cu")
	)
	(gr_line
		(start 91.8083 -174.47768)
		(end 92.023692 -174.262034)
		(stroke
			(width 0.0508)
			(type default)
		)
		(layer "F.Cu")
	)
	(gr_arc
		(start 91.824048 -188.250068)
		(mid 91.750948 -188.366384)
		(end 91.73972 -188.503306)
		(stroke
			(width 0.0508)
			(type default)
		)
		(layer "F.Cu")
	)
	(gr_line
		(start 91.853512 -180.080412)
		(end 92.068904 -179.864766)
		(stroke
			(width 0.0508)
			(type default)
		)
		(layer "F.Cu")
	)
	(gr_arc
		(start 91.925648 -177.034952)
		(mid 91.788746 -177.046227)
		(end 91.67241 -177.11928)
		(stroke
			(width 0.0508)
			(type default)
		)
		(layer "F.Cu")
	)
	(gr_arc
		(start 91.925648 -177.034952)
		(mid 92.062596 -177.023588)
		(end 92.178886 -176.95037)
		(stroke
			(width 0.0508)
			(type default)
		)
		(layer "F.Cu")
	)
	(gr_arc
		(start 91.934538 -185.544714)
		(mid 91.797584 -185.556068)
		(end 91.6813 -185.629296)
		(stroke
			(width 0.0508)
			(type default)
		)
		(layer "F.Cu")
	)
	(gr_arc
		(start 91.934538 -185.544714)
		(mid 92.071463 -185.533484)
		(end 92.187776 -185.460386)
		(stroke
			(width 0.0508)
			(type default)
		)
		(layer "F.Cu")
	)
	(gr_arc
		(start 92.023692 -174.262034)
		(mid 92.096915 -174.145746)
		(end 92.108274 -174.008796)
		(stroke
			(width 0.0508)
			(type default)
		)
		(layer "F.Cu")
	)
	(gr_line
		(start 92.041472 -187.547504)
		(end 92.443554 -187.145422)
		(stroke
			(width 0.0508)
			(type default)
		)
		(layer "F.Cu")
	)
	(gr_arc
		(start 92.068904 -179.864766)
		(mid 92.142127 -179.748478)
		(end 92.153486 -179.611528)
		(stroke
			(width 0.0508)
			(type default)
		)
		(layer "F.Cu")
	)
	(gr_line
		(start 92.178886 -176.95037)
		(end 92.394278 -176.734978)
		(stroke
			(width 0.0508)
			(type default)
		)
		(layer "F.Cu")
	)
	(gr_line
		(start 92.187776 -185.460386)
		(end 92.403422 -185.24474)
		(stroke
			(width 0.0508)
			(type default)
		)
		(layer "F.Cu")
	)
	(gr_arc
		(start 92.192602 -173.755558)
		(mid 92.11951 -173.871876)
		(end 92.108274 -174.008796)
		(stroke
			(width 0.0508)
			(type default)
		)
		(layer "F.Cu")
	)
	(gr_arc
		(start 92.237814 -179.35829)
		(mid 92.164732 -179.474608)
		(end 92.153486 -179.611528)
		(stroke
			(width 0.0508)
			(type default)
		)
		(layer "F.Cu")
	)
	(gr_arc
		(start 92.292932 -187.950094)
		(mid 92.156031 -187.961375)
		(end 92.039694 -188.034422)
		(stroke
			(width 0.0508)
			(type default)
		)
		(layer "F.Cu")
	)
	(gr_arc
		(start 92.292932 -187.950094)
		(mid 92.42988 -187.93873)
		(end 92.54617 -187.865512)
		(stroke
			(width 0.0508)
			(type default)
		)
		(layer "F.Cu")
	)
	(gr_arc
		(start 92.394278 -176.734978)
		(mid 92.467501 -176.61869)
		(end 92.47886 -176.48174)
		(stroke
			(width 0.0508)
			(type default)
		)
		(layer "F.Cu")
	)
	(gr_arc
		(start 92.403422 -185.24474)
		(mid 92.476482 -185.128415)
		(end 92.48775 -184.991502)
		(stroke
			(width 0.0508)
			(type default)
		)
		(layer "F.Cu")
	)
	(gr_line
		(start 92.455238 -178.655726)
		(end 92.85732 -178.253644)
		(stroke
			(width 0.0508)
			(type default)
		)
		(layer "F.Cu")
	)
	(gr_line
		(start 92.54617 -187.865512)
		(end 92.761562 -187.65012)
		(stroke
			(width 0.0508)
			(type default)
		)
		(layer "F.Cu")
	)
	(gr_arc
		(start 92.563188 -176.228502)
		(mid 92.490076 -176.344819)
		(end 92.47886 -176.48174)
		(stroke
			(width 0.0508)
			(type default)
		)
		(layer "F.Cu")
	)
	(gr_arc
		(start 92.572332 -184.738264)
		(mid 92.499116 -184.854554)
		(end 92.48775 -184.991502)
		(stroke
			(width 0.0508)
			(type default)
		)
		(layer "F.Cu")
	)
	(gr_arc
		(start 92.706698 -179.058316)
		(mid 92.569782 -179.06957)
		(end 92.45346 -179.142644)
		(stroke
			(width 0.0508)
			(type default)
		)
		(layer "F.Cu")
	)
	(gr_arc
		(start 92.706698 -179.058316)
		(mid 92.843623 -179.047086)
		(end 92.959936 -178.973988)
		(stroke
			(width 0.0508)
			(type default)
		)
		(layer "F.Cu")
	)
	(gr_line
		(start 92.74556 -39.3954)
		(end 92.837508 -39.3954)
		(stroke
			(width 0.0508)
			(type default)
		)
		(layer "F.Cu")
	)
	(gr_line
		(start 92.750132 -41.796716)
		(end 92.983304 -41.796716)
		(stroke
			(width 0.0508)
			(type default)
		)
		(layer "F.Cu")
	)
	(gr_arc
		(start 92.761562 -187.65012)
		(mid 92.834785 -187.533832)
		(end 92.846144 -187.396882)
		(stroke
			(width 0.0508)
			(type default)
		)
		(layer "F.Cu")
	)
	(gr_line
		(start 92.789502 -184.035954)
		(end 93.191584 -183.633872)
		(stroke
			(width 0.0508)
			(type default)
		)
		(layer "F.Cu")
	)
	(gr_line
		(start 92.862908 -181.109112)
		(end 93.26499 -180.70703)
		(stroke
			(width 0.0508)
			(type default)
		)
		(layer "F.Cu")
	)
	(gr_arc
		(start 92.930472 -187.143644)
		(mid 92.857381 -187.259963)
		(end 92.846144 -187.396882)
		(stroke
			(width 0.0508)
			(type default)
		)
		(layer "F.Cu")
	)
	(gr_line
		(start 92.959936 -178.973988)
		(end 93.175328 -178.758342)
		(stroke
			(width 0.0508)
			(type default)
		)
		(layer "F.Cu")
	)
	(gr_arc
		(start 92.981018 -39.454836)
		(mid 92.915173 -39.41085)
		(end 92.837508 -39.3954)
		(stroke
			(width 0.0508)
			(type default)
		)
		(layer "F.Cu")
	)
	(gr_line
		(start 92.981018 -39.454836)
		(end 93.090746 -39.564564)
		(stroke
			(width 0.0508)
			(type default)
		)
		(layer "F.Cu")
	)
	(gr_arc
		(start 93.040962 -184.438544)
		(mid 92.904056 -184.449813)
		(end 92.787724 -184.522872)
		(stroke
			(width 0.0508)
			(type default)
		)
		(layer "F.Cu")
	)
	(gr_arc
		(start 93.040962 -184.438544)
		(mid 93.17791 -184.42718)
		(end 93.2942 -184.353962)
		(stroke
			(width 0.0508)
			(type default)
		)
		(layer "F.Cu")
	)
	(gr_arc
		(start 93.072966 -41.8338)
		(mid 93.031815 -41.806367)
		(end 92.983304 -41.796716)
		(stroke
			(width 0.0508)
			(type default)
		)
		(layer "F.Cu")
	)
	(gr_line
		(start 93.072966 -41.8338)
		(end 93.113098 -41.873932)
		(stroke
			(width 0.0508)
			(type default)
		)
		(layer "F.Cu")
	)
	(gr_arc
		(start 93.114368 -181.511702)
		(mid 92.977459 -181.522968)
		(end 92.86113 -181.59603)
		(stroke
			(width 0.0508)
			(type default)
		)
		(layer "F.Cu")
	)
	(gr_arc
		(start 93.114368 -181.511702)
		(mid 93.251293 -181.500472)
		(end 93.367606 -181.427374)
		(stroke
			(width 0.0508)
			(type default)
		)
		(layer "F.Cu")
	)
	(gr_line
		(start 93.147896 -186.44108)
		(end 93.549978 -186.038998)
		(stroke
			(width 0.0508)
			(type default)
		)
		(layer "F.Cu")
	)
	(gr_line
		(start 93.150182 -42.999914)
		(end 93.15958 -42.999914)
		(stroke
			(width 0.0508)
			(type default)
		)
		(layer "F.Cu")
	)
	(gr_arc
		(start 93.150182 -41.963594)
		(mid 93.140549 -41.915076)
		(end 93.113098 -41.873932)
		(stroke
			(width 0.0508)
			(type default)
		)
		(layer "F.Cu")
	)
	(gr_line
		(start 93.150182 -41.963594)
		(end 93.150182 -42.199814)
		(stroke
			(width 0.0508)
			(type default)
		)
		(layer "F.Cu")
	)
	(gr_line
		(start 93.150182 -40.599868)
		(end 93.159072 -40.599868)
		(stroke
			(width 0.0508)
			(type default)
		)
		(layer "F.Cu")
	)
	(gr_arc
		(start 93.150182 -39.708074)
		(mid 93.134754 -39.630398)
		(end 93.090746 -39.564564)
		(stroke
			(width 0.0508)
			(type default)
		)
		(layer "F.Cu")
	)
	(gr_line
		(start 93.150182 -39.708074)
		(end 93.150182 -39.800022)
		(stroke
			(width 0.0508)
			(type default)
		)
		(layer "F.Cu")
	)
	(gr_line
		(start 93.150182 -38.199822)
		(end 93.168978 -38.199822)
		(stroke
			(width 0.0508)
			(type default)
		)
		(layer "F.Cu")
	)
	(gr_line
		(start 93.150182 -37.399976)
		(end 93.164406 -37.4142)
		(stroke
			(width 0.0508)
			(type default)
		)
		(layer "F.Cu")
	)
	(gr_line
		(start 93.150182 -35.80511)
		(end 93.541342 -36.19627)
		(stroke
			(width 0.0508)
			(type default)
		)
		(layer "F.Cu")
	)
	(gr_line
		(start 93.150182 -35.80003)
		(end 93.150182 -35.80511)
		(stroke
			(width 0.0508)
			(type default)
		)
		(layer "F.Cu")
	)
	(gr_line
		(start 93.150182 -34.99993)
		(end 93.153738 -34.99993)
		(stroke
			(width 0.0508)
			(type default)
		)
		(layer "F.Cu")
	)
	(gr_arc
		(start 93.150182 -33.399984)
		(mid 93.202054 -33.322376)
		(end 93.220286 -33.23082)
		(stroke
			(width 0.06985)
			(type default)
		)
		(layer "F.Cu")
	)
	(gr_line
		(start 93.153738 -34.99993)
		(end 93.547184 -34.606484)
		(stroke
			(width 0.0508)
			(type default)
		)
		(layer "F.Cu")
	)
	(gr_line
		(start 93.159072 -40.599868)
		(end 93.554804 -40.9956)
		(stroke
			(width 0.0508)
			(type default)
		)
		(layer "F.Cu")
	)
	(gr_line
		(start 93.15958 -42.999914)
		(end 93.550486 -43.39082)
		(stroke
			(width 0.0508)
			(type default)
		)
		(layer "F.Cu")
	)
	(gr_line
		(start 93.164406 -37.4142)
		(end 93.27769 -37.4142)
		(stroke
			(width 0.0508)
			(type default)
		)
		(layer "F.Cu")
	)
	(gr_line
		(start 93.168978 -38.199822)
		(end 93.52026 -38.551104)
		(stroke
			(width 0.0508)
			(type default)
		)
		(layer "F.Cu")
	)
	(gr_arc
		(start 93.175328 -178.758342)
		(mid 93.248388 -178.642017)
		(end 93.259656 -178.505104)
		(stroke
			(width 0.0508)
			(type default)
		)
		(layer "F.Cu")
	)
	(gr_line
		(start 93.220286 -33.049972)
		(end 93.220286 -33.23082)
		(stroke
			(width 0.06985)
			(type default)
		)
		(layer "F.Cu")
	)
	(gr_arc
		(start 93.27769 -37.4142)
		(mid 93.287525 -37.413219)
		(end 93.296994 -37.41039)
		(stroke
			(width 0.0508)
			(type default)
		)
		(layer "F.Cu")
	)
	(gr_line
		(start 93.2942 -184.353962)
		(end 93.509846 -184.13857)
		(stroke
			(width 0.0508)
			(type default)
		)
		(layer "F.Cu")
	)
	(gr_line
		(start 93.296994 -37.41039)
		(end 93.327982 -37.398198)
		(stroke
			(width 0.0508)
			(type default)
		)
		(layer "F.Cu")
	)
	(gr_arc
		(start 93.344238 -178.251866)
		(mid 93.271022 -178.368156)
		(end 93.259656 -178.505104)
		(stroke
			(width 0.0508)
			(type default)
		)
		(layer "F.Cu")
	)
	(gr_arc
		(start 93.363288 -37.391848)
		(mid 93.345352 -37.39345)
		(end 93.327982 -37.398198)
		(stroke
			(width 0.0508)
			(type default)
		)
		(layer "F.Cu")
	)
	(gr_line
		(start 93.363288 -37.391848)
		(end 93.378782 -37.391848)
		(stroke
			(width 0.0508)
			(type default)
		)
		(layer "F.Cu")
	)
	(gr_line
		(start 93.367606 -181.427374)
		(end 93.582998 -181.211728)
		(stroke
			(width 0.0508)
			(type default)
		)
		(layer "F.Cu")
	)
	(gr_line
		(start 93.378782 -37.391848)
		(end 93.526102 -37.244528)
		(stroke
			(width 0.0508)
			(type default)
		)
		(layer "F.Cu")
	)
	(gr_arc
		(start 93.399356 -186.84367)
		(mid 93.262453 -186.854943)
		(end 93.146118 -186.927998)
		(stroke
			(width 0.0508)
			(type default)
		)
		(layer "F.Cu")
	)
	(gr_arc
		(start 93.399356 -186.84367)
		(mid 93.536281 -186.83244)
		(end 93.652594 -186.759342)
		(stroke
			(width 0.0508)
			(type default)
		)
		(layer "F.Cu")
	)
	(gr_arc
		(start 93.509846 -184.13857)
		(mid 93.582906 -184.022245)
		(end 93.594174 -183.885332)
		(stroke
			(width 0.0508)
			(type default)
		)
		(layer "F.Cu")
	)
	(gr_line
		(start 93.52026 -38.561518)
		(end 93.555566 -38.596824)
		(stroke
			(width 0.0508)
			(type default)
		)
		(layer "F.Cu")
	)
	(gr_line
		(start 93.52026 -38.551104)
		(end 93.52026 -38.561518)
		(stroke
			(width 0.0508)
			(type default)
		)
		(layer "F.Cu")
	)
	(gr_arc
		(start 93.52788 -37.228526)
		(mid 93.526528 -37.236476)
		(end 93.526102 -37.244528)
		(stroke
			(width 0.0508)
			(type default)
		)
		(layer "F.Cu")
	)
	(gr_line
		(start 93.52788 -37.228526)
		(end 93.547946 -37.141912)
		(stroke
			(width 0.0508)
			(type default)
		)
		(layer "F.Cu")
	)
	(gr_line
		(start 93.540834 -40.200072)
		(end 93.574362 -40.2336)
		(stroke
			(width 0.0508)
			(type default)
		)
		(layer "F.Cu")
	)
	(gr_line
		(start 93.541342 -36.19627)
		(end 93.551756 -36.19627)
		(stroke
			(width 0.0508)
			(type default)
		)
		(layer "F.Cu")
	)
	(gr_arc
		(start 93.547946 -37.141912)
		(mid 93.550798 -37.125256)
		(end 93.551756 -37.108384)
		(stroke
			(width 0.0508)
			(type default)
		)
		(layer "F.Cu")
	)
	(gr_line
		(start 93.54947 -35.43427)
		(end 93.91523 -35.80003)
		(stroke
			(width 0.0508)
			(type default)
		)
		(layer "F.Cu")
	)
	(gr_line
		(start 93.54947 -35.407854)
		(end 93.54947 -35.43427)
		(stroke
			(width 0.0508)
			(type default)
		)
		(layer "F.Cu")
	)
	(gr_line
		(start 93.551756 -37.00272)
		(end 93.551756 -37.108384)
		(stroke
			(width 0.0508)
			(type default)
		)
		(layer "F.Cu")
	)
	(gr_line
		(start 93.55455 -41.80459)
		(end 93.949774 -42.199814)
		(stroke
			(width 0.0508)
			(type default)
		)
		(layer "F.Cu")
	)
	(gr_line
		(start 93.556582 -39.397178)
		(end 93.950028 -39.790624)
		(stroke
			(width 0.0508)
			(type default)
		)
		(layer "F.Cu")
	)
	(gr_line
		(start 93.556582 -37.802058)
		(end 93.55836 -37.803836)
		(stroke
			(width 0.0508)
			(type default)
		)
		(layer "F.Cu")
	)
	(gr_line
		(start 93.556836 -42.62247)
		(end 93.93428 -42.999914)
		(stroke
			(width 0.0508)
			(type default)
		)
		(layer "F.Cu")
	)
	(gr_line
		(start 93.556836 -42.597324)
		(end 93.556836 -42.62247)
		(stroke
			(width 0.0508)
			(type default)
		)
		(layer "F.Cu")
	)
	(gr_line
		(start 93.55836 -37.803836)
		(end 93.689424 -37.803836)
		(stroke
			(width 0.0508)
			(type default)
		)
		(layer "F.Cu")
	)
	(gr_line
		(start 93.561408 -177.549556)
		(end 93.963744 -177.14722)
		(stroke
			(width 0.0508)
			(type default)
		)
		(layer "F.Cu")
	)
	(gr_arc
		(start 93.563186 -32.704532)
		(mid 93.619894 -32.989624)
		(end 93.781372 -33.231328)
		(stroke
			(width 0.06985)
			(type default)
		)
		(layer "F.Cu")
	)
	(gr_line
		(start 93.574362 -40.2336)
		(end 93.58376 -40.2336)
		(stroke
			(width 0.0508)
			(type default)
		)
		(layer "F.Cu")
	)
	(gr_arc
		(start 93.582998 -181.211728)
		(mid 93.656221 -181.09544)
		(end 93.66758 -180.95849)
		(stroke
			(width 0.0508)
			(type default)
		)
		(layer "F.Cu")
	)
	(gr_line
		(start 93.58376 -40.2336)
		(end 93.950028 -40.599868)
		(stroke
			(width 0.0508)
			(type default)
		)
		(layer "F.Cu")
	)
	(gr_line
		(start 93.652594 -186.759342)
		(end 93.867986 -186.543696)
		(stroke
			(width 0.0508)
			(type default)
		)
		(layer "F.Cu")
	)
	(gr_arc
		(start 93.678502 -183.632094)
		(mid 93.605383 -183.74841)
		(end 93.594174 -183.885332)
		(stroke
			(width 0.0508)
			(type default)
		)
		(layer "F.Cu")
	)
	(gr_arc
		(start 93.751908 -180.705252)
		(mid 93.678812 -180.82157)
		(end 93.66758 -180.95849)
		(stroke
			(width 0.0508)
			(type default)
		)
		(layer "F.Cu")
	)
	(gr_arc
		(start 93.779086 -37.84092)
		(mid 93.737935 -37.813487)
		(end 93.689424 -37.803836)
		(stroke
			(width 0.0508)
			(type default)
		)
		(layer "F.Cu")
	)
	(gr_line
		(start 93.779086 -37.84092)
		(end 93.912944 -37.974778)
		(stroke
			(width 0.0508)
			(type default)
		)
		(layer "F.Cu")
	)
	(gr_line
		(start 93.781372 -33.231328)
		(end 93.950028 -33.399984)
		(stroke
			(width 0.06985)
			(type default)
		)
		(layer "F.Cu")
	)
	(gr_arc
		(start 93.812868 -177.951892)
		(mid 93.675906 -177.963233)
		(end 93.55963 -178.036474)
		(stroke
			(width 0.0508)
			(type default)
		)
		(layer "F.Cu")
	)
	(gr_arc
		(start 93.812868 -177.951892)
		(mid 93.949793 -177.940662)
		(end 94.066106 -177.867564)
		(stroke
			(width 0.0508)
			(type default)
		)
		(layer "F.Cu")
	)
	(gr_arc
		(start 93.867986 -186.543696)
		(mid 93.941209 -186.427408)
		(end 93.952568 -186.290458)
		(stroke
			(width 0.0508)
			(type default)
		)
		(layer "F.Cu")
	)
	(gr_line
		(start 93.91523 -35.80003)
		(end 93.950028 -35.80003)
		(stroke
			(width 0.0508)
			(type default)
		)
		(layer "F.Cu")
	)
	(gr_line
		(start 93.93428 -42.999914)
		(end 93.950028 -42.999914)
		(stroke
			(width 0.0508)
			(type default)
		)
		(layer "F.Cu")
	)
	(gr_line
		(start 93.949774 -42.199814)
		(end 93.950028 -42.199814)
		(stroke
			(width 0.0508)
			(type default)
		)
		(layer "F.Cu")
	)
	(gr_line
		(start 93.950028 -39.790624)
		(end 93.950028 -39.800022)
		(stroke
			(width 0.0508)
			(type default)
		)
		(layer "F.Cu")
	)
	(gr_arc
		(start 93.950028 -38.06444)
		(mid 93.940395 -38.015922)
		(end 93.912944 -37.974778)
		(stroke
			(width 0.0508)
			(type default)
		)
		(layer "F.Cu")
	)
	(gr_line
		(start 93.950028 -38.06444)
		(end 93.950028 -38.199822)
		(stroke
			(width 0.0508)
			(type default)
		)
		(layer "F.Cu")
	)
	(gr_line
		(start 93.950028 -37.399976)
		(end 94.350586 -36.999418)
		(stroke
			(width 0.0508)
			(type default)
		)
		(layer "F.Cu")
	)
	(gr_line
		(start 93.950028 -34.99993)
		(end 94.349824 -34.600134)
		(stroke
			(width 0.0508)
			(type default)
		)
		(layer "F.Cu")
	)
	(gr_line
		(start 93.969332 -180.002688)
		(end 94.371414 -179.600606)
		(stroke
			(width 0.0508)
			(type default)
		)
		(layer "F.Cu")
	)
	(gr_arc
		(start 94.036896 -186.03722)
		(mid 93.963789 -186.153537)
		(end 93.952568 -186.290458)
		(stroke
			(width 0.0508)
			(type default)
		)
		(layer "F.Cu")
	)
	(gr_line
		(start 94.066106 -177.867564)
		(end 94.281752 -177.651918)
		(stroke
			(width 0.0508)
			(type default)
		)
		(layer "F.Cu")
	)
	(gr_arc
		(start 94.220792 -180.405278)
		(mid 94.08388 -180.416536)
		(end 93.967554 -180.489606)
		(stroke
			(width 0.0508)
			(type default)
		)
		(layer "F.Cu")
	)
	(gr_arc
		(start 94.220792 -180.405278)
		(mid 94.357717 -180.394048)
		(end 94.47403 -180.32095)
		(stroke
			(width 0.0508)
			(type default)
		)
		(layer "F.Cu")
	)
	(gr_arc
		(start 94.281752 -177.651918)
		(mid 94.354812 -177.535593)
		(end 94.36608 -177.39868)
		(stroke
			(width 0.0508)
			(type default)
		)
		(layer "F.Cu")
	)
	(gr_line
		(start 94.350586 -36.999418)
		(end 94.359222 -36.999418)
		(stroke
			(width 0.0508)
			(type default)
		)
		(layer "F.Cu")
	)
	(gr_arc
		(start 94.450662 -177.145442)
		(mid 94.37743 -177.26173)
		(end 94.36608 -177.39868)
		(stroke
			(width 0.0508)
			(type default)
		)
		(layer "F.Cu")
	)
	(gr_line
		(start 94.47403 -180.32095)
		(end 94.689422 -180.105304)
		(stroke
			(width 0.0508)
			(type default)
		)
		(layer "F.Cu")
	)
	(gr_arc
		(start 94.689422 -180.105304)
		(mid 94.762482 -179.988979)
		(end 94.77375 -179.852066)
		(stroke
			(width 0.0508)
			(type default)
		)
		(layer "F.Cu")
	)
	(gr_arc
		(start 94.858332 -179.598828)
		(mid 94.785102 -179.715117)
		(end 94.77375 -179.852066)
		(stroke
			(width 0.0508)
			(type default)
		)
		(layer "F.Cu")
	)
	(gr_line
		(start 95.075502 -178.896518)
		(end 95.477838 -178.494182)
		(stroke
			(width 0.0508)
			(type default)
		)
		(layer "F.Cu")
	)
	(gr_arc
		(start 95.1484 -35.44062)
		(mid 95.154938 -35.473589)
		(end 95.173546 -35.50158)
		(stroke
			(width 0.06985)
			(type default)
		)
		(layer "F.Cu")
	)
	(gr_line
		(start 95.1484 -35.40506)
		(end 95.1484 -35.44062)
		(stroke
			(width 0.06985)
			(type default)
		)
		(layer "F.Cu")
	)
	(gr_line
		(start 95.150178 -36.20008)
		(end 95.549974 -36.599876)
		(stroke
			(width 0.06985)
			(type default)
		)
		(layer "F.Cu")
	)
	(gr_line
		(start 95.173546 -35.50158)
		(end 95.416878 -35.744912)
		(stroke
			(width 0.06985)
			(type default)
		)
		(layer "F.Cu")
	)
	(gr_arc
		(start 95.326962 -179.298854)
		(mid 95.190004 -179.310199)
		(end 95.073724 -179.383436)
		(stroke
			(width 0.0508)
			(type default)
		)
		(layer "F.Cu")
	)
	(gr_arc
		(start 95.326962 -179.298854)
		(mid 95.463887 -179.287624)
		(end 95.5802 -179.214526)
		(stroke
			(width 0.0508)
			(type default)
		)
		(layer "F.Cu")
	)
	(gr_arc
		(start 95.416878 -35.744912)
		(mid 95.477948 -35.785698)
		(end 95.549974 -35.80003)
		(stroke
			(width 0.06985)
			(type default)
		)
		(layer "F.Cu")
	)
	(gr_line
		(start 95.549974 -34.050986)
		(end 95.549974 -34.19983)
		(stroke
			(width 0.06985)
			(type default)
		)
		(layer "F.Cu")
	)
	(gr_arc
		(start 95.549974 -33.399984)
		(mid 95.48111 -33.053309)
		(end 95.284798 -32.759396)
		(stroke
			(width 0.06985)
			(type default)
		)
		(layer "F.Cu")
	)
	(gr_line
		(start 95.5802 -179.214526)
		(end 95.795846 -178.99888)
		(stroke
			(width 0.0508)
			(type default)
		)
		(layer "F.Cu")
	)
	(gr_arc
		(start 95.635572 -33.844484)
		(mid 95.572225 -33.939217)
		(end 95.549974 -34.050986)
		(stroke
			(width 0.06985)
			(type default)
		)
		(layer "F.Cu")
	)
	(gr_line
		(start 95.635572 -33.844484)
		(end 95.801688 -33.678368)
		(stroke
			(width 0.06985)
			(type default)
		)
		(layer "F.Cu")
	)
	(gr_line
		(start 95.649542 -32.639)
		(end 95.72625 -32.715962)
		(stroke
			(width 0.06985)
			(type default)
		)
		(layer "F.Cu")
	)
	(gr_arc
		(start 95.795846 -178.99888)
		(mid 95.868906 -178.882555)
		(end 95.880174 -178.745642)
		(stroke
			(width 0.0508)
			(type default)
		)
		(layer "F.Cu")
	)
	(gr_arc
		(start 95.801688 -33.678368)
		(mid 95.89269 -33.542268)
		(end 95.924624 -33.381696)
		(stroke
			(width 0.06985)
			(type default)
		)
		(layer "F.Cu")
	)
	(gr_line
		(start 95.924624 -33.19526)
		(end 95.924624 -33.381696)
		(stroke
			(width 0.06985)
			(type default)
		)
		(layer "F.Cu")
	)
	(gr_arc
		(start 95.9485 -35.54349)
		(mid 95.963948 -35.621154)
		(end 96.007936 -35.687)
		(stroke
			(width 0.06985)
			(type default)
		)
		(layer "F.Cu")
	)
	(gr_line
		(start 95.9485 -35.4076)
		(end 95.9485 -35.54349)
		(stroke
			(width 0.06985)
			(type default)
		)
		(layer "F.Cu")
	)
	(gr_line
		(start 95.950278 -36.20008)
		(end 96.350074 -36.599876)
		(stroke
			(width 0.06985)
			(type default)
		)
		(layer "F.Cu")
	)
	(gr_arc
		(start 95.964756 -178.492404)
		(mid 95.891551 -178.608694)
		(end 95.880174 -178.745642)
		(stroke
			(width 0.0508)
			(type default)
		)
		(layer "F.Cu")
	)
	(gr_line
		(start 96.007936 -35.687)
		(end 96.083882 -35.762946)
		(stroke
			(width 0.06985)
			(type default)
		)
		(layer "F.Cu")
	)
	(gr_arc
		(start 96.083882 -35.762946)
		(mid 96.125027 -35.790401)
		(end 96.173544 -35.80003)
		(stroke
			(width 0.06985)
			(type default)
		)
		(layer "F.Cu")
	)
	(gr_line
		(start 96.173544 -35.80003)
		(end 96.350074 -35.80003)
		(stroke
			(width 0.06985)
			(type default)
		)
		(layer "F.Cu")
	)
	(gr_line
		(start 96.173798 -172.132752)
		(end 96.57588 -171.73067)
		(stroke
			(width 0.0508)
			(type default)
		)
		(layer "F.Cu")
	)
	(gr_line
		(start 96.350074 -34.19983)
		(end 96.547178 -34.002726)
		(stroke
			(width 0.06985)
			(type default)
		)
		(layer "F.Cu")
	)
	(gr_arc
		(start 96.350074 -33.399984)
		(mid 96.37359 -33.36479)
		(end 96.381824 -33.323276)
		(stroke
			(width 0.06985)
			(type default)
		)
		(layer "F.Cu")
	)
	(gr_arc
		(start 96.425258 -172.535342)
		(mid 96.288353 -172.546613)
		(end 96.17202 -172.61967)
		(stroke
			(width 0.0508)
			(type default)
		)
		(layer "F.Cu")
	)
	(gr_arc
		(start 96.425258 -172.535342)
		(mid 96.562183 -172.524112)
		(end 96.678496 -172.451014)
		(stroke
			(width 0.0508)
			(type default)
		)
		(layer "F.Cu")
	)
	(gr_line
		(start 96.497902 -168.965118)
		(end 96.899984 -168.563036)
		(stroke
			(width 0.0508)
			(type default)
		)
		(layer "F.Cu")
	)
	(gr_arc
		(start 96.547178 -34.002726)
		(mid 96.678593 -33.806144)
		(end 96.724724 -33.574228)
		(stroke
			(width 0.06985)
			(type default)
		)
		(layer "F.Cu")
	)
	(gr_line
		(start 96.678496 -172.451014)
		(end 96.893888 -172.235368)
		(stroke
			(width 0.0508)
			(type default)
		)
		(layer "F.Cu")
	)
	(gr_arc
		(start 96.749362 -169.367708)
		(mid 96.612454 -169.378976)
		(end 96.496124 -169.452036)
		(stroke
			(width 0.0508)
			(type default)
		)
		(layer "F.Cu")
	)
	(gr_arc
		(start 96.749362 -169.367708)
		(mid 96.886287 -169.356478)
		(end 97.0026 -169.28338)
		(stroke
			(width 0.0508)
			(type default)
		)
		(layer "F.Cu")
	)
	(gr_arc
		(start 96.893888 -172.235368)
		(mid 96.967111 -172.11908)
		(end 96.97847 -171.98213)
		(stroke
			(width 0.0508)
			(type default)
		)
		(layer "F.Cu")
	)
	(gr_line
		(start 97.0026 -169.28338)
		(end 97.217992 -169.067734)
		(stroke
			(width 0.0508)
			(type default)
		)
		(layer "F.Cu")
	)
	(gr_arc
		(start 97.062798 -171.728892)
		(mid 96.989721 -171.845211)
		(end 96.97847 -171.98213)
		(stroke
			(width 0.0508)
			(type default)
		)
		(layer "F.Cu")
	)
	(gr_arc
		(start 97.217992 -169.067734)
		(mid 97.291215 -168.951446)
		(end 97.302574 -168.814496)
		(stroke
			(width 0.0508)
			(type default)
		)
		(layer "F.Cu")
	)
	(gr_line
		(start 97.272602 -179.552854)
		(end 97.674684 -179.150772)
		(stroke
			(width 0.0508)
			(type default)
		)
		(layer "F.Cu")
	)
	(gr_arc
		(start 97.386902 -168.561258)
		(mid 97.31381 -168.677576)
		(end 97.302574 -168.814496)
		(stroke
			(width 0.0508)
			(type default)
		)
		(layer "F.Cu")
	)
	(gr_arc
		(start 97.524062 -179.955444)
		(mid 97.387156 -179.966713)
		(end 97.270824 -180.039772)
		(stroke
			(width 0.0508)
			(type default)
		)
		(layer "F.Cu")
	)
	(gr_arc
		(start 97.524062 -179.955444)
		(mid 97.660987 -179.944214)
		(end 97.7773 -179.871116)
		(stroke
			(width 0.0508)
			(type default)
		)
		(layer "F.Cu")
	)
	(gr_line
		(start 97.540826 -35.400234)
		(end 97.940622 -35.80003)
		(stroke
			(width 0.06985)
			(type default)
		)
		(layer "F.Cu")
	)
	(gr_line
		(start 97.550224 -36.20008)
		(end 97.95002 -36.599876)
		(stroke
			(width 0.06985)
			(type default)
		)
		(layer "F.Cu")
	)
	(gr_line
		(start 97.604072 -167.858948)
		(end 98.006408 -167.456612)
		(stroke
			(width 0.0508)
			(type default)
		)
		(layer "F.Cu")
	)
	(gr_line
		(start 97.630742 -181.958234)
		(end 98.032824 -181.556152)
		(stroke
			(width 0.0508)
			(type default)
		)
		(layer "F.Cu")
	)
	(gr_line
		(start 97.7773 -179.871116)
		(end 97.992692 -179.65547)
		(stroke
			(width 0.0508)
			(type default)
		)
		(layer "F.Cu")
	)
	(gr_arc
		(start 97.855786 -168.261284)
		(mid 97.718705 -168.272601)
		(end 97.602294 -168.345866)
		(stroke
			(width 0.0508)
			(type default)
		)
		(layer "F.Cu")
	)
	(gr_arc
		(start 97.855786 -168.261284)
		(mid 97.992711 -168.250054)
		(end 98.109024 -168.176956)
		(stroke
			(width 0.0508)
			(type default)
		)
		(layer "F.Cu")
	)
	(gr_arc
		(start 97.882202 -182.360824)
		(mid 97.745285 -182.372076)
		(end 97.628964 -182.445152)
		(stroke
			(width 0.0508)
			(type default)
		)
		(layer "F.Cu")
	)
	(gr_arc
		(start 97.882202 -182.360824)
		(mid 98.01915 -182.34946)
		(end 98.13544 -182.276242)
		(stroke
			(width 0.0508)
			(type default)
		)
		(layer "F.Cu")
	)
	(gr_line
		(start 97.940622 -35.80003)
		(end 97.95002 -35.80003)
		(stroke
			(width 0.06985)
			(type default)
		)
		(layer "F.Cu")
	)
	(gr_line
		(start 97.95002 -34.19983)
		(end 98.068638 -34.080958)
		(stroke
			(width 0.06985)
			(type default)
		)
		(layer "F.Cu")
	)
	(gr_arc
		(start 97.95002 -33.399984)
		(mid 97.973536 -33.36479)
		(end 97.98177 -33.323276)
		(stroke
			(width 0.06985)
			(type default)
		)
		(layer "F.Cu")
	)
	(gr_arc
		(start 97.992692 -179.65547)
		(mid 98.065752 -179.539145)
		(end 98.07702 -179.402232)
		(stroke
			(width 0.0508)
			(type default)
		)
		(layer "F.Cu")
	)
	(gr_arc
		(start 98.068638 -34.080958)
		(mid 98.258093 -33.797557)
		(end 98.32467 -33.46323)
		(stroke
			(width 0.06985)
			(type default)
		)
		(layer "F.Cu")
	)
	(gr_line
		(start 98.109024 -168.176956)
		(end 98.324416 -167.96131)
		(stroke
			(width 0.0508)
			(type default)
		)
		(layer "F.Cu")
	)
	(gr_line
		(start 98.13544 -182.276242)
		(end 98.351086 -182.06085)
		(stroke
			(width 0.0508)
			(type default)
		)
		(layer "F.Cu")
	)
	(gr_arc
		(start 98.161602 -179.148994)
		(mid 98.088381 -179.265282)
		(end 98.07702 -179.402232)
		(stroke
			(width 0.0508)
			(type default)
		)
		(layer "F.Cu")
	)
	(gr_line
		(start 98.193098 -172.917866)
		(end 98.59518 -172.515784)
		(stroke
			(width 0.0508)
			(type default)
		)
		(layer "F.Cu")
	)
	(gr_arc
		(start 98.324416 -167.96131)
		(mid 98.397476 -167.844985)
		(end 98.408744 -167.708072)
		(stroke
			(width 0.0508)
			(type default)
		)
		(layer "F.Cu")
	)
	(gr_line
		(start 98.341942 -35.401504)
		(end 98.740468 -35.80003)
		(stroke
			(width 0.06985)
			(type default)
		)
		(layer "F.Cu")
	)
	(gr_line
		(start 98.350324 -36.20008)
		(end 98.75012 -36.599876)
		(stroke
			(width 0.06985)
			(type default)
		)
		(layer "F.Cu")
	)
	(gr_arc
		(start 98.351086 -182.06085)
		(mid 98.424146 -181.944525)
		(end 98.435414 -181.807612)
		(stroke
			(width 0.0508)
			(type default)
		)
		(layer "F.Cu")
	)
	(gr_line
		(start 98.378772 -178.446684)
		(end 98.781108 -178.044348)
		(stroke
			(width 0.0508)
			(type default)
		)
		(layer "F.Cu")
	)
	(gr_arc
		(start 98.444558 -173.320456)
		(mid 98.307654 -173.331727)
		(end 98.19132 -173.404784)
		(stroke
			(width 0.0508)
			(type default)
		)
		(layer "F.Cu")
	)
	(gr_arc
		(start 98.444558 -173.320456)
		(mid 98.581506 -173.309092)
		(end 98.697796 -173.235874)
		(stroke
			(width 0.0508)
			(type default)
		)
		(layer "F.Cu")
	)
	(gr_arc
		(start 98.493326 -167.454834)
		(mid 98.4201 -167.571124)
		(end 98.408744 -167.708072)
		(stroke
			(width 0.0508)
			(type default)
		)
		(layer "F.Cu")
	)
	(gr_arc
		(start 98.519742 -181.554374)
		(mid 98.446646 -181.670691)
		(end 98.435414 -181.807612)
		(stroke
			(width 0.0508)
			(type default)
		)
		(layer "F.Cu")
	)
	(gr_arc
		(start 98.630232 -178.84902)
		(mid 98.49328 -178.860377)
		(end 98.376994 -178.933602)
		(stroke
			(width 0.0508)
			(type default)
		)
		(layer "F.Cu")
	)
	(gr_arc
		(start 98.630232 -178.84902)
		(mid 98.767157 -178.83779)
		(end 98.88347 -178.764692)
		(stroke
			(width 0.0508)
			(type default)
		)
		(layer "F.Cu")
	)
	(gr_line
		(start 98.653854 -175.318166)
		(end 99.055936 -174.916084)
		(stroke
			(width 0.0508)
			(type default)
		)
		(layer "F.Cu")
	)
	(gr_line
		(start 98.697796 -173.235874)
		(end 98.913442 -173.020482)
		(stroke
			(width 0.0508)
			(type default)
		)
		(layer "F.Cu")
	)
	(gr_line
		(start 98.710496 -166.752524)
		(end 99.112832 -166.350188)
		(stroke
			(width 0.0508)
			(type default)
		)
		(layer "F.Cu")
	)
	(gr_line
		(start 98.737166 -180.85181)
		(end 99.139248 -180.449728)
		(stroke
			(width 0.0508)
			(type default)
		)
		(layer "F.Cu")
	)
	(gr_line
		(start 98.740468 -35.80003)
		(end 98.75012 -35.80003)
		(stroke
			(width 0.06985)
			(type default)
		)
		(layer "F.Cu")
	)
	(gr_line
		(start 98.75012 -34.073592)
		(end 98.75012 -34.19983)
		(stroke
			(width 0.06985)
			(type default)
		)
		(layer "F.Cu")
	)
	(gr_arc
		(start 98.75012 -33.399984)
		(mid 98.773402 -33.36514)
		(end 98.781616 -33.324038)
		(stroke
			(width 0.06985)
			(type default)
		)
		(layer "F.Cu")
	)
	(gr_line
		(start 98.78187 -32.234378)
		(end 98.78187 -32.434784)
		(stroke
			(width 0.06985)
			(type default)
		)
		(layer "F.Cu")
	)
	(gr_arc
		(start 98.81997 -33.90519)
		(mid 98.768263 -33.982432)
		(end 98.75012 -34.073592)
		(stroke
			(width 0.06985)
			(type default)
		)
		(layer "F.Cu")
	)
	(gr_line
		(start 98.81997 -33.90519)
		(end 98.969068 -33.756092)
		(stroke
			(width 0.06985)
			(type default)
		)
		(layer "F.Cu")
	)
	(gr_line
		(start 98.88347 -178.764692)
		(end 99.099116 -178.549046)
		(stroke
			(width 0.0508)
			(type default)
		)
		(layer "F.Cu")
	)
	(gr_arc
		(start 98.905314 -175.720502)
		(mid 98.768366 -175.731866)
		(end 98.652076 -175.805084)
		(stroke
			(width 0.0508)
			(type default)
		)
		(layer "F.Cu")
	)
	(gr_arc
		(start 98.905314 -175.720502)
		(mid 99.042239 -175.709272)
		(end 99.158552 -175.636174)
		(stroke
			(width 0.0508)
			(type default)
		)
		(layer "F.Cu")
	)
	(gr_arc
		(start 98.913442 -173.020482)
		(mid 98.986502 -172.904157)
		(end 98.99777 -172.767244)
		(stroke
			(width 0.0508)
			(type default)
		)
		(layer "F.Cu")
	)
	(gr_arc
		(start 98.961956 -167.15486)
		(mid 98.825 -167.166208)
		(end 98.708718 -167.239442)
		(stroke
			(width 0.0508)
			(type default)
		)
		(layer "F.Cu")
	)
	(gr_arc
		(start 98.961956 -167.15486)
		(mid 99.098881 -167.14363)
		(end 99.215194 -167.070532)
		(stroke
			(width 0.0508)
			(type default)
		)
		(layer "F.Cu")
	)
	(gr_arc
		(start 98.969068 -33.756092)
		(mid 99.084287 -33.583749)
		(end 99.12477 -33.380426)
		(stroke
			(width 0.06985)
			(type default)
		)
		(layer "F.Cu")
	)
	(gr_arc
		(start 98.988626 -181.2544)
		(mid 98.851727 -181.265683)
		(end 98.735388 -181.338728)
		(stroke
			(width 0.0508)
			(type default)
		)
		(layer "F.Cu")
	)
	(gr_arc
		(start 98.988626 -181.2544)
		(mid 99.125551 -181.24317)
		(end 99.241864 -181.170072)
		(stroke
			(width 0.0508)
			(type default)
		)
		(layer "F.Cu")
	)
	(gr_arc
		(start 99.082098 -172.514006)
		(mid 99.008985 -172.630323)
		(end 98.99777 -172.767244)
		(stroke
			(width 0.0508)
			(type default)
		)
		(layer "F.Cu")
	)
	(gr_arc
		(start 99.099116 -178.549046)
		(mid 99.172176 -178.432721)
		(end 99.183444 -178.295808)
		(stroke
			(width 0.0508)
			(type default)
		)
		(layer "F.Cu")
	)
	(gr_line
		(start 99.124516 -32.577278)
		(end 99.124516 -32.777684)
		(stroke
			(width 0.06985)
			(type default)
		)
		(layer "F.Cu")
	)
	(gr_line
		(start 99.158552 -175.636174)
		(end 99.374198 -175.420782)
		(stroke
			(width 0.0508)
			(type default)
		)
		(layer "F.Cu")
	)
	(gr_line
		(start 99.215194 -167.070532)
		(end 99.43084 -166.85514)
		(stroke
			(width 0.0508)
			(type default)
		)
		(layer "F.Cu")
	)
	(gr_line
		(start 99.241864 -181.170072)
		(end 99.457256 -180.954426)
		(stroke
			(width 0.0508)
			(type default)
		)
		(layer "F.Cu")
	)
	(gr_arc
		(start 99.268026 -178.04257)
		(mid 99.194814 -178.158861)
		(end 99.183444 -178.295808)
		(stroke
			(width 0.0508)
			(type default)
		)
		(layer "F.Cu")
	)
	(gr_arc
		(start 99.374198 -175.420782)
		(mid 99.447258 -175.304457)
		(end 99.458526 -175.167544)
		(stroke
			(width 0.0508)
			(type default)
		)
		(layer "F.Cu")
	)
	(gr_arc
		(start 99.43084 -166.85514)
		(mid 99.5039 -166.738815)
		(end 99.515168 -166.601902)
		(stroke
			(width 0.0508)
			(type default)
		)
		(layer "F.Cu")
	)
	(gr_arc
		(start 99.457256 -180.954426)
		(mid 99.530479 -180.838138)
		(end 99.541838 -180.701188)
		(stroke
			(width 0.0508)
			(type default)
		)
		(layer "F.Cu")
	)
	(gr_line
		(start 99.485196 -177.34026)
		(end 99.887278 -176.938178)
		(stroke
			(width 0.0508)
			(type default)
		)
		(layer "F.Cu")
	)
	(gr_arc
		(start 99.542854 -174.914306)
		(mid 99.469727 -175.03062)
		(end 99.458526 -175.167544)
		(stroke
			(width 0.0508)
			(type default)
		)
		(layer "F.Cu")
	)
	(gr_arc
		(start 99.59975 -166.34841)
		(mid 99.526459 -166.46481)
		(end 99.515168 -166.601902)
		(stroke
			(width 0.0508)
			(type default)
		)
		(layer "F.Cu")
	)
	(gr_arc
		(start 99.626166 -180.44795)
		(mid 99.553079 -180.56427)
		(end 99.541838 -180.701188)
		(stroke
			(width 0.0508)
			(type default)
		)
		(layer "F.Cu")
	)
	(gr_arc
		(start 99.736656 -177.74285)
		(mid 99.599752 -177.754122)
		(end 99.483418 -177.827178)
		(stroke
			(width 0.0508)
			(type default)
		)
		(layer "F.Cu")
	)
	(gr_arc
		(start 99.736656 -177.74285)
		(mid 99.873604 -177.731486)
		(end 99.989894 -177.658268)
		(stroke
			(width 0.0508)
			(type default)
		)
		(layer "F.Cu")
	)
	(gr_line
		(start 99.84359 -179.745386)
		(end 100.245672 -179.343304)
		(stroke
			(width 0.0508)
			(type default)
		)
		(layer "F.Cu")
	)
	(gr_line
		(start 99.95027 -36.20008)
		(end 100.350066 -36.599876)
		(stroke
			(width 0.06985)
			(type default)
		)
		(layer "F.Cu")
	)
	(gr_line
		(start 99.95154 -35.39236)
		(end 100.350066 -35.790886)
		(stroke
			(width 0.06985)
			(type default)
		)
		(layer "F.Cu")
	)
	(gr_line
		(start 99.989894 -177.658268)
		(end 100.20554 -177.442876)
		(stroke
			(width 0.0508)
			(type default)
		)
		(layer "F.Cu")
	)
	(gr_line
		(start 100.000562 -254.28194)
		(end 100.000562 -256.25044)
		(stroke
			(width 0.0508)
			(type default)
		)
		(layer "F.Cu")
	)
	(gr_arc
		(start 100.09505 -180.147976)
		(mid 99.958148 -180.159251)
		(end 99.841812 -180.232304)
		(stroke
			(width 0.0508)
			(type default)
		)
		(layer "F.Cu")
	)
	(gr_arc
		(start 100.09505 -180.147976)
		(mid 100.231975 -180.136746)
		(end 100.348288 -180.063648)
		(stroke
			(width 0.0508)
			(type default)
		)
		(layer "F.Cu")
	)
	(gr_arc
		(start 100.102162 -254.18034)
		(mid 100.030359 -254.210114)
		(end 100.000562 -254.28194)
		(stroke
			(width 0.0508)
			(type default)
		)
		(layer "F.Cu")
	)
	(gr_line
		(start 100.102162 -254.18034)
		(end 100.227384 -254.18034)
		(stroke
			(width 0.0508)
			(type default)
		)
		(layer "F.Cu")
	)
	(gr_arc
		(start 100.20554 -177.442876)
		(mid 100.2786 -177.326551)
		(end 100.289868 -177.189638)
		(stroke
			(width 0.0508)
			(type default)
		)
		(layer "F.Cu")
	)
	(gr_arc
		(start 100.227384 -254.18034)
		(mid 100.299226 -254.150582)
		(end 100.328984 -254.07874)
		(stroke
			(width 0.0508)
			(type default)
		)
		(layer "F.Cu")
	)
	(gr_line
		(start 100.348288 -180.063648)
		(end 100.56368 -179.848002)
		(stroke
			(width 0.0508)
			(type default)
		)
		(layer "F.Cu")
	)
	(gr_line
		(start 100.350066 -35.790886)
		(end 100.350066 -35.80003)
		(stroke
			(width 0.06985)
			(type default)
		)
		(layer "F.Cu")
	)
	(gr_line
		(start 100.350066 -34.19983)
		(end 100.485702 -34.06394)
		(stroke
			(width 0.06985)
			(type default)
		)
		(layer "F.Cu")
	)
	(gr_arc
		(start 100.350066 -33.399984)
		(mid 100.368832 -33.371899)
		(end 100.375466 -33.33877)
		(stroke
			(width 0.06985)
			(type default)
		)
		(layer "F.Cu")
	)
	(gr_arc
		(start 100.374196 -176.9364)
		(mid 100.301081 -177.052717)
		(end 100.289868 -177.189638)
		(stroke
			(width 0.0508)
			(type default)
		)
		(layer "F.Cu")
	)
	(gr_arc
		(start 100.485702 -34.06394)
		(mid 100.657871 -33.80641)
		(end 100.718366 -33.5026)
		(stroke
			(width 0.06985)
			(type default)
		)
		(layer "F.Cu")
	)
	(gr_arc
		(start 100.56368 -179.848002)
		(mid 100.63674 -179.731677)
		(end 100.648008 -179.594764)
		(stroke
			(width 0.0508)
			(type default)
		)
		(layer "F.Cu")
	)
	(gr_arc
		(start 100.671884 -254.07874)
		(mid 100.701655 -254.150562)
		(end 100.773484 -254.18034)
		(stroke
			(width 0.0508)
			(type default)
		)
		(layer "F.Cu")
	)
	(gr_arc
		(start 100.73259 -179.341526)
		(mid 100.659344 -179.457813)
		(end 100.648008 -179.594764)
		(stroke
			(width 0.0508)
			(type default)
		)
		(layer "F.Cu")
	)
	(gr_line
		(start 100.75037 -36.20008)
		(end 101.150166 -36.599876)
		(stroke
			(width 0.06985)
			(type default)
		)
		(layer "F.Cu")
	)
	(gr_arc
		(start 100.757482 -35.571938)
		(mid 100.76712 -35.620454)
		(end 100.794566 -35.6616)
		(stroke
			(width 0.06985)
			(type default)
		)
		(layer "F.Cu")
	)
	(gr_line
		(start 100.757482 -35.397948)
		(end 100.757482 -35.571938)
		(stroke
			(width 0.06985)
			(type default)
		)
		(layer "F.Cu")
	)
	(gr_line
		(start 100.773484 -254.18034)
		(end 100.898452 -254.18034)
		(stroke
			(width 0.0508)
			(type default)
		)
		(layer "F.Cu")
	)
	(gr_line
		(start 100.794566 -35.6616)
		(end 100.895912 -35.762946)
		(stroke
			(width 0.06985)
			(type default)
		)
		(layer "F.Cu")
	)
	(gr_arc
		(start 100.895912 -35.762946)
		(mid 100.937058 -35.790391)
		(end 100.985574 -35.80003)
		(stroke
			(width 0.06985)
			(type default)
		)
		(layer "F.Cu")
	)
	(gr_line
		(start 100.985574 -35.80003)
		(end 101.150166 -35.80003)
		(stroke
			(width 0.06985)
			(type default)
		)
		(layer "F.Cu")
	)
	(gr_arc
		(start 101.000052 -254.28194)
		(mid 100.970294 -254.210098)
		(end 100.898452 -254.18034)
		(stroke
			(width 0.0508)
			(type default)
		)
		(layer "F.Cu")
	)
	(gr_line
		(start 101.000052 -254.28194)
		(end 101.000052 -256.25044)
		(stroke
			(width 0.0508)
			(type default)
		)
		(layer "F.Cu")
	)
	(gr_line
		(start 101.150166 -34.19983)
		(end 101.19233 -34.19983)
		(stroke
			(width 0.06985)
			(type default)
		)
		(layer "F.Cu")
	)
	(gr_line
		(start 101.150166 -33.399984)
		(end 101.229922 -33.320228)
		(stroke
			(width 0.06985)
			(type default)
		)
		(layer "F.Cu")
	)
	(gr_line
		(start 101.19233 -34.19983)
		(end 101.393498 -33.998662)
		(stroke
			(width 0.06985)
			(type default)
		)
		(layer "F.Cu")
	)
	(gr_arc
		(start 101.393498 -33.998662)
		(mid 101.528106 -33.797302)
		(end 101.575362 -33.55975)
		(stroke
			(width 0.06985)
			(type default)
		)
		(layer "F.Cu")
	)
	(gr_line
		(start 101.74097 -113.798096)
		(end 101.74097 -114.0206)
		(stroke
			(width 0.0508)
			(type default)
		)
		(layer "F.Cu")
	)
	(gr_arc
		(start 101.814122 -113.62182)
		(mid 101.759997 -113.702674)
		(end 101.74097 -113.798096)
		(stroke
			(width 0.0508)
			(type default)
		)
		(layer "F.Cu")
	)
	(gr_line
		(start 101.814122 -113.62182)
		(end 101.844348 -113.591594)
		(stroke
			(width 0.0508)
			(type default)
		)
		(layer "F.Cu")
	)
	(gr_arc
		(start 101.844348 -113.591594)
		(mid 101.875933 -113.544135)
		(end 101.88702 -113.488216)
		(stroke
			(width 0.0508)
			(type default)
		)
		(layer "F.Cu")
	)
	(gr_arc
		(start 101.88702 -114.931952)
		(mid 101.849066 -114.741145)
		(end 101.74097 -114.5794)
		(stroke
			(width 0.0508)
			(type default)
		)
		(layer "F.Cu")
	)
	(gr_arc
		(start 102.22992 -113.487962)
		(mid 102.241062 -113.544057)
		(end 102.272846 -113.591594)
		(stroke
			(width 0.0508)
			(type default)
		)
		(layer "F.Cu")
	)
	(gr_line
		(start 102.272846 -113.591594)
		(end 102.303072 -113.62182)
		(stroke
			(width 0.0508)
			(type default)
		)
		(layer "F.Cu")
	)
	(gr_line
		(start 102.350062 -35.39998)
		(end 102.750112 -35.80003)
		(stroke
			(width 0.06985)
			(type default)
		)
		(layer "F.Cu")
	)
	(gr_line
		(start 102.350316 -36.20008)
		(end 102.750112 -36.599876)
		(stroke
			(width 0.06985)
			(type default)
		)
		(layer "F.Cu")
	)
	(gr_arc
		(start 102.37597 -114.5794)
		(mid 102.267342 -114.792625)
		(end 102.22992 -115.02898)
		(stroke
			(width 0.0508)
			(type default)
		)
		(layer "F.Cu")
	)
	(gr_arc
		(start 102.37597 -113.798096)
		(mid 102.357033 -113.702713)
		(end 102.303072 -113.62182)
		(stroke
			(width 0.0508)
			(type default)
		)
		(layer "F.Cu")
	)
	(gr_line
		(start 102.37597 -113.798096)
		(end 102.37597 -114.0206)
		(stroke
			(width 0.0508)
			(type default)
		)
		(layer "F.Cu")
	)
	(gr_line
		(start 102.750112 -34.166048)
		(end 102.750112 -34.19983)
		(stroke
			(width 0.06985)
			(type default)
		)
		(layer "F.Cu")
	)
	(gr_line
		(start 102.750112 -34.166048)
		(end 102.959154 -33.957006)
		(stroke
			(width 0.06985)
			(type default)
		)
		(layer "F.Cu")
	)
	(gr_line
		(start 102.750112 -33.399984)
		(end 102.779322 -33.370774)
		(stroke
			(width 0.06985)
			(type default)
		)
		(layer "F.Cu")
	)
	(gr_arc
		(start 102.831392 -32.938974)
		(mid 102.794756 -32.993873)
		(end 102.781862 -33.058608)
		(stroke
			(width 0.06985)
			(type default)
		)
		(layer "F.Cu")
	)
	(gr_arc
		(start 102.831392 -32.938974)
		(mid 102.868067 -32.884085)
		(end 102.880922 -32.81934)
		(stroke
			(width 0.06985)
			(type default)
		)
		(layer "F.Cu")
	)
	(gr_arc
		(start 102.959154 -33.957006)
		(mid 103.081717 -33.773578)
		(end 103.124762 -33.55721)
		(stroke
			(width 0.06985)
			(type default)
		)
		(layer "F.Cu")
	)
	(gr_line
		(start 103.150162 -36.20008)
		(end 103.549958 -36.599876)
		(stroke
			(width 0.06985)
			(type default)
		)
		(layer "F.Cu")
	)
	(gr_line
		(start 103.150162 -35.400234)
		(end 103.549958 -35.80003)
		(stroke
			(width 0.06985)
			(type default)
		)
		(layer "F.Cu")
	)
	(gr_arc
		(start 103.174292 -33.07207)
		(mid 103.137655 -33.126969)
		(end 103.124762 -33.191704)
		(stroke
			(width 0.06985)
			(type default)
		)
		(layer "F.Cu")
	)
	(gr_arc
		(start 103.174292 -33.07207)
		(mid 103.210967 -33.017181)
		(end 103.223822 -32.952436)
		(stroke
			(width 0.06985)
			(type default)
		)
		(layer "F.Cu")
	)
	(gr_arc
		(start 103.51897 -114.607848)
		(mid 103.524259 -114.634379)
		(end 103.53929 -114.65687)
		(stroke
			(width 0.0508)
			(type default)
		)
		(layer "F.Cu")
	)
	(gr_line
		(start 103.51897 -114.5794)
		(end 103.51897 -114.607848)
		(stroke
			(width 0.0508)
			(type default)
		)
		(layer "F.Cu")
	)
	(gr_line
		(start 103.51897 -113.773458)
		(end 103.51897 -114.0206)
		(stroke
			(width 0.0508)
			(type default)
		)
		(layer "F.Cu")
	)
	(gr_line
		(start 103.53929 -114.65687)
		(end 103.592122 -114.709448)
		(stroke
			(width 0.0508)
			(type default)
		)
		(layer "F.Cu")
	)
	(gr_line
		(start 103.549958 -34.050986)
		(end 103.549958 -34.19983)
		(stroke
			(width 0.06985)
			(type default)
		)
		(layer "F.Cu")
	)
	(gr_arc
		(start 103.549958 -33.399984)
		(mid 103.573474 -33.36479)
		(end 103.581708 -33.323276)
		(stroke
			(width 0.06985)
			(type default)
		)
		(layer "F.Cu")
	)
	(gr_arc
		(start 103.556054 -113.683796)
		(mid 103.528604 -113.724941)
		(end 103.51897 -113.773458)
		(stroke
			(width 0.0508)
			(type default)
		)
		(layer "F.Cu")
	)
	(gr_line
		(start 103.556054 -113.683796)
		(end 103.627936 -113.611914)
		(stroke
			(width 0.0508)
			(type default)
		)
		(layer "F.Cu")
	)
	(gr_arc
		(start 103.627936 -113.611914)
		(mid 103.655369 -113.570763)
		(end 103.66502 -113.522252)
		(stroke
			(width 0.0508)
			(type default)
		)
		(layer "F.Cu")
	)
	(gr_arc
		(start 103.635556 -33.844484)
		(mid 103.572212 -33.939218)
		(end 103.549958 -34.050986)
		(stroke
			(width 0.06985)
			(type default)
		)
		(layer "F.Cu")
	)
	(gr_line
		(start 103.635556 -33.844484)
		(end 103.801672 -33.678368)
		(stroke
			(width 0.06985)
			(type default)
		)
		(layer "F.Cu")
	)
	(gr_arc
		(start 103.66502 -114.885978)
		(mid 103.646116 -114.790472)
		(end 103.592122 -114.709448)
		(stroke
			(width 0.0508)
			(type default)
		)
		(layer "F.Cu")
	)
	(gr_arc
		(start 103.801672 -33.678368)
		(mid 103.892674 -33.542268)
		(end 103.924608 -33.381696)
		(stroke
			(width 0.06985)
			(type default)
		)
		(layer "F.Cu")
	)
	(gr_line
		(start 103.844852 -221.030292)
		(end 103.844852 -221.599252)
		(stroke
			(width 0.0508)
			(type default)
		)
		(layer "F.Cu")
	)
	(gr_line
		(start 103.844852 -219.465652)
		(end 103.844852 -220.034612)
		(stroke
			(width 0.0508)
			(type default)
		)
		(layer "F.Cu")
	)
	(gr_line
		(start 103.844852 -217.901012)
		(end 103.844852 -218.469972)
		(stroke
			(width 0.0508)
			(type default)
		)
		(layer "F.Cu")
	)
	(gr_line
		(start 103.844852 -216.336372)
		(end 103.844852 -216.905332)
		(stroke
			(width 0.0508)
			(type default)
		)
		(layer "F.Cu")
	)
	(gr_arc
		(start 104.00792 -113.522252)
		(mid 104.017565 -113.570763)
		(end 104.045004 -113.611914)
		(stroke
			(width 0.0508)
			(type default)
		)
		(layer "F.Cu")
	)
	(gr_line
		(start 104.045004 -113.611914)
		(end 104.116886 -113.683796)
		(stroke
			(width 0.0508)
			(type default)
		)
		(layer "F.Cu")
	)
	(gr_arc
		(start 104.131618 -114.633502)
		(mid 104.040086 -114.770559)
		(end 104.00792 -114.932206)
		(stroke
			(width 0.0508)
			(type default)
		)
		(layer "F.Cu")
	)
	(gr_arc
		(start 104.131618 -114.633502)
		(mid 104.14815 -114.608666)
		(end 104.15397 -114.5794)
		(stroke
			(width 0.0508)
			(type default)
		)
		(layer "F.Cu")
	)
	(gr_arc
		(start 104.15397 -113.773458)
		(mid 104.144337 -113.72494)
		(end 104.116886 -113.683796)
		(stroke
			(width 0.0508)
			(type default)
		)
		(layer "F.Cu")
	)
	(gr_line
		(start 104.15397 -113.773458)
		(end 104.15397 -114.0206)
		(stroke
			(width 0.0508)
			(type default)
		)
		(layer "F.Cu")
	)
	(gr_arc
		(start 104.187752 -220.684852)
		(mid 104.218336 -220.818785)
		(end 104.307132 -220.923612)
		(stroke
			(width 0.0508)
			(type default)
		)
		(layer "F.Cu")
	)
	(gr_arc
		(start 104.187752 -219.120212)
		(mid 104.218321 -219.254157)
		(end 104.307132 -219.358972)
		(stroke
			(width 0.0508)
			(type default)
		)
		(layer "F.Cu")
	)
	(gr_arc
		(start 104.187752 -217.555572)
		(mid 104.218343 -217.689499)
		(end 104.307132 -217.794332)
		(stroke
			(width 0.0508)
			(type default)
		)
		(layer "F.Cu")
	)
	(gr_arc
		(start 104.187752 -215.990932)
		(mid 104.218328 -216.124871)
		(end 104.307132 -216.229692)
		(stroke
			(width 0.0508)
			(type default)
		)
		(layer "F.Cu")
	)
	(gr_arc
		(start 104.307132 -221.705932)
		(mid 104.21823 -221.810707)
		(end 104.187752 -221.944692)
		(stroke
			(width 0.0508)
			(type default)
		)
		(layer "F.Cu")
	)
	(gr_arc
		(start 104.307132 -221.705932)
		(mid 104.395926 -221.601118)
		(end 104.426512 -221.467172)
		(stroke
			(width 0.0508)
			(type default)
		)
		(layer "F.Cu")
	)
	(gr_arc
		(start 104.307132 -220.141292)
		(mid 104.218215 -220.246064)
		(end 104.187752 -220.380052)
		(stroke
			(width 0.0508)
			(type default)
		)
		(layer "F.Cu")
	)
	(gr_arc
		(start 104.307132 -220.141292)
		(mid 104.395926 -220.036478)
		(end 104.426512 -219.902532)
		(stroke
			(width 0.0508)
			(type default)
		)
		(layer "F.Cu")
	)
	(gr_arc
		(start 104.307132 -218.576652)
		(mid 104.218237 -218.681428)
		(end 104.187752 -218.815412)
		(stroke
			(width 0.0508)
			(type default)
		)
		(layer "F.Cu")
	)
	(gr_arc
		(start 104.307132 -218.576652)
		(mid 104.395926 -218.471838)
		(end 104.426512 -218.337892)
		(stroke
			(width 0.0508)
			(type default)
		)
		(layer "F.Cu")
	)
	(gr_arc
		(start 104.307132 -217.012012)
		(mid 104.218223 -217.116786)
		(end 104.187752 -217.250772)
		(stroke
			(width 0.0508)
			(type default)
		)
		(layer "F.Cu")
	)
	(gr_arc
		(start 104.307132 -217.012012)
		(mid 104.395926 -216.907198)
		(end 104.426512 -216.773252)
		(stroke
			(width 0.0508)
			(type default)
		)
		(layer "F.Cu")
	)
	(gr_arc
		(start 104.426512 -221.162372)
		(mid 104.39602 -221.028379)
		(end 104.307132 -220.923612)
		(stroke
			(width 0.0508)
			(type default)
		)
		(layer "F.Cu")
	)
	(gr_line
		(start 104.426512 -221.162372)
		(end 104.426512 -221.467172)
		(stroke
			(width 0.0508)
			(type default)
		)
		(layer "F.Cu")
	)
	(gr_arc
		(start 104.426512 -219.597732)
		(mid 104.39602 -219.463739)
		(end 104.307132 -219.358972)
		(stroke
			(width 0.0508)
			(type default)
		)
		(layer "F.Cu")
	)
	(gr_line
		(start 104.426512 -219.597732)
		(end 104.426512 -219.902532)
		(stroke
			(width 0.0508)
			(type default)
		)
		(layer "F.Cu")
	)
	(gr_arc
		(start 104.426512 -218.033092)
		(mid 104.39602 -217.899099)
		(end 104.307132 -217.794332)
		(stroke
			(width 0.0508)
			(type default)
		)
		(layer "F.Cu")
	)
	(gr_line
		(start 104.426512 -218.033092)
		(end 104.426512 -218.337892)
		(stroke
			(width 0.0508)
			(type default)
		)
		(layer "F.Cu")
	)
	(gr_arc
		(start 104.426512 -216.468452)
		(mid 104.39602 -216.334459)
		(end 104.307132 -216.229692)
		(stroke
			(width 0.0508)
			(type default)
		)
		(layer "F.Cu")
	)
	(gr_line
		(start 104.426512 -216.468452)
		(end 104.426512 -216.773252)
		(stroke
			(width 0.0508)
			(type default)
		)
		(layer "F.Cu")
	)
	(gr_arc
		(start 105.29697 -114.704622)
		(mid 105.316007 -114.800154)
		(end 105.370122 -114.881152)
		(stroke
			(width 0.0508)
			(type default)
		)
		(layer "F.Cu")
	)
	(gr_line
		(start 105.29697 -114.5794)
		(end 105.29697 -114.704622)
		(stroke
			(width 0.0508)
			(type default)
		)
		(layer "F.Cu")
	)
	(gr_line
		(start 105.29697 -113.811558)
		(end 105.29697 -114.0206)
		(stroke
			(width 0.0508)
			(type default)
		)
		(layer "F.Cu")
	)
	(gr_arc
		(start 105.334054 -113.721896)
		(mid 105.306604 -113.763041)
		(end 105.29697 -113.811558)
		(stroke
			(width 0.0508)
			(type default)
		)
		(layer "F.Cu")
	)
	(gr_line
		(start 105.334054 -113.721896)
		(end 105.405936 -113.650014)
		(stroke
			(width 0.0508)
			(type default)
		)
		(layer "F.Cu")
	)
	(gr_arc
		(start 105.405936 -113.650014)
		(mid 105.433369 -113.608863)
		(end 105.44302 -113.560352)
		(stroke
			(width 0.0508)
			(type default)
		)
		(layer "F.Cu")
	)
	(gr_arc
		(start 105.44302 -115.057428)
		(mid 105.424083 -114.962045)
		(end 105.370122 -114.881152)
		(stroke
			(width 0.0508)
			(type default)
		)
		(layer "F.Cu")
	)
	(gr_arc
		(start 105.78592 -113.565432)
		(mid 105.795559 -113.613948)
		(end 105.823004 -113.655094)
		(stroke
			(width 0.0508)
			(type default)
		)
		(layer "F.Cu")
	)
	(gr_line
		(start 105.823004 -113.655094)
		(end 105.894886 -113.726976)
		(stroke
			(width 0.0508)
			(type default)
		)
		(layer "F.Cu")
	)
	(gr_arc
		(start 105.858818 -114.804952)
		(mid 105.80486 -114.885713)
		(end 105.78592 -114.980974)
		(stroke
			(width 0.0508)
			(type default)
		)
		(layer "F.Cu")
	)
	(gr_arc
		(start 105.858818 -114.804952)
		(mid 105.912936 -114.723959)
		(end 105.93197 -114.628422)
		(stroke
			(width 0.0508)
			(type default)
		)
		(layer "F.Cu")
	)
	(gr_line
		(start 105.93197 -114.5794)
		(end 105.93197 -114.628422)
		(stroke
			(width 0.0508)
			(type default)
		)
		(layer "F.Cu")
	)
	(gr_arc
		(start 105.93197 -113.816638)
		(mid 105.922337 -113.76812)
		(end 105.894886 -113.726976)
		(stroke
			(width 0.0508)
			(type default)
		)
		(layer "F.Cu")
	)
	(gr_line
		(start 105.93197 -113.816638)
		(end 105.93197 -114.0206)
		(stroke
			(width 0.0508)
			(type default)
		)
		(layer "F.Cu")
	)
	(gr_arc
		(start 106.815636 -107.597194)
		(mid 106.816917 -107.595935)
		(end 106.818176 -107.594654)
		(stroke
			(width 0.0508)
			(type default)
		)
		(layer "F.Cu")
	)
	(gr_arc
		(start 106.818176 -107.594654)
		(mid 106.81933 -107.593394)
		(end 106.820462 -107.592114)
		(stroke
			(width 0.0508)
			(type default)
		)
		(layer "F.Cu")
	)
	(gr_arc
		(start 106.820462 -107.592114)
		(mid 106.823184 -107.589243)
		(end 106.825796 -107.586272)
		(stroke
			(width 0.0508)
			(type default)
		)
		(layer "F.Cu")
	)
	(gr_arc
		(start 106.825796 -107.586272)
		(mid 106.830846 -107.580484)
		(end 106.835448 -107.574334)
		(stroke
			(width 0.0508)
			(type default)
		)
		(layer "F.Cu")
	)
	(gr_arc
		(start 106.835448 -107.574334)
		(mid 106.84446 -107.562732)
		(end 106.851704 -107.54995)
		(stroke
			(width 0.0508)
			(type default)
		)
		(layer "F.Cu")
	)
	(gr_line
		(start 106.849672 -103.850186)
		(end 107.349798 -103.35006)
		(stroke
			(width 0.0508)
			(type default)
		)
		(layer "F.Cu")
	)
	(gr_line
		(start 106.849672 -102.850188)
		(end 107.349798 -102.350062)
		(stroke
			(width 0.0508)
			(type default)
		)
		(layer "F.Cu")
	)
	(gr_arc
		(start 106.851704 -107.54995)
		(mid 106.936757 -107.419705)
		(end 106.968798 -107.267502)
		(stroke
			(width 0.0508)
			(type default)
		)
		(layer "F.Cu")
	)
	(gr_arc
		(start 107.07497 -114.681)
		(mid 107.09367 -114.774885)
		(end 107.146852 -114.854482)
		(stroke
			(width 0.0508)
			(type default)
		)
		(layer "F.Cu")
	)
	(gr_line
		(start 107.07497 -114.5794)
		(end 107.07497 -114.681)
		(stroke
			(width 0.0508)
			(type default)
		)
		(layer "F.Cu")
	)
	(gr_line
		(start 107.07497 -113.98758)
		(end 107.07497 -114.0206)
		(stroke
			(width 0.0508)
			(type default)
		)
		(layer "F.Cu")
	)
	(gr_line
		(start 107.085892 -107.812332)
		(end 107.086908 -107.811316)
		(stroke
			(width 0.0508)
			(type default)
		)
		(layer "F.Cu")
	)
	(gr_arc
		(start 107.093512 -106.966258)
		(mid 107.001214 -107.104484)
		(end 106.968798 -107.267502)
		(stroke
			(width 0.0508)
			(type default)
		)
		(layer "F.Cu")
	)
	(gr_line
		(start 107.093512 -106.966258)
		(end 107.222544 -106.837226)
		(stroke
			(width 0.0508)
			(type default)
		)
		(layer "F.Cu")
	)
	(gr_arc
		(start 107.098338 -113.931192)
		(mid 107.081039 -113.95706)
		(end 107.07497 -113.98758)
		(stroke
			(width 0.0508)
			(type default)
		)
		(layer "F.Cu")
	)
	(gr_line
		(start 107.098338 -113.931192)
		(end 107.202986 -113.826544)
		(stroke
			(width 0.0508)
			(type default)
		)
		(layer "F.Cu")
	)
	(gr_line
		(start 107.146852 -114.854482)
		(end 107.148122 -114.855752)
		(stroke
			(width 0.0508)
			(type default)
		)
		(layer "F.Cu")
	)
	(gr_arc
		(start 107.202986 -113.826544)
		(mid 107.230419 -113.785393)
		(end 107.24007 -113.736882)
		(stroke
			(width 0.0508)
			(type default)
		)
		(layer "F.Cu")
	)
	(gr_arc
		(start 107.22102 -115.032028)
		(mid 107.202083 -114.936645)
		(end 107.148122 -114.855752)
		(stroke
			(width 0.0508)
			(type default)
		)
		(layer "F.Cu")
	)
	(gr_arc
		(start 107.222544 -106.837226)
		(mid 107.316685 -106.696334)
		(end 107.349798 -106.53014)
		(stroke
			(width 0.0508)
			(type default)
		)
		(layer "F.Cu")
	)
	(gr_line
		(start 107.302554 -107.386628)
		(end 107.349798 -107.350052)
		(stroke
			(width 0.0508)
			(type default)
		)
		(layer "F.Cu")
	)
	(gr_arc
		(start 107.311698 -107.388152)
		(mid 107.307152 -107.387238)
		(end 107.302554 -107.386628)
		(stroke
			(width 0.0508)
			(type default)
		)
		(layer "F.Cu")
	)
	(gr_line
		(start 107.349798 -106.350054)
		(end 107.349798 -106.53014)
		(stroke
			(width 0.0508)
			(type default)
		)
		(layer "F.Cu")
	)
	(gr_arc
		(start 107.560364 -108.18622)
		(mid 107.681507 -108.010012)
		(end 107.731814 -107.802172)
		(stroke
			(width 0.0508)
			(type default)
		)
		(layer "F.Cu")
	)
	(gr_arc
		(start 107.58297 -113.714022)
		(mid 107.592635 -113.762521)
		(end 107.620054 -113.803684)
		(stroke
			(width 0.0508)
			(type default)
		)
		(layer "F.Cu")
	)
	(gr_line
		(start 107.620054 -113.803684)
		(end 107.672886 -113.856516)
		(stroke
			(width 0.0508)
			(type default)
		)
		(layer "F.Cu")
	)
	(gr_arc
		(start 107.636564 -114.785902)
		(mid 107.582782 -114.866708)
		(end 107.56392 -114.961924)
		(stroke
			(width 0.0508)
			(type default)
		)
		(layer "F.Cu")
	)
	(gr_line
		(start 107.636564 -114.785902)
		(end 107.636818 -114.785648)
		(stroke
			(width 0.0508)
			(type default)
		)
		(layer "F.Cu")
	)
	(gr_arc
		(start 107.636818 -114.785648)
		(mid 107.690965 -114.7048)
		(end 107.70997 -114.609372)
		(stroke
			(width 0.0508)
			(type default)
		)
		(layer "F.Cu")
	)
	(gr_line
		(start 107.70997 -114.5794)
		(end 107.70997 -114.609372)
		(stroke
			(width 0.0508)
			(type default)
		)
		(layer "F.Cu")
	)
	(gr_arc
		(start 107.70997 -113.946178)
		(mid 107.700337 -113.89766)
		(end 107.672886 -113.856516)
		(stroke
			(width 0.0508)
			(type default)
		)
		(layer "F.Cu")
	)
	(gr_line
		(start 107.70997 -113.946178)
		(end 107.70997 -114.0206)
		(stroke
			(width 0.0508)
			(type default)
		)
		(layer "F.Cu")
	)
	(gr_arc
		(start 107.731814 -107.802172)
		(mid 107.732543 -107.785923)
		(end 107.73283 -107.76966)
		(stroke
			(width 0.0508)
			(type default)
		)
		(layer "F.Cu")
	)
	(gr_line
		(start 107.73283 -106.57078)
		(end 107.73283 -107.76966)
		(stroke
			(width 0.0508)
			(type default)
		)
		(layer "F.Cu")
	)
	(gr_line
		(start 107.84967 -103.850186)
		(end 108.349796 -103.35006)
		(stroke
			(width 0.0508)
			(type default)
		)
		(layer "F.Cu")
	)
	(gr_line
		(start 107.84967 -102.850188)
		(end 108.349796 -102.350062)
		(stroke
			(width 0.0508)
			(type default)
		)
		(layer "F.Cu")
	)
	(gr_line
		(start 107.884722 -199.90435)
		(end 108.287058 -199.502014)
		(stroke
			(width 0.0508)
			(type default)
		)
		(layer "F.Cu")
	)
	(gr_line
		(start 107.96651 -106.721402)
		(end 107.96651 -107.81538)
		(stroke
			(width 0.0508)
			(type default)
		)
		(layer "F.Cu")
	)
	(gr_arc
		(start 107.977686 -106.637074)
		(mid 107.969274 -106.678864)
		(end 107.96651 -106.721402)
		(stroke
			(width 0.0508)
			(type default)
		)
		(layer "F.Cu")
	)
	(gr_arc
		(start 108.00461 -106.56951)
		(mid 107.989233 -106.602529)
		(end 107.977686 -106.637074)
		(stroke
			(width 0.0508)
			(type default)
		)
		(layer "F.Cu")
	)
	(gr_line
		(start 108.020612 -203.708)
		(end 108.573062 -203.708)
		(stroke
			(width 0.0508)
			(type default)
		)
		(layer "F.Cu")
	)
	(gr_arc
		(start 108.06049 -106.49458)
		(mid 108.029817 -106.530006)
		(end 108.00461 -106.56951)
		(stroke
			(width 0.0508)
			(type default)
		)
		(layer "F.Cu")
	)
	(gr_line
		(start 108.06049 -106.49458)
		(end 108.065824 -106.489246)
		(stroke
			(width 0.0508)
			(type default)
		)
		(layer "F.Cu")
	)
	(gr_line
		(start 108.067856 -106.487214)
		(end 108.102654 -106.452416)
		(stroke
			(width 0.0508)
			(type default)
		)
		(layer "F.Cu")
	)
	(gr_arc
		(start 108.136182 -200.306686)
		(mid 107.999241 -200.318063)
		(end 107.882944 -200.391268)
		(stroke
			(width 0.0508)
			(type default)
		)
		(layer "F.Cu")
	)
	(gr_arc
		(start 108.136182 -200.306686)
		(mid 108.273107 -200.295456)
		(end 108.38942 -200.222358)
		(stroke
			(width 0.0508)
			(type default)
		)
		(layer "F.Cu")
	)
	(gr_arc
		(start 108.159804 -105.540048)
		(mid 107.843796 -106.012943)
		(end 107.73283 -106.57078)
		(stroke
			(width 0.0508)
			(type default)
		)
		(layer "F.Cu")
	)
	(gr_line
		(start 108.159804 -105.540048)
		(end 108.349796 -105.350056)
		(stroke
			(width 0.0508)
			(type default)
		)
		(layer "F.Cu")
	)
	(gr_arc
		(start 108.349796 -106.350054)
		(mid 108.216051 -106.376663)
		(end 108.102654 -106.452416)
		(stroke
			(width 0.0508)
			(type default)
		)
		(layer "F.Cu")
	)
	(gr_line
		(start 108.38942 -200.222358)
		(end 108.605066 -200.006712)
		(stroke
			(width 0.0508)
			(type default)
		)
		(layer "F.Cu")
	)
	(gr_arc
		(start 108.605066 -200.006712)
		(mid 108.678126 -199.890387)
		(end 108.689394 -199.753474)
		(stroke
			(width 0.0508)
			(type default)
		)
		(layer "F.Cu")
	)
	(gr_arc
		(start 108.617004 -111.26724)
		(mid 108.615723 -111.268499)
		(end 108.614464 -111.26978)
		(stroke
			(width 0.0508)
			(type default)
		)
		(layer "F.Cu")
	)
	(gr_arc
		(start 108.674662 -203.8096)
		(mid 108.644904 -203.737758)
		(end 108.573062 -203.708)
		(stroke
			(width 0.0508)
			(type default)
		)
		(layer "F.Cu")
	)
	(gr_arc
		(start 108.773976 -199.500236)
		(mid 108.700738 -199.616523)
		(end 108.689394 -199.753474)
		(stroke
			(width 0.0508)
			(type default)
		)
		(layer "F.Cu")
	)
	(gr_line
		(start 108.849668 -103.850186)
		(end 109.349794 -103.35006)
		(stroke
			(width 0.0508)
			(type default)
		)
		(layer "F.Cu")
	)
	(gr_line
		(start 108.849668 -102.850188)
		(end 109.349794 -102.350062)
		(stroke
			(width 0.0508)
			(type default)
		)
		(layer "F.Cu")
	)
	(gr_arc
		(start 108.85297 -114.658648)
		(mid 108.867623 -114.732093)
		(end 108.909358 -114.794284)
		(stroke
			(width 0.0508)
			(type default)
		)
		(layer "F.Cu")
	)
	(gr_line
		(start 108.85297 -114.5794)
		(end 108.85297 -114.658648)
		(stroke
			(width 0.0508)
			(type default)
		)
		(layer "F.Cu")
	)
	(gr_line
		(start 108.85297 -113.821718)
		(end 108.85297 -114.0206)
		(stroke
			(width 0.0508)
			(type default)
		)
		(layer "F.Cu")
	)
	(gr_line
		(start 108.882942 -106.928666)
		(end 108.882942 -107.142026)
		(stroke
			(width 0.0508)
			(type default)
		)
		(layer "F.Cu")
	)
	(gr_arc
		(start 108.890054 -113.732056)
		(mid 108.862591 -113.773199)
		(end 108.85297 -113.821718)
		(stroke
			(width 0.0508)
			(type default)
		)
		(layer "F.Cu")
	)
	(gr_line
		(start 108.890054 -113.732056)
		(end 108.953808 -113.668302)
		(stroke
			(width 0.0508)
			(type default)
		)
		(layer "F.Cu")
	)
	(gr_line
		(start 108.909358 -114.794284)
		(end 108.926122 -114.811048)
		(stroke
			(width 0.0508)
			(type default)
		)
		(layer "F.Cu")
	)
	(gr_arc
		(start 108.920026 -106.839004)
		(mid 108.892584 -106.880151)
		(end 108.882942 -106.928666)
		(stroke
			(width 0.0508)
			(type default)
		)
		(layer "F.Cu")
	)
	(gr_line
		(start 108.920026 -106.839004)
		(end 109.328966 -106.430064)
		(stroke
			(width 0.0508)
			(type default)
		)
		(layer "F.Cu")
	)
	(gr_arc
		(start 108.953808 -113.668302)
		(mid 108.981241 -113.627151)
		(end 108.990892 -113.57864)
		(stroke
			(width 0.0508)
			(type default)
		)
		(layer "F.Cu")
	)
	(gr_line
		(start 108.991146 -198.797926)
		(end 109.393228 -198.395844)
		(stroke
			(width 0.0508)
			(type default)
		)
		(layer "F.Cu")
	)
	(gr_arc
		(start 108.99902 -114.987578)
		(mid 108.980116 -114.892072)
		(end 108.926122 -114.811048)
		(stroke
			(width 0.0508)
			(type default)
		)
		(layer "F.Cu")
	)
	(gr_line
		(start 108.999782 -254.28194)
		(end 108.999782 -256.25044)
		(stroke
			(width 0.0508)
			(type default)
		)
		(layer "F.Cu")
	)
	(gr_arc
		(start 109.101382 -254.18034)
		(mid 109.029566 -254.210107)
		(end 108.999782 -254.28194)
		(stroke
			(width 0.0508)
			(type default)
		)
		(layer "F.Cu")
	)
	(gr_line
		(start 109.101382 -254.18034)
		(end 109.227112 -254.18034)
		(stroke
			(width 0.0508)
			(type default)
		)
		(layer "F.Cu")
	)
	(gr_arc
		(start 109.119162 -203.708)
		(mid 109.047345 -203.737771)
		(end 109.017562 -203.8096)
		(stroke
			(width 0.0508)
			(type default)
		)
		(layer "F.Cu")
	)
	(gr_line
		(start 109.119162 -203.708)
		(end 109.671612 -203.708)
		(stroke
			(width 0.0508)
			(type default)
		)
		(layer "F.Cu")
	)
	(gr_arc
		(start 109.227112 -254.18034)
		(mid 109.298954 -254.150582)
		(end 109.328712 -254.07874)
		(stroke
			(width 0.0508)
			(type default)
		)
		(layer "F.Cu")
	)
	(gr_arc
		(start 109.242606 -199.200262)
		(mid 109.105663 -199.211631)
		(end 108.989368 -199.284844)
		(stroke
			(width 0.0508)
			(type default)
		)
		(layer "F.Cu")
	)
	(gr_arc
		(start 109.242606 -199.200262)
		(mid 109.379531 -199.189032)
		(end 109.495844 -199.115934)
		(stroke
			(width 0.0508)
			(type default)
		)
		(layer "F.Cu")
	)
	(gr_arc
		(start 109.262926 -107.397804)
		(mid 109.235484 -107.438951)
		(end 109.225842 -107.487466)
		(stroke
			(width 0.0508)
			(type default)
		)
		(layer "F.Cu")
	)
	(gr_line
		(start 109.262926 -107.397804)
		(end 109.310678 -107.350052)
		(stroke
			(width 0.0508)
			(type default)
		)
		(layer "F.Cu")
	)
	(gr_line
		(start 109.310678 -107.350052)
		(end 109.349794 -107.350052)
		(stroke
			(width 0.0508)
			(type default)
		)
		(layer "F.Cu")
	)
	(gr_arc
		(start 109.328966 -106.430064)
		(mid 109.344378 -106.406858)
		(end 109.349794 -106.379518)
		(stroke
			(width 0.0508)
			(type default)
		)
		(layer "F.Cu")
	)
	(gr_arc
		(start 109.333792 -113.529364)
		(mid 109.343439 -113.577874)
		(end 109.370876 -113.619026)
		(stroke
			(width 0.0508)
			(type default)
		)
		(layer "F.Cu")
	)
	(gr_line
		(start 109.349794 -106.350054)
		(end 109.349794 -106.379518)
		(stroke
			(width 0.0508)
			(type default)
		)
		(layer "F.Cu")
	)
	(gr_line
		(start 109.370876 -113.619026)
		(end 109.450886 -113.699036)
		(stroke
			(width 0.0508)
			(type default)
		)
		(layer "F.Cu")
	)
	(gr_arc
		(start 109.414564 -114.785902)
		(mid 109.360782 -114.866708)
		(end 109.34192 -114.961924)
		(stroke
			(width 0.0508)
			(type default)
		)
		(layer "F.Cu")
	)
	(gr_line
		(start 109.414564 -114.785902)
		(end 109.414818 -114.785648)
		(stroke
			(width 0.0508)
			(type default)
		)
		(layer "F.Cu")
	)
	(gr_arc
		(start 109.414818 -114.785648)
		(mid 109.468965 -114.7048)
		(end 109.48797 -114.609372)
		(stroke
			(width 0.0508)
			(type default)
		)
		(layer "F.Cu")
	)
	(gr_line
		(start 109.48797 -114.5794)
		(end 109.48797 -114.609372)
		(stroke
			(width 0.0508)
			(type default)
		)
		(layer "F.Cu")
	)
	(gr_arc
		(start 109.48797 -113.788698)
		(mid 109.478337 -113.74018)
		(end 109.450886 -113.699036)
		(stroke
			(width 0.0508)
			(type default)
		)
		(layer "F.Cu")
	)
	(gr_line
		(start 109.48797 -113.788698)
		(end 109.48797 -114.0206)
		(stroke
			(width 0.0508)
			(type default)
		)
		(layer "F.Cu")
	)
	(gr_line
		(start 109.495844 -199.115934)
		(end 109.71149 -198.900542)
		(stroke
			(width 0.0508)
			(type default)
		)
		(layer "F.Cu")
	)
	(gr_line
		(start 109.544612 -224.282)
		(end 109.956092 -223.87052)
		(stroke
			(width 0.0508)
			(type default)
		)
		(layer "F.Cu")
	)
	(gr_arc
		(start 109.670596 -108.314236)
		(mid 109.63653 -108.513101)
		(end 109.62513 -108.71454)
		(stroke
			(width 0.0508)
			(type default)
		)
		(layer "F.Cu")
	)
	(gr_arc
		(start 109.670596 -108.314236)
		(mid 109.715656 -108.095551)
		(end 109.730794 -107.872784)
		(stroke
			(width 0.0508)
			(type default)
		)
		(layer "F.Cu")
	)
	(gr_arc
		(start 109.671612 -254.07874)
		(mid 109.701385 -254.150552)
		(end 109.773212 -254.18034)
		(stroke
			(width 0.0508)
			(type default)
		)
		(layer "F.Cu")
	)
	(gr_arc
		(start 109.71149 -198.900542)
		(mid 109.78455 -198.784217)
		(end 109.795818 -198.647304)
		(stroke
			(width 0.0508)
			(type default)
		)
		(layer "F.Cu")
	)
	(gr_line
		(start 109.730794 -106.909108)
		(end 109.730794 -107.872784)
		(stroke
			(width 0.0508)
			(type default)
		)
		(layer "F.Cu")
	)
	(gr_line
		(start 109.730794 -106.909108)
		(end 109.733842 -106.90606)
		(stroke
			(width 0.0508)
			(type default)
		)
		(layer "F.Cu")
	)
	(gr_line
		(start 109.733842 -106.50474)
		(end 109.733842 -106.90606)
		(stroke
			(width 0.0508)
			(type default)
		)
		(layer "F.Cu")
	)
	(gr_line
		(start 109.733842 -106.3117)
		(end 109.733842 -106.499406)
		(stroke
			(width 0.0508)
			(type default)
		)
		(layer "F.Cu")
	)
	(gr_line
		(start 109.773212 -254.18034)
		(end 109.898942 -254.18034)
		(stroke
			(width 0.0508)
			(type default)
		)
		(layer "F.Cu")
	)
	(gr_line
		(start 109.849666 -103.850186)
		(end 110.349792 -103.35006)
		(stroke
			(width 0.0508)
			(type default)
		)
		(layer "F.Cu")
	)
	(gr_line
		(start 109.849666 -102.850188)
		(end 110.349792 -102.350062)
		(stroke
			(width 0.0508)
			(type default)
		)
		(layer "F.Cu")
	)
	(gr_arc
		(start 109.880146 -198.394066)
		(mid 109.807046 -198.510382)
		(end 109.795818 -198.647304)
		(stroke
			(width 0.0508)
			(type default)
		)
		(layer "F.Cu")
	)
	(gr_arc
		(start 109.956092 -223.87052)
		(mid 110.097445 -223.658876)
		(end 110.1471 -223.409256)
		(stroke
			(width 0.0508)
			(type default)
		)
		(layer "F.Cu")
	)
	(gr_line
		(start 109.96803 -108.218224)
		(end 109.96803 -108.3691)
		(stroke
			(width 0.0508)
			(type default)
		)
		(layer "F.Cu")
	)
	(gr_line
		(start 109.96803 -106.922316)
		(end 109.96803 -108.215684)
		(stroke
			(width 0.0508)
			(type default)
		)
		(layer "F.Cu")
	)
	(gr_arc
		(start 109.97819 -105.721404)
		(mid 109.797307 -105.992247)
		(end 109.733842 -106.3117)
		(stroke
			(width 0.0508)
			(type default)
		)
		(layer "F.Cu")
	)
	(gr_line
		(start 109.97819 -105.721404)
		(end 110.349792 -105.350056)
		(stroke
			(width 0.0508)
			(type default)
		)
		(layer "F.Cu")
	)
	(gr_arc
		(start 110.000542 -254.28194)
		(mid 109.970784 -254.210098)
		(end 109.898942 -254.18034)
		(stroke
			(width 0.0508)
			(type default)
		)
		(layer "F.Cu")
	)
	(gr_line
		(start 110.000542 -254.28194)
		(end 110.000542 -256.25044)
		(stroke
			(width 0.0508)
			(type default)
		)
		(layer "F.Cu")
	)
	(gr_arc
		(start 110.039404 -106.660442)
		(mid 109.986194 -106.786603)
		(end 109.96803 -106.922316)
		(stroke
			(width 0.0508)
			(type default)
		)
		(layer "F.Cu")
	)
	(gr_line
		(start 110.039404 -106.660442)
		(end 110.076742 -106.623104)
		(stroke
			(width 0.0508)
			(type default)
		)
		(layer "F.Cu")
	)
	(gr_line
		(start 110.079282 -106.620564)
		(end 110.349792 -106.350054)
		(stroke
			(width 0.0508)
			(type default)
		)
		(layer "F.Cu")
	)
	(gr_line
		(start 110.09757 -197.691502)
		(end 110.499652 -197.28942)
		(stroke
			(width 0.0508)
			(type default)
		)
		(layer "F.Cu")
	)
	(gr_arc
		(start 110.34903 -198.094092)
		(mid 110.212134 -198.105376)
		(end 110.095792 -198.17842)
		(stroke
			(width 0.0508)
			(type default)
		)
		(layer "F.Cu")
	)
	(gr_arc
		(start 110.34903 -198.094092)
		(mid 110.485978 -198.082728)
		(end 110.602268 -198.00951)
		(stroke
			(width 0.0508)
			(type default)
		)
		(layer "F.Cu")
	)
	(gr_arc
		(start 110.49 -223.139)
		(mid 110.570444 -223.54302)
		(end 110.799372 -223.885506)
		(stroke
			(width 0.0508)
			(type default)
		)
		(layer "F.Cu")
	)
	(gr_line
		(start 110.602268 -198.00951)
		(end 110.817914 -197.794118)
		(stroke
			(width 0.0508)
			(type default)
		)
		(layer "F.Cu")
	)
	(gr_arc
		(start 110.63097 -114.6302)
		(mid 110.640271 -114.677068)
		(end 110.666784 -114.716814)
		(stroke
			(width 0.0508)
			(type default)
		)
		(layer "F.Cu")
	)
	(gr_line
		(start 110.63097 -114.5794)
		(end 110.63097 -114.6302)
		(stroke
			(width 0.0508)
			(type default)
		)
		(layer "F.Cu")
	)
	(gr_line
		(start 110.63097 -113.748058)
		(end 110.63097 -114.0206)
		(stroke
			(width 0.0508)
			(type default)
		)
		(layer "F.Cu")
	)
	(gr_line
		(start 110.666784 -114.716814)
		(end 110.704122 -114.754152)
		(stroke
			(width 0.0508)
			(type default)
		)
		(layer "F.Cu")
	)
	(gr_arc
		(start 110.668054 -113.658396)
		(mid 110.640604 -113.699541)
		(end 110.63097 -113.748058)
		(stroke
			(width 0.0508)
			(type default)
		)
		(layer "F.Cu")
	)
	(gr_line
		(start 110.668054 -113.658396)
		(end 110.746286 -113.580164)
		(stroke
			(width 0.0508)
			(type default)
		)
		(layer "F.Cu")
	)
	(gr_arc
		(start 110.746286 -113.580164)
		(mid 110.773719 -113.539013)
		(end 110.78337 -113.490502)
		(stroke
			(width 0.0508)
			(type default)
		)
		(layer "F.Cu")
	)
	(gr_arc
		(start 110.77702 -114.930428)
		(mid 110.758083 -114.835045)
		(end 110.704122 -114.754152)
		(stroke
			(width 0.0508)
			(type default)
		)
		(layer "F.Cu")
	)
	(gr_line
		(start 110.799372 -223.885506)
		(end 111.195612 -224.282)
		(stroke
			(width 0.0508)
			(type default)
		)
		(layer "F.Cu")
	)
	(gr_arc
		(start 110.817914 -197.794118)
		(mid 110.890974 -197.677793)
		(end 110.902242 -197.54088)
		(stroke
			(width 0.0508)
			(type default)
		)
		(layer "F.Cu")
	)
	(gr_line
		(start 110.849664 -103.850186)
		(end 111.34979 -103.35006)
		(stroke
			(width 0.0508)
			(type default)
		)
		(layer "F.Cu")
	)
	(gr_line
		(start 110.849664 -102.850188)
		(end 111.34979 -102.350062)
		(stroke
			(width 0.0508)
			(type default)
		)
		(layer "F.Cu")
	)
	(gr_arc
		(start 110.86973 -107.456732)
		(mid 110.887541 -107.54636)
		(end 110.93831 -107.62234)
		(stroke
			(width 0.0508)
			(type default)
		)
		(layer "F.Cu")
	)
	(gr_line
		(start 110.86973 -107.022138)
		(end 110.86973 -107.456732)
		(stroke
			(width 0.0508)
			(type default)
		)
		(layer "F.Cu")
	)
	(gr_arc
		(start 110.98657 -197.287642)
		(mid 110.913479 -197.403961)
		(end 110.902242 -197.54088)
		(stroke
			(width 0.0508)
			(type default)
		)
		(layer "F.Cu")
	)
	(gr_arc
		(start 111.00689 -107.787948)
		(mid 110.989063 -107.698328)
		(end 110.93831 -107.62234)
		(stroke
			(width 0.0508)
			(type default)
		)
		(layer "F.Cu")
	)
	(gr_line
		(start 111.00689 -107.787948)
		(end 111.00689 -108.112052)
		(stroke
			(width 0.0508)
			(type default)
		)
		(layer "F.Cu")
	)
	(gr_arc
		(start 111.055658 -106.573066)
		(mid 110.918059 -106.779119)
		(end 110.86973 -107.022138)
		(stroke
			(width 0.0508)
			(type default)
		)
		(layer "F.Cu")
	)
	(gr_line
		(start 111.055658 -106.573066)
		(end 111.27867 -106.350054)
		(stroke
			(width 0.0508)
			(type default)
		)
		(layer "F.Cu")
	)
	(gr_arc
		(start 111.12627 -113.513362)
		(mid 111.135915 -113.561874)
		(end 111.163354 -113.603024)
		(stroke
			(width 0.0508)
			(type default)
		)
		(layer "F.Cu")
	)
	(gr_line
		(start 111.163354 -113.603024)
		(end 111.228886 -113.668556)
		(stroke
			(width 0.0508)
			(type default)
		)
		(layer "F.Cu")
	)
	(gr_arc
		(start 111.192564 -114.760502)
		(mid 111.138782 -114.841308)
		(end 111.11992 -114.936524)
		(stroke
			(width 0.0508)
			(type default)
		)
		(layer "F.Cu")
	)
	(gr_line
		(start 111.192564 -114.760502)
		(end 111.192818 -114.760248)
		(stroke
			(width 0.0508)
			(type default)
		)
		(layer "F.Cu")
	)
	(gr_arc
		(start 111.192818 -114.760248)
		(mid 111.246965 -114.6794)
		(end 111.26597 -114.583972)
		(stroke
			(width 0.0508)
			(type default)
		)
		(layer "F.Cu")
	)
	(gr_line
		(start 111.26597 -114.5794)
		(end 111.26597 -114.583972)
		(stroke
			(width 0.0508)
			(type default)
		)
		(layer "F.Cu")
	)
	(gr_arc
		(start 111.26597 -113.758218)
		(mid 111.256337 -113.7097)
		(end 111.228886 -113.668556)
		(stroke
			(width 0.0508)
			(type default)
		)
		(layer "F.Cu")
	)
	(gr_line
		(start 111.26597 -113.758218)
		(end 111.26597 -114.0206)
		(stroke
			(width 0.0508)
			(type default)
		)
		(layer "F.Cu")
	)
	(gr_line
		(start 111.27867 -106.350054)
		(end 111.34979 -106.350054)
		(stroke
			(width 0.0508)
			(type default)
		)
		(layer "F.Cu")
	)
	(gr_line
		(start 111.322612 -206.3115)
		(end 111.4425 -206.3115)
		(stroke
			(width 0.0508)
			(type default)
		)
		(layer "F.Cu")
	)
	(gr_line
		(start 111.322612 -205.4225)
		(end 111.533686 -205.4225)
		(stroke
			(width 0.0508)
			(type default)
		)
		(layer "F.Cu")
	)
	(gr_line
		(start 111.322612 -203.7334)
		(end 111.322612 -204.5335)
		(stroke
			(width 0.0508)
			(type default)
		)
		(layer "F.Cu")
	)
	(gr_line
		(start 111.349536 -107.769152)
		(end 111.34979 -107.769152)
		(stroke
			(width 0.0508)
			(type default)
		)
		(layer "F.Cu")
	)
	(gr_line
		(start 111.349536 -107.74426)
		(end 111.34979 -107.350052)
		(stroke
			(width 0.0508)
			(type default)
		)
		(layer "F.Cu")
	)
	(gr_arc
		(start 111.533686 -205.4225)
		(mid 111.695872 -205.398585)
		(end 111.844328 -205.329028)
		(stroke
			(width 0.0508)
			(type default)
		)
		(layer "F.Cu")
	)
	(gr_line
		(start 111.73079 -106.60888)
		(end 111.73079 -109.009434)
		(stroke
			(width 0.0508)
			(type default)
		)
		(layer "F.Cu")
	)
	(gr_arc
		(start 111.844328 -205.329028)
		(mid 111.965801 -205.147232)
		(end 112.008412 -204.932788)
		(stroke
			(width 0.0508)
			(type default)
		)
		(layer "F.Cu")
	)
	(gr_line
		(start 111.849662 -103.850186)
		(end 112.349788 -103.35006)
		(stroke
			(width 0.0508)
			(type default)
		)
		(layer "F.Cu")
	)
	(gr_line
		(start 111.849662 -102.850188)
		(end 112.349788 -102.350062)
		(stroke
			(width 0.0508)
			(type default)
		)
		(layer "F.Cu")
	)
	(gr_arc
		(start 111.96447 -108.666534)
		(mid 111.982171 -108.755467)
		(end 112.032542 -108.830872)
		(stroke
			(width 0.0508)
			(type default)
		)
		(layer "F.Cu")
	)
	(gr_line
		(start 111.96447 -106.622596)
		(end 111.96447 -108.666534)
		(stroke
			(width 0.0508)
			(type default)
		)
		(layer "F.Cu")
	)
	(gr_arc
		(start 112.014 -206.883)
		(mid 111.846612 -206.478888)
		(end 111.4425 -206.3115)
		(stroke
			(width 0.0508)
			(type default)
		)
		(layer "F.Cu")
	)
	(gr_arc
		(start 112.051592 -106.412284)
		(mid 111.987116 -106.508776)
		(end 111.96447 -106.622596)
		(stroke
			(width 0.0508)
			(type default)
		)
		(layer "F.Cu")
	)
	(gr_arc
		(start 112.07369 -109.001052)
		(mid 112.063267 -108.913505)
		(end 112.032542 -108.830872)
		(stroke
			(width 0.0508)
			(type default)
		)
		(layer "F.Cu")
	)
	(gr_arc
		(start 112.183164 -105.51668)
		(mid 111.848379 -106.017798)
		(end 111.73079 -106.60888)
		(stroke
			(width 0.0508)
			(type default)
		)
		(layer "F.Cu")
	)
	(gr_line
		(start 112.183164 -105.51668)
		(end 112.349788 -105.350056)
		(stroke
			(width 0.0508)
			(type default)
		)
		(layer "F.Cu")
	)
	(gr_arc
		(start 112.242092 -106.350054)
		(mid 112.141886 -106.365995)
		(end 112.051592 -106.412284)
		(stroke
			(width 0.0508)
			(type default)
		)
		(layer "F.Cu")
	)
	(gr_line
		(start 112.242092 -106.350054)
		(end 112.349788 -106.350054)
		(stroke
			(width 0.0508)
			(type default)
		)
		(layer "F.Cu")
	)
	(gr_arc
		(start 112.351312 -204.951838)
		(mid 112.391401 -205.153227)
		(end 112.50549 -205.323948)
		(stroke
			(width 0.0508)
			(type default)
		)
		(layer "F.Cu")
	)
	(gr_arc
		(start 112.40897 -114.634772)
		(mid 112.427991 -114.730314)
		(end 112.482122 -114.811302)
		(stroke
			(width 0.0508)
			(type default)
		)
		(layer "F.Cu")
	)
	(gr_line
		(start 112.40897 -114.5794)
		(end 112.40897 -114.634772)
		(stroke
			(width 0.0508)
			(type default)
		)
		(layer "F.Cu")
	)
	(gr_line
		(start 112.40897 -113.798096)
		(end 112.40897 -114.0206)
		(stroke
			(width 0.0508)
			(type default)
		)
		(layer "F.Cu")
	)
	(gr_arc
		(start 112.416336 -206.442564)
		(mid 112.372344 -206.508408)
		(end 112.3569 -206.586074)
		(stroke
			(width 0.0508)
			(type default)
		)
		(layer "F.Cu")
	)
	(gr_line
		(start 112.416336 -206.442564)
		(end 112.487964 -206.370936)
		(stroke
			(width 0.0508)
			(type default)
		)
		(layer "F.Cu")
	)
	(gr_arc
		(start 112.482122 -113.62182)
		(mid 112.427997 -113.702674)
		(end 112.40897 -113.798096)
		(stroke
			(width 0.0508)
			(type default)
		)
		(layer "F.Cu")
	)
	(gr_line
		(start 112.482122 -113.62182)
		(end 112.512348 -113.591594)
		(stroke
			(width 0.0508)
			(type default)
		)
		(layer "F.Cu")
	)
	(gr_arc
		(start 112.50549 -205.323948)
		(mid 112.653712 -205.397285)
		(end 112.817148 -205.4225)
		(stroke
			(width 0.0508)
			(type default)
		)
		(layer "F.Cu")
	)
	(gr_arc
		(start 112.512348 -113.591594)
		(mid 112.543933 -113.544135)
		(end 112.55502 -113.488216)
		(stroke
			(width 0.0508)
			(type default)
		)
		(layer "F.Cu")
	)
	(gr_arc
		(start 112.55502 -114.987324)
		(mid 112.536072 -114.892066)
		(end 112.482122 -114.811302)
		(stroke
			(width 0.0508)
			(type default)
		)
		(layer "F.Cu")
	)
	(gr_arc
		(start 112.631474 -206.3115)
		(mid 112.553797 -206.326927)
		(end 112.487964 -206.370936)
		(stroke
			(width 0.0508)
			(type default)
		)
		(layer "F.Cu")
	)
	(gr_line
		(start 112.631474 -206.3115)
		(end 112.973612 -206.3115)
		(stroke
			(width 0.0508)
			(type default)
		)
		(layer "F.Cu")
	)
	(gr_line
		(start 112.817148 -205.4225)
		(end 112.973612 -205.4225)
		(stroke
			(width 0.0508)
			(type default)
		)
		(layer "F.Cu")
	)
	(gr_line
		(start 112.846612 -223.3295)
		(end 112.846612 -224.282)
		(stroke
			(width 0.0508)
			(type default)
		)
		(layer "F.Cu")
	)
	(gr_line
		(start 112.846612 -222.4405)
		(end 112.953292 -222.4405)
		(stroke
			(width 0.0508)
			(type default)
		)
		(layer "F.Cu")
	)
	(gr_line
		(start 112.846612 -221.5515)
		(end 112.953038 -221.5515)
		(stroke
			(width 0.0508)
			(type default)
		)
		(layer "F.Cu")
	)
	(gr_line
		(start 112.84966 -103.850186)
		(end 113.349786 -103.35006)
		(stroke
			(width 0.0508)
			(type default)
		)
		(layer "F.Cu")
	)
	(gr_line
		(start 112.84966 -102.850188)
		(end 113.349786 -102.350062)
		(stroke
			(width 0.0508)
			(type default)
		)
		(layer "F.Cu")
	)
	(gr_line
		(start 112.879378 -107.485688)
		(end 112.879378 -107.518708)
		(stroke
			(width 0.0508)
			(type default)
		)
		(layer "F.Cu")
	)
	(gr_arc
		(start 112.89792 -113.487962)
		(mid 112.909062 -113.544057)
		(end 112.940846 -113.591594)
		(stroke
			(width 0.0508)
			(type default)
		)
		(layer "F.Cu")
	)
	(gr_line
		(start 112.940846 -113.591594)
		(end 112.971072 -113.62182)
		(stroke
			(width 0.0508)
			(type default)
		)
		(layer "F.Cu")
	)
	(gr_arc
		(start 112.953038 -221.5515)
		(mid 113.030702 -221.536052)
		(end 113.096548 -221.492064)
		(stroke
			(width 0.0508)
			(type default)
		)
		(layer "F.Cu")
	)
	(gr_line
		(start 112.973612 -203.7334)
		(end 112.973612 -204.5335)
		(stroke
			(width 0.0508)
			(type default)
		)
		(layer "F.Cu")
	)
	(gr_arc
		(start 112.98555 -114.72037)
		(mid 112.920685 -114.817446)
		(end 112.89792 -114.931952)
		(stroke
			(width 0.0508)
			(type default)
		)
		(layer "F.Cu")
	)
	(gr_arc
		(start 112.98555 -114.72037)
		(mid 113.028766 -114.655692)
		(end 113.04397 -114.5794)
		(stroke
			(width 0.0508)
			(type default)
		)
		(layer "F.Cu")
	)
	(gr_line
		(start 113.000282 -254.420878)
		(end 113.000282 -256.25044)
		(stroke
			(width 0.0508)
			(type default)
		)
		(layer "F.Cu")
	)
	(gr_arc
		(start 113.001044 -222.447866)
		(mid 112.97745 -222.442353)
		(end 112.953292 -222.4405)
		(stroke
			(width 0.0508)
			(type default)
		)
		(layer "F.Cu")
	)
	(gr_line
		(start 113.001044 -222.447866)
		(end 113.318036 -222.548196)
		(stroke
			(width 0.0508)
			(type default)
		)
		(layer "F.Cu")
	)
	(gr_arc
		(start 113.04397 -113.798096)
		(mid 113.025033 -113.702713)
		(end 112.971072 -113.62182)
		(stroke
			(width 0.0508)
			(type default)
		)
		(layer "F.Cu")
	)
	(gr_line
		(start 113.04397 -113.798096)
		(end 113.04397 -114.0206)
		(stroke
			(width 0.0508)
			(type default)
		)
		(layer "F.Cu")
	)
	(gr_arc
		(start 113.069624 -254.174498)
		(mid 113.017939 -254.292899)
		(end 113.000282 -254.420878)
		(stroke
			(width 0.0508)
			(type default)
		)
		(layer "F.Cu")
	)
	(gr_line
		(start 113.096548 -221.492064)
		(end 113.423954 -221.164658)
		(stroke
			(width 0.0508)
			(type default)
		)
		(layer "F.Cu")
	)
	(gr_arc
		(start 113.138712 -254.086614)
		(mid 113.101556 -254.128503)
		(end 113.069624 -254.174498)
		(stroke
			(width 0.0508)
			(type default)
		)
		(layer "F.Cu")
	)
	(gr_arc
		(start 113.155222 -254.047244)
		(mid 113.143051 -254.065285)
		(end 113.138712 -254.086614)
		(stroke
			(width 0.0508)
			(type default)
		)
		(layer "F.Cu")
	)
	(gr_line
		(start 113.155222 -254.047244)
		(end 113.227612 -253.9746)
		(stroke
			(width 0.0508)
			(type default)
		)
		(layer "F.Cu")
	)
	(gr_line
		(start 113.20907 -107.67314)
		(end 113.20907 -107.861608)
		(stroke
			(width 0.0508)
			(type default)
		)
		(layer "F.Cu")
	)
	(gr_line
		(start 113.227612 -253.9746)
		(end 113.234978 -253.96698)
		(stroke
			(width 0.0508)
			(type default)
		)
		(layer "F.Cu")
	)
	(gr_arc
		(start 113.234978 -253.96698)
		(mid 113.302805 -253.865609)
		(end 113.326672 -253.746)
		(stroke
			(width 0.0508)
			(type default)
		)
		(layer "F.Cu")
	)
	(gr_line
		(start 113.251742 -107.459018)
		(end 113.259362 -107.44073)
		(stroke
			(width 0.0508)
			(type default)
		)
		(layer "F.Cu")
	)
	(gr_line
		(start 113.259362 -107.44073)
		(end 113.349786 -107.350306)
		(stroke
			(width 0.0508)
			(type default)
		)
		(layer "F.Cu")
	)
	(gr_line
		(start 113.326672 -249.539252)
		(end 113.326672 -250.108212)
		(stroke
			(width 0.0508)
			(type default)
		)
		(layer "F.Cu")
	)
	(gr_line
		(start 113.326672 -247.974612)
		(end 113.326672 -248.543572)
		(stroke
			(width 0.0508)
			(type default)
		)
		(layer "F.Cu")
	)
	(gr_line
		(start 113.326672 -245.282212)
		(end 113.326672 -245.851172)
		(stroke
			(width 0.0508)
			(type default)
		)
		(layer "F.Cu")
	)
	(gr_line
		(start 113.326672 -243.717572)
		(end 113.326672 -244.286532)
		(stroke
			(width 0.0508)
			(type default)
		)
		(layer "F.Cu")
	)
	(gr_line
		(start 113.326672 -242.152932)
		(end 113.326672 -242.721892)
		(stroke
			(width 0.0508)
			(type default)
		)
		(layer "F.Cu")
	)
	(gr_line
		(start 113.326672 -237.847378)
		(end 113.326672 -238.416338)
		(stroke
			(width 0.0508)
			(type default)
		)
		(layer "F.Cu")
	)
	(gr_line
		(start 113.326672 -236.282738)
		(end 113.326672 -236.851698)
		(stroke
			(width 0.0508)
			(type default)
		)
		(layer "F.Cu")
	)
	(gr_line
		(start 113.349786 -107.350052)
		(end 113.349786 -107.350306)
		(stroke
			(width 0.0508)
			(type default)
		)
		(layer "F.Cu")
	)
	(gr_arc
		(start 113.349786 -106.350054)
		(mid 113.001613 -106.87108)
		(end 112.879378 -107.485688)
		(stroke
			(width 0.0508)
			(type default)
		)
		(layer "F.Cu")
	)
	(gr_arc
		(start 113.423954 -221.164658)
		(mid 113.467949 -221.098815)
		(end 113.48339 -221.021148)
		(stroke
			(width 0.0508)
			(type default)
		)
		(layer "F.Cu")
	)
	(gr_arc
		(start 113.444528 -222.66402)
		(mid 113.394102 -222.592104)
		(end 113.318036 -222.548196)
		(stroke
			(width 0.0508)
			(type default)
		)
		(layer "F.Cu")
	)
	(gr_line
		(start 113.444528 -222.66402)
		(end 113.478818 -222.746824)
		(stroke
			(width 0.0508)
			(type default)
		)
		(layer "F.Cu")
	)
	(gr_arc
		(start 113.494312 -222.824548)
		(mid 113.49041 -222.784918)
		(end 113.478818 -222.746824)
		(stroke
			(width 0.0508)
			(type default)
		)
		(layer "F.Cu")
	)
	(gr_arc
		(start 113.669572 -253.595378)
		(mid 113.671359 -253.642137)
		(end 113.676938 -253.688596)
		(stroke
			(width 0.0508)
			(type default)
		)
		(layer "F.Cu")
	)
	(gr_arc
		(start 113.669572 -249.193812)
		(mid 113.700082 -249.327779)
		(end 113.788952 -249.432572)
		(stroke
			(width 0.0508)
			(type default)
		)
		(layer "F.Cu")
	)
	(gr_arc
		(start 113.669572 -247.629172)
		(mid 113.700067 -247.763151)
		(end 113.788952 -247.867932)
		(stroke
			(width 0.0508)
			(type default)
		)
		(layer "F.Cu")
	)
	(gr_arc
		(start 113.669572 -244.936772)
		(mid 113.700067 -245.070751)
		(end 113.788952 -245.175532)
		(stroke
			(width 0.0508)
			(type default)
		)
		(layer "F.Cu")
	)
	(gr_arc
		(start 113.669572 -243.372132)
		(mid 113.700053 -243.506123)
		(end 113.788952 -243.610892)
		(stroke
			(width 0.0508)
			(type default)
		)
		(layer "F.Cu")
	)
	(gr_arc
		(start 113.669572 -241.807492)
		(mid 113.700075 -241.941465)
		(end 113.788952 -242.046252)
		(stroke
			(width 0.0508)
			(type default)
		)
		(layer "F.Cu")
	)
	(gr_arc
		(start 113.669572 -237.501938)
		(mid 113.700152 -237.635873)
		(end 113.788952 -237.740698)
		(stroke
			(width 0.0508)
			(type default)
		)
		(layer "F.Cu")
	)
	(gr_arc
		(start 113.669572 -235.937298)
		(mid 113.700137 -236.071245)
		(end 113.788952 -236.176058)
		(stroke
			(width 0.0508)
			(type default)
		)
		(layer "F.Cu")
	)
	(gr_arc
		(start 113.676938 -253.688596)
		(mid 113.678287 -253.696098)
		(end 113.679732 -253.703582)
		(stroke
			(width 0.0508)
			(type default)
		)
		(layer "F.Cu")
	)
	(gr_arc
		(start 113.679732 -253.703582)
		(mid 113.695365 -253.765735)
		(end 113.717832 -253.825756)
		(stroke
			(width 0.0508)
			(type default)
		)
		(layer "F.Cu")
	)
	(gr_arc
		(start 113.717832 -253.825756)
		(mid 113.722191 -253.835321)
		(end 113.726722 -253.844806)
		(stroke
			(width 0.0508)
			(type default)
		)
		(layer "F.Cu")
	)
	(gr_arc
		(start 113.726722 -253.844806)
		(mid 113.727608 -253.846712)
		(end 113.7285 -253.848616)
		(stroke
			(width 0.0508)
			(type default)
		)
		(layer "F.Cu")
	)
	(gr_arc
		(start 113.7285 -253.848616)
		(mid 113.776653 -253.928762)
		(end 113.837212 -254)
		(stroke
			(width 0.0508)
			(type default)
		)
		(layer "F.Cu")
	)
	(gr_line
		(start 113.733834 -106.836972)
		(end 113.733834 -108.683806)
		(stroke
			(width 0.0508)
			(type default)
		)
		(layer "F.Cu")
	)
	(gr_arc
		(start 113.788952 -250.214892)
		(mid 113.700059 -250.319672)
		(end 113.669572 -250.453652)
		(stroke
			(width 0.0508)
			(type default)
		)
		(layer "F.Cu")
	)
	(gr_arc
		(start 113.788952 -250.214892)
		(mid 113.87784 -250.110097)
		(end 113.908332 -249.976132)
		(stroke
			(width 0.0508)
			(type default)
		)
		(layer "F.Cu")
	)
	(gr_arc
		(start 113.788952 -248.650252)
		(mid 113.700081 -248.755036)
		(end 113.669572 -248.889012)
		(stroke
			(width 0.0508)
			(type default)
		)
		(layer "F.Cu")
	)
	(gr_arc
		(start 113.788952 -248.650252)
		(mid 113.87784 -248.545457)
		(end 113.908332 -248.411492)
		(stroke
			(width 0.0508)
			(type default)
		)
		(layer "F.Cu")
	)
	(gr_arc
		(start 113.788952 -245.957852)
		(mid 113.700081 -246.062636)
		(end 113.669572 -246.196612)
		(stroke
			(width 0.0508)
			(type default)
		)
		(layer "F.Cu")
	)
	(gr_arc
		(start 113.788952 -245.957852)
		(mid 113.87784 -245.853057)
		(end 113.908332 -245.719092)
		(stroke
			(width 0.0508)
			(type default)
		)
		(layer "F.Cu")
	)
	(gr_arc
		(start 113.788952 -244.393212)
		(mid 113.700067 -244.497993)
		(end 113.669572 -244.631972)
		(stroke
			(width 0.0508)
			(type default)
		)
		(layer "F.Cu")
	)
	(gr_arc
		(start 113.788952 -244.393212)
		(mid 113.87784 -244.288417)
		(end 113.908332 -244.154452)
		(stroke
			(width 0.0508)
			(type default)
		)
		(layer "F.Cu")
	)
	(gr_arc
		(start 113.788952 -242.828572)
		(mid 113.700052 -242.93335)
		(end 113.669572 -243.067332)
		(stroke
			(width 0.0508)
			(type default)
		)
		(layer "F.Cu")
	)
	(gr_arc
		(start 113.788952 -242.828572)
		(mid 113.87784 -242.723777)
		(end 113.908332 -242.589812)
		(stroke
			(width 0.0508)
			(type default)
		)
		(layer "F.Cu")
	)
	(gr_arc
		(start 113.788952 -238.523018)
		(mid 113.700069 -238.627799)
		(end 113.669572 -238.761778)
		(stroke
			(width 0.0508)
			(type default)
		)
		(layer "F.Cu")
	)
	(gr_arc
		(start 113.788952 -238.523018)
		(mid 113.877746 -238.418204)
		(end 113.908332 -238.284258)
		(stroke
			(width 0.0508)
			(type default)
		)
		(layer "F.Cu")
	)
	(gr_arc
		(start 113.788952 -236.958378)
		(mid 113.700054 -237.063157)
		(end 113.669572 -237.197138)
		(stroke
			(width 0.0508)
			(type default)
		)
		(layer "F.Cu")
	)
	(gr_arc
		(start 113.788952 -236.958378)
		(mid 113.877746 -236.853564)
		(end 113.908332 -236.719618)
		(stroke
			(width 0.0508)
			(type default)
		)
		(layer "F.Cu")
	)
	(gr_arc
		(start 113.82629 -220.910404)
		(mid 113.841742 -220.988065)
		(end 113.885726 -221.053914)
		(stroke
			(width 0.0508)
			(type default)
		)
		(layer "F.Cu")
	)
	(gr_line
		(start 113.849658 -103.850186)
		(end 114.349784 -103.35006)
		(stroke
			(width 0.0508)
			(type default)
		)
		(layer "F.Cu")
	)
	(gr_line
		(start 113.849658 -102.850188)
		(end 114.349784 -102.350062)
		(stroke
			(width 0.0508)
			(type default)
		)
		(layer "F.Cu")
	)
	(gr_line
		(start 113.885726 -221.053914)
		(end 114.323876 -221.492064)
		(stroke
			(width 0.0508)
			(type default)
		)
		(layer "F.Cu")
	)
	(gr_arc
		(start 113.908332 -249.671332)
		(mid 113.87784 -249.537339)
		(end 113.788952 -249.432572)
		(stroke
			(width 0.0508)
			(type default)
		)
		(layer "F.Cu")
	)
	(gr_line
		(start 113.908332 -249.671332)
		(end 113.908332 -249.976132)
		(stroke
			(width 0.0508)
			(type default)
		)
		(layer "F.Cu")
	)
	(gr_arc
		(start 113.908332 -248.106692)
		(mid 113.87784 -247.972699)
		(end 113.788952 -247.867932)
		(stroke
			(width 0.0508)
			(type default)
		)
		(layer "F.Cu")
	)
	(gr_line
		(start 113.908332 -248.106692)
		(end 113.908332 -248.411492)
		(stroke
			(width 0.0508)
			(type default)
		)
		(layer "F.Cu")
	)
	(gr_arc
		(start 113.908332 -245.414292)
		(mid 113.87784 -245.280299)
		(end 113.788952 -245.175532)
		(stroke
			(width 0.0508)
			(type default)
		)
		(layer "F.Cu")
	)
	(gr_line
		(start 113.908332 -245.414292)
		(end 113.908332 -245.719092)
		(stroke
			(width 0.0508)
			(type default)
		)
		(layer "F.Cu")
	)
	(gr_arc
		(start 113.908332 -243.849652)
		(mid 113.87784 -243.715659)
		(end 113.788952 -243.610892)
		(stroke
			(width 0.0508)
			(type default)
		)
		(layer "F.Cu")
	)
	(gr_line
		(start 113.908332 -243.849652)
		(end 113.908332 -244.154452)
		(stroke
			(width 0.0508)
			(type default)
		)
		(layer "F.Cu")
	)
	(gr_arc
		(start 113.908332 -242.285012)
		(mid 113.87784 -242.151019)
		(end 113.788952 -242.046252)
		(stroke
			(width 0.0508)
			(type default)
		)
		(layer "F.Cu")
	)
	(gr_line
		(start 113.908332 -242.285012)
		(end 113.908332 -242.589812)
		(stroke
			(width 0.0508)
			(type default)
		)
		(layer "F.Cu")
	)
	(gr_arc
		(start 113.908332 -237.979458)
		(mid 113.87784 -237.845465)
		(end 113.788952 -237.740698)
		(stroke
			(width 0.0508)
			(type default)
		)
		(layer "F.Cu")
	)
	(gr_line
		(start 113.908332 -237.979458)
		(end 113.908332 -238.284258)
		(stroke
			(width 0.0508)
			(type default)
		)
		(layer "F.Cu")
	)
	(gr_arc
		(start 113.908332 -236.414818)
		(mid 113.87784 -236.280825)
		(end 113.788952 -236.176058)
		(stroke
			(width 0.0508)
			(type default)
		)
		(layer "F.Cu")
	)
	(gr_line
		(start 113.908332 -236.414818)
		(end 113.908332 -236.719618)
		(stroke
			(width 0.0508)
			(type default)
		)
		(layer "F.Cu")
	)
	(gr_arc
		(start 113.96599 -108.340906)
		(mid 113.980509 -108.413906)
		(end 114.02187 -108.47578)
		(stroke
			(width 0.0508)
			(type default)
		)
		(layer "F.Cu")
	)
	(gr_line
		(start 113.96599 -106.9848)
		(end 113.96599 -108.340906)
		(stroke
			(width 0.0508)
			(type default)
		)
		(layer "F.Cu")
	)
	(gr_arc
		(start 113.999772 -254.39243)
		(mid 113.957526 -254.180045)
		(end 113.837212 -254)
		(stroke
			(width 0.0508)
			(type default)
		)
		(layer "F.Cu")
	)
	(gr_line
		(start 113.999772 -254.39243)
		(end 113.999772 -256.25044)
		(stroke
			(width 0.0508)
			(type default)
		)
		(layer "F.Cu")
	)
	(gr_arc
		(start 114.021616 -222.555562)
		(mid 113.885137 -222.759858)
		(end 113.837212 -223.000824)
		(stroke
			(width 0.0508)
			(type default)
		)
		(layer "F.Cu")
	)
	(gr_arc
		(start 114.076734 -108.608114)
		(mid 114.062484 -108.536476)
		(end 114.02187 -108.47578)
		(stroke
			(width 0.0508)
			(type default)
		)
		(layer "F.Cu")
	)
	(gr_arc
		(start 114.143536 -106.556556)
		(mid 114.01218 -106.753025)
		(end 113.96599 -106.9848)
		(stroke
			(width 0.0508)
			(type default)
		)
		(layer "F.Cu")
	)
	(gr_line
		(start 114.143536 -106.556556)
		(end 114.349784 -106.350054)
		(stroke
			(width 0.0508)
			(type default)
		)
		(layer "F.Cu")
	)
	(gr_arc
		(start 114.18697 -114.6429)
		(mid 114.198668 -114.701601)
		(end 114.231928 -114.751358)
		(stroke
			(width 0.0508)
			(type default)
		)
		(layer "F.Cu")
	)
	(gr_line
		(start 114.18697 -114.5794)
		(end 114.18697 -114.6429)
		(stroke
			(width 0.0508)
			(type default)
		)
		(layer "F.Cu")
	)
	(gr_arc
		(start 114.18697 -114.0206)
		(mid 114.309143 -113.837755)
		(end 114.35207 -113.622074)
		(stroke
			(width 0.0508)
			(type default)
		)
		(layer "F.Cu")
	)
	(gr_line
		(start 114.231928 -114.751358)
		(end 114.260122 -114.779552)
		(stroke
			(width 0.0508)
			(type default)
		)
		(layer "F.Cu")
	)
	(gr_arc
		(start 114.323876 -221.492064)
		(mid 114.389721 -221.536052)
		(end 114.467386 -221.5515)
		(stroke
			(width 0.0508)
			(type default)
		)
		(layer "F.Cu")
	)
	(gr_arc
		(start 114.33302 -114.955828)
		(mid 114.314083 -114.860445)
		(end 114.260122 -114.779552)
		(stroke
			(width 0.0508)
			(type default)
		)
		(layer "F.Cu")
	)
	(gr_arc
		(start 114.349784 -105.350056)
		(mid 113.893911 -106.032246)
		(end 113.733834 -106.836972)
		(stroke
			(width 0.0508)
			(type default)
		)
		(layer "F.Cu")
	)
	(gr_arc
		(start 114.362738 -222.4405)
		(mid 114.182733 -222.470033)
		(end 114.021616 -222.555562)
		(stroke
			(width 0.0508)
			(type default)
		)
		(layer "F.Cu")
	)
	(gr_line
		(start 114.362738 -222.4405)
		(end 114.497612 -222.4405)
		(stroke
			(width 0.0508)
			(type default)
		)
		(layer "F.Cu")
	)
	(gr_line
		(start 114.467386 -221.5515)
		(end 114.497612 -221.5515)
		(stroke
			(width 0.0508)
			(type default)
		)
		(layer "F.Cu")
	)
	(gr_line
		(start 114.497612 -223.3295)
		(end 114.497612 -224.282)
		(stroke
			(width 0.0508)
			(type default)
		)
		(layer "F.Cu")
	)
	(gr_arc
		(start 114.69497 -113.714022)
		(mid 114.727978 -113.879943)
		(end 114.82197 -114.0206)
		(stroke
			(width 0.0508)
			(type default)
		)
		(layer "F.Cu")
	)
	(gr_arc
		(start 114.750088 -114.752882)
		(mid 114.695185 -114.83504)
		(end 114.67592 -114.931952)
		(stroke
			(width 0.0508)
			(type default)
		)
		(layer "F.Cu")
	)
	(gr_arc
		(start 114.750088 -114.752882)
		(mid 114.803271 -114.673288)
		(end 114.82197 -114.5794)
		(stroke
			(width 0.0508)
			(type default)
		)
		(layer "F.Cu")
	)
	(gr_line
		(start 114.864642 -103.830882)
		(end 115.345464 -103.35006)
		(stroke
			(width 0.0508)
			(type default)
		)
		(layer "F.Cu")
	)
	(gr_line
		(start 114.864642 -102.840282)
		(end 115.350036 -102.354888)
		(stroke
			(width 0.0508)
			(type default)
		)
		(layer "F.Cu")
	)
	(gr_arc
		(start 114.954304 -107.305602)
		(mid 114.942716 -107.343698)
		(end 114.93881 -107.383326)
		(stroke
			(width 0.0508)
			(type default)
		)
		(layer "F.Cu")
	)
	(gr_line
		(start 114.954304 -107.305602)
		(end 115.350036 -106.350054)
		(stroke
			(width 0.0508)
			(type default)
		)
		(layer "F.Cu")
	)
	(gr_line
		(start 115.345464 -103.35006)
		(end 115.350036 -103.35006)
		(stroke
			(width 0.0508)
			(type default)
		)
		(layer "F.Cu")
	)
	(gr_arc
		(start 115.350036 -107.350052)
		(mid 115.299473 -107.425674)
		(end 115.28171 -107.514898)
		(stroke
			(width 0.0508)
			(type default)
		)
		(layer "F.Cu")
	)
	(gr_line
		(start 115.350036 -102.350062)
		(end 115.350036 -102.354888)
		(stroke
			(width 0.0508)
			(type default)
		)
		(layer "F.Cu")
	)
	(gr_line
		(start 115.734084 -106.7181)
		(end 115.734084 -109.8042)
		(stroke
			(width 0.0508)
			(type default)
		)
		(layer "F.Cu")
	)
	(gr_line
		(start 115.734084 -106.4006)
		(end 115.734084 -106.71556)
		(stroke
			(width 0.0508)
			(type default)
		)
		(layer "F.Cu")
	)
	(gr_line
		(start 115.880642 -103.830882)
		(end 116.350034 -103.36149)
		(stroke
			(width 0.0508)
			(type default)
		)
		(layer "F.Cu")
	)
	(gr_line
		(start 115.880642 -102.840282)
		(end 116.350034 -102.37089)
		(stroke
			(width 0.0508)
			(type default)
		)
		(layer "F.Cu")
	)
	(gr_line
		(start 115.894612 -203.7334)
		(end 116.447062 -203.7334)
		(stroke
			(width 0.0508)
			(type default)
		)
		(layer "F.Cu")
	)
	(gr_arc
		(start 115.96497 -114.642646)
		(mid 115.976752 -114.701503)
		(end 116.010182 -114.751358)
		(stroke
			(width 0.0508)
			(type default)
		)
		(layer "F.Cu")
	)
	(gr_line
		(start 115.96497 -114.5794)
		(end 115.96497 -114.642646)
		(stroke
			(width 0.0508)
			(type default)
		)
		(layer "F.Cu")
	)
	(gr_arc
		(start 115.96497 -114.0206)
		(mid 116.058955 -113.879941)
		(end 116.09197 -113.714022)
		(stroke
			(width 0.0508)
			(type default)
		)
		(layer "F.Cu")
	)
	(gr_arc
		(start 115.96624 -109.571282)
		(mid 115.970661 -109.663283)
		(end 115.98402 -109.754416)
		(stroke
			(width 0.0508)
			(type default)
		)
		(layer "F.Cu")
	)
	(gr_line
		(start 115.96624 -107.061)
		(end 115.96624 -109.571282)
		(stroke
			(width 0.0508)
			(type default)
		)
		(layer "F.Cu")
	)
	(gr_line
		(start 116.010182 -114.751358)
		(end 116.038122 -114.779298)
		(stroke
			(width 0.0508)
			(type default)
		)
		(layer "F.Cu")
	)
	(gr_line
		(start 116.024406 -110.504732)
		(end 116.026946 -110.507272)
		(stroke
			(width 0.0508)
			(type default)
		)
		(layer "F.Cu")
	)
	(gr_arc
		(start 116.041424 -105.658666)
		(mid 115.813941 -105.999059)
		(end 115.734084 -106.4006)
		(stroke
			(width 0.0508)
			(type default)
		)
		(layer "F.Cu")
	)
	(gr_line
		(start 116.041424 -105.658666)
		(end 116.350034 -105.350056)
		(stroke
			(width 0.0508)
			(type default)
		)
		(layer "F.Cu")
	)
	(gr_arc
		(start 116.11102 -114.955828)
		(mid 116.092116 -114.860322)
		(end 116.038122 -114.779298)
		(stroke
			(width 0.0508)
			(type default)
		)
		(layer "F.Cu")
	)
	(gr_arc
		(start 116.197634 -106.502454)
		(mid 116.141612 -106.56456)
		(end 116.092478 -106.632248)
		(stroke
			(width 0.0508)
			(type default)
		)
		(layer "F.Cu")
	)
	(gr_line
		(start 116.197634 -106.502454)
		(end 116.350034 -106.350054)
		(stroke
			(width 0.0508)
			(type default)
		)
		(layer "F.Cu")
	)
	(gr_line
		(start 116.26342 -110.25886)
		(end 116.270532 -110.265972)
		(stroke
			(width 0.0508)
			(type default)
		)
		(layer "F.Cu")
	)
	(gr_line
		(start 116.350034 -103.35006)
		(end 116.350034 -103.36149)
		(stroke
			(width 0.0508)
			(type default)
		)
		(layer "F.Cu")
	)
	(gr_line
		(start 116.350034 -102.350062)
		(end 116.350034 -102.37089)
		(stroke
			(width 0.0508)
			(type default)
		)
		(layer "F.Cu")
	)
	(gr_arc
		(start 116.43487 -113.62182)
		(mid 116.468455 -113.790766)
		(end 116.564156 -113.933986)
		(stroke
			(width 0.0508)
			(type default)
		)
		(layer "F.Cu")
	)
	(gr_arc
		(start 116.548662 -203.835)
		(mid 116.518904 -203.763158)
		(end 116.447062 -203.7334)
		(stroke
			(width 0.0508)
			(type default)
		)
		(layer "F.Cu")
	)
	(gr_arc
		(start 116.559584 -114.676936)
		(mid 116.48138 -114.79393)
		(end 116.45392 -114.931952)
		(stroke
			(width 0.0508)
			(type default)
		)
		(layer "F.Cu")
	)
	(gr_arc
		(start 116.559584 -114.676936)
		(mid 116.589485 -114.632186)
		(end 116.59997 -114.5794)
		(stroke
			(width 0.0508)
			(type default)
		)
		(layer "F.Cu")
	)
	(gr_arc
		(start 116.59997 -114.0206)
		(mid 116.590666 -113.973735)
		(end 116.564156 -113.933986)
		(stroke
			(width 0.0508)
			(type default)
		)
		(layer "F.Cu")
	)
	(gr_arc
		(start 116.963444 -107.262168)
		(mid 116.951456 -107.300987)
		(end 116.947442 -107.341416)
		(stroke
			(width 0.0508)
			(type default)
		)
		(layer "F.Cu")
	)
	(gr_line
		(start 116.963444 -107.262168)
		(end 117.350032 -106.350054)
		(stroke
			(width 0.0508)
			(type default)
		)
		(layer "F.Cu")
	)
	(gr_arc
		(start 116.993162 -203.7334)
		(mid 116.921345 -203.763171)
		(end 116.891562 -203.835)
		(stroke
			(width 0.0508)
			(type default)
		)
		(layer "F.Cu")
	)
	(gr_line
		(start 116.993162 -203.7334)
		(end 117.545612 -203.7334)
		(stroke
			(width 0.0508)
			(type default)
		)
		(layer "F.Cu")
	)
	(gr_line
		(start 116.999512 -254.507492)
		(end 116.999512 -256.25044)
		(stroke
			(width 0.0508)
			(type default)
		)
		(layer "F.Cu")
	)
	(gr_line
		(start 117.037612 -224.282)
		(end 117.499384 -223.819974)
		(stroke
			(width 0.0508)
			(type default)
		)
		(layer "F.Cu")
	)
	(gr_arc
		(start 117.169692 -254.09652)
		(mid 117.043729 -254.285083)
		(end 116.999512 -254.507492)
		(stroke
			(width 0.0508)
			(type default)
		)
		(layer "F.Cu")
	)
	(gr_arc
		(start 117.169692 -254.09652)
		(mid 117.295627 -253.90795)
		(end 117.339872 -253.685548)
		(stroke
			(width 0.0508)
			(type default)
		)
		(layer "F.Cu")
	)
	(gr_line
		(start 117.291866 -108.612178)
		(end 117.300248 -108.761022)
		(stroke
			(width 0.0508)
			(type default)
		)
		(layer "F.Cu")
	)
	(gr_line
		(start 117.339872 -250.931172)
		(end 117.339872 -251.500132)
		(stroke
			(width 0.0508)
			(type default)
		)
		(layer "F.Cu")
	)
	(gr_line
		(start 117.339872 -249.366532)
		(end 117.339872 -249.935492)
		(stroke
			(width 0.0508)
			(type default)
		)
		(layer "F.Cu")
	)
	(gr_line
		(start 117.339872 -247.801892)
		(end 117.339872 -248.370852)
		(stroke
			(width 0.0508)
			(type default)
		)
		(layer "F.Cu")
	)
	(gr_line
		(start 117.339872 -243.483892)
		(end 117.339872 -244.052852)
		(stroke
			(width 0.0508)
			(type default)
		)
		(layer "F.Cu")
	)
	(gr_line
		(start 117.339872 -241.919252)
		(end 117.339872 -242.488212)
		(stroke
			(width 0.0508)
			(type default)
		)
		(layer "F.Cu")
	)
	(gr_line
		(start 117.339872 -240.354612)
		(end 117.339872 -240.923572)
		(stroke
			(width 0.0508)
			(type default)
		)
		(layer "F.Cu")
	)
	(gr_line
		(start 117.339872 -237.40491)
		(end 117.339872 -237.97387)
		(stroke
			(width 0.0508)
			(type default)
		)
		(layer "F.Cu")
	)
	(gr_arc
		(start 117.350032 -107.350052)
		(mid 117.307651 -107.411532)
		(end 117.290342 -107.484164)
		(stroke
			(width 0.0508)
			(type default)
		)
		(layer "F.Cu")
	)
	(gr_line
		(start 117.350032 -103.35006)
		(end 117.850158 -103.850186)
		(stroke
			(width 0.0508)
			(type default)
		)
		(layer "F.Cu")
	)
	(gr_line
		(start 117.350032 -102.350062)
		(end 117.850158 -102.850188)
		(stroke
			(width 0.0508)
			(type default)
		)
		(layer "F.Cu")
	)
	(gr_arc
		(start 117.499384 -223.819974)
		(mid 117.669295 -223.565824)
		(end 117.729 -223.266)
		(stroke
			(width 0.0508)
			(type default)
		)
		(layer "F.Cu")
	)
	(gr_arc
		(start 117.682772 -253.760224)
		(mid 117.724014 -253.967662)
		(end 117.841522 -254.14351)
		(stroke
			(width 0.0508)
			(type default)
		)
		(layer "F.Cu")
	)
	(gr_arc
		(start 117.682772 -250.585732)
		(mid 117.71335 -250.719669)
		(end 117.802152 -250.824492)
		(stroke
			(width 0.0508)
			(type default)
		)
		(layer "F.Cu")
	)
	(gr_arc
		(start 117.682772 -249.021092)
		(mid 117.713335 -249.155041)
		(end 117.802152 -249.259852)
		(stroke
			(width 0.0508)
			(type default)
		)
		(layer "F.Cu")
	)
	(gr_arc
		(start 117.682772 -247.456452)
		(mid 117.713357 -247.590383)
		(end 117.802152 -247.695212)
		(stroke
			(width 0.0508)
			(type default)
		)
		(layer "F.Cu")
	)
	(gr_arc
		(start 117.682772 -243.138452)
		(mid 117.713357 -243.272383)
		(end 117.802152 -243.377212)
		(stroke
			(width 0.0508)
			(type default)
		)
		(layer "F.Cu")
	)
	(gr_arc
		(start 117.682772 -241.573812)
		(mid 117.713343 -241.707755)
		(end 117.802152 -241.812572)
		(stroke
			(width 0.0508)
			(type default)
		)
		(layer "F.Cu")
	)
	(gr_arc
		(start 117.682772 -240.009172)
		(mid 117.713365 -240.143097)
		(end 117.802152 -240.247932)
		(stroke
			(width 0.0508)
			(type default)
		)
		(layer "F.Cu")
	)
	(gr_arc
		(start 117.682772 -237.05947)
		(mid 117.713364 -237.193396)
		(end 117.802152 -237.29823)
		(stroke
			(width 0.0508)
			(type default)
		)
		(layer "F.Cu")
	)
	(gr_line
		(start 117.73281 -106.840274)
		(end 117.73281 -108.266992)
		(stroke
			(width 0.0508)
			(type default)
		)
		(layer "F.Cu")
	)
	(gr_arc
		(start 117.74297 -114.5794)
		(mid 117.758172 -114.65569)
		(end 117.80139 -114.72037)
		(stroke
			(width 0.0508)
			(type default)
		)
		(layer "F.Cu")
	)
	(gr_line
		(start 117.74297 -113.919)
		(end 117.74297 -114.0206)
		(stroke
			(width 0.0508)
			(type default)
		)
		(layer "F.Cu")
	)
	(gr_arc
		(start 117.802152 -251.606812)
		(mid 117.713349 -251.71164)
		(end 117.682772 -251.845572)
		(stroke
			(width 0.0508)
			(type default)
		)
		(layer "F.Cu")
	)
	(gr_arc
		(start 117.802152 -251.606812)
		(mid 117.890946 -251.501998)
		(end 117.921532 -251.368052)
		(stroke
			(width 0.0508)
			(type default)
		)
		(layer "F.Cu")
	)
	(gr_arc
		(start 117.802152 -250.042172)
		(mid 117.713371 -250.147004)
		(end 117.682772 -250.280932)
		(stroke
			(width 0.0508)
			(type default)
		)
		(layer "F.Cu")
	)
	(gr_arc
		(start 117.802152 -250.042172)
		(mid 117.890946 -249.937358)
		(end 117.921532 -249.803412)
		(stroke
			(width 0.0508)
			(type default)
		)
		(layer "F.Cu")
	)
	(gr_arc
		(start 117.802152 -248.477532)
		(mid 117.713357 -248.582361)
		(end 117.682772 -248.716292)
		(stroke
			(width 0.0508)
			(type default)
		)
		(layer "F.Cu")
	)
	(gr_arc
		(start 117.802152 -248.477532)
		(mid 117.890946 -248.372718)
		(end 117.921532 -248.238772)
		(stroke
			(width 0.0508)
			(type default)
		)
		(layer "F.Cu")
	)
	(gr_arc
		(start 117.802152 -244.159532)
		(mid 117.713274 -244.264314)
		(end 117.682772 -244.398292)
		(stroke
			(width 0.0508)
			(type default)
		)
		(layer "F.Cu")
	)
	(gr_arc
		(start 117.802152 -244.159532)
		(mid 117.890946 -244.054718)
		(end 117.921532 -243.920772)
		(stroke
			(width 0.0508)
			(type default)
		)
		(layer "F.Cu")
	)
	(gr_arc
		(start 117.802152 -242.594892)
		(mid 117.713259 -242.699672)
		(end 117.682772 -242.833652)
		(stroke
			(width 0.0508)
			(type default)
		)
		(layer "F.Cu")
	)
	(gr_arc
		(start 117.802152 -242.594892)
		(mid 117.890946 -242.490078)
		(end 117.921532 -242.356132)
		(stroke
			(width 0.0508)
			(type default)
		)
		(layer "F.Cu")
	)
	(gr_arc
		(start 117.802152 -241.030252)
		(mid 117.713281 -241.135036)
		(end 117.682772 -241.269012)
		(stroke
			(width 0.0508)
			(type default)
		)
		(layer "F.Cu")
	)
	(gr_arc
		(start 117.802152 -241.030252)
		(mid 117.890946 -240.925438)
		(end 117.921532 -240.791492)
		(stroke
			(width 0.0508)
			(type default)
		)
		(layer "F.Cu")
	)
	(gr_arc
		(start 117.802152 -238.08055)
		(mid 117.713281 -238.185334)
		(end 117.682772 -238.31931)
		(stroke
			(width 0.0508)
			(type default)
		)
		(layer "F.Cu")
	)
	(gr_arc
		(start 117.802152 -238.08055)
		(mid 117.890946 -237.975736)
		(end 117.921532 -237.84179)
		(stroke
			(width 0.0508)
			(type default)
		)
		(layer "F.Cu")
	)
	(gr_arc
		(start 117.814852 -113.745518)
		(mid 117.761641 -113.825105)
		(end 117.74297 -113.919)
		(stroke
			(width 0.0508)
			(type default)
		)
		(layer "F.Cu")
	)
	(gr_line
		(start 117.814852 -113.745518)
		(end 117.816122 -113.744248)
		(stroke
			(width 0.0508)
			(type default)
		)
		(layer "F.Cu")
	)
	(gr_arc
		(start 117.816122 -113.744248)
		(mid 117.870054 -113.663343)
		(end 117.88902 -113.567972)
		(stroke
			(width 0.0508)
			(type default)
		)
		(layer "F.Cu")
	)
	(gr_arc
		(start 117.88902 -114.931952)
		(mid 117.866244 -114.817449)
		(end 117.80139 -114.72037)
		(stroke
			(width 0.0508)
			(type default)
		)
		(layer "F.Cu")
	)
	(gr_arc
		(start 117.921532 -251.063252)
		(mid 117.890946 -250.929334)
		(end 117.802152 -250.824492)
		(stroke
			(width 0.0508)
			(type default)
		)
		(layer "F.Cu")
	)
	(gr_line
		(start 117.921532 -251.063252)
		(end 117.921532 -251.368052)
		(stroke
			(width 0.0508)
			(type default)
		)
		(layer "F.Cu")
	)
	(gr_arc
		(start 117.921532 -249.498612)
		(mid 117.890946 -249.364694)
		(end 117.802152 -249.259852)
		(stroke
			(width 0.0508)
			(type default)
		)
		(layer "F.Cu")
	)
	(gr_line
		(start 117.921532 -249.498612)
		(end 117.921532 -249.803412)
		(stroke
			(width 0.0508)
			(type default)
		)
		(layer "F.Cu")
	)
	(gr_arc
		(start 117.921532 -247.933972)
		(mid 117.890946 -247.800054)
		(end 117.802152 -247.695212)
		(stroke
			(width 0.0508)
			(type default)
		)
		(layer "F.Cu")
	)
	(gr_line
		(start 117.921532 -247.933972)
		(end 117.921532 -248.238772)
		(stroke
			(width 0.0508)
			(type default)
		)
		(layer "F.Cu")
	)
	(gr_arc
		(start 117.921532 -243.615972)
		(mid 117.89104 -243.481979)
		(end 117.802152 -243.377212)
		(stroke
			(width 0.0508)
			(type default)
		)
		(layer "F.Cu")
	)
	(gr_line
		(start 117.921532 -243.615972)
		(end 117.921532 -243.920772)
		(stroke
			(width 0.0508)
			(type default)
		)
		(layer "F.Cu")
	)
	(gr_arc
		(start 117.921532 -242.051332)
		(mid 117.89104 -241.917339)
		(end 117.802152 -241.812572)
		(stroke
			(width 0.0508)
			(type default)
		)
		(layer "F.Cu")
	)
	(gr_line
		(start 117.921532 -242.051332)
		(end 117.921532 -242.356132)
		(stroke
			(width 0.0508)
			(type default)
		)
		(layer "F.Cu")
	)
	(gr_arc
		(start 117.921532 -240.486692)
		(mid 117.89104 -240.352699)
		(end 117.802152 -240.247932)
		(stroke
			(width 0.0508)
			(type default)
		)
		(layer "F.Cu")
	)
	(gr_line
		(start 117.921532 -240.486692)
		(end 117.921532 -240.791492)
		(stroke
			(width 0.0508)
			(type default)
		)
		(layer "F.Cu")
	)
	(gr_arc
		(start 117.921532 -237.53699)
		(mid 117.89104 -237.402997)
		(end 117.802152 -237.29823)
		(stroke
			(width 0.0508)
			(type default)
		)
		(layer "F.Cu")
	)
	(gr_line
		(start 117.921532 -237.53699)
		(end 117.921532 -237.84179)
		(stroke
			(width 0.0508)
			(type default)
		)
		(layer "F.Cu")
	)
	(gr_arc
		(start 117.966236 -108.198412)
		(mid 118.04069 -108.441064)
		(end 118.18874 -108.64723)
		(stroke
			(width 0.0508)
			(type default)
		)
		(layer "F.Cu")
	)
	(gr_line
		(start 117.966236 -106.80065)
		(end 117.966236 -108.198412)
		(stroke
			(width 0.0508)
			(type default)
		)
		(layer "F.Cu")
	)
	(gr_arc
		(start 118.000272 -254.526796)
		(mid 117.959012 -254.319368)
		(end 117.841522 -254.14351)
		(stroke
			(width 0.0508)
			(type default)
		)
		(layer "F.Cu")
	)
	(gr_line
		(start 118.000272 -254.526796)
		(end 118.000272 -256.25044)
		(stroke
			(width 0.0508)
			(type default)
		)
		(layer "F.Cu")
	)
	(gr_arc
		(start 118.0719 -223.465644)
		(mid 118.108632 -223.650114)
		(end 118.213124 -223.806512)
		(stroke
			(width 0.0508)
			(type default)
		)
		(layer "F.Cu")
	)
	(gr_arc
		(start 118.13159 -106.401362)
		(mid 118.009214 -106.584566)
		(end 117.966236 -106.80065)
		(stroke
			(width 0.0508)
			(type default)
		)
		(layer "F.Cu")
	)
	(gr_line
		(start 118.18874 -108.64723)
		(end 118.26494 -108.72343)
		(stroke
			(width 0.0508)
			(type default)
		)
		(layer "F.Cu")
	)
	(gr_line
		(start 118.213124 -223.806512)
		(end 118.688612 -224.282)
		(stroke
			(width 0.0508)
			(type default)
		)
		(layer "F.Cu")
	)
	(gr_arc
		(start 118.23192 -113.542572)
		(mid 118.250869 -113.637951)
		(end 118.304818 -113.718848)
		(stroke
			(width 0.0508)
			(type default)
		)
		(layer "F.Cu")
	)
	(gr_arc
		(start 118.255542 -106.350054)
		(mid 118.188455 -106.363361)
		(end 118.13159 -106.401362)
		(stroke
			(width 0.0508)
			(type default)
		)
		(layer "F.Cu")
	)
	(gr_line
		(start 118.255542 -106.350054)
		(end 118.35003 -106.350054)
		(stroke
			(width 0.0508)
			(type default)
		)
		(layer "F.Cu")
	)
	(gr_arc
		(start 118.337584 -114.676936)
		(mid 118.25938 -114.79393)
		(end 118.23192 -114.931952)
		(stroke
			(width 0.0508)
			(type default)
		)
		(layer "F.Cu")
	)
	(gr_arc
		(start 118.337584 -114.676936)
		(mid 118.367485 -114.632186)
		(end 118.37797 -114.5794)
		(stroke
			(width 0.0508)
			(type default)
		)
		(layer "F.Cu")
	)
	(gr_arc
		(start 118.35003 -105.350056)
		(mid 117.89325 -106.033792)
		(end 117.73281 -106.840274)
		(stroke
			(width 0.0508)
			(type default)
		)
		(layer "F.Cu")
	)
	(gr_line
		(start 118.35003 -103.35006)
		(end 118.850156 -103.850186)
		(stroke
			(width 0.0508)
			(type default)
		)
		(layer "F.Cu")
	)
	(gr_line
		(start 118.35003 -102.350062)
		(end 118.850156 -102.850188)
		(stroke
			(width 0.0508)
			(type default)
		)
		(layer "F.Cu")
	)
	(gr_arc
		(start 118.37797 -113.895378)
		(mid 118.358964 -113.799829)
		(end 118.304818 -113.718848)
		(stroke
			(width 0.0508)
			(type default)
		)
		(layer "F.Cu")
	)
	(gr_line
		(start 118.37797 -113.895378)
		(end 118.37797 -114.0206)
		(stroke
			(width 0.0508)
			(type default)
		)
		(layer "F.Cu")
	)
	(gr_line
		(start 118.63197 -77.870812)
		(end 118.637558 -77.8764)
		(stroke
			(width 0.0508)
			(type default)
		)
		(layer "F.Cu")
	)
	(gr_line
		(start 118.63197 -75.1967)
		(end 118.63197 -77.870812)
		(stroke
			(width 0.0508)
			(type default)
		)
		(layer "F.Cu")
	)
	(gr_line
		(start 118.63197 -75.1967)
		(end 119.20347 -74.6252)
		(stroke
			(width 0.0508)
			(type default)
		)
		(layer "F.Cu")
	)
	(gr_line
		(start 118.637558 -77.997558)
		(end 119.499888 -78.859888)
		(stroke
			(width 0.0508)
			(type default)
		)
		(layer "F.Cu")
	)
	(gr_line
		(start 118.637558 -77.8764)
		(end 118.637558 -77.997558)
		(stroke
			(width 0.0508)
			(type default)
		)
		(layer "F.Cu")
	)
	(gr_line
		(start 119.196612 -206.3115)
		(end 119.308626 -206.3115)
		(stroke
			(width 0.0508)
			(type default)
		)
		(layer "F.Cu")
	)
	(gr_line
		(start 119.196612 -205.4225)
		(end 119.335042 -205.4225)
		(stroke
			(width 0.0508)
			(type default)
		)
		(layer "F.Cu")
	)
	(gr_line
		(start 119.196612 -203.7334)
		(end 119.196612 -204.5335)
		(stroke
			(width 0.0508)
			(type default)
		)
		(layer "F.Cu")
	)
	(gr_arc
		(start 119.335042 -205.4225)
		(mid 119.524097 -205.391223)
		(end 119.692928 -205.30058)
		(stroke
			(width 0.0508)
			(type default)
		)
		(layer "F.Cu")
	)
	(gr_arc
		(start 119.45239 -206.370936)
		(mid 119.386416 -206.326946)
		(end 119.308626 -206.3115)
		(stroke
			(width 0.0508)
			(type default)
		)
		(layer "F.Cu")
	)
	(gr_line
		(start 119.45239 -206.370936)
		(end 119.791226 -206.710026)
		(stroke
			(width 0.0508)
			(type default)
		)
		(layer "F.Cu")
	)
	(gr_arc
		(start 119.52097 -114.0206)
		(mid 119.629049 -113.858848)
		(end 119.66702 -113.668048)
		(stroke
			(width 0.0508)
			(type default)
		)
		(layer "F.Cu")
	)
	(gr_arc
		(start 119.66702 -114.931952)
		(mid 119.629066 -114.741145)
		(end 119.52097 -114.5794)
		(stroke
			(width 0.0508)
			(type default)
		)
		(layer "F.Cu")
	)
	(gr_arc
		(start 119.692928 -205.30058)
		(mid 119.804979 -205.132884)
		(end 119.844312 -204.935074)
		(stroke
			(width 0.0508)
			(type default)
		)
		(layer "F.Cu")
	)
	(gr_line
		(start 119.845328 -77.844142)
		(end 119.845328 -78.516988)
		(stroke
			(width 0.0508)
			(type default)
		)
		(layer "F.Cu")
	)
	(gr_line
		(start 119.845328 -77.844142)
		(end 120.09247 -77.597)
		(stroke
			(width 0.0508)
			(type default)
		)
		(layer "F.Cu")
	)
	(gr_arc
		(start 119.850662 -206.853536)
		(mid 119.835214 -206.775872)
		(end 119.791226 -206.710026)
		(stroke
			(width 0.0508)
			(type default)
		)
		(layer "F.Cu")
	)
	(gr_arc
		(start 120.00992 -113.834672)
		(mid 120.013634 -113.872357)
		(end 120.024652 -113.908586)
		(stroke
			(width 0.0508)
			(type default)
		)
		(layer "F.Cu")
	)
	(gr_line
		(start 120.024652 -113.908586)
		(end 120.044972 -113.957354)
		(stroke
			(width 0.0508)
			(type default)
		)
		(layer "F.Cu")
	)
	(gr_arc
		(start 120.025414 -114.694462)
		(mid 120.013818 -114.732557)
		(end 120.00992 -114.772186)
		(stroke
			(width 0.0508)
			(type default)
		)
		(layer "F.Cu")
	)
	(gr_line
		(start 120.025414 -114.694462)
		(end 120.047004 -114.642138)
		(stroke
			(width 0.0508)
			(type default)
		)
		(layer "F.Cu")
	)
	(gr_arc
		(start 120.044972 -113.957354)
		(mid 120.082622 -114.003304)
		(end 120.13946 -114.0206)
		(stroke
			(width 0.0508)
			(type default)
		)
		(layer "F.Cu")
	)
	(gr_line
		(start 120.09247 -77.597)
		(end 120.93067 -76.7588)
		(stroke
			(width 0.0508)
			(type default)
		)
		(layer "F.Cu")
	)
	(gr_line
		(start 120.13946 -114.0206)
		(end 120.15597 -114.0206)
		(stroke
			(width 0.0508)
			(type default)
		)
		(layer "F.Cu")
	)
	(gr_arc
		(start 120.14073 -114.5794)
		(mid 120.084363 -114.596557)
		(end 120.047004 -114.642138)
		(stroke
			(width 0.0508)
			(type default)
		)
		(layer "F.Cu")
	)
	(gr_line
		(start 120.14073 -114.5794)
		(end 120.15597 -114.5794)
		(stroke
			(width 0.0508)
			(type default)
		)
		(layer "F.Cu")
	)
	(gr_arc
		(start 120.187212 -204.928978)
		(mid 120.228107 -205.134343)
		(end 120.344438 -205.308454)
		(stroke
			(width 0.0508)
			(type default)
		)
		(layer "F.Cu")
	)
	(gr_arc
		(start 120.252998 -206.797656)
		(mid 120.209011 -206.863502)
		(end 120.193562 -206.941166)
		(stroke
			(width 0.0508)
			(type default)
		)
		(layer "F.Cu")
	)
	(gr_line
		(start 120.252998 -206.797656)
		(end 120.67921 -206.37119)
		(stroke
			(width 0.0508)
			(type default)
		)
		(layer "F.Cu")
	)
	(gr_line
		(start 120.339612 -223.3295)
		(end 120.339612 -224.282)
		(stroke
			(width 0.0508)
			(type default)
		)
		(layer "F.Cu")
	)
	(gr_line
		(start 120.339612 -222.4405)
		(end 120.522238 -222.4405)
		(stroke
			(width 0.0508)
			(type default)
		)
		(layer "F.Cu")
	)
	(gr_arc
		(start 120.339612 -221.5515)
		(mid 120.828497 -221.348997)
		(end 121.031 -220.860112)
		(stroke
			(width 0.0508)
			(type default)
		)
		(layer "F.Cu")
	)
	(gr_arc
		(start 120.344438 -205.308454)
		(mid 120.497283 -205.393181)
		(end 120.669558 -205.4225)
		(stroke
			(width 0.0508)
			(type default)
		)
		(layer "F.Cu")
	)
	(gr_line
		(start 120.350026 -83.349846)
		(end 120.91797 -82.781902)
		(stroke
			(width 0.0508)
			(type default)
		)
		(layer "F.Cu")
	)
	(gr_line
		(start 120.350026 -82.349848)
		(end 120.494044 -82.20583)
		(stroke
			(width 0.0508)
			(type default)
		)
		(layer "F.Cu")
	)
	(gr_line
		(start 120.669558 -205.4225)
		(end 120.847612 -205.4225)
		(stroke
			(width 0.0508)
			(type default)
		)
		(layer "F.Cu")
	)
	(gr_arc
		(start 120.822974 -206.3115)
		(mid 120.745131 -206.326996)
		(end 120.67921 -206.37119)
		(stroke
			(width 0.0508)
			(type default)
		)
		(layer "F.Cu")
	)
	(gr_line
		(start 120.822974 -206.3115)
		(end 120.847612 -206.3115)
		(stroke
			(width 0.0508)
			(type default)
		)
		(layer "F.Cu")
	)
	(gr_line
		(start 120.847612 -203.7334)
		(end 120.847612 -204.5335)
		(stroke
			(width 0.0508)
			(type default)
		)
		(layer "F.Cu")
	)
	(gr_arc
		(start 120.850914 -222.523304)
		(mid 120.691712 -222.461516)
		(end 120.522238 -222.4405)
		(stroke
			(width 0.0508)
			(type default)
		)
		(layer "F.Cu")
	)
	(gr_line
		(start 120.91797 -82.141314)
		(end 120.91797 -82.781902)
		(stroke
			(width 0.0508)
			(type default)
		)
		(layer "F.Cu")
	)
	(gr_line
		(start 120.93067 -76.7588)
		(end 122.4788 -76.7588)
		(stroke
			(width 0.0508)
			(type default)
		)
		(layer "F.Cu")
	)
	(gr_line
		(start 121.000012 -254.646176)
		(end 121.000012 -256.25044)
		(stroke
			(width 0.0508)
			(type default)
		)
		(layer "F.Cu")
	)
	(gr_arc
		(start 121.012712 -222.913956)
		(mid 120.970659 -222.702543)
		(end 120.850914 -222.523304)
		(stroke
			(width 0.0508)
			(type default)
		)
		(layer "F.Cu")
	)
	(gr_arc
		(start 121.241312 -254.0635)
		(mid 121.062743 -254.33085)
		(end 121.000012 -254.646176)
		(stroke
			(width 0.0508)
			(type default)
		)
		(layer "F.Cu")
	)
	(gr_arc
		(start 121.241312 -254.0635)
		(mid 121.39362 -253.835555)
		(end 121.447052 -253.566676)
		(stroke
			(width 0.0508)
			(type default)
		)
		(layer "F.Cu")
	)
	(gr_arc
		(start 121.29897 -114.0206)
		(mid 121.407049 -113.858848)
		(end 121.44502 -113.668048)
		(stroke
			(width 0.0508)
			(type default)
		)
		(layer "F.Cu")
	)
	(gr_arc
		(start 121.3739 -221.269052)
		(mid 121.383813 -221.318811)
		(end 121.412 -221.361)
		(stroke
			(width 0.0508)
			(type default)
		)
		(layer "F.Cu")
	)
	(gr_line
		(start 121.3739 -221.205552)
		(end 121.3739 -221.269052)
		(stroke
			(width 0.0508)
			(type default)
		)
		(layer "F.Cu")
	)
	(gr_arc
		(start 121.412 -221.361)
		(mid 121.623058 -221.501976)
		(end 121.871994 -221.5515)
		(stroke
			(width 0.0508)
			(type default)
		)
		(layer "F.Cu")
	)
	(gr_arc
		(start 121.44502 -114.931952)
		(mid 121.407066 -114.741145)
		(end 121.29897 -114.5794)
		(stroke
			(width 0.0508)
			(type default)
		)
		(layer "F.Cu")
	)
	(gr_line
		(start 121.447052 -249.686572)
		(end 121.447052 -250.255532)
		(stroke
			(width 0.0508)
			(type default)
		)
		(layer "F.Cu")
	)
	(gr_line
		(start 121.447052 -248.121932)
		(end 121.447052 -248.690892)
		(stroke
			(width 0.0508)
			(type default)
		)
		(layer "F.Cu")
	)
	(gr_line
		(start 121.447052 -246.557292)
		(end 121.447052 -247.126252)
		(stroke
			(width 0.0508)
			(type default)
		)
		(layer "F.Cu")
	)
	(gr_line
		(start 121.447052 -243.895626)
		(end 121.447052 -244.464586)
		(stroke
			(width 0.0508)
			(type default)
		)
		(layer "F.Cu")
	)
	(gr_line
		(start 121.447052 -242.330986)
		(end 121.447052 -242.899946)
		(stroke
			(width 0.0508)
			(type default)
		)
		(layer "F.Cu")
	)
	(gr_line
		(start 121.447052 -240.766346)
		(end 121.447052 -241.335306)
		(stroke
			(width 0.0508)
			(type default)
		)
		(layer "F.Cu")
	)
	(gr_line
		(start 121.447052 -237.736634)
		(end 121.447052 -238.305594)
		(stroke
			(width 0.0508)
			(type default)
		)
		(layer "F.Cu")
	)
	(gr_arc
		(start 121.519442 -222.502476)
		(mid 121.398195 -222.683919)
		(end 121.355612 -222.897954)
		(stroke
			(width 0.0508)
			(type default)
		)
		(layer "F.Cu")
	)
	(gr_arc
		(start 121.772172 -222.4405)
		(mid 121.642066 -222.456229)
		(end 121.519442 -222.502476)
		(stroke
			(width 0.0508)
			(type default)
		)
		(layer "F.Cu")
	)
	(gr_line
		(start 121.772172 -222.4405)
		(end 121.990612 -222.4405)
		(stroke
			(width 0.0508)
			(type default)
		)
		(layer "F.Cu")
	)
	(gr_arc
		(start 121.78792 -113.853214)
		(mid 121.795744 -113.903814)
		(end 121.8184 -113.949734)
		(stroke
			(width 0.0508)
			(type default)
		)
		(layer "F.Cu")
	)
	(gr_arc
		(start 121.789952 -254.020066)
		(mid 121.805389 -254.097737)
		(end 121.849388 -254.163576)
		(stroke
			(width 0.0508)
			(type default)
		)
		(layer "F.Cu")
	)
	(gr_line
		(start 121.789952 -253.912116)
		(end 121.789952 -254.020066)
		(stroke
			(width 0.0508)
			(type default)
		)
		(layer "F.Cu")
	)
	(gr_arc
		(start 121.789952 -249.341132)
		(mid 121.820438 -249.475116)
		(end 121.909332 -249.579892)
		(stroke
			(width 0.0508)
			(type default)
		)
		(layer "F.Cu")
	)
	(gr_arc
		(start 121.789952 -247.776492)
		(mid 121.820461 -247.910458)
		(end 121.909332 -248.015252)
		(stroke
			(width 0.0508)
			(type default)
		)
		(layer "F.Cu")
	)
	(gr_arc
		(start 121.789952 -246.211852)
		(mid 121.820446 -246.34583)
		(end 121.909332 -246.450612)
		(stroke
			(width 0.0508)
			(type default)
		)
		(layer "F.Cu")
	)
	(gr_arc
		(start 121.789952 -243.550186)
		(mid 121.820548 -243.684109)
		(end 121.909332 -243.788946)
		(stroke
			(width 0.0508)
			(type default)
		)
		(layer "F.Cu")
	)
	(gr_arc
		(start 121.789952 -241.985546)
		(mid 121.820534 -242.119481)
		(end 121.909332 -242.224306)
		(stroke
			(width 0.0508)
			(type default)
		)
		(layer "F.Cu")
	)
	(gr_arc
		(start 121.789952 -240.420906)
		(mid 121.820519 -240.554852)
		(end 121.909332 -240.659666)
		(stroke
			(width 0.0508)
			(type default)
		)
		(layer "F.Cu")
	)
	(gr_arc
		(start 121.789952 -237.391194)
		(mid 121.820514 -237.525144)
		(end 121.909332 -237.629954)
		(stroke
			(width 0.0508)
			(type default)
		)
		(layer "F.Cu")
	)
	(gr_arc
		(start 121.803414 -114.719862)
		(mid 121.791818 -114.757957)
		(end 121.78792 -114.797586)
		(stroke
			(width 0.0508)
			(type default)
		)
		(layer "F.Cu")
	)
	(gr_line
		(start 121.803414 -114.719862)
		(end 121.835672 -114.642138)
		(stroke
			(width 0.0508)
			(type default)
		)
		(layer "F.Cu")
	)
	(gr_line
		(start 121.8184 -113.949734)
		(end 121.844054 -113.986564)
		(stroke
			(width 0.0508)
			(type default)
		)
		(layer "F.Cu")
	)
	(gr_arc
		(start 121.844054 -113.986564)
		(mid 121.872626 -114.011662)
		(end 121.909586 -114.0206)
		(stroke
			(width 0.0508)
			(type default)
		)
		(layer "F.Cu")
	)
	(gr_line
		(start 121.849388 -254.163576)
		(end 121.940066 -254.254254)
		(stroke
			(width 0.0508)
			(type default)
		)
		(layer "F.Cu")
	)
	(gr_line
		(start 121.871994 -221.5515)
		(end 121.990612 -221.5515)
		(stroke
			(width 0.0508)
			(type default)
		)
		(layer "F.Cu")
	)
	(gr_arc
		(start 121.909332 -250.362212)
		(mid 121.820423 -250.466986)
		(end 121.789952 -250.600972)
		(stroke
			(width 0.0508)
			(type default)
		)
		(layer "F.Cu")
	)
	(gr_arc
		(start 121.909332 -250.362212)
		(mid 121.99822 -250.257417)
		(end 122.028712 -250.123452)
		(stroke
			(width 0.0508)
			(type default)
		)
		(layer "F.Cu")
	)
	(gr_arc
		(start 121.909332 -248.797572)
		(mid 121.820408 -248.902343)
		(end 121.789952 -249.036332)
		(stroke
			(width 0.0508)
			(type default)
		)
		(layer "F.Cu")
	)
	(gr_arc
		(start 121.909332 -248.797572)
		(mid 121.99822 -248.692777)
		(end 122.028712 -248.558812)
		(stroke
			(width 0.0508)
			(type default)
		)
		(layer "F.Cu")
	)
	(gr_arc
		(start 121.909332 -247.232932)
		(mid 121.82043 -247.337707)
		(end 121.789952 -247.471692)
		(stroke
			(width 0.0508)
			(type default)
		)
		(layer "F.Cu")
	)
	(gr_arc
		(start 121.909332 -247.232932)
		(mid 121.99822 -247.128137)
		(end 122.028712 -246.994172)
		(stroke
			(width 0.0508)
			(type default)
		)
		(layer "F.Cu")
	)
	(gr_arc
		(start 121.909332 -244.571266)
		(mid 121.820443 -244.676044)
		(end 121.789952 -244.810026)
		(stroke
			(width 0.0508)
			(type default)
		)
		(layer "F.Cu")
	)
	(gr_arc
		(start 121.909332 -244.571266)
		(mid 121.998126 -244.466452)
		(end 122.028712 -244.332506)
		(stroke
			(width 0.0508)
			(type default)
		)
		(layer "F.Cu")
	)
	(gr_arc
		(start 121.909332 -243.006626)
		(mid 121.820428 -243.111401)
		(end 121.789952 -243.245386)
		(stroke
			(width 0.0508)
			(type default)
		)
		(layer "F.Cu")
	)
	(gr_arc
		(start 121.909332 -243.006626)
		(mid 121.998126 -242.901812)
		(end 122.028712 -242.767866)
		(stroke
			(width 0.0508)
			(type default)
		)
		(layer "F.Cu")
	)
	(gr_arc
		(start 121.909332 -241.441986)
		(mid 121.820413 -241.546758)
		(end 121.789952 -241.680746)
		(stroke
			(width 0.0508)
			(type default)
		)
		(layer "F.Cu")
	)
	(gr_arc
		(start 121.909332 -241.441986)
		(mid 121.998126 -241.337172)
		(end 122.028712 -241.203226)
		(stroke
			(width 0.0508)
			(type default)
		)
		(layer "F.Cu")
	)
	(gr_arc
		(start 121.909332 -238.412274)
		(mid 121.820409 -238.517045)
		(end 121.789952 -238.651034)
		(stroke
			(width 0.0508)
			(type default)
		)
		(layer "F.Cu")
	)
	(gr_arc
		(start 121.909332 -238.412274)
		(mid 121.998126 -238.30746)
		(end 122.028712 -238.173514)
		(stroke
			(width 0.0508)
			(type default)
		)
		(layer "F.Cu")
	)
	(gr_line
		(start 121.909586 -114.0206)
		(end 121.93397 -114.0206)
		(stroke
			(width 0.0508)
			(type default)
		)
		(layer "F.Cu")
	)
	(gr_arc
		(start 121.929398 -114.5794)
		(mid 121.873002 -114.596531)
		(end 121.835672 -114.642138)
		(stroke
			(width 0.0508)
			(type default)
		)
		(layer "F.Cu")
	)
	(gr_line
		(start 121.929398 -114.5794)
		(end 121.93397 -114.5794)
		(stroke
			(width 0.0508)
			(type default)
		)
		(layer "F.Cu")
	)
	(gr_line
		(start 121.990612 -223.3295)
		(end 121.990612 -224.282)
		(stroke
			(width 0.0508)
			(type default)
		)
		(layer "F.Cu")
	)
	(gr_arc
		(start 121.999502 -254.397764)
		(mid 121.984054 -254.3201)
		(end 121.940066 -254.254254)
		(stroke
			(width 0.0508)
			(type default)
		)
		(layer "F.Cu")
	)
	(gr_line
		(start 121.999502 -254.397764)
		(end 121.999502 -256.25044)
		(stroke
			(width 0.0508)
			(type default)
		)
		(layer "F.Cu")
	)
	(gr_arc
		(start 122.028712 -249.818652)
		(mid 121.99822 -249.684659)
		(end 121.909332 -249.579892)
		(stroke
			(width 0.0508)
			(type default)
		)
		(layer "F.Cu")
	)
	(gr_line
		(start 122.028712 -249.818652)
		(end 122.028712 -250.123452)
		(stroke
			(width 0.0508)
			(type default)
		)
		(layer "F.Cu")
	)
	(gr_arc
		(start 122.028712 -248.254012)
		(mid 121.99822 -248.120019)
		(end 121.909332 -248.015252)
		(stroke
			(width 0.0508)
			(type default)
		)
		(layer "F.Cu")
	)
	(gr_line
		(start 122.028712 -248.254012)
		(end 122.028712 -248.558812)
		(stroke
			(width 0.0508)
			(type default)
		)
		(layer "F.Cu")
	)
	(gr_arc
		(start 122.028712 -246.689372)
		(mid 121.99822 -246.555379)
		(end 121.909332 -246.450612)
		(stroke
			(width 0.0508)
			(type default)
		)
		(layer "F.Cu")
	)
	(gr_line
		(start 122.028712 -246.689372)
		(end 122.028712 -246.994172)
		(stroke
			(width 0.0508)
			(type default)
		)
		(layer "F.Cu")
	)
	(gr_arc
		(start 122.028712 -244.027706)
		(mid 121.99822 -243.893713)
		(end 121.909332 -243.788946)
		(stroke
			(width 0.0508)
			(type default)
		)
		(layer "F.Cu")
	)
	(gr_line
		(start 122.028712 -244.027706)
		(end 122.028712 -244.332506)
		(stroke
			(width 0.0508)
			(type default)
		)
		(layer "F.Cu")
	)
	(gr_arc
		(start 122.028712 -242.463066)
		(mid 121.99822 -242.329073)
		(end 121.909332 -242.224306)
		(stroke
			(width 0.0508)
			(type default)
		)
		(layer "F.Cu")
	)
	(gr_line
		(start 122.028712 -242.463066)
		(end 122.028712 -242.767866)
		(stroke
			(width 0.0508)
			(type default)
		)
		(layer "F.Cu")
	)
	(gr_arc
		(start 122.028712 -240.898426)
		(mid 121.99822 -240.764433)
		(end 121.909332 -240.659666)
		(stroke
			(width 0.0508)
			(type default)
		)
		(layer "F.Cu")
	)
	(gr_line
		(start 122.028712 -240.898426)
		(end 122.028712 -241.203226)
		(stroke
			(width 0.0508)
			(type default)
		)
		(layer "F.Cu")
	)
	(gr_arc
		(start 122.028712 -237.868714)
		(mid 121.99822 -237.734721)
		(end 121.909332 -237.629954)
		(stroke
			(width 0.0508)
			(type default)
		)
		(layer "F.Cu")
	)
	(gr_line
		(start 122.028712 -237.868714)
		(end 122.028712 -238.173514)
		(stroke
			(width 0.0508)
			(type default)
		)
		(layer "F.Cu")
	)
	(gr_line
		(start 122.350022 -93.349826)
		(end 122.376946 -93.349826)
		(stroke
			(width 0.0508)
			(type default)
		)
		(layer "F.Cu")
	)
	(gr_line
		(start 122.350022 -92.349828)
		(end 122.372628 -92.349828)
		(stroke
			(width 0.0508)
			(type default)
		)
		(layer "F.Cu")
	)
	(gr_line
		(start 122.350022 -91.34983)
		(end 122.850148 -90.849704)
		(stroke
			(width 0.0508)
			(type default)
		)
		(layer "F.Cu")
	)
	(gr_line
		(start 122.350022 -90.349832)
		(end 122.850148 -89.849706)
		(stroke
			(width 0.0508)
			(type default)
		)
		(layer "F.Cu")
	)
	(gr_line
		(start 122.350022 -89.333578)
		(end 122.350022 -89.349834)
		(stroke
			(width 0.0508)
			(type default)
		)
		(layer "F.Cu")
	)
	(gr_line
		(start 122.350022 -89.333578)
		(end 122.833892 -88.849708)
		(stroke
			(width 0.0508)
			(type default)
		)
		(layer "F.Cu")
	)
	(gr_line
		(start 122.350022 -88.349836)
		(end 122.850148 -87.84971)
		(stroke
			(width 0.0508)
			(type default)
		)
		(layer "F.Cu")
	)
	(gr_arc
		(start 122.350022 -87.349838)
		(mid 122.399213 -87.34006)
		(end 122.440954 -87.312246)
		(stroke
			(width 0.0508)
			(type default)
		)
		(layer "F.Cu")
	)
	(gr_line
		(start 122.350022 -86.34984)
		(end 122.850148 -85.849714)
		(stroke
			(width 0.0508)
			(type default)
		)
		(layer "F.Cu")
	)
	(gr_line
		(start 122.350022 -85.294978)
		(end 122.350022 -85.349842)
		(stroke
			(width 0.0508)
			(type default)
		)
		(layer "F.Cu")
	)
	(gr_line
		(start 122.350022 -85.294978)
		(end 122.795284 -84.849716)
		(stroke
			(width 0.0508)
			(type default)
		)
		(layer "F.Cu")
	)
	(gr_line
		(start 122.350022 -84.349844)
		(end 122.850148 -83.849718)
		(stroke
			(width 0.0508)
			(type default)
		)
		(layer "F.Cu")
	)
	(gr_line
		(start 122.350022 -83.349846)
		(end 122.850148 -82.84972)
		(stroke
			(width 0.0508)
			(type default)
		)
		(layer "F.Cu")
	)
	(gr_line
		(start 122.372628 -92.349828)
		(end 122.850402 -92.827602)
		(stroke
			(width 0.0508)
			(type default)
		)
		(layer "F.Cu")
	)
	(gr_line
		(start 122.376946 -93.349826)
		(end 122.855482 -93.828362)
		(stroke
			(width 0.0508)
			(type default)
		)
		(layer "F.Cu")
	)
	(gr_line
		(start 122.440954 -87.312246)
		(end 122.831352 -86.921848)
		(stroke
			(width 0.0508)
			(type default)
		)
		(layer "F.Cu")
	)
	(gr_line
		(start 122.4788 -76.7588)
		(end 123.0884 -77.3684)
		(stroke
			(width 0.0508)
			(type default)
		)
		(layer "F.Cu")
	)
	(gr_line
		(start 122.795284 -84.849716)
		(end 122.850148 -84.849716)
		(stroke
			(width 0.0508)
			(type default)
		)
		(layer "F.Cu")
	)
	(gr_arc
		(start 122.831352 -86.921848)
		(mid 122.845257 -86.900977)
		(end 122.850148 -86.876382)
		(stroke
			(width 0.0508)
			(type default)
		)
		(layer "F.Cu")
	)
	(gr_line
		(start 122.833892 -88.849708)
		(end 122.850148 -88.849708)
		(stroke
			(width 0.0508)
			(type default)
		)
		(layer "F.Cu")
	)
	(gr_line
		(start 122.850148 -91.849702)
		(end 123.35002 -92.349574)
		(stroke
			(width 0.0508)
			(type default)
		)
		(layer "F.Cu")
	)
	(gr_line
		(start 122.850148 -86.849712)
		(end 122.850148 -86.876382)
		(stroke
			(width 0.0508)
			(type default)
		)
		(layer "F.Cu")
	)
	(gr_line
		(start 122.936 -81.788)
		(end 122.93727 -81.788)
		(stroke
			(width 0.0508)
			(type default)
		)
		(layer "F.Cu")
	)
	(gr_line
		(start 123.0884 -77.3684)
		(end 124.92736 -77.3684)
		(stroke
			(width 0.0508)
			(type default)
		)
		(layer "F.Cu")
	)
	(gr_arc
		(start 123.1519 -81.8769)
		(mid 123.053427 -81.811106)
		(end 122.93727 -81.788)
		(stroke
			(width 0.0508)
			(type default)
		)
		(layer "F.Cu")
	)
	(gr_line
		(start 123.1519 -81.8769)
		(end 123.2408 -81.9658)
		(stroke
			(width 0.0508)
			(type default)
		)
		(layer "F.Cu")
	)
	(gr_line
		(start 123.35002 -93.349826)
		(end 123.352306 -93.349826)
		(stroke
			(width 0.0508)
			(type default)
		)
		(layer "F.Cu")
	)
	(gr_line
		(start 123.35002 -92.349574)
		(end 123.35002 -92.349828)
		(stroke
			(width 0.0508)
			(type default)
		)
		(layer "F.Cu")
	)
	(gr_line
		(start 123.35002 -91.34983)
		(end 123.850146 -90.849704)
		(stroke
			(width 0.0508)
			(type default)
		)
		(layer "F.Cu")
	)
	(gr_line
		(start 123.35002 -90.349832)
		(end 123.850146 -89.849706)
		(stroke
			(width 0.0508)
			(type default)
		)
		(layer "F.Cu")
	)
	(gr_line
		(start 123.35002 -89.349834)
		(end 123.850146 -88.849708)
		(stroke
			(width 0.0508)
			(type default)
		)
		(layer "F.Cu")
	)
	(gr_line
		(start 123.35002 -88.349836)
		(end 123.850146 -87.84971)
		(stroke
			(width 0.0508)
			(type default)
		)
		(layer "F.Cu")
	)
	(gr_line
		(start 123.35002 -87.26678)
		(end 123.35002 -87.349838)
		(stroke
			(width 0.0508)
			(type default)
		)
		(layer "F.Cu")
	)
	(gr_line
		(start 123.35002 -87.26678)
		(end 123.767088 -86.849712)
		(stroke
			(width 0.0508)
			(type default)
		)
		(layer "F.Cu")
	)
	(gr_line
		(start 123.35002 -86.34984)
		(end 123.850146 -85.849714)
		(stroke
			(width 0.0508)
			(type default)
		)
		(layer "F.Cu")
	)
	(gr_line
		(start 123.35002 -85.31098)
		(end 123.35002 -85.349842)
		(stroke
			(width 0.0508)
			(type default)
		)
		(layer "F.Cu")
	)
	(gr_line
		(start 123.35002 -85.31098)
		(end 123.825 -84.836)
		(stroke
			(width 0.0508)
			(type default)
		)
		(layer "F.Cu")
	)
	(gr_line
		(start 123.35002 -84.349844)
		(end 123.850146 -83.849718)
		(stroke
			(width 0.0508)
			(type default)
		)
		(layer "F.Cu")
	)
	(gr_line
		(start 123.35002 -83.349846)
		(end 123.850146 -82.84972)
		(stroke
			(width 0.0508)
			(type default)
		)
		(layer "F.Cu")
	)
	(gr_arc
		(start 123.35002 -82.229452)
		(mid 123.321624 -82.086768)
		(end 123.2408 -81.9658)
		(stroke
			(width 0.0508)
			(type default)
		)
		(layer "F.Cu")
	)
	(gr_line
		(start 123.352306 -93.349826)
		(end 123.851162 -93.848682)
		(stroke
			(width 0.0508)
			(type default)
		)
		(layer "F.Cu")
	)
	(gr_arc
		(start 123.69292 -82.091276)
		(mid 123.708368 -82.16894)
		(end 123.752356 -82.234786)
		(stroke
			(width 0.0508)
			(type default)
		)
		(layer "F.Cu")
	)
	(gr_line
		(start 123.73737 -81.7626)
		(end 123.752356 -81.777586)
		(stroke
			(width 0.0508)
			(type default)
		)
		(layer "F.Cu")
	)
	(gr_line
		(start 123.752356 -82.234786)
		(end 123.807982 -82.290412)
		(stroke
			(width 0.0508)
			(type default)
		)
		(layer "F.Cu")
	)
	(gr_arc
		(start 123.752356 -81.798414)
		(mid 123.708361 -81.864257)
		(end 123.69292 -81.941924)
		(stroke
			(width 0.0508)
			(type default)
		)
		(layer "F.Cu")
	)
	(gr_line
		(start 123.752356 -81.777586)
		(end 123.752356 -81.798414)
		(stroke
			(width 0.0508)
			(type default)
		)
		(layer "F.Cu")
	)
	(gr_line
		(start 123.767088 -86.849712)
		(end 123.850146 -86.849712)
		(stroke
			(width 0.0508)
			(type default)
		)
		(layer "F.Cu")
	)
	(gr_arc
		(start 123.807982 -82.290412)
		(mid 123.873825 -82.334407)
		(end 123.951492 -82.349848)
		(stroke
			(width 0.0508)
			(type default)
		)
		(layer "F.Cu")
	)
	(gr_line
		(start 123.825 -84.793582)
		(end 123.825 -84.836)
		(stroke
			(width 0.0508)
			(type default)
		)
		(layer "F.Cu")
	)
	(gr_line
		(start 123.951492 -82.349848)
		(end 124.350018 -82.349848)
		(stroke
			(width 0.0508)
			(type default)
		)
		(layer "F.Cu")
	)
	(gr_line
		(start 124.92736 -77.3684)
		(end 125.507242 -77.948282)
		(stroke
			(width 0.0508)
			(type default)
		)
		(layer "F.Cu")
	)
	(gr_line
		(start 125.000512 -254.195326)
		(end 125.000512 -256.25044)
		(stroke
			(width 0.0508)
			(type default)
		)
		(layer "F.Cu")
	)
	(gr_arc
		(start 125.165612 -253.7968)
		(mid 125.043418 -253.979639)
		(end 125.000512 -254.195326)
		(stroke
			(width 0.0508)
			(type default)
		)
		(layer "F.Cu")
	)
	(gr_arc
		(start 125.165612 -253.7968)
		(mid 125.269019 -253.64204)
		(end 125.305312 -253.459488)
		(stroke
			(width 0.0508)
			(type default)
		)
		(layer "F.Cu")
	)
	(gr_line
		(start 125.305312 -251.314458)
		(end 125.305312 -251.883418)
		(stroke
			(width 0.0508)
			(type default)
		)
		(layer "F.Cu")
	)
	(gr_line
		(start 125.305312 -249.749818)
		(end 125.305312 -250.318778)
		(stroke
			(width 0.0508)
			(type default)
		)
		(layer "F.Cu")
	)
	(gr_line
		(start 125.305312 -248.185178)
		(end 125.305312 -248.754138)
		(stroke
			(width 0.0508)
			(type default)
		)
		(layer "F.Cu")
	)
	(gr_line
		(start 125.305312 -245.155212)
		(end 125.305312 -245.724172)
		(stroke
			(width 0.0508)
			(type default)
		)
		(layer "F.Cu")
	)
	(gr_line
		(start 125.305312 -243.590572)
		(end 125.305312 -244.159532)
		(stroke
			(width 0.0508)
			(type default)
		)
		(layer "F.Cu")
	)
	(gr_line
		(start 125.305312 -242.025932)
		(end 125.305312 -242.594892)
		(stroke
			(width 0.0508)
			(type default)
		)
		(layer "F.Cu")
	)
	(gr_line
		(start 125.350016 -92.349828)
		(end 125.600714 -92.60078)
		(stroke
			(width 0.0508)
			(type default)
		)
		(layer "F.Cu")
	)
	(gr_line
		(start 125.350016 -86.34984)
		(end 125.791468 -85.908388)
		(stroke
			(width 0.04445)
			(type default)
		)
		(layer "F.Cu")
	)
	(gr_line
		(start 125.350016 -84.349844)
		(end 125.616716 -84.083144)
		(stroke
			(width 0.04445)
			(type default)
		)
		(layer "F.Cu")
	)
	(gr_arc
		(start 125.600714 -92.60078)
		(mid 125.806296 -92.738065)
		(end 126.04877 -92.7862)
		(stroke
			(width 0.0508)
			(type default)
		)
		(layer "F.Cu")
	)
	(gr_arc
		(start 125.648212 -253.738126)
		(mid 125.66364 -253.815802)
		(end 125.707648 -253.881636)
		(stroke
			(width 0.0508)
			(type default)
		)
		(layer "F.Cu")
	)
	(gr_arc
		(start 125.648212 -250.969018)
		(mid 125.678788 -251.102955)
		(end 125.767592 -251.207778)
		(stroke
			(width 0.0508)
			(type default)
		)
		(layer "F.Cu")
	)
	(gr_arc
		(start 125.648212 -249.404378)
		(mid 125.67881 -249.538298)
		(end 125.767592 -249.643138)
		(stroke
			(width 0.0508)
			(type default)
		)
		(layer "F.Cu")
	)
	(gr_arc
		(start 125.648212 -247.839738)
		(mid 125.678795 -247.973669)
		(end 125.767592 -248.078498)
		(stroke
			(width 0.0508)
			(type default)
		)
		(layer "F.Cu")
	)
	(gr_arc
		(start 125.648212 -244.809772)
		(mid 125.678808 -244.943693)
		(end 125.767592 -245.048532)
		(stroke
			(width 0.0508)
			(type default)
		)
		(layer "F.Cu")
	)
	(gr_arc
		(start 125.648212 -243.245132)
		(mid 125.678793 -243.379065)
		(end 125.767592 -243.483892)
		(stroke
			(width 0.0508)
			(type default)
		)
		(layer "F.Cu")
	)
	(gr_arc
		(start 125.648212 -241.680492)
		(mid 125.678778 -241.814437)
		(end 125.767592 -241.919252)
		(stroke
			(width 0.0508)
			(type default)
		)
		(layer "F.Cu")
	)
	(gr_line
		(start 125.707648 -253.881636)
		(end 125.940566 -254.114554)
		(stroke
			(width 0.0508)
			(type default)
		)
		(layer "F.Cu")
	)
	(gr_arc
		(start 125.767592 -251.990098)
		(mid 125.678689 -252.094874)
		(end 125.648212 -252.228858)
		(stroke
			(width 0.0508)
			(type default)
		)
		(layer "F.Cu")
	)
	(gr_arc
		(start 125.767592 -251.990098)
		(mid 125.856386 -251.885284)
		(end 125.886972 -251.751338)
		(stroke
			(width 0.0508)
			(type default)
		)
		(layer "F.Cu")
	)
	(gr_arc
		(start 125.767592 -250.425458)
		(mid 125.678712 -250.530239)
		(end 125.648212 -250.664218)
		(stroke
			(width 0.0508)
			(type default)
		)
		(layer "F.Cu")
	)
	(gr_arc
		(start 125.767592 -250.425458)
		(mid 125.856386 -250.320644)
		(end 125.886972 -250.186698)
		(stroke
			(width 0.0508)
			(type default)
		)
		(layer "F.Cu")
	)
	(gr_arc
		(start 125.767592 -248.860818)
		(mid 125.678697 -248.965596)
		(end 125.648212 -249.099578)
		(stroke
			(width 0.0508)
			(type default)
		)
		(layer "F.Cu")
	)
	(gr_arc
		(start 125.767592 -248.860818)
		(mid 125.856386 -248.756004)
		(end 125.886972 -248.622058)
		(stroke
			(width 0.0508)
			(type default)
		)
		(layer "F.Cu")
	)
	(gr_arc
		(start 125.767592 -245.830852)
		(mid 125.678709 -245.935632)
		(end 125.648212 -246.069612)
		(stroke
			(width 0.0508)
			(type default)
		)
		(layer "F.Cu")
	)
	(gr_arc
		(start 125.767592 -245.830852)
		(mid 125.856386 -245.726038)
		(end 125.886972 -245.592092)
		(stroke
			(width 0.0508)
			(type default)
		)
		(layer "F.Cu")
	)
	(gr_arc
		(start 125.767592 -244.266212)
		(mid 125.678695 -244.370989)
		(end 125.648212 -244.504972)
		(stroke
			(width 0.0508)
			(type default)
		)
		(layer "F.Cu")
	)
	(gr_arc
		(start 125.767592 -244.266212)
		(mid 125.856386 -244.161398)
		(end 125.886972 -244.027452)
		(stroke
			(width 0.0508)
			(type default)
		)
		(layer "F.Cu")
	)
	(gr_arc
		(start 125.767592 -242.701572)
		(mid 125.67868 -242.806346)
		(end 125.648212 -242.940332)
		(stroke
			(width 0.0508)
			(type default)
		)
		(layer "F.Cu")
	)
	(gr_arc
		(start 125.767592 -242.701572)
		(mid 125.856386 -242.596758)
		(end 125.886972 -242.462812)
		(stroke
			(width 0.0508)
			(type default)
		)
		(layer "F.Cu")
	)
	(gr_line
		(start 125.791468 -85.908388)
		(end 126.013972 -85.764624)
		(stroke
			(width 0.04445)
			(type default)
		)
		(layer "F.Cu")
	)
	(gr_arc
		(start 125.886972 -251.446538)
		(mid 125.85648 -251.312545)
		(end 125.767592 -251.207778)
		(stroke
			(width 0.0508)
			(type default)
		)
		(layer "F.Cu")
	)
	(gr_line
		(start 125.886972 -251.446538)
		(end 125.886972 -251.751338)
		(stroke
			(width 0.0508)
			(type default)
		)
		(layer "F.Cu")
	)
	(gr_arc
		(start 125.886972 -249.881898)
		(mid 125.85648 -249.747905)
		(end 125.767592 -249.643138)
		(stroke
			(width 0.0508)
			(type default)
		)
		(layer "F.Cu")
	)
	(gr_line
		(start 125.886972 -249.881898)
		(end 125.886972 -250.186698)
		(stroke
			(width 0.0508)
			(type default)
		)
		(layer "F.Cu")
	)
	(gr_arc
		(start 125.886972 -248.317258)
		(mid 125.85648 -248.183265)
		(end 125.767592 -248.078498)
		(stroke
			(width 0.0508)
			(type default)
		)
		(layer "F.Cu")
	)
	(gr_line
		(start 125.886972 -248.317258)
		(end 125.886972 -248.622058)
		(stroke
			(width 0.0508)
			(type default)
		)
		(layer "F.Cu")
	)
	(gr_arc
		(start 125.886972 -245.287292)
		(mid 125.85648 -245.153299)
		(end 125.767592 -245.048532)
		(stroke
			(width 0.0508)
			(type default)
		)
		(layer "F.Cu")
	)
	(gr_line
		(start 125.886972 -245.287292)
		(end 125.886972 -245.592092)
		(stroke
			(width 0.0508)
			(type default)
		)
		(layer "F.Cu")
	)
	(gr_arc
		(start 125.886972 -243.722652)
		(mid 125.85648 -243.588659)
		(end 125.767592 -243.483892)
		(stroke
			(width 0.0508)
			(type default)
		)
		(layer "F.Cu")
	)
	(gr_line
		(start 125.886972 -243.722652)
		(end 125.886972 -244.027452)
		(stroke
			(width 0.0508)
			(type default)
		)
		(layer "F.Cu")
	)
	(gr_arc
		(start 125.886972 -242.158012)
		(mid 125.85648 -242.024019)
		(end 125.767592 -241.919252)
		(stroke
			(width 0.0508)
			(type default)
		)
		(layer "F.Cu")
	)
	(gr_line
		(start 125.886972 -242.158012)
		(end 125.886972 -242.462812)
		(stroke
			(width 0.0508)
			(type default)
		)
		(layer "F.Cu")
	)
	(gr_arc
		(start 125.95606 -94.60103)
		(mid 125.67802 -94.415156)
		(end 125.350016 -94.349824)
		(stroke
			(width 0.0508)
			(type default)
		)
		(layer "F.Cu")
	)
	(gr_line
		(start 125.95606 -94.60103)
		(end 126.1999 -94.844616)
		(stroke
			(width 0.0508)
			(type default)
		)
		(layer "F.Cu")
	)
	(gr_arc
		(start 125.95606 -90.601038)
		(mid 125.67802 -90.415164)
		(end 125.350016 -90.349832)
		(stroke
			(width 0.0508)
			(type default)
		)
		(layer "F.Cu")
	)
	(gr_line
		(start 125.95606 -90.601038)
		(end 126.1999 -90.844624)
		(stroke
			(width 0.0508)
			(type default)
		)
		(layer "F.Cu")
	)
	(gr_arc
		(start 125.95606 -88.601042)
		(mid 125.67802 -88.415168)
		(end 125.350016 -88.349836)
		(stroke
			(width 0.0508)
			(type default)
		)
		(layer "F.Cu")
	)
	(gr_line
		(start 125.95606 -88.601042)
		(end 126.1999 -88.844628)
		(stroke
			(width 0.0508)
			(type default)
		)
		(layer "F.Cu")
	)
	(gr_arc
		(start 126.000002 -254.258064)
		(mid 125.984554 -254.1804)
		(end 125.940566 -254.114554)
		(stroke
			(width 0.0508)
			(type default)
		)
		(layer "F.Cu")
	)
	(gr_line
		(start 126.000002 -254.258064)
		(end 126.000002 -256.25044)
		(stroke
			(width 0.0508)
			(type default)
		)
		(layer "F.Cu")
	)
	(gr_line
		(start 126.04877 -92.7862)
		(end 126.293118 -92.7862)
		(stroke
			(width 0.0508)
			(type default)
		)
		(layer "F.Cu")
	)
	(gr_arc
		(start 126.101602 -83.8327)
		(mid 125.839685 -83.920217)
		(end 125.616716 -84.083144)
		(stroke
			(width 0.04445)
			(type default)
		)
		(layer "F.Cu")
	)
	(gr_arc
		(start 126.110746 -85.724492)
		(mid 126.058354 -85.734913)
		(end 126.013972 -85.764624)
		(stroke
			(width 0.04445)
			(type default)
		)
		(layer "F.Cu")
	)
	(gr_arc
		(start 126.1237 -86.0298)
		(mid 126.13656 -86.111967)
		(end 126.181866 -86.181692)
		(stroke
			(width 0.04445)
			(type default)
		)
		(layer "F.Cu")
	)
	(gr_line
		(start 126.1237 -86.0298)
		(end 126.193042 -85.960458)
		(stroke
			(width 0.04445)
			(type default)
		)
		(layer "F.Cu")
	)
	(gr_line
		(start 126.181866 -86.181692)
		(end 126.350014 -86.34984)
		(stroke
			(width 0.04445)
			(type default)
		)
		(layer "F.Cu")
	)
	(gr_arc
		(start 126.1999 -94.844616)
		(mid 126.331004 -94.932207)
		(end 126.48565 -94.96298)
		(stroke
			(width 0.0508)
			(type default)
		)
		(layer "F.Cu")
	)
	(gr_arc
		(start 126.1999 -90.844624)
		(mid 126.331005 -90.932214)
		(end 126.48565 -90.962988)
		(stroke
			(width 0.0508)
			(type default)
		)
		(layer "F.Cu")
	)
	(gr_arc
		(start 126.1999 -88.844628)
		(mid 126.331005 -88.932217)
		(end 126.48565 -88.962992)
		(stroke
			(width 0.0508)
			(type default)
		)
		(layer "F.Cu")
	)
	(gr_arc
		(start 126.25197 -83.82)
		(mid 126.17652 -83.823195)
		(end 126.101602 -83.8327)
		(stroke
			(width 0.04445)
			(type default)
		)
		(layer "F.Cu")
	)
	(gr_line
		(start 126.25197 -83.82)
		(end 126.45517 -83.82)
		(stroke
			(width 0.04445)
			(type default)
		)
		(layer "F.Cu")
	)
	(gr_arc
		(start 126.30277 -85.914992)
		(mid 126.24338 -85.926805)
		(end 126.193042 -85.960458)
		(stroke
			(width 0.04445)
			(type default)
		)
		(layer "F.Cu")
	)
	(gr_arc
		(start 126.349506 -92.809568)
		(mid 126.323635 -92.792282)
		(end 126.293118 -92.7862)
		(stroke
			(width 0.0508)
			(type default)
		)
		(layer "F.Cu")
	)
	(gr_arc
		(start 126.349506 -92.809568)
		(mid 126.525951 -92.927426)
		(end 126.734062 -92.968826)
		(stroke
			(width 0.0508)
			(type default)
		)
		(layer "F.Cu")
	)
	(gr_line
		(start 126.350014 -94.349824)
		(end 126.517654 -94.517718)
		(stroke
			(width 0.0508)
			(type default)
		)
		(layer "F.Cu")
	)
	(gr_line
		(start 126.350014 -92.349828)
		(end 126.423166 -92.42298)
		(stroke
			(width 0.0508)
			(type default)
		)
		(layer "F.Cu")
	)
	(gr_arc
		(start 126.350014 -91.34983)
		(mid 126.377807 -91.489618)
		(end 126.456948 -91.608148)
		(stroke
			(width 0.0508)
			(type default)
		)
		(layer "F.Cu")
	)
	(gr_line
		(start 126.350014 -90.349832)
		(end 126.517654 -90.517726)
		(stroke
			(width 0.0508)
			(type default)
		)
		(layer "F.Cu")
	)
	(gr_line
		(start 126.350014 -89.349834)
		(end 126.600712 -89.600786)
		(stroke
			(width 0.0508)
			(type default)
		)
		(layer "F.Cu")
	)
	(gr_line
		(start 126.350014 -88.349836)
		(end 126.517654 -88.51773)
		(stroke
			(width 0.0508)
			(type default)
		)
		(layer "F.Cu")
	)
	(gr_line
		(start 126.350014 -87.349838)
		(end 126.600712 -87.60079)
		(stroke
			(width 0.0508)
			(type default)
		)
		(layer "F.Cu")
	)
	(gr_line
		(start 126.350014 -85.349842)
		(end 126.621286 -85.07857)
		(stroke
			(width 0.0508)
			(type default)
		)
		(layer "F.Cu")
	)
	(gr_line
		(start 126.350014 -84.349844)
		(end 126.671832 -84.02828)
		(stroke
			(width 0.04445)
			(type default)
		)
		(layer "F.Cu")
	)
	(gr_arc
		(start 126.423166 -92.42298)
		(mid 126.617293 -92.5759)
		(end 126.841758 -92.679266)
		(stroke
			(width 0.0508)
			(type default)
		)
		(layer "F.Cu")
	)
	(gr_line
		(start 126.456948 -91.608148)
		(end 126.584964 -91.736164)
		(stroke
			(width 0.0508)
			(type default)
		)
		(layer "F.Cu")
	)
	(gr_line
		(start 126.48565 -94.96298)
		(end 127.637032 -94.96298)
		(stroke
			(width 0.0508)
			(type default)
		)
		(layer "F.Cu")
	)
	(gr_line
		(start 126.48565 -90.962988)
		(end 126.74473 -90.962988)
		(stroke
			(width 0.0508)
			(type default)
		)
		(layer "F.Cu")
	)
	(gr_line
		(start 126.48565 -88.962992)
		(end 126.74473 -88.962992)
		(stroke
			(width 0.0508)
			(type default)
		)
		(layer "F.Cu")
	)
	(gr_arc
		(start 126.517654 -94.517718)
		(mid 126.577704 -94.572032)
		(end 126.642876 -94.62008)
		(stroke
			(width 0.0508)
			(type default)
		)
		(layer "F.Cu")
	)
	(gr_arc
		(start 126.517654 -90.517726)
		(mid 126.780338 -90.693169)
		(end 127.09017 -90.754708)
		(stroke
			(width 0.0508)
			(type default)
		)
		(layer "F.Cu")
	)
	(gr_arc
		(start 126.517654 -88.51773)
		(mid 126.780338 -88.693172)
		(end 127.09017 -88.754712)
		(stroke
			(width 0.0508)
			(type default)
		)
		(layer "F.Cu")
	)
	(gr_arc
		(start 126.52248 -82.93354)
		(mid 126.394856 -83.124543)
		(end 126.350014 -83.349846)
		(stroke
			(width 0.0508)
			(type default)
		)
		(layer "F.Cu")
	)
	(gr_line
		(start 126.52248 -82.93354)
		(end 126.727204 -82.728054)
		(stroke
			(width 0.0508)
			(type default)
		)
		(layer "F.Cu")
	)
	(gr_arc
		(start 126.584964 -91.736164)
		(mid 126.819675 -91.892959)
		(end 127.09652 -91.948)
		(stroke
			(width 0.0508)
			(type default)
		)
		(layer "F.Cu")
	)
	(gr_arc
		(start 126.600712 -89.600786)
		(mid 126.806294 -89.738071)
		(end 127.048768 -89.786206)
		(stroke
			(width 0.0508)
			(type default)
		)
		(layer "F.Cu")
	)
	(gr_arc
		(start 126.600712 -87.60079)
		(mid 126.806294 -87.738074)
		(end 127.048768 -87.78621)
		(stroke
			(width 0.0508)
			(type default)
		)
		(layer "F.Cu")
	)
	(gr_arc
		(start 126.608586 -83.7565)
		(mid 126.525576 -83.773012)
		(end 126.45517 -83.82)
		(stroke
			(width 0.04445)
			(type default)
		)
		(layer "F.Cu")
	)
	(gr_line
		(start 126.608586 -83.7565)
		(end 126.66853 -83.7565)
		(stroke
			(width 0.04445)
			(type default)
		)
		(layer "F.Cu")
	)
	(gr_line
		(start 126.621286 -85.07857)
		(end 126.66091 -85.038692)
		(stroke
			(width 0.0508)
			(type default)
		)
		(layer "F.Cu")
	)
	(gr_line
		(start 126.642876 -94.62008)
		(end 126.764796 -94.742)
		(stroke
			(width 0.0508)
			(type default)
		)
		(layer "F.Cu")
	)
	(gr_line
		(start 126.727204 -82.728054)
		(end 126.727712 -82.7278)
		(stroke
			(width 0.0508)
			(type default)
		)
		(layer "F.Cu")
	)
	(gr_line
		(start 126.727712 -82.7278)
		(end 126.739904 -82.715354)
		(stroke
			(width 0.0508)
			(type default)
		)
		(layer "F.Cu")
	)
	(gr_line
		(start 126.734062 -92.968826)
		(end 126.82093 -92.968826)
		(stroke
			(width 0.0508)
			(type default)
		)
		(layer "F.Cu")
	)
	(gr_line
		(start 126.739904 -82.715354)
		(end 126.774194 -82.681064)
		(stroke
			(width 0.0508)
			(type default)
		)
		(layer "F.Cu")
	)
	(gr_line
		(start 126.74727 -90.962988)
		(end 127.6604 -90.962988)
		(stroke
			(width 0.0508)
			(type default)
		)
		(layer "F.Cu")
	)
	(gr_line
		(start 126.74727 -88.962992)
		(end 127.6604 -88.962992)
		(stroke
			(width 0.0508)
			(type default)
		)
		(layer "F.Cu")
	)
	(gr_line
		(start 126.764796 -94.742)
		(end 127.901192 -94.742)
		(stroke
			(width 0.0508)
			(type default)
		)
		(layer "F.Cu")
	)
	(gr_line
		(start 126.774194 -82.681064)
		(end 126.786132 -82.669634)
		(stroke
			(width 0.0508)
			(type default)
		)
		(layer "F.Cu")
	)
	(gr_line
		(start 126.786132 -82.669634)
		(end 126.800864 -82.654648)
		(stroke
			(width 0.0508)
			(type default)
		)
		(layer "F.Cu")
	)
	(gr_line
		(start 126.800864 -82.654648)
		(end 126.908052 -82.547714)
		(stroke
			(width 0.0508)
			(type default)
		)
		(layer "F.Cu")
	)
	(gr_line
		(start 126.82347 -92.968826)
		(end 127.429768 -92.968826)
		(stroke
			(width 0.0508)
			(type default)
		)
		(layer "F.Cu")
	)
	(gr_arc
		(start 126.841758 -92.679266)
		(mid 127.002035 -92.717815)
		(end 127.16637 -92.730828)
		(stroke
			(width 0.0508)
			(type default)
		)
		(layer "F.Cu")
	)
	(gr_arc
		(start 126.86157 -83.94954)
		(mid 126.758882 -83.97006)
		(end 126.671832 -84.02828)
		(stroke
			(width 0.04445)
			(type default)
		)
		(layer "F.Cu")
	)
	(gr_arc
		(start 126.90983 -93.581728)
		(mid 126.652984 -93.410109)
		(end 126.350014 -93.349826)
		(stroke
			(width 0.0508)
			(type default)
		)
		(layer "F.Cu")
	)
	(gr_line
		(start 126.90983 -93.581728)
		(end 126.91237 -93.584268)
		(stroke
			(width 0.0508)
			(type default)
		)
		(layer "F.Cu")
	)
	(gr_arc
		(start 126.91237 -93.584268)
		(mid 127.209994 -93.783176)
		(end 127.561086 -93.853)
		(stroke
			(width 0.0508)
			(type default)
		)
		(layer "F.Cu")
	)
	(gr_line
		(start 127.048768 -89.786206)
		(end 127.293116 -89.786206)
		(stroke
			(width 0.0508)
			(type default)
		)
		(layer "F.Cu")
	)
	(gr_line
		(start 127.048768 -87.78621)
		(end 127.293116 -87.78621)
		(stroke
			(width 0.0508)
			(type default)
		)
		(layer "F.Cu")
	)
	(gr_line
		(start 127.09017 -90.754708)
		(end 127.913892 -90.754708)
		(stroke
			(width 0.0508)
			(type default)
		)
		(layer "F.Cu")
	)
	(gr_line
		(start 127.09017 -88.754712)
		(end 127.913892 -88.754712)
		(stroke
			(width 0.0508)
			(type default)
		)
		(layer "F.Cu")
	)
	(gr_line
		(start 127.09652 -91.948)
		(end 127.39624 -91.948)
		(stroke
			(width 0.0508)
			(type default)
		)
		(layer "F.Cu")
	)
	(gr_arc
		(start 127.14097 -83.132422)
		(mid 127.150603 -83.18094)
		(end 127.178054 -83.222084)
		(stroke
			(width 0.0508)
			(type default)
		)
		(layer "F.Cu")
	)
	(gr_line
		(start 127.14097 -82.852768)
		(end 127.14097 -83.132422)
		(stroke
			(width 0.0508)
			(type default)
		)
		(layer "F.Cu")
	)
	(gr_line
		(start 127.16637 -92.730828)
		(end 127.719328 -92.730828)
		(stroke
			(width 0.0508)
			(type default)
		)
		(layer "F.Cu")
	)
	(gr_line
		(start 127.178054 -83.222084)
		(end 127.274574 -83.318604)
		(stroke
			(width 0.0508)
			(type default)
		)
		(layer "F.Cu")
	)
	(gr_arc
		(start 127.178054 -82.763106)
		(mid 127.150621 -82.804257)
		(end 127.14097 -82.852768)
		(stroke
			(width 0.0508)
			(type default)
		)
		(layer "F.Cu")
	)
	(gr_line
		(start 127.191262 -84.818982)
		(end 127.45593 -84.818982)
		(stroke
			(width 0.0508)
			(type default)
		)
		(layer "F.Cu")
	)
	(gr_arc
		(start 127.274574 -83.318604)
		(mid 127.309185 -83.34173)
		(end 127.350012 -83.349846)
		(stroke
			(width 0.0508)
			(type default)
		)
		(layer "F.Cu")
	)
	(gr_arc
		(start 127.349504 -89.809574)
		(mid 127.323633 -89.792288)
		(end 127.293116 -89.786206)
		(stroke
			(width 0.0508)
			(type default)
		)
		(layer "F.Cu")
	)
	(gr_arc
		(start 127.349504 -89.809574)
		(mid 127.52595 -89.927432)
		(end 127.73406 -89.968832)
		(stroke
			(width 0.0508)
			(type default)
		)
		(layer "F.Cu")
	)
	(gr_arc
		(start 127.349504 -87.809578)
		(mid 127.323633 -87.792292)
		(end 127.293116 -87.78621)
		(stroke
			(width 0.0508)
			(type default)
		)
		(layer "F.Cu")
	)
	(gr_arc
		(start 127.349504 -87.809578)
		(mid 127.52595 -87.927435)
		(end 127.73406 -87.968836)
		(stroke
			(width 0.0508)
			(type default)
		)
		(layer "F.Cu")
	)
	(gr_arc
		(start 127.350012 -93.349826)
		(mid 127.438293 -93.421466)
		(end 127.539496 -93.47327)
		(stroke
			(width 0.0508)
			(type default)
		)
		(layer "F.Cu")
	)
	(gr_line
		(start 127.350012 -91.34983)
		(end 127.490728 -91.490546)
		(stroke
			(width 0.0508)
			(type default)
		)
		(layer "F.Cu")
	)
	(gr_line
		(start 127.350012 -89.349834)
		(end 127.423164 -89.422986)
		(stroke
			(width 0.0508)
			(type default)
		)
		(layer "F.Cu")
	)
	(gr_line
		(start 127.350012 -87.349838)
		(end 127.423164 -87.42299)
		(stroke
			(width 0.0508)
			(type default)
		)
		(layer "F.Cu")
	)
	(gr_line
		(start 127.350012 -85.349842)
		(end 127.351536 -85.348064)
		(stroke
			(width 0.0508)
			(type default)
		)
		(layer "F.Cu")
	)
	(gr_arc
		(start 127.355346 -85.344)
		(mid 127.353437 -85.346028)
		(end 127.351536 -85.348064)
		(stroke
			(width 0.0508)
			(type default)
		)
		(layer "F.Cu")
	)
	(gr_arc
		(start 127.39624 -91.948)
		(mid 127.512407 -91.924913)
		(end 127.61087 -91.8591)
		(stroke
			(width 0.0508)
			(type default)
		)
		(layer "F.Cu")
	)
	(gr_arc
		(start 127.423164 -89.422986)
		(mid 127.617285 -89.575918)
		(end 127.841756 -89.679272)
		(stroke
			(width 0.0508)
			(type default)
		)
		(layer "F.Cu")
	)
	(gr_arc
		(start 127.423164 -87.42299)
		(mid 127.617285 -87.575922)
		(end 127.841756 -87.679276)
		(stroke
			(width 0.0508)
			(type default)
		)
		(layer "F.Cu")
	)
	(gr_arc
		(start 127.539496 -93.47327)
		(mid 127.591351 -93.490372)
		(end 127.644652 -93.502226)
		(stroke
			(width 0.0508)
			(type default)
		)
		(layer "F.Cu")
	)
	(gr_arc
		(start 127.54737 -83.7565)
		(mid 127.645941 -83.736907)
		(end 127.729488 -83.681062)
		(stroke
			(width 0.04445)
			(type default)
		)
		(layer "F.Cu")
	)
	(gr_arc
		(start 127.563372 -93.024198)
		(mid 127.502074 -92.98324)
		(end 127.429768 -92.968826)
		(stroke
			(width 0.0508)
			(type default)
		)
		(layer "F.Cu")
	)
	(gr_arc
		(start 127.563372 -93.024198)
		(mid 127.646339 -93.079664)
		(end 127.74422 -93.099128)
		(stroke
			(width 0.0508)
			(type default)
		)
		(layer "F.Cu")
	)
	(gr_arc
		(start 127.58166 -83.94954)
		(mid 127.75417 -83.91518)
		(end 127.90043 -83.81746)
		(stroke
			(width 0.04445)
			(type default)
		)
		(layer "F.Cu")
	)
	(gr_line
		(start 127.637032 -94.96298)
		(end 127.686054 -95.012002)
		(stroke
			(width 0.0508)
			(type default)
		)
		(layer "F.Cu")
	)
	(gr_arc
		(start 127.703326 -85.169248)
		(mid 127.515631 -85.229337)
		(end 127.355346 -85.344)
		(stroke
			(width 0.0508)
			(type default)
		)
		(layer "F.Cu")
	)
	(gr_arc
		(start 127.719328 -92.730828)
		(mid 127.7474 -92.749641)
		(end 127.780542 -92.756228)
		(stroke
			(width 0.0508)
			(type default)
		)
		(layer "F.Cu")
	)
	(gr_line
		(start 127.729488 -83.681062)
		(end 127.92456 -83.48599)
		(stroke
			(width 0.04445)
			(type default)
		)
		(layer "F.Cu")
	)
	(gr_line
		(start 127.73406 -89.968832)
		(end 127.820928 -89.968832)
		(stroke
			(width 0.0508)
			(type default)
		)
		(layer "F.Cu")
	)
	(gr_line
		(start 127.73406 -87.968836)
		(end 127.820928 -87.968836)
		(stroke
			(width 0.0508)
			(type default)
		)
		(layer "F.Cu")
	)
	(gr_arc
		(start 127.80137 -91.021408)
		(mid 127.736692 -90.978192)
		(end 127.6604 -90.962988)
		(stroke
			(width 0.0508)
			(type default)
		)
		(layer "F.Cu")
	)
	(gr_arc
		(start 127.80137 -89.021412)
		(mid 127.736692 -88.978196)
		(end 127.6604 -88.962992)
		(stroke
			(width 0.0508)
			(type default)
		)
		(layer "F.Cu")
	)
	(gr_arc
		(start 127.80137 -85.161882)
		(mid 127.752205 -85.163666)
		(end 127.703326 -85.169248)
		(stroke
			(width 0.0508)
			(type default)
		)
		(layer "F.Cu")
	)
	(gr_line
		(start 127.823468 -89.968832)
		(end 128.768348 -89.968832)
		(stroke
			(width 0.0508)
			(type default)
		)
		(layer "F.Cu")
	)
	(gr_line
		(start 127.823468 -87.968836)
		(end 128.768348 -87.968836)
		(stroke
			(width 0.0508)
			(type default)
		)
		(layer "F.Cu")
	)
	(gr_arc
		(start 127.841756 -89.679272)
		(mid 128.002033 -89.717821)
		(end 128.166368 -89.730834)
		(stroke
			(width 0.0508)
			(type default)
		)
		(layer "F.Cu")
	)
	(gr_arc
		(start 127.841756 -87.679276)
		(mid 127.930508 -87.703919)
		(end 128.02108 -87.720678)
		(stroke
			(width 0.0508)
			(type default)
		)
		(layer "F.Cu")
	)
	(gr_line
		(start 127.90043 -83.81746)
		(end 127.96393 -83.75396)
		(stroke
			(width 0.04445)
			(type default)
		)
		(layer "F.Cu")
	)
	(gr_arc
		(start 127.940816 -83.447128)
		(mid 127.92882 -83.464943)
		(end 127.92456 -83.48599)
		(stroke
			(width 0.04445)
			(type default)
		)
		(layer "F.Cu")
	)
	(gr_line
		(start 127.940816 -83.447128)
		(end 127.98933 -83.39836)
		(stroke
			(width 0.04445)
			(type default)
		)
		(layer "F.Cu")
	)
	(gr_line
		(start 127.965962 -83.751928)
		(end 128.04013 -83.67776)
		(stroke
			(width 0.04445)
			(type default)
		)
		(layer "F.Cu")
	)
	(gr_line
		(start 127.98933 -83.39836)
		(end 128.063498 -83.324192)
		(stroke
			(width 0.0508)
			(type default)
		)
		(layer "F.Cu")
	)
	(gr_arc
		(start 128.02108 -87.720678)
		(mid 128.093548 -87.728278)
		(end 128.166368 -87.730838)
		(stroke
			(width 0.0508)
			(type default)
		)
		(layer "F.Cu")
	)
	(gr_line
		(start 128.04013 -83.67776)
		(end 128.143 -83.67776)
		(stroke
			(width 0.04445)
			(type default)
		)
		(layer "F.Cu")
	)
	(gr_arc
		(start 128.09474 -90.829638)
		(mid 128.011766 -90.774197)
		(end 127.913892 -90.754708)
		(stroke
			(width 0.0508)
			(type default)
		)
		(layer "F.Cu")
	)
	(gr_arc
		(start 128.09474 -88.829642)
		(mid 128.011766 -88.774201)
		(end 127.913892 -88.754712)
		(stroke
			(width 0.0508)
			(type default)
		)
		(layer "F.Cu")
	)
	(gr_arc
		(start 128.143 -83.67776)
		(mid 128.191116 -83.668191)
		(end 128.2319 -83.64093)
		(stroke
			(width 0.04445)
			(type default)
		)
		(layer "F.Cu")
	)
	(gr_line
		(start 128.166368 -89.730834)
		(end 128.768602 -89.730834)
		(stroke
			(width 0.0508)
			(type default)
		)
		(layer "F.Cu")
	)
	(gr_line
		(start 128.166368 -87.730838)
		(end 128.768602 -87.730838)
		(stroke
			(width 0.0508)
			(type default)
		)
		(layer "F.Cu")
	)
	(gr_line
		(start 128.305052 -85.695282)
		(end 128.32207 -85.7123)
		(stroke
			(width 0.04445)
			(type default)
		)
		(layer "F.Cu")
	)
	(gr_arc
		(start 128.32207 -85.7123)
		(mid 128.415769 -85.774892)
		(end 128.526286 -85.796882)
		(stroke
			(width 0.04445)
			(type default)
		)
		(layer "F.Cu")
	)
	(gr_line
		(start 128.419352 -85.539326)
		(end 128.468882 -85.539326)
		(stroke
			(width 0.04445)
			(type default)
		)
		(layer "F.Cu")
	)
	(gr_arc
		(start 128.468882 -85.539326)
		(mid 128.58036 -85.517128)
		(end 128.674876 -85.453982)
		(stroke
			(width 0.04445)
			(type default)
		)
		(layer "F.Cu")
	)
	(gr_line
		(start 128.526286 -85.796882)
		(end 128.686052 -85.796882)
		(stroke
			(width 0.04445)
			(type default)
		)
		(layer "F.Cu")
	)
	(gr_line
		(start 128.674876 -85.453982)
		(end 128.686052 -85.453982)
		(stroke
			(width 0.04445)
			(type default)
		)
		(layer "F.Cu")
	)
	(gr_line
		(start 128.686052 -85.796882)
		(end 128.735582 -85.796882)
		(stroke
			(width 0.0508)
			(type default)
		)
		(layer "F.Cu")
	)
	(gr_line
		(start 128.768348 -89.968832)
		(end 128.820926 -90.02141)
		(stroke
			(width 0.0508)
			(type default)
		)
		(layer "F.Cu")
	)
	(gr_line
		(start 128.768348 -87.968836)
		(end 128.820926 -88.021414)
		(stroke
			(width 0.0508)
			(type default)
		)
		(layer "F.Cu")
	)
	(gr_line
		(start 128.768602 -89.730834)
		(end 128.820926 -89.67851)
		(stroke
			(width 0.0508)
			(type default)
		)
		(layer "F.Cu")
	)
	(gr_line
		(start 128.768602 -87.730838)
		(end 128.820926 -87.678514)
		(stroke
			(width 0.0508)
			(type default)
		)
		(layer "F.Cu")
	)
	(gr_line
		(start 128.820926 -90.02141)
		(end 129.111502 -90.02141)
		(stroke
			(width 0.0508)
			(type default)
		)
		(layer "F.Cu")
	)
	(gr_line
		(start 128.820926 -89.67851)
		(end 129.111248 -89.67851)
		(stroke
			(width 0.0508)
			(type default)
		)
		(layer "F.Cu")
	)
	(gr_line
		(start 128.820926 -88.021414)
		(end 129.111502 -88.021414)
		(stroke
			(width 0.0508)
			(type default)
		)
		(layer "F.Cu")
	)
	(gr_line
		(start 128.820926 -87.678514)
		(end 129.111248 -87.678514)
		(stroke
			(width 0.0508)
			(type default)
		)
		(layer "F.Cu")
	)
	(gr_line
		(start 128.999742 -254.263144)
		(end 128.999742 -256.25044)
		(stroke
			(width 0.0508)
			(type default)
		)
		(layer "F.Cu")
	)
	(gr_arc
		(start 129.059178 -254.119634)
		(mid 129.015167 -254.185474)
		(end 128.999742 -254.263144)
		(stroke
			(width 0.0508)
			(type default)
		)
		(layer "F.Cu")
	)
	(gr_line
		(start 129.059178 -254.119634)
		(end 129.259076 -253.919736)
		(stroke
			(width 0.0508)
			(type default)
		)
		(layer "F.Cu")
	)
	(gr_arc
		(start 129.259076 -253.919736)
		(mid 129.28874 -253.881807)
		(end 129.308606 -253.837948)
		(stroke
			(width 0.0508)
			(type default)
		)
		(layer "F.Cu")
	)
	(gr_arc
		(start 129.308606 -253.837948)
		(mid 129.308993 -253.836425)
		(end 129.309368 -253.8349)
		(stroke
			(width 0.0508)
			(type default)
		)
		(layer "F.Cu")
	)
	(gr_arc
		(start 129.309368 -253.8349)
		(mid 129.316098 -253.805899)
		(end 129.318512 -253.776226)
		(stroke
			(width 0.0508)
			(type default)
		)
		(layer "F.Cu")
	)
	(gr_line
		(start 129.318512 -249.737372)
		(end 129.318512 -250.306332)
		(stroke
			(width 0.0508)
			(type default)
		)
		(layer "F.Cu")
	)
	(gr_line
		(start 129.318512 -248.172732)
		(end 129.318512 -248.741692)
		(stroke
			(width 0.0508)
			(type default)
		)
		(layer "F.Cu")
	)
	(gr_line
		(start 129.318512 -244.966744)
		(end 129.318512 -245.535704)
		(stroke
			(width 0.0508)
			(type default)
		)
		(layer "F.Cu")
	)
	(gr_line
		(start 129.318512 -243.402104)
		(end 129.318512 -243.971064)
		(stroke
			(width 0.0508)
			(type default)
		)
		(layer "F.Cu")
	)
	(gr_line
		(start 129.318512 -241.837464)
		(end 129.318512 -242.406424)
		(stroke
			(width 0.0508)
			(type default)
		)
		(layer "F.Cu")
	)
	(gr_arc
		(start 129.661412 -253.763526)
		(mid 129.67684 -253.841202)
		(end 129.720848 -253.907036)
		(stroke
			(width 0.0508)
			(type default)
		)
		(layer "F.Cu")
	)
	(gr_arc
		(start 129.661412 -249.391932)
		(mid 129.691993 -249.525865)
		(end 129.780792 -249.630692)
		(stroke
			(width 0.0508)
			(type default)
		)
		(layer "F.Cu")
	)
	(gr_arc
		(start 129.661412 -247.827292)
		(mid 129.691978 -247.961237)
		(end 129.780792 -248.066052)
		(stroke
			(width 0.0508)
			(type default)
		)
		(layer "F.Cu")
	)
	(gr_arc
		(start 129.661412 -244.621304)
		(mid 129.691982 -244.755245)
		(end 129.780792 -244.860064)
		(stroke
			(width 0.0508)
			(type default)
		)
		(layer "F.Cu")
	)
	(gr_arc
		(start 129.661412 -243.056664)
		(mid 129.692005 -243.190588)
		(end 129.780792 -243.295424)
		(stroke
			(width 0.0508)
			(type default)
		)
		(layer "F.Cu")
	)
	(gr_arc
		(start 129.661412 -241.492024)
		(mid 129.69199 -241.62596)
		(end 129.780792 -241.730784)
		(stroke
			(width 0.0508)
			(type default)
		)
		(layer "F.Cu")
	)
	(gr_line
		(start 129.720848 -253.907036)
		(end 129.764536 -253.95047)
		(stroke
			(width 0.0508)
			(type default)
		)
		(layer "F.Cu")
	)
	(gr_arc
		(start 129.764536 -253.95047)
		(mid 129.795259 -253.975691)
		(end 129.830322 -253.994412)
		(stroke
			(width 0.0508)
			(type default)
		)
		(layer "F.Cu")
	)
	(gr_arc
		(start 129.780792 -250.413012)
		(mid 129.691978 -250.517836)
		(end 129.661412 -250.651772)
		(stroke
			(width 0.0508)
			(type default)
		)
		(layer "F.Cu")
	)
	(gr_arc
		(start 129.780792 -250.413012)
		(mid 129.869586 -250.308198)
		(end 129.900172 -250.174252)
		(stroke
			(width 0.0508)
			(type default)
		)
		(layer "F.Cu")
	)
	(gr_arc
		(start 129.780792 -248.848372)
		(mid 129.692 -248.953201)
		(end 129.661412 -249.087132)
		(stroke
			(width 0.0508)
			(type default)
		)
		(layer "F.Cu")
	)
	(gr_arc
		(start 129.780792 -248.848372)
		(mid 129.869586 -248.743558)
		(end 129.900172 -248.609612)
		(stroke
			(width 0.0508)
			(type default)
		)
		(layer "F.Cu")
	)
	(gr_arc
		(start 129.780792 -245.642384)
		(mid 129.691884 -245.747159)
		(end 129.661412 -245.881144)
		(stroke
			(width 0.0508)
			(type default)
		)
		(layer "F.Cu")
	)
	(gr_arc
		(start 129.780792 -245.642384)
		(mid 129.869586 -245.53757)
		(end 129.900172 -245.403624)
		(stroke
			(width 0.0508)
			(type default)
		)
		(layer "F.Cu")
	)
	(gr_arc
		(start 129.780792 -244.077744)
		(mid 129.691906 -244.182524)
		(end 129.661412 -244.316504)
		(stroke
			(width 0.0508)
			(type default)
		)
		(layer "F.Cu")
	)
	(gr_arc
		(start 129.780792 -244.077744)
		(mid 129.869586 -243.97293)
		(end 129.900172 -243.838984)
		(stroke
			(width 0.0508)
			(type default)
		)
		(layer "F.Cu")
	)
	(gr_arc
		(start 129.780792 -242.513104)
		(mid 129.691892 -242.617881)
		(end 129.661412 -242.751864)
		(stroke
			(width 0.0508)
			(type default)
		)
		(layer "F.Cu")
	)
	(gr_arc
		(start 129.780792 -242.513104)
		(mid 129.869586 -242.40829)
		(end 129.900172 -242.274344)
		(stroke
			(width 0.0508)
			(type default)
		)
		(layer "F.Cu")
	)
	(gr_line
		(start 129.830322 -253.994412)
		(end 129.92481 -254.033274)
		(stroke
			(width 0.0508)
			(type default)
		)
		(layer "F.Cu")
	)
	(gr_arc
		(start 129.900172 -249.869452)
		(mid 129.869586 -249.735534)
		(end 129.780792 -249.630692)
		(stroke
			(width 0.0508)
			(type default)
		)
		(layer "F.Cu")
	)
	(gr_line
		(start 129.900172 -249.869452)
		(end 129.900172 -250.174252)
		(stroke
			(width 0.0508)
			(type default)
		)
		(layer "F.Cu")
	)
	(gr_arc
		(start 129.900172 -248.304812)
		(mid 129.869586 -248.170894)
		(end 129.780792 -248.066052)
		(stroke
			(width 0.0508)
			(type default)
		)
		(layer "F.Cu")
	)
	(gr_line
		(start 129.900172 -248.304812)
		(end 129.900172 -248.609612)
		(stroke
			(width 0.0508)
			(type default)
		)
		(layer "F.Cu")
	)
	(gr_arc
		(start 129.900172 -245.098824)
		(mid 129.86968 -244.964831)
		(end 129.780792 -244.860064)
		(stroke
			(width 0.0508)
			(type default)
		)
		(layer "F.Cu")
	)
	(gr_line
		(start 129.900172 -245.098824)
		(end 129.900172 -245.403624)
		(stroke
			(width 0.0508)
			(type default)
		)
		(layer "F.Cu")
	)
	(gr_arc
		(start 129.900172 -243.534184)
		(mid 129.86968 -243.400191)
		(end 129.780792 -243.295424)
		(stroke
			(width 0.0508)
			(type default)
		)
		(layer "F.Cu")
	)
	(gr_line
		(start 129.900172 -243.534184)
		(end 129.900172 -243.838984)
		(stroke
			(width 0.0508)
			(type default)
		)
		(layer "F.Cu")
	)
	(gr_arc
		(start 129.900172 -241.969544)
		(mid 129.86968 -241.835551)
		(end 129.780792 -241.730784)
		(stroke
			(width 0.0508)
			(type default)
		)
		(layer "F.Cu")
	)
	(gr_line
		(start 129.900172 -241.969544)
		(end 129.900172 -242.274344)
		(stroke
			(width 0.0508)
			(type default)
		)
		(layer "F.Cu")
	)
	(gr_arc
		(start 129.98323 -254.091948)
		(mid 129.959867 -254.056784)
		(end 129.92481 -254.033274)
		(stroke
			(width 0.0508)
			(type default)
		)
		(layer "F.Cu")
	)
	(gr_line
		(start 129.98323 -254.091948)
		(end 129.99212 -254.113538)
		(stroke
			(width 0.0508)
			(type default)
		)
		(layer "F.Cu")
	)
	(gr_arc
		(start 130.000502 -254.155194)
		(mid 129.998361 -254.133953)
		(end 129.99212 -254.113538)
		(stroke
			(width 0.0508)
			(type default)
		)
		(layer "F.Cu")
	)
	(gr_line
		(start 130.000502 -254.155194)
		(end 130.000502 -256.25044)
		(stroke
			(width 0.0508)
			(type default)
		)
		(layer "F.Cu")
	)
	(gr_arc
		(start 130.532124 -84.6201)
		(mid 130.567324 -84.613123)
		(end 130.597148 -84.593176)
		(stroke
			(width 0.0508)
			(type default)
		)
		(layer "F.Cu")
	)
	(gr_line
		(start 130.597148 -84.593176)
		(end 130.790442 -84.399882)
		(stroke
			(width 0.0508)
			(type default)
		)
		(layer "F.Cu")
	)
	(gr_arc
		(start 130.732022 -87.376)
		(mid 130.897942 -87.34299)
		(end 131.0386 -87.249)
		(stroke
			(width 0.0508)
			(type default)
		)
		(layer "F.Cu")
	)
	(gr_arc
		(start 130.7338 -89.916)
		(mid 130.898073 -89.883327)
		(end 131.03733 -89.79027)
		(stroke
			(width 0.0508)
			(type default)
		)
		(layer "F.Cu")
	)
	(gr_arc
		(start 130.7846 -88.646)
		(mid 130.901876 -88.622593)
		(end 131.001262 -88.556084)
		(stroke
			(width 0.0508)
			(type default)
		)
		(layer "F.Cu")
	)
	(gr_arc
		(start 130.790442 -85.034882)
		(mid 130.710848 -84.981699)
		(end 130.61696 -84.963)
		(stroke
			(width 0.0508)
			(type default)
		)
		(layer "F.Cu")
	)
	(gr_line
		(start 130.809746 -91.3511)
		(end 130.946652 -91.3511)
		(stroke
			(width 0.0508)
			(type default)
		)
		(layer "F.Cu")
	)
	(gr_arc
		(start 130.936492 -89.051638)
		(mid 130.866788 -89.005157)
		(end 130.7846 -88.9889)
		(stroke
			(width 0.0508)
			(type default)
		)
		(layer "F.Cu")
	)
	(gr_line
		(start 130.936492 -89.051638)
		(end 131.0386 -89.154)
		(stroke
			(width 0.0508)
			(type default)
		)
		(layer "F.Cu")
	)
	(gr_arc
		(start 130.946652 -91.3511)
		(mid 130.996411 -91.341187)
		(end 131.0386 -91.313)
		(stroke
			(width 0.0508)
			(type default)
		)
		(layer "F.Cu")
	)
	(gr_arc
		(start 130.972306 -90.357706)
		(mid 130.862879 -90.284589)
		(end 130.7338 -90.2589)
		(stroke
			(width 0.0508)
			(type default)
		)
		(layer "F.Cu")
	)
	(gr_line
		(start 130.972306 -90.357706)
		(end 131.0386 -90.424)
		(stroke
			(width 0.0508)
			(type default)
		)
		(layer "F.Cu")
	)
	(gr_line
		(start 131.001262 -88.556084)
		(end 131.0386 -88.519)
		(stroke
			(width 0.0508)
			(type default)
		)
		(layer "F.Cu")
	)
	(gr_line
		(start 131.03733 -89.79027)
		(end 131.0386 -89.789)
		(stroke
			(width 0.0508)
			(type default)
		)
		(layer "F.Cu")
	)
	(gr_arc
		(start 131.0386 -91.9226)
		(mid 130.971645 -91.760955)
		(end 130.81 -91.694)
		(stroke
			(width 0.0508)
			(type default)
		)
		(layer "F.Cu")
	)
	(gr_line
		(start 131.0386 -91.9226)
		(end 131.0386 -91.948)
		(stroke
			(width 0.0508)
			(type default)
		)
		(layer "F.Cu")
	)
	(gr_arc
		(start 131.0386 -87.884)
		(mid 130.855755 -87.761827)
		(end 130.640074 -87.7189)
		(stroke
			(width 0.0508)
			(type default)
		)
		(layer "F.Cu")
	)
	(gr_line
		(start 131.135882 -81.426558)
		(end 131.280916 -81.571846)
		(stroke
			(width 0.0508)
			(type default)
		)
		(layer "F.Cu")
	)
	(gr_line
		(start 131.135882 -80.562958)
		(end 131.135882 -80.867758)
		(stroke
			(width 0.0508)
			(type default)
		)
		(layer "F.Cu")
	)
	(gr_arc
		(start 131.135882 -79.80045)
		(mid 131.086573 -79.767566)
		(end 131.02844 -79.756)
		(stroke
			(width 0.0508)
			(type default)
		)
		(layer "F.Cu")
	)
	(gr_line
		(start 131.135882 -79.80045)
		(end 131.342892 -80.00746)
		(stroke
			(width 0.0508)
			(type default)
		)
		(layer "F.Cu")
	)
	(gr_arc
		(start 131.15417 -99.502722)
		(mid 131.121823 -99.340104)
		(end 131.02971 -99.20224)
		(stroke
			(width 0.0508)
			(type default)
		)
		(layer "F.Cu")
	)
	(gr_arc
		(start 131.237482 -80.461358)
		(mid 131.165637 -80.49112)
		(end 131.135882 -80.562958)
		(stroke
			(width 0.0508)
			(type default)
		)
		(layer "F.Cu")
	)
	(gr_line
		(start 131.237482 -80.461358)
		(end 131.243832 -80.461358)
		(stroke
			(width 0.0508)
			(type default)
		)
		(layer "F.Cu")
	)
	(gr_arc
		(start 131.243832 -80.461358)
		(mid 131.315674 -80.4316)
		(end 131.345432 -80.359758)
		(stroke
			(width 0.0508)
			(type default)
		)
		(layer "F.Cu")
	)
	(gr_line
		(start 131.349242 -85.034882)
		(end 131.63296 -85.034882)
		(stroke
			(width 0.0508)
			(type default)
		)
		(layer "F.Cu")
	)
	(gr_line
		(start 131.349242 -84.399882)
		(end 131.63296 -84.399882)
		(stroke
			(width 0.0508)
			(type default)
		)
		(layer "F.Cu")
	)
	(gr_arc
		(start 131.52247 -98.300032)
		(mid 131.559449 -98.485874)
		(end 131.66471 -98.64344)
		(stroke
			(width 0.0508)
			(type default)
		)
		(layer "F.Cu")
	)
	(gr_line
		(start 131.52247 -98.281744)
		(end 131.52247 -98.300032)
		(stroke
			(width 0.0508)
			(type default)
		)
		(layer "F.Cu")
	)
	(gr_arc
		(start 131.572 -82.7151)
		(mid 131.702456 -82.689176)
		(end 131.813046 -82.615278)
		(stroke
			(width 0.0508)
			(type default)
		)
		(layer "F.Cu")
	)
	(gr_line
		(start 131.5974 -91.948)
		(end 131.900422 -91.948)
		(stroke
			(width 0.0508)
			(type default)
		)
		(layer "F.Cu")
	)
	(gr_line
		(start 131.5974 -91.313)
		(end 131.861814 -91.313)
		(stroke
			(width 0.0508)
			(type default)
		)
		(layer "F.Cu")
	)
	(gr_line
		(start 131.5974 -90.424)
		(end 131.881118 -90.424)
		(stroke
			(width 0.0508)
			(type default)
		)
		(layer "F.Cu")
	)
	(gr_line
		(start 131.5974 -89.789)
		(end 131.881118 -89.789)
		(stroke
			(width 0.0508)
			(type default)
		)
		(layer "F.Cu")
	)
	(gr_line
		(start 131.5974 -89.154)
		(end 131.900422 -89.154)
		(stroke
			(width 0.0508)
			(type default)
		)
		(layer "F.Cu")
	)
	(gr_line
		(start 131.5974 -88.519)
		(end 131.861814 -88.519)
		(stroke
			(width 0.0508)
			(type default)
		)
		(layer "F.Cu")
	)
	(gr_line
		(start 131.5974 -87.884)
		(end 131.881118 -87.884)
		(stroke
			(width 0.0508)
			(type default)
		)
		(layer "F.Cu")
	)
	(gr_line
		(start 131.5974 -87.249)
		(end 131.881118 -87.249)
		(stroke
			(width 0.0508)
			(type default)
		)
		(layer "F.Cu")
	)
	(gr_arc
		(start 131.63296 -85.034882)
		(mid 131.671855 -85.027163)
		(end 131.704842 -85.005164)
		(stroke
			(width 0.0508)
			(type default)
		)
		(layer "F.Cu")
	)
	(gr_arc
		(start 131.655058 -99.211638)
		(mid 131.538075 -99.386797)
		(end 131.49707 -99.5934)
		(stroke
			(width 0.0508)
			(type default)
		)
		(layer "F.Cu")
	)
	(gr_line
		(start 131.655058 -99.211638)
		(end 131.66471 -99.20224)
		(stroke
			(width 0.0508)
			(type default)
		)
		(layer "F.Cu")
	)
	(gr_arc
		(start 131.688332 -80.359758)
		(mid 131.718077 -80.431616)
		(end 131.789932 -80.461358)
		(stroke
			(width 0.0508)
			(type default)
		)
		(layer "F.Cu")
	)
	(gr_line
		(start 131.704842 -85.005164)
		(end 131.791456 -84.91855)
		(stroke
			(width 0.0508)
			(type default)
		)
		(layer "F.Cu")
	)
	(gr_arc
		(start 131.704842 -84.4296)
		(mid 131.671853 -84.407602)
		(end 131.63296 -84.399882)
		(stroke
			(width 0.0508)
			(type default)
		)
		(layer "F.Cu")
	)
	(gr_line
		(start 131.704842 -84.4296)
		(end 131.791456 -84.516214)
		(stroke
			(width 0.0508)
			(type default)
		)
		(layer "F.Cu")
	)
	(gr_line
		(start 131.789932 -80.461358)
		(end 131.796282 -80.461358)
		(stroke
			(width 0.0508)
			(type default)
		)
		(layer "F.Cu")
	)
	(gr_arc
		(start 131.791456 -84.516214)
		(mid 131.82445 -84.538197)
		(end 131.863338 -84.545932)
		(stroke
			(width 0.0508)
			(type default)
		)
		(layer "F.Cu")
	)
	(gr_line
		(start 131.813046 -82.615278)
		(end 131.933442 -82.494882)
		(stroke
			(width 0.0508)
			(type default)
		)
		(layer "F.Cu")
	)
	(gr_arc
		(start 131.861814 -91.313)
		(mid 132.048635 -91.275839)
		(end 132.207 -91.169998)
		(stroke
			(width 0.0508)
			(type default)
		)
		(layer "F.Cu")
	)
	(gr_arc
		(start 131.861814 -88.519)
		(mid 132.048635 -88.481839)
		(end 132.207 -88.375998)
		(stroke
			(width 0.0508)
			(type default)
		)
		(layer "F.Cu")
	)
	(gr_arc
		(start 131.863338 -84.888832)
		(mid 131.82445 -84.896564)
		(end 131.791456 -84.91855)
		(stroke
			(width 0.0508)
			(type default)
		)
		(layer "F.Cu")
	)
	(gr_arc
		(start 131.881118 -90.424)
		(mid 131.920013 -90.416281)
		(end 131.953 -90.394282)
		(stroke
			(width 0.0508)
			(type default)
		)
		(layer "F.Cu")
	)
	(gr_arc
		(start 131.881118 -87.884)
		(mid 131.920013 -87.876281)
		(end 131.953 -87.854282)
		(stroke
			(width 0.0508)
			(type default)
		)
		(layer "F.Cu")
	)
	(gr_arc
		(start 131.897882 -81.426558)
		(mid 131.73031 -81.495968)
		(end 131.6609 -81.66354)
		(stroke
			(width 0.0508)
			(type default)
		)
		(layer "F.Cu")
	)
	(gr_arc
		(start 131.897882 -80.562958)
		(mid 131.868124 -80.491116)
		(end 131.796282 -80.461358)
		(stroke
			(width 0.0508)
			(type default)
		)
		(layer "F.Cu")
	)
	(gr_line
		(start 131.897882 -80.562958)
		(end 131.897882 -80.867758)
		(stroke
			(width 0.0508)
			(type default)
		)
		(layer "F.Cu")
	)
	(gr_arc
		(start 131.933442 -83.129882)
		(mid 131.853848 -83.076699)
		(end 131.75996 -83.058)
		(stroke
			(width 0.0508)
			(type default)
		)
		(layer "F.Cu")
	)
	(gr_arc
		(start 131.942332 -79.756)
		(mid 131.762706 -79.830384)
		(end 131.688332 -80.01)
		(stroke
			(width 0.0508)
			(type default)
		)
		(layer "F.Cu")
	)
	(gr_line
		(start 131.942332 -79.756)
		(end 132.005324 -79.756)
		(stroke
			(width 0.0508)
			(type default)
		)
		(layer "F.Cu")
	)
	(gr_line
		(start 131.953 -90.394282)
		(end 132.039614 -90.307668)
		(stroke
			(width 0.0508)
			(type default)
		)
		(layer "F.Cu")
	)
	(gr_arc
		(start 131.953 -89.818718)
		(mid 131.920016 -89.796697)
		(end 131.881118 -89.789)
		(stroke
			(width 0.0508)
			(type default)
		)
		(layer "F.Cu")
	)
	(gr_line
		(start 131.953 -89.818718)
		(end 132.039614 -89.905332)
		(stroke
			(width 0.0508)
			(type default)
		)
		(layer "F.Cu")
	)
	(gr_line
		(start 131.953 -87.854282)
		(end 132.039614 -87.767668)
		(stroke
			(width 0.0508)
			(type default)
		)
		(layer "F.Cu")
	)
	(gr_arc
		(start 131.953 -87.278718)
		(mid 131.920016 -87.256697)
		(end 131.881118 -87.249)
		(stroke
			(width 0.0508)
			(type default)
		)
		(layer "F.Cu")
	)
	(gr_line
		(start 131.953 -87.278718)
		(end 132.039614 -87.365332)
		(stroke
			(width 0.0508)
			(type default)
		)
		(layer "F.Cu")
	)
	(gr_arc
		(start 132.039614 -89.905332)
		(mid 132.072608 -89.927315)
		(end 132.111496 -89.93505)
		(stroke
			(width 0.0508)
			(type default)
		)
		(layer "F.Cu")
	)
	(gr_arc
		(start 132.039614 -87.365332)
		(mid 132.072608 -87.387315)
		(end 132.111496 -87.39505)
		(stroke
			(width 0.0508)
			(type default)
		)
		(layer "F.Cu")
	)
	(gr_arc
		(start 132.111496 -90.27795)
		(mid 132.072618 -90.285697)
		(end 132.039614 -90.307668)
		(stroke
			(width 0.0508)
			(type default)
		)
		(layer "F.Cu")
	)
	(gr_arc
		(start 132.111496 -87.73795)
		(mid 132.072618 -87.745697)
		(end 132.039614 -87.767668)
		(stroke
			(width 0.0508)
			(type default)
		)
		(layer "F.Cu")
	)
	(gr_arc
		(start 132.207 -92.075)
		(mid 132.066346 -91.980991)
		(end 131.900422 -91.948)
		(stroke
			(width 0.0508)
			(type default)
		)
		(layer "F.Cu")
	)
	(gr_arc
		(start 132.207 -89.281)
		(mid 132.066346 -89.186991)
		(end 131.900422 -89.154)
		(stroke
			(width 0.0508)
			(type default)
		)
		(layer "F.Cu")
	)
	(gr_line
		(start 132.492242 -83.129882)
		(end 132.77596 -83.129882)
		(stroke
			(width 0.0508)
			(type default)
		)
		(layer "F.Cu")
	)
	(gr_line
		(start 132.492242 -82.494882)
		(end 132.77596 -82.494882)
		(stroke
			(width 0.0508)
			(type default)
		)
		(layer "F.Cu")
	)
	(gr_arc
		(start 132.72897 -99.369118)
		(mid 132.73669 -99.408013)
		(end 132.758688 -99.441)
		(stroke
			(width 0.0508)
			(type default)
		)
		(layer "F.Cu")
	)
	(gr_line
		(start 132.72897 -99.0854)
		(end 132.72897 -99.369118)
		(stroke
			(width 0.0508)
			(type default)
		)
		(layer "F.Cu")
	)
	(gr_arc
		(start 132.72897 -98.5266)
		(mid 132.822955 -98.385941)
		(end 132.85597 -98.220022)
		(stroke
			(width 0.0508)
			(type default)
		)
		(layer "F.Cu")
	)
	(gr_line
		(start 132.758688 -99.441)
		(end 132.845302 -99.527614)
		(stroke
			(width 0.0508)
			(type default)
		)
		(layer "F.Cu")
	)
	(gr_arc
		(start 132.77596 -83.129882)
		(mid 132.814855 -83.122163)
		(end 132.847842 -83.100164)
		(stroke
			(width 0.0508)
			(type default)
		)
		(layer "F.Cu")
	)
	(gr_line
		(start 132.847842 -83.100164)
		(end 132.934456 -83.01355)
		(stroke
			(width 0.0508)
			(type default)
		)
		(layer "F.Cu")
	)
	(gr_arc
		(start 132.847842 -82.5246)
		(mid 132.814853 -82.502602)
		(end 132.77596 -82.494882)
		(stroke
			(width 0.0508)
			(type default)
		)
		(layer "F.Cu")
	)
	(gr_line
		(start 132.847842 -82.5246)
		(end 132.934456 -82.611214)
		(stroke
			(width 0.0508)
			(type default)
		)
		(layer "F.Cu")
	)
	(gr_arc
		(start 132.87502 -99.599496)
		(mid 132.867301 -99.560601)
		(end 132.845302 -99.527614)
		(stroke
			(width 0.0508)
			(type default)
		)
		(layer "F.Cu")
	)
	(gr_line
		(start 132.930392 -81.117186)
		(end 133.193282 -81.380076)
		(stroke
			(width 0.0508)
			(type default)
		)
		(layer "F.Cu")
	)
	(gr_arc
		(start 132.934456 -82.611214)
		(mid 132.96745 -82.633197)
		(end 133.006338 -82.640932)
		(stroke
			(width 0.0508)
			(type default)
		)
		(layer "F.Cu")
	)
	(gr_line
		(start 133.000242 -254.4064)
		(end 133.000242 -256.25044)
		(stroke
			(width 0.0508)
			(type default)
		)
		(layer "F.Cu")
	)
	(gr_arc
		(start 133.006338 -82.983832)
		(mid 132.96745 -82.991564)
		(end 132.934456 -83.01355)
		(stroke
			(width 0.0508)
			(type default)
		)
		(layer "F.Cu")
	)
	(gr_arc
		(start 133.152134 -254.040132)
		(mid 133.039751 -254.208159)
		(end 133.000242 -254.4064)
		(stroke
			(width 0.0508)
			(type default)
		)
		(layer "F.Cu")
	)
	(gr_line
		(start 133.152134 -254.040132)
		(end 133.217412 -253.9746)
		(stroke
			(width 0.0508)
			(type default)
		)
		(layer "F.Cu")
	)
	(gr_arc
		(start 133.19887 -98.20275)
		(mid 133.22806 -98.349419)
		(end 133.311138 -98.473768)
		(stroke
			(width 0.0508)
			(type default)
		)
		(layer "F.Cu")
	)
	(gr_arc
		(start 133.217412 -253.9746)
		(mid 133.247423 -253.939459)
		(end 133.271768 -253.900178)
		(stroke
			(width 0.0508)
			(type default)
		)
		(layer "F.Cu")
	)
	(gr_arc
		(start 133.223 -81.451958)
		(mid 133.215281 -81.413063)
		(end 133.193282 -81.380076)
		(stroke
			(width 0.0508)
			(type default)
		)
		(layer "F.Cu")
	)
	(gr_arc
		(start 133.232398 -83.9851)
		(mid 133.354194 -83.960877)
		(end 133.457442 -83.891882)
		(stroke
			(width 0.0508)
			(type default)
		)
		(layer "F.Cu")
	)
	(gr_arc
		(start 133.247638 -99.527614)
		(mid 133.225638 -99.560604)
		(end 133.21792 -99.599496)
		(stroke
			(width 0.0508)
			(type default)
		)
		(layer "F.Cu")
	)
	(gr_line
		(start 133.247638 -99.527614)
		(end 133.334252 -99.441)
		(stroke
			(width 0.0508)
			(type default)
		)
		(layer "F.Cu")
	)
	(gr_arc
		(start 133.271768 -253.900178)
		(mid 133.285561 -253.869732)
		(end 133.295898 -253.837948)
		(stroke
			(width 0.0508)
			(type default)
		)
		(layer "F.Cu")
	)
	(gr_arc
		(start 133.295898 -253.837948)
		(mid 133.303637 -253.799298)
		(end 133.306312 -253.75997)
		(stroke
			(width 0.0508)
			(type default)
		)
		(layer "F.Cu")
	)
	(gr_line
		(start 133.306312 -241.824002)
		(end 133.306312 -242.392962)
		(stroke
			(width 0.0508)
			(type default)
		)
		(layer "F.Cu")
	)
	(gr_line
		(start 133.306312 -240.259362)
		(end 133.306312 -240.828322)
		(stroke
			(width 0.0508)
			(type default)
		)
		(layer "F.Cu")
	)
	(gr_line
		(start 133.306312 -238.694722)
		(end 133.306312 -239.263682)
		(stroke
			(width 0.0508)
			(type default)
		)
		(layer "F.Cu")
	)
	(gr_line
		(start 133.311138 -98.473768)
		(end 133.36397 -98.5266)
		(stroke
			(width 0.0508)
			(type default)
		)
		(layer "F.Cu")
	)
	(gr_arc
		(start 133.334252 -99.441)
		(mid 133.356235 -99.408006)
		(end 133.36397 -99.369118)
		(stroke
			(width 0.0508)
			(type default)
		)
		(layer "F.Cu")
	)
	(gr_line
		(start 133.36397 -99.0854)
		(end 133.36397 -99.369118)
		(stroke
			(width 0.0508)
			(type default)
		)
		(layer "F.Cu")
	)
	(gr_arc
		(start 133.400038 -87.39505)
		(mid 133.446223 -87.385881)
		(end 133.485382 -87.359744)
		(stroke
			(width 0.0508)
			(type default)
		)
		(layer "F.Cu")
	)
	(gr_arc
		(start 133.407912 -89.93505)
		(mid 133.446807 -89.927331)
		(end 133.479794 -89.905332)
		(stroke
			(width 0.0508)
			(type default)
		)
		(layer "F.Cu")
	)
	(gr_arc
		(start 133.457442 -84.526882)
		(mid 133.237189 -84.379713)
		(end 132.977382 -84.328)
		(stroke
			(width 0.0508)
			(type default)
		)
		(layer "F.Cu")
	)
	(gr_arc
		(start 133.47954 -90.307668)
		(mid 133.446549 -90.285677)
		(end 133.407658 -90.27795)
		(stroke
			(width 0.0508)
			(type default)
		)
		(layer "F.Cu")
	)
	(gr_line
		(start 133.47954 -90.307668)
		(end 133.731 -90.559128)
		(stroke
			(width 0.0508)
			(type default)
		)
		(layer "F.Cu")
	)
	(gr_line
		(start 133.479794 -89.905332)
		(end 133.731 -89.654126)
		(stroke
			(width 0.0508)
			(type default)
		)
		(layer "F.Cu")
	)
	(gr_line
		(start 133.485382 -87.359744)
		(end 133.731 -87.114126)
		(stroke
			(width 0.0508)
			(type default)
		)
		(layer "F.Cu")
	)
	(gr_arc
		(start 133.520434 -87.808562)
		(mid 133.442244 -87.756293)
		(end 133.35 -87.73795)
		(stroke
			(width 0.0508)
			(type default)
		)
		(layer "F.Cu")
	)
	(gr_line
		(start 133.520434 -87.808562)
		(end 133.731 -88.019128)
		(stroke
			(width 0.0508)
			(type default)
		)
		(layer "F.Cu")
	)
	(gr_arc
		(start 133.595618 -81.380076)
		(mid 133.573622 -81.413065)
		(end 133.5659 -81.451958)
		(stroke
			(width 0.0508)
			(type default)
		)
		(layer "F.Cu")
	)
	(gr_line
		(start 133.595618 -81.380076)
		(end 133.858508 -81.117186)
		(stroke
			(width 0.0508)
			(type default)
		)
		(layer "F.Cu")
	)
	(gr_arc
		(start 133.649212 -253.703836)
		(mid 133.67558 -253.836638)
		(end 133.750812 -253.9492)
		(stroke
			(width 0.0508)
			(type default)
		)
		(layer "F.Cu")
	)
	(gr_arc
		(start 133.649212 -241.478562)
		(mid 133.679804 -241.612486)
		(end 133.768592 -241.717322)
		(stroke
			(width 0.0508)
			(type default)
		)
		(layer "F.Cu")
	)
	(gr_arc
		(start 133.649212 -239.913922)
		(mid 133.679789 -240.047858)
		(end 133.768592 -240.152682)
		(stroke
			(width 0.0508)
			(type default)
		)
		(layer "F.Cu")
	)
	(gr_arc
		(start 133.649212 -238.349282)
		(mid 133.679811 -238.4832)
		(end 133.768592 -238.588042)
		(stroke
			(width 0.0508)
			(type default)
		)
		(layer "F.Cu")
	)
	(gr_line
		(start 133.750812 -253.9492)
		(end 133.892798 -254.007874)
		(stroke
			(width 0.0508)
			(type default)
		)
		(layer "F.Cu")
	)
	(gr_arc
		(start 133.768592 -242.499642)
		(mid 133.679706 -242.604421)
		(end 133.649212 -242.738402)
		(stroke
			(width 0.0508)
			(type default)
		)
		(layer "F.Cu")
	)
	(gr_arc
		(start 133.768592 -242.499642)
		(mid 133.857386 -242.394828)
		(end 133.887972 -242.260882)
		(stroke
			(width 0.0508)
			(type default)
		)
		(layer "F.Cu")
	)
	(gr_arc
		(start 133.768592 -240.935002)
		(mid 133.679691 -241.039779)
		(end 133.649212 -241.173762)
		(stroke
			(width 0.0508)
			(type default)
		)
		(layer "F.Cu")
	)
	(gr_arc
		(start 133.768592 -240.935002)
		(mid 133.857386 -240.830188)
		(end 133.887972 -240.696242)
		(stroke
			(width 0.0508)
			(type default)
		)
		(layer "F.Cu")
	)
	(gr_arc
		(start 133.768592 -239.370362)
		(mid 133.679713 -239.475143)
		(end 133.649212 -239.609122)
		(stroke
			(width 0.0508)
			(type default)
		)
		(layer "F.Cu")
	)
	(gr_arc
		(start 133.768592 -239.370362)
		(mid 133.857386 -239.265548)
		(end 133.887972 -239.131602)
		(stroke
			(width 0.0508)
			(type default)
		)
		(layer "F.Cu")
	)
	(gr_arc
		(start 133.887972 -241.956082)
		(mid 133.85748 -241.822089)
		(end 133.768592 -241.717322)
		(stroke
			(width 0.0508)
			(type default)
		)
		(layer "F.Cu")
	)
	(gr_line
		(start 133.887972 -241.956082)
		(end 133.887972 -242.260882)
		(stroke
			(width 0.0508)
			(type default)
		)
		(layer "F.Cu")
	)
	(gr_arc
		(start 133.887972 -240.391442)
		(mid 133.85748 -240.257449)
		(end 133.768592 -240.152682)
		(stroke
			(width 0.0508)
			(type default)
		)
		(layer "F.Cu")
	)
	(gr_line
		(start 133.887972 -240.391442)
		(end 133.887972 -240.696242)
		(stroke
			(width 0.0508)
			(type default)
		)
		(layer "F.Cu")
	)
	(gr_arc
		(start 133.887972 -238.826802)
		(mid 133.85748 -238.692809)
		(end 133.768592 -238.588042)
		(stroke
			(width 0.0508)
			(type default)
		)
		(layer "F.Cu")
	)
	(gr_line
		(start 133.887972 -238.826802)
		(end 133.887972 -239.131602)
		(stroke
			(width 0.0508)
			(type default)
		)
		(layer "F.Cu")
	)
	(gr_arc
		(start 133.9596 -254.052324)
		(mid 133.928422 -254.026755)
		(end 133.892798 -254.007874)
		(stroke
			(width 0.0508)
			(type default)
		)
		(layer "F.Cu")
	)
	(gr_line
		(start 133.9596 -254.052324)
		(end 133.965188 -254.058166)
		(stroke
			(width 0.0508)
			(type default)
		)
		(layer "F.Cu")
	)
	(gr_arc
		(start 133.999732 -254.20193)
		(mid 133.991013 -254.127991)
		(end 133.965188 -254.058166)
		(stroke
			(width 0.0508)
			(type default)
		)
		(layer "F.Cu")
	)
	(gr_line
		(start 133.999732 -254.20193)
		(end 133.999732 -256.25044)
		(stroke
			(width 0.0508)
			(type default)
		)
		(layer "F.Cu")
	)
	(gr_line
		(start 134.016242 -84.526882)
		(end 134.29996 -84.526882)
		(stroke
			(width 0.0508)
			(type default)
		)
		(layer "F.Cu")
	)
	(gr_line
		(start 134.016242 -83.891882)
		(end 134.29996 -83.891882)
		(stroke
			(width 0.0508)
			(type default)
		)
		(layer "F.Cu")
	)
	(gr_arc
		(start 134.29996 -84.526882)
		(mid 134.338855 -84.519163)
		(end 134.371842 -84.497164)
		(stroke
			(width 0.0508)
			(type default)
		)
		(layer "F.Cu")
	)
	(gr_line
		(start 134.371842 -84.497164)
		(end 134.458456 -84.41055)
		(stroke
			(width 0.0508)
			(type default)
		)
		(layer "F.Cu")
	)
	(gr_arc
		(start 134.371842 -83.9216)
		(mid 134.338853 -83.899602)
		(end 134.29996 -83.891882)
		(stroke
			(width 0.0508)
			(type default)
		)
		(layer "F.Cu")
	)
	(gr_line
		(start 134.371842 -83.9216)
		(end 134.458456 -84.008214)
		(stroke
			(width 0.0508)
			(type default)
		)
		(layer "F.Cu")
	)
	(gr_arc
		(start 134.458456 -84.008214)
		(mid 134.49145 -84.030197)
		(end 134.530338 -84.037932)
		(stroke
			(width 0.0508)
			(type default)
		)
		(layer "F.Cu")
	)
	(gr_arc
		(start 134.50697 -98.5266)
		(mid 134.619799 -98.357739)
		(end 134.65937 -98.158554)
		(stroke
			(width 0.0508)
			(type default)
		)
		(layer "F.Cu")
	)
	(gr_arc
		(start 134.530338 -84.380832)
		(mid 134.49145 -84.388564)
		(end 134.458456 -84.41055)
		(stroke
			(width 0.0508)
			(type default)
		)
		(layer "F.Cu")
	)
	(gr_line
		(start 134.581392 -82.677)
		(end 134.844282 -82.93989)
		(stroke
			(width 0.0508)
			(type default)
		)
		(layer "F.Cu")
	)
	(gr_arc
		(start 134.65937 -99.453446)
		(mid 134.619753 -99.25428)
		(end 134.50697 -99.0854)
		(stroke
			(width 0.0508)
			(type default)
		)
		(layer "F.Cu")
	)
	(gr_arc
		(start 134.874 -83.011772)
		(mid 134.866281 -82.972877)
		(end 134.844282 -82.93989)
		(stroke
			(width 0.0508)
			(type default)
		)
		(layer "F.Cu")
	)
	(gr_arc
		(start 135.00227 -98.189288)
		(mid 135.038549 -98.371852)
		(end 135.14197 -98.5266)
		(stroke
			(width 0.0508)
			(type default)
		)
		(layer "F.Cu")
	)
	(gr_arc
		(start 135.14197 -99.0854)
		(mid 135.038591 -99.240167)
		(end 135.00227 -99.422712)
		(stroke
			(width 0.0508)
			(type default)
		)
		(layer "F.Cu")
	)
	(gr_arc
		(start 135.246618 -82.93989)
		(mid 135.224626 -82.97288)
		(end 135.2169 -83.011772)
		(stroke
			(width 0.0508)
			(type default)
		)
		(layer "F.Cu")
	)
	(gr_line
		(start 135.246618 -82.93989)
		(end 135.509508 -82.677)
		(stroke
			(width 0.0508)
			(type default)
		)
		(layer "F.Cu")
	)
	(gr_line
		(start 135.87984 -81.534)
		(end 136.020048 -81.674462)
		(stroke
			(width 0.0508)
			(type default)
		)
		(layer "F.Cu")
	)
	(gr_arc
		(start 136.172448 -82.042)
		(mid 136.132787 -81.843082)
		(end 136.020048 -81.674462)
		(stroke
			(width 0.0508)
			(type default)
		)
		(layer "F.Cu")
	)
	(gr_arc
		(start 136.271 -99.369118)
		(mid 136.278716 -99.408017)
		(end 136.300718 -99.441)
		(stroke
			(width 0.0508)
			(type default)
		)
		(layer "F.Cu")
	)
	(gr_line
		(start 136.271 -99.0854)
		(end 136.271 -99.369118)
		(stroke
			(width 0.0508)
			(type default)
		)
		(layer "F.Cu")
	)
	(gr_line
		(start 136.271 -98.242882)
		(end 136.271 -98.5266)
		(stroke
			(width 0.0508)
			(type default)
		)
		(layer "F.Cu")
	)
	(gr_line
		(start 136.300718 -99.441)
		(end 136.387332 -99.527614)
		(stroke
			(width 0.0508)
			(type default)
		)
		(layer "F.Cu")
	)
	(gr_arc
		(start 136.300718 -98.171)
		(mid 136.278697 -98.203984)
		(end 136.271 -98.242882)
		(stroke
			(width 0.0508)
			(type default)
		)
		(layer "F.Cu")
	)
	(gr_line
		(start 136.300718 -98.171)
		(end 136.387332 -98.084386)
		(stroke
			(width 0.0508)
			(type default)
		)
		(layer "F.Cu")
	)
	(gr_arc
		(start 136.387332 -98.084386)
		(mid 136.409315 -98.051392)
		(end 136.41705 -98.012504)
		(stroke
			(width 0.0508)
			(type default)
		)
		(layer "F.Cu")
	)
	(gr_arc
		(start 136.41705 -99.599496)
		(mid 136.409331 -99.560601)
		(end 136.387332 -99.527614)
		(stroke
			(width 0.0508)
			(type default)
		)
		(layer "F.Cu")
	)
	(gr_arc
		(start 136.667748 -81.674462)
		(mid 136.555001 -81.843079)
		(end 136.515348 -82.042)
		(stroke
			(width 0.0508)
			(type default)
		)
		(layer "F.Cu")
	)
	(gr_line
		(start 136.667748 -81.674462)
		(end 136.807956 -81.534)
		(stroke
			(width 0.0508)
			(type default)
		)
		(layer "F.Cu")
	)
	(gr_arc
		(start 136.75995 -98.012504)
		(mid 136.767697 -98.051382)
		(end 136.789668 -98.084386)
		(stroke
			(width 0.0508)
			(type default)
		)
		(layer "F.Cu")
	)
	(gr_arc
		(start 136.789668 -99.527614)
		(mid 136.767662 -99.560602)
		(end 136.75995 -99.599496)
		(stroke
			(width 0.0508)
			(type default)
		)
		(layer "F.Cu")
	)
	(gr_line
		(start 136.789668 -99.527614)
		(end 136.876282 -99.441)
		(stroke
			(width 0.0508)
			(type default)
		)
		(layer "F.Cu")
	)
	(gr_line
		(start 136.789668 -98.084386)
		(end 136.876282 -98.171)
		(stroke
			(width 0.0508)
			(type default)
		)
		(layer "F.Cu")
	)
	(gr_arc
		(start 136.876282 -99.441)
		(mid 136.898265 -99.408006)
		(end 136.906 -99.369118)
		(stroke
			(width 0.0508)
			(type default)
		)
		(layer "F.Cu")
	)
	(gr_line
		(start 136.906 -99.0854)
		(end 136.906 -99.369118)
		(stroke
			(width 0.0508)
			(type default)
		)
		(layer "F.Cu")
	)
	(gr_arc
		(start 136.906 -98.242882)
		(mid 136.898281 -98.203987)
		(end 136.876282 -98.171)
		(stroke
			(width 0.0508)
			(type default)
		)
		(layer "F.Cu")
	)
	(gr_line
		(start 136.906 -98.242882)
		(end 136.906 -98.5266)
		(stroke
			(width 0.0508)
			(type default)
		)
		(layer "F.Cu")
	)
	(gr_line
		(start 136.999472 -254.24384)
		(end 136.999472 -256.25044)
		(stroke
			(width 0.0508)
			(type default)
		)
		(layer "F.Cu")
	)
	(gr_arc
		(start 137.062972 -254.090932)
		(mid 137.016037 -254.161078)
		(end 136.999472 -254.24384)
		(stroke
			(width 0.0508)
			(type default)
		)
		(layer "F.Cu")
	)
	(gr_line
		(start 137.062972 -254.090932)
		(end 137.075418 -254.078232)
		(stroke
			(width 0.0508)
			(type default)
		)
		(layer "F.Cu")
	)
	(gr_line
		(start 137.075418 -254.078232)
		(end 137.185908 -253.967742)
		(stroke
			(width 0.0508)
			(type default)
		)
		(layer "F.Cu")
	)
	(gr_arc
		(start 137.185908 -253.967742)
		(mid 137.20576 -253.94457)
		(end 137.221976 -253.91872)
		(stroke
			(width 0.0508)
			(type default)
		)
		(layer "F.Cu")
	)
	(gr_arc
		(start 137.221976 -253.91872)
		(mid 137.23994 -253.872067)
		(end 137.246106 -253.822454)
		(stroke
			(width 0.0508)
			(type default)
		)
		(layer "F.Cu")
	)
	(gr_line
		(start 137.246106 -244.745764)
		(end 137.246106 -245.314724)
		(stroke
			(width 0.0508)
			(type default)
		)
		(layer "F.Cu")
	)
	(gr_line
		(start 137.246106 -243.181124)
		(end 137.246106 -243.750084)
		(stroke
			(width 0.0508)
			(type default)
		)
		(layer "F.Cu")
	)
	(gr_line
		(start 137.246106 -241.616484)
		(end 137.246106 -242.185444)
		(stroke
			(width 0.0508)
			(type default)
		)
		(layer "F.Cu")
	)
	(gr_arc
		(start 137.589006 -253.73838)
		(mid 137.599506 -253.791158)
		(end 137.629392 -253.835916)
		(stroke
			(width 0.0508)
			(type default)
		)
		(layer "F.Cu")
	)
	(gr_arc
		(start 137.589006 -244.400324)
		(mid 137.619583 -244.53426)
		(end 137.708386 -244.639084)
		(stroke
			(width 0.0508)
			(type default)
		)
		(layer "F.Cu")
	)
	(gr_arc
		(start 137.589006 -242.835684)
		(mid 137.619606 -242.969602)
		(end 137.708386 -243.074444)
		(stroke
			(width 0.0508)
			(type default)
		)
		(layer "F.Cu")
	)
	(gr_arc
		(start 137.589006 -241.271044)
		(mid 137.619591 -241.404974)
		(end 137.708386 -241.509804)
		(stroke
			(width 0.0508)
			(type default)
		)
		(layer "F.Cu")
	)
	(gr_line
		(start 137.629392 -253.835916)
		(end 137.911078 -254.117602)
		(stroke
			(width 0.0508)
			(type default)
		)
		(layer "F.Cu")
	)
	(gr_arc
		(start 137.708386 -245.421404)
		(mid 137.619487 -245.526181)
		(end 137.589006 -245.660164)
		(stroke
			(width 0.0508)
			(type default)
		)
		(layer "F.Cu")
	)
	(gr_arc
		(start 137.708386 -245.421404)
		(mid 137.79718 -245.31659)
		(end 137.827766 -245.182644)
		(stroke
			(width 0.0508)
			(type default)
		)
		(layer "F.Cu")
	)
	(gr_arc
		(start 137.708386 -243.856764)
		(mid 137.61951 -243.961546)
		(end 137.589006 -244.095524)
		(stroke
			(width 0.0508)
			(type default)
		)
		(layer "F.Cu")
	)
	(gr_arc
		(start 137.708386 -243.856764)
		(mid 137.79718 -243.75195)
		(end 137.827766 -243.618004)
		(stroke
			(width 0.0508)
			(type default)
		)
		(layer "F.Cu")
	)
	(gr_arc
		(start 137.708386 -242.292124)
		(mid 137.619495 -242.396903)
		(end 137.589006 -242.530884)
		(stroke
			(width 0.0508)
			(type default)
		)
		(layer "F.Cu")
	)
	(gr_arc
		(start 137.708386 -242.292124)
		(mid 137.79718 -242.18731)
		(end 137.827766 -242.053364)
		(stroke
			(width 0.0508)
			(type default)
		)
		(layer "F.Cu")
	)
	(gr_arc
		(start 137.827766 -244.877844)
		(mid 137.797274 -244.743851)
		(end 137.708386 -244.639084)
		(stroke
			(width 0.0508)
			(type default)
		)
		(layer "F.Cu")
	)
	(gr_line
		(start 137.827766 -244.877844)
		(end 137.827766 -245.182644)
		(stroke
			(width 0.0508)
			(type default)
		)
		(layer "F.Cu")
	)
	(gr_arc
		(start 137.827766 -243.313204)
		(mid 137.797274 -243.179211)
		(end 137.708386 -243.074444)
		(stroke
			(width 0.0508)
			(type default)
		)
		(layer "F.Cu")
	)
	(gr_line
		(start 137.827766 -243.313204)
		(end 137.827766 -243.618004)
		(stroke
			(width 0.0508)
			(type default)
		)
		(layer "F.Cu")
	)
	(gr_arc
		(start 137.827766 -241.748564)
		(mid 137.797274 -241.614571)
		(end 137.708386 -241.509804)
		(stroke
			(width 0.0508)
			(type default)
		)
		(layer "F.Cu")
	)
	(gr_line
		(start 137.827766 -241.748564)
		(end 137.827766 -242.053364)
		(stroke
			(width 0.0508)
			(type default)
		)
		(layer "F.Cu")
	)
	(gr_arc
		(start 138.000232 -254.332486)
		(mid 137.977006 -254.216189)
		(end 137.911078 -254.117602)
		(stroke
			(width 0.0508)
			(type default)
		)
		(layer "F.Cu")
	)
	(gr_line
		(start 138.000232 -254.332486)
		(end 138.000232 -256.25044)
		(stroke
			(width 0.0508)
			(type default)
		)
		(layer "F.Cu")
	)
	(gr_line
		(start 139.81811 -18.391378)
		(end 139.81811 -18.401538)
		(stroke
			(width 0.06985)
			(type default)
		)
		(layer "F.Cu")
	)
	(gr_line
		(start 143.000222 -254.062738)
		(end 143.000222 -256.25044)
		(stroke
			(width 0.0508)
			(type default)
		)
		(layer "F.Cu")
	)
	(gr_arc
		(start 143.047212 -253.9492)
		(mid 143.012438 -254.001302)
		(end 143.000222 -254.062738)
		(stroke
			(width 0.0508)
			(type default)
		)
		(layer "F.Cu")
	)
	(gr_arc
		(start 143.108426 -253.9238)
		(mid 143.075301 -253.930433)
		(end 143.047212 -253.9492)
		(stroke
			(width 0.0508)
			(type default)
		)
		(layer "F.Cu")
	)
	(gr_line
		(start 143.108426 -253.9238)
		(end 143.21663 -253.9238)
		(stroke
			(width 0.0508)
			(type default)
		)
		(layer "F.Cu")
	)
	(gr_arc
		(start 143.21663 -253.9238)
		(mid 143.278727 -253.910388)
		(end 143.329914 -253.872746)
		(stroke
			(width 0.0508)
			(type default)
		)
		(layer "F.Cu")
	)
	(gr_line
		(start 143.329914 -253.872746)
		(end 143.368268 -253.82982)
		(stroke
			(width 0.0508)
			(type default)
		)
		(layer "F.Cu")
	)
	(gr_arc
		(start 143.368268 -253.82982)
		(mid 143.403235 -253.76906)
		(end 143.415512 -253.700026)
		(stroke
			(width 0.0508)
			(type default)
		)
		(layer "F.Cu")
	)
	(gr_line
		(start 143.415512 -250.593606)
		(end 143.415512 -251.162566)
		(stroke
			(width 0.0508)
			(type default)
		)
		(layer "F.Cu")
	)
	(gr_line
		(start 143.415512 -249.028966)
		(end 143.415512 -249.597926)
		(stroke
			(width 0.0508)
			(type default)
		)
		(layer "F.Cu")
	)
	(gr_line
		(start 143.415512 -244.488208)
		(end 143.415512 -245.057168)
		(stroke
			(width 0.0508)
			(type default)
		)
		(layer "F.Cu")
	)
	(gr_line
		(start 143.415512 -242.923568)
		(end 143.415512 -243.492528)
		(stroke
			(width 0.0508)
			(type default)
		)
		(layer "F.Cu")
	)
	(gr_line
		(start 143.415512 -241.358928)
		(end 143.415512 -241.927888)
		(stroke
			(width 0.0508)
			(type default)
		)
		(layer "F.Cu")
	)
	(gr_arc
		(start 143.758412 -253.686056)
		(mid 143.760785 -253.729763)
		(end 143.768064 -253.772924)
		(stroke
			(width 0.0508)
			(type default)
		)
		(layer "F.Cu")
	)
	(gr_arc
		(start 143.758412 -250.248166)
		(mid 143.788908 -250.382143)
		(end 143.877792 -250.486926)
		(stroke
			(width 0.0508)
			(type default)
		)
		(layer "F.Cu")
	)
	(gr_arc
		(start 143.758412 -248.683526)
		(mid 143.788893 -248.817515)
		(end 143.877792 -248.922286)
		(stroke
			(width 0.0508)
			(type default)
		)
		(layer "F.Cu")
	)
	(gr_arc
		(start 143.758412 -244.142768)
		(mid 143.788909 -244.276745)
		(end 143.877792 -244.381528)
		(stroke
			(width 0.0508)
			(type default)
		)
		(layer "F.Cu")
	)
	(gr_arc
		(start 143.758412 -242.578128)
		(mid 143.788894 -242.712117)
		(end 143.877792 -242.816888)
		(stroke
			(width 0.0508)
			(type default)
		)
		(layer "F.Cu")
	)
	(gr_arc
		(start 143.758412 -241.013488)
		(mid 143.788916 -241.147459)
		(end 143.877792 -241.252248)
		(stroke
			(width 0.0508)
			(type default)
		)
		(layer "F.Cu")
	)
	(gr_arc
		(start 143.768064 -253.772924)
		(mid 143.782255 -253.820495)
		(end 143.802354 -253.865888)
		(stroke
			(width 0.0508)
			(type default)
		)
		(layer "F.Cu")
	)
	(gr_arc
		(start 143.802354 -253.865888)
		(mid 143.833858 -253.916587)
		(end 143.872712 -253.9619)
		(stroke
			(width 0.0508)
			(type default)
		)
		(layer "F.Cu")
	)
	(gr_arc
		(start 143.877792 -251.269246)
		(mid 143.788907 -251.374026)
		(end 143.758412 -251.508006)
		(stroke
			(width 0.0508)
			(type default)
		)
		(layer "F.Cu")
	)
	(gr_arc
		(start 143.877792 -251.269246)
		(mid 143.96668 -251.164451)
		(end 143.997172 -251.030486)
		(stroke
			(width 0.0508)
			(type default)
		)
		(layer "F.Cu")
	)
	(gr_arc
		(start 143.877792 -249.704606)
		(mid 143.788892 -249.809383)
		(end 143.758412 -249.943366)
		(stroke
			(width 0.0508)
			(type default)
		)
		(layer "F.Cu")
	)
	(gr_arc
		(start 143.877792 -249.704606)
		(mid 143.96668 -249.599811)
		(end 143.997172 -249.465846)
		(stroke
			(width 0.0508)
			(type default)
		)
		(layer "F.Cu")
	)
	(gr_arc
		(start 143.877792 -245.163848)
		(mid 143.788908 -245.268628)
		(end 143.758412 -245.402608)
		(stroke
			(width 0.0508)
			(type default)
		)
		(layer "F.Cu")
	)
	(gr_arc
		(start 143.877792 -245.163848)
		(mid 143.96668 -245.059053)
		(end 143.997172 -244.925088)
		(stroke
			(width 0.0508)
			(type default)
		)
		(layer "F.Cu")
	)
	(gr_arc
		(start 143.877792 -243.599208)
		(mid 143.788893 -243.703985)
		(end 143.758412 -243.837968)
		(stroke
			(width 0.0508)
			(type default)
		)
		(layer "F.Cu")
	)
	(gr_arc
		(start 143.877792 -243.599208)
		(mid 143.96668 -243.494413)
		(end 143.997172 -243.360448)
		(stroke
			(width 0.0508)
			(type default)
		)
		(layer "F.Cu")
	)
	(gr_arc
		(start 143.877792 -242.034568)
		(mid 143.788915 -242.139349)
		(end 143.758412 -242.273328)
		(stroke
			(width 0.0508)
			(type default)
		)
		(layer "F.Cu")
	)
	(gr_arc
		(start 143.877792 -242.034568)
		(mid 143.96668 -241.929773)
		(end 143.997172 -241.795808)
		(stroke
			(width 0.0508)
			(type default)
		)
		(layer "F.Cu")
	)
	(gr_arc
		(start 143.997172 -250.725686)
		(mid 143.96668 -250.591693)
		(end 143.877792 -250.486926)
		(stroke
			(width 0.0508)
			(type default)
		)
		(layer "F.Cu")
	)
	(gr_line
		(start 143.997172 -250.725686)
		(end 143.997172 -251.030486)
		(stroke
			(width 0.0508)
			(type default)
		)
		(layer "F.Cu")
	)
	(gr_arc
		(start 143.997172 -249.161046)
		(mid 143.96668 -249.027053)
		(end 143.877792 -248.922286)
		(stroke
			(width 0.0508)
			(type default)
		)
		(layer "F.Cu")
	)
	(gr_line
		(start 143.997172 -249.161046)
		(end 143.997172 -249.465846)
		(stroke
			(width 0.0508)
			(type default)
		)
		(layer "F.Cu")
	)
	(gr_arc
		(start 143.997172 -244.620288)
		(mid 143.96668 -244.486295)
		(end 143.877792 -244.381528)
		(stroke
			(width 0.0508)
			(type default)
		)
		(layer "F.Cu")
	)
	(gr_line
		(start 143.997172 -244.620288)
		(end 143.997172 -244.925088)
		(stroke
			(width 0.0508)
			(type default)
		)
		(layer "F.Cu")
	)
	(gr_arc
		(start 143.997172 -243.055648)
		(mid 143.96668 -242.921655)
		(end 143.877792 -242.816888)
		(stroke
			(width 0.0508)
			(type default)
		)
		(layer "F.Cu")
	)
	(gr_line
		(start 143.997172 -243.055648)
		(end 143.997172 -243.360448)
		(stroke
			(width 0.0508)
			(type default)
		)
		(layer "F.Cu")
	)
	(gr_arc
		(start 143.997172 -241.491008)
		(mid 143.96668 -241.357015)
		(end 143.877792 -241.252248)
		(stroke
			(width 0.0508)
			(type default)
		)
		(layer "F.Cu")
	)
	(gr_line
		(start 143.997172 -241.491008)
		(end 143.997172 -241.795808)
		(stroke
			(width 0.0508)
			(type default)
		)
		(layer "F.Cu")
	)
	(gr_arc
		(start 143.999712 -254.268478)
		(mid 143.966708 -254.102555)
		(end 143.872712 -253.9619)
		(stroke
			(width 0.0508)
			(type default)
		)
		(layer "F.Cu")
	)
	(gr_line
		(start 143.999712 -254.268478)
		(end 143.999712 -256.25044)
		(stroke
			(width 0.0508)
			(type default)
		)
		(layer "F.Cu")
	)
	(gr_line
		(start 146.999452 -254.170434)
		(end 146.999452 -256.25044)
		(stroke
			(width 0.0508)
			(type default)
		)
		(layer "F.Cu")
	)
	(gr_arc
		(start 147.058888 -254.026924)
		(mid 147.014905 -254.092769)
		(end 146.999452 -254.170434)
		(stroke
			(width 0.0508)
			(type default)
		)
		(layer "F.Cu")
	)
	(gr_line
		(start 147.058888 -254.026924)
		(end 147.280376 -253.805436)
		(stroke
			(width 0.0508)
			(type default)
		)
		(layer "F.Cu")
	)
	(gr_arc
		(start 147.280376 -253.805436)
		(mid 147.324371 -253.739593)
		(end 147.339812 -253.661926)
		(stroke
			(width 0.0508)
			(type default)
		)
		(layer "F.Cu")
	)
	(gr_line
		(start 147.339812 -249.372882)
		(end 147.339812 -249.941842)
		(stroke
			(width 0.0508)
			(type default)
		)
		(layer "F.Cu")
	)
	(gr_line
		(start 147.339812 -247.808242)
		(end 147.339812 -248.377202)
		(stroke
			(width 0.0508)
			(type default)
		)
		(layer "F.Cu")
	)
	(gr_line
		(start 147.339812 -243.994178)
		(end 147.339812 -244.563138)
		(stroke
			(width 0.0508)
			(type default)
		)
		(layer "F.Cu")
	)
	(gr_line
		(start 147.339812 -242.429538)
		(end 147.339812 -242.998498)
		(stroke
			(width 0.0508)
			(type default)
		)
		(layer "F.Cu")
	)
	(gr_line
		(start 147.339812 -240.864898)
		(end 147.339812 -241.433858)
		(stroke
			(width 0.0508)
			(type default)
		)
		(layer "F.Cu")
	)
	(gr_arc
		(start 147.682712 -253.611888)
		(mid 147.718993 -253.794449)
		(end 147.822412 -253.9492)
		(stroke
			(width 0.0508)
			(type default)
		)
		(layer "F.Cu")
	)
	(gr_arc
		(start 147.682712 -249.027442)
		(mid 147.713296 -249.161372)
		(end 147.802092 -249.266202)
		(stroke
			(width 0.0508)
			(type default)
		)
		(layer "F.Cu")
	)
	(gr_arc
		(start 147.682712 -247.462802)
		(mid 147.713282 -247.596744)
		(end 147.802092 -247.701562)
		(stroke
			(width 0.0508)
			(type default)
		)
		(layer "F.Cu")
	)
	(gr_arc
		(start 147.682712 -243.648738)
		(mid 147.713295 -243.782669)
		(end 147.802092 -243.887498)
		(stroke
			(width 0.0508)
			(type default)
		)
		(layer "F.Cu")
	)
	(gr_arc
		(start 147.682712 -242.084098)
		(mid 147.71328 -242.218041)
		(end 147.802092 -242.322858)
		(stroke
			(width 0.0508)
			(type default)
		)
		(layer "F.Cu")
	)
	(gr_arc
		(start 147.682712 -240.519458)
		(mid 147.713302 -240.653383)
		(end 147.802092 -240.758218)
		(stroke
			(width 0.0508)
			(type default)
		)
		(layer "F.Cu")
	)
	(gr_arc
		(start 147.802092 -250.048522)
		(mid 147.713198 -250.1533)
		(end 147.682712 -250.287282)
		(stroke
			(width 0.0508)
			(type default)
		)
		(layer "F.Cu")
	)
	(gr_arc
		(start 147.802092 -250.048522)
		(mid 147.890886 -249.943708)
		(end 147.921472 -249.809762)
		(stroke
			(width 0.0508)
			(type default)
		)
		(layer "F.Cu")
	)
	(gr_arc
		(start 147.802092 -248.483882)
		(mid 147.713184 -248.588657)
		(end 147.682712 -248.722642)
		(stroke
			(width 0.0508)
			(type default)
		)
		(layer "F.Cu")
	)
	(gr_arc
		(start 147.802092 -248.483882)
		(mid 147.890886 -248.379068)
		(end 147.921472 -248.245122)
		(stroke
			(width 0.0508)
			(type default)
		)
		(layer "F.Cu")
	)
	(gr_arc
		(start 147.802092 -244.669818)
		(mid 147.713197 -244.774596)
		(end 147.682712 -244.908578)
		(stroke
			(width 0.0508)
			(type default)
		)
		(layer "F.Cu")
	)
	(gr_arc
		(start 147.802092 -244.669818)
		(mid 147.890886 -244.565004)
		(end 147.921472 -244.431058)
		(stroke
			(width 0.0508)
			(type default)
		)
		(layer "F.Cu")
	)
	(gr_arc
		(start 147.802092 -243.105178)
		(mid 147.713182 -243.209953)
		(end 147.682712 -243.343938)
		(stroke
			(width 0.0508)
			(type default)
		)
		(layer "F.Cu")
	)
	(gr_arc
		(start 147.802092 -243.105178)
		(mid 147.890886 -243.000364)
		(end 147.921472 -242.866418)
		(stroke
			(width 0.0508)
			(type default)
		)
		(layer "F.Cu")
	)
	(gr_arc
		(start 147.802092 -241.540538)
		(mid 147.713204 -241.645317)
		(end 147.682712 -241.779298)
		(stroke
			(width 0.0508)
			(type default)
		)
		(layer "F.Cu")
	)
	(gr_arc
		(start 147.802092 -241.540538)
		(mid 147.890886 -241.435724)
		(end 147.921472 -241.301778)
		(stroke
			(width 0.0508)
			(type default)
		)
		(layer "F.Cu")
	)
	(gr_arc
		(start 147.921472 -249.504962)
		(mid 147.89098 -249.370969)
		(end 147.802092 -249.266202)
		(stroke
			(width 0.0508)
			(type default)
		)
		(layer "F.Cu")
	)
	(gr_line
		(start 147.921472 -249.504962)
		(end 147.921472 -249.809762)
		(stroke
			(width 0.0508)
			(type default)
		)
		(layer "F.Cu")
	)
	(gr_arc
		(start 147.921472 -247.940322)
		(mid 147.89098 -247.806329)
		(end 147.802092 -247.701562)
		(stroke
			(width 0.0508)
			(type default)
		)
		(layer "F.Cu")
	)
	(gr_line
		(start 147.921472 -247.940322)
		(end 147.921472 -248.245122)
		(stroke
			(width 0.0508)
			(type default)
		)
		(layer "F.Cu")
	)
	(gr_arc
		(start 147.921472 -244.126258)
		(mid 147.89098 -243.992265)
		(end 147.802092 -243.887498)
		(stroke
			(width 0.0508)
			(type default)
		)
		(layer "F.Cu")
	)
	(gr_line
		(start 147.921472 -244.126258)
		(end 147.921472 -244.431058)
		(stroke
			(width 0.0508)
			(type default)
		)
		(layer "F.Cu")
	)
	(gr_arc
		(start 147.921472 -242.561618)
		(mid 147.89098 -242.427625)
		(end 147.802092 -242.322858)
		(stroke
			(width 0.0508)
			(type default)
		)
		(layer "F.Cu")
	)
	(gr_line
		(start 147.921472 -242.561618)
		(end 147.921472 -242.866418)
		(stroke
			(width 0.0508)
			(type default)
		)
		(layer "F.Cu")
	)
	(gr_arc
		(start 147.921472 -240.996978)
		(mid 147.89098 -240.862985)
		(end 147.802092 -240.758218)
		(stroke
			(width 0.0508)
			(type default)
		)
		(layer "F.Cu")
	)
	(gr_line
		(start 147.921472 -240.996978)
		(end 147.921472 -241.301778)
		(stroke
			(width 0.0508)
			(type default)
		)
		(layer "F.Cu")
	)
	(gr_arc
		(start 148.000212 -254.37846)
		(mid 147.954002 -254.146148)
		(end 147.822412 -253.9492)
		(stroke
			(width 0.0508)
			(type default)
		)
		(layer "F.Cu")
	)
	(gr_line
		(start 148.000212 -254.37846)
		(end 148.000212 -256.25044)
		(stroke
			(width 0.0508)
			(type default)
		)
		(layer "F.Cu")
	)
	(gr_arc
		(start 155.946348 -77.0255)
		(mid 156.199779 -76.646305)
		(end 156.28874 -76.198984)
		(stroke
			(width 0.06985)
			(type default)
		)
		(layer "F.Cu")
	)
	(gr_arc
		(start 156.63164 -76.30922)
		(mid 156.708746 -76.69686)
		(end 156.928312 -77.0255)
		(stroke
			(width 0.06985)
			(type default)
		)
		(layer "F.Cu")
	)
	(gr_arc
		(start 159.946848 -77.0255)
		(mid 160.200279 -76.646305)
		(end 160.28924 -76.198984)
		(stroke
			(width 0.06985)
			(type default)
		)
		(layer "F.Cu")
	)
	(gr_arc
		(start 160.63214 -76.30922)
		(mid 160.709246 -76.69686)
		(end 160.928812 -77.0255)
		(stroke
			(width 0.06985)
			(type default)
		)
		(layer "F.Cu")
	)
	(gr_arc
		(start 163.946078 -77.0255)
		(mid 164.199502 -76.646304)
		(end 164.28847 -76.198984)
		(stroke
			(width 0.06985)
			(type default)
		)
		(layer "F.Cu")
	)
	(gr_arc
		(start 164.63137 -76.30922)
		(mid 164.708476 -76.69686)
		(end 164.928042 -77.0255)
		(stroke
			(width 0.06985)
			(type default)
		)
		(layer "F.Cu")
	)
	(gr_arc
		(start 167.946578 -77.0255)
		(mid 168.200002 -76.646304)
		(end 168.28897 -76.198984)
		(stroke
			(width 0.06985)
			(type default)
		)
		(layer "F.Cu")
	)
	(gr_arc
		(start 168.63187 -76.30922)
		(mid 168.708976 -76.69686)
		(end 168.928542 -77.0255)
		(stroke
			(width 0.06985)
			(type default)
		)
		(layer "F.Cu")
	)
	(gr_arc
		(start 171.286932 -26.20518)
		(mid 171.386576 -26.271744)
		(end 171.504102 -26.295096)
		(stroke
			(width 0.06985)
			(type default)
		)
		(layer "F.Cu")
	)
	(gr_line
		(start 171.504102 -26.295096)
		(end 172.231304 -26.295096)
		(stroke
			(width 0.06985)
			(type default)
		)
		(layer "F.Cu")
	)
	(gr_arc
		(start 171.533312 -25.152096)
		(mid 171.415212 -25.175588)
		(end 171.315126 -25.24252)
		(stroke
			(width 0.06985)
			(type default)
		)
		(layer "F.Cu")
	)
	(gr_line
		(start 171.533312 -25.152096)
		(end 172.231304 -25.152096)
		(stroke
			(width 0.06985)
			(type default)
		)
		(layer "F.Cu")
	)
	(gr_line
		(start 172.268388 -31.201868)
		(end 172.306488 -31.163768)
		(stroke
			(width 0.06985)
			(type default)
		)
		(layer "F.Cu")
	)
	(gr_line
		(start 172.306488 -31.163768)
		(end 173.325028 -31.163768)
		(stroke
			(width 0.06985)
			(type default)
		)
		(layer "F.Cu")
	)
	(gr_line
		(start 173.120304 -26.295096)
		(end 174.075344 -27.250136)
		(stroke
			(width 0.06985)
			(type default)
		)
		(layer "F.Cu")
	)
	(gr_line
		(start 173.120304 -26.295096)
		(end 174.110396 -26.295096)
		(stroke
			(width 0.06985)
			(type default)
		)
		(layer "F.Cu")
	)
	(gr_line
		(start 173.120304 -25.152096)
		(end 173.183804 -25.215596)
		(stroke
			(width 0.06985)
			(type default)
		)
		(layer "F.Cu")
	)
	(gr_line
		(start 173.120304 -25.152096)
		(end 174.072804 -24.199596)
		(stroke
			(width 0.06985)
			(type default)
		)
		(layer "F.Cu")
	)
	(gr_line
		(start 173.183804 -25.215596)
		(end 174.059088 -25.215596)
		(stroke
			(width 0.06985)
			(type default)
		)
		(layer "F.Cu")
	)
	(gr_line
		(start 173.325028 -33.005776)
		(end 173.334172 -33.01492)
		(stroke
			(width 0.06985)
			(type default)
		)
		(layer "F.Cu")
	)
	(gr_line
		(start 173.325028 -32.052768)
		(end 173.325028 -33.005776)
		(stroke
			(width 0.06985)
			(type default)
		)
		(layer "F.Cu")
	)
	(gr_line
		(start 173.325028 -31.163768)
		(end 173.373796 -31.115)
		(stroke
			(width 0.06985)
			(type default)
		)
		(layer "F.Cu")
	)
	(gr_line
		(start 173.373796 -31.115)
		(end 174.497492 -31.115)
		(stroke
			(width 0.06985)
			(type default)
		)
		(layer "F.Cu")
	)
	(gr_line
		(start 174.037244 -27.405076)
		(end 174.037244 -29.200856)
		(stroke
			(width 0.06985)
			(type default)
		)
		(layer "F.Cu")
	)
	(gr_line
		(start 174.037244 -27.405076)
		(end 174.075344 -27.366976)
		(stroke
			(width 0.06985)
			(type default)
		)
		(layer "F.Cu")
	)
	(gr_line
		(start 174.059088 -25.215596)
		(end 174.179992 -25.3365)
		(stroke
			(width 0.06985)
			(type default)
		)
		(layer "F.Cu")
	)
	(gr_line
		(start 174.072804 -24.113236)
		(end 174.072804 -24.199596)
		(stroke
			(width 0.06985)
			(type default)
		)
		(layer "F.Cu")
	)
	(gr_line
		(start 174.072804 -24.113236)
		(end 174.743364 -23.442676)
		(stroke
			(width 0.06985)
			(type default)
		)
		(layer "F.Cu")
	)
	(gr_line
		(start 174.075344 -27.250136)
		(end 174.075344 -27.366976)
		(stroke
			(width 0.06985)
			(type default)
		)
		(layer "F.Cu")
	)
	(gr_line
		(start 174.110396 -26.295096)
		(end 174.179992 -26.2255)
		(stroke
			(width 0.06985)
			(type default)
		)
		(layer "F.Cu")
	)
	(gr_line
		(start 174.179992 -26.225246)
		(end 174.179992 -26.2255)
		(stroke
			(width 0.06985)
			(type default)
		)
		(layer "F.Cu")
	)
	(gr_line
		(start 174.179992 -26.225246)
		(end 174.421292 -25.983946)
		(stroke
			(width 0.06985)
			(type default)
		)
		(layer "F.Cu")
	)
	(gr_arc
		(start 174.179992 -25.3365)
		(mid 174.348503 -25.449096)
		(end 174.547276 -25.488646)
		(stroke
			(width 0.06985)
			(type default)
		)
		(layer "F.Cu")
	)
	(gr_line
		(start 174.218092 -33.274)
		(end 174.218092 -33.87852)
		(stroke
			(width 0.06985)
			(type default)
		)
		(layer "F.Cu")
	)
	(gr_arc
		(start 174.344584 -32.968692)
		(mid 174.250988 -33.108769)
		(end 174.218092 -33.274)
		(stroke
			(width 0.06985)
			(type default)
		)
		(layer "F.Cu")
	)
	(gr_line
		(start 174.344584 -32.968692)
		(end 174.353728 -32.959548)
		(stroke
			(width 0.06985)
			(type default)
		)
		(layer "F.Cu")
	)
	(gr_line
		(start 174.353728 -32.070548)
		(end 175.374808 -32.070548)
		(stroke
			(width 0.06985)
			(type default)
		)
		(layer "F.Cu")
	)
	(gr_line
		(start 174.497492 -30.774132)
		(end 174.497492 -31.115)
		(stroke
			(width 0.06985)
			(type default)
		)
		(layer "F.Cu")
	)
	(gr_arc
		(start 174.66056 -30.380432)
		(mid 174.539885 -30.561067)
		(end 174.497492 -30.774132)
		(stroke
			(width 0.06985)
			(type default)
		)
		(layer "F.Cu")
	)
	(gr_line
		(start 174.66056 -30.380432)
		(end 175.132492 -29.9085)
		(stroke
			(width 0.06985)
			(type default)
		)
		(layer "F.Cu")
	)
	(gr_line
		(start 174.743364 -22.490176)
		(end 174.743364 -23.442676)
		(stroke
			(width 0.06985)
			(type default)
		)
		(layer "F.Cu")
	)
	(gr_arc
		(start 174.789592 -25.831546)
		(mid 174.590275 -25.871099)
		(end 174.421292 -25.983946)
		(stroke
			(width 0.06985)
			(type default)
		)
		(layer "F.Cu")
	)
	(gr_line
		(start 175.374808 -32.070548)
		(end 175.390048 -32.055308)
		(stroke
			(width 0.06985)
			(type default)
		)
		(layer "F.Cu")
	)
	(gr_line
		(start 175.386492 -31.115)
		(end 175.390048 -31.118556)
		(stroke
			(width 0.06985)
			(type default)
		)
		(layer "F.Cu")
	)
	(gr_line
		(start 175.386492 -30.323536)
		(end 175.386492 -31.115)
		(stroke
			(width 0.06985)
			(type default)
		)
		(layer "F.Cu")
	)
	(gr_line
		(start 175.390048 -31.118556)
		(end 175.390048 -32.055308)
		(stroke
			(width 0.06985)
			(type default)
		)
		(layer "F.Cu")
	)
	(gr_arc
		(start 175.494696 -30.062424)
		(mid 175.414595 -30.182208)
		(end 175.386492 -30.323536)
		(stroke
			(width 0.06985)
			(type default)
		)
		(layer "F.Cu")
	)
	(gr_arc
		(start 179.021994 -30.66542)
		(mid 179.070512 -30.655787)
		(end 179.111656 -30.628336)
		(stroke
			(width 0.06985)
			(type default)
		)
		(layer "F.Cu")
	)
	(gr_arc
		(start 179.091336 -29.056076)
		(mid 179.05943 -29.062378)
		(end 179.032408 -29.08046)
		(stroke
			(width 0.06985)
			(type default)
		)
		(layer "F.Cu")
	)
	(gr_line
		(start 179.091336 -29.056076)
		(end 179.886864 -29.056076)
		(stroke
			(width 0.06985)
			(type default)
		)
		(layer "F.Cu")
	)
	(gr_line
		(start 179.111656 -30.628336)
		(end 179.146708 -30.593284)
		(stroke
			(width 0.06985)
			(type default)
		)
		(layer "F.Cu")
	)
	(gr_line
		(start 179.127912 -31.00832)
		(end 179.151788 -31.032196)
		(stroke
			(width 0.06985)
			(type default)
		)
		(layer "F.Cu")
	)
	(gr_arc
		(start 179.129436 -29.460444)
		(mid 179.088285 -29.433011)
		(end 179.039774 -29.42336)
		(stroke
			(width 0.06985)
			(type default)
		)
		(layer "F.Cu")
	)
	(gr_line
		(start 179.129436 -29.460444)
		(end 179.18811 -29.519118)
		(stroke
			(width 0.06985)
			(type default)
		)
		(layer "F.Cu")
	)
	(gr_arc
		(start 179.151788 -31.032196)
		(mid 179.178242 -31.049872)
		(end 179.209446 -31.056072)
		(stroke
			(width 0.06985)
			(type default)
		)
		(layer "F.Cu")
	)
	(gr_arc
		(start 179.18811 -29.519118)
		(mid 179.22926 -29.546549)
		(end 179.277772 -29.556202)
		(stroke
			(width 0.06985)
			(type default)
		)
		(layer "F.Cu")
	)
	(gr_line
		(start 179.209446 -31.056072)
		(end 179.886864 -31.056072)
		(stroke
			(width 0.06985)
			(type default)
		)
		(layer "F.Cu")
	)
	(gr_arc
		(start 179.23637 -30.5562)
		(mid 179.187853 -30.565837)
		(end 179.146708 -30.593284)
		(stroke
			(width 0.06985)
			(type default)
		)
		(layer "F.Cu")
	)
	(gr_line
		(start 179.23637 -30.5562)
		(end 179.886864 -30.5562)
		(stroke
			(width 0.06985)
			(type default)
		)
		(layer "F.Cu")
	)
	(gr_line
		(start 179.277772 -29.556202)
		(end 179.886864 -29.556202)
		(stroke
			(width 0.06985)
			(type default)
		)
		(layer "F.Cu")
	)
	(gr_arc
		(start 191.947038 -77.0255)
		(mid 192.200471 -76.646306)
		(end 192.28943 -76.198984)
		(stroke
			(width 0.06985)
			(type default)
		)
		(layer "F.Cu")
	)
	(gr_arc
		(start 192.63233 -76.30922)
		(mid 192.709436 -76.69686)
		(end 192.929002 -77.0255)
		(stroke
			(width 0.06985)
			(type default)
		)
		(layer "F.Cu")
	)
	(gr_arc
		(start 195.947538 -77.0255)
		(mid 196.200971 -76.646306)
		(end 196.28993 -76.198984)
		(stroke
			(width 0.06985)
			(type default)
		)
		(layer "F.Cu")
	)
	(gr_arc
		(start 196.63283 -76.30922)
		(mid 196.709936 -76.69686)
		(end 196.929502 -77.0255)
		(stroke
			(width 0.06985)
			(type default)
		)
		(layer "F.Cu")
	)
	(gr_arc
		(start 199.946768 -77.0255)
		(mid 200.200194 -76.646304)
		(end 200.28916 -76.198984)
		(stroke
			(width 0.06985)
			(type default)
		)
		(layer "F.Cu")
	)
	(gr_arc
		(start 200.63206 -76.30922)
		(mid 200.709166 -76.69686)
		(end 200.928732 -77.0255)
		(stroke
			(width 0.06985)
			(type default)
		)
		(layer "F.Cu")
	)
	(gr_arc
		(start 203.947268 -77.0255)
		(mid 204.200694 -76.646304)
		(end 204.28966 -76.198984)
		(stroke
			(width 0.06985)
			(type default)
		)
		(layer "F.Cu")
	)
	(gr_arc
		(start 204.63256 -76.30922)
		(mid 204.709666 -76.69686)
		(end 204.929232 -77.0255)
		(stroke
			(width 0.06985)
			(type default)
		)
		(layer "F.Cu")
	)
	(gr_line
		(start 270.999966 -10.989818)
		(end 271.560798 -10.989818)
		(stroke
			(width 0.06985)
			(type default)
		)
		(layer "F.Cu")
	)
	(gr_arc
		(start 271.7038 -11.049)
		(mid 271.638179 -11.005192)
		(end 271.560798 -10.989818)
		(stroke
			(width 0.06985)
			(type default)
		)
		(layer "F.Cu")
	)
	(gr_arc
		(start 271.828514 -11.34999)
		(mid 271.796086 -11.187092)
		(end 271.7038 -11.049)
		(stroke
			(width 0.06985)
			(type default)
		)
		(layer "F.Cu")
	)
	(gr_arc
		(start 272.2626 -11.1252)
		(mid 272.195089 -11.226237)
		(end 272.171414 -11.345418)
		(stroke
			(width 0.06985)
			(type default)
		)
		(layer "F.Cu")
	)
	(gr_arc
		(start 272.589498 -10.989818)
		(mid 272.412591 -11.025007)
		(end 272.2626 -11.1252)
		(stroke
			(width 0.06985)
			(type default)
		)
		(layer "F.Cu")
	)
	(gr_line
		(start 272.589498 -10.989818)
		(end 272.999962 -10.989818)
		(stroke
			(width 0.06985)
			(type default)
		)
		(layer "F.Cu")
	)
	(gr_line
		(start 276.867112 -32.131)
		(end 276.963632 -32.03448)
		(stroke
			(width 0.06985)
			(type default)
		)
		(layer "F.Cu")
	)
	(gr_arc
		(start 276.875494 -27.048714)
		(mid 276.911205 -27.228245)
		(end 277.012908 -27.380438)
		(stroke
			(width 0.06985)
			(type default)
		)
		(layer "F.Cu")
	)
	(gr_line
		(start 276.875494 -26.629868)
		(end 276.875494 -27.048714)
		(stroke
			(width 0.06985)
			(type default)
		)
		(layer "F.Cu")
	)
	(gr_line
		(start 276.875494 -24.290274)
		(end 276.875494 -24.953468)
		(stroke
			(width 0.06985)
			(type default)
		)
		(layer "F.Cu")
	)
	(gr_arc
		(start 276.963632 -32.03448)
		(mid 277.128657 -31.787409)
		(end 277.186644 -31.496)
		(stroke
			(width 0.06985)
			(type default)
		)
		(layer "F.Cu")
	)
	(gr_arc
		(start 276.9997 -23.9903)
		(mid 276.907799 -24.127946)
		(end 276.875494 -24.290274)
		(stroke
			(width 0.06985)
			(type default)
		)
		(layer "F.Cu")
	)
	(gr_line
		(start 276.9997 -23.9903)
		(end 277.3045 -23.6855)
		(stroke
			(width 0.06985)
			(type default)
		)
		(layer "F.Cu")
	)
	(gr_line
		(start 277.012908 -27.380438)
		(end 277.039578 -27.407108)
		(stroke
			(width 0.06985)
			(type default)
		)
		(layer "F.Cu")
	)
	(gr_arc
		(start 277.186644 -27.7622)
		(mid 277.148445 -27.570018)
		(end 277.039578 -27.407108)
		(stroke
			(width 0.06985)
			(type default)
		)
		(layer "F.Cu")
	)
	(gr_line
		(start 277.3045 -23.6855)
		(end 277.4696 -23.5204)
		(stroke
			(width 0.0508)
			(type default)
		)
		(layer "F.Cu")
	)
	(gr_line
		(start 277.4696 -22.2758)
		(end 277.4696 -23.5204)
		(stroke
			(width 0.0508)
			(type default)
		)
		(layer "F.Cu")
	)
	(gr_line
		(start 277.4696 -21.944838)
		(end 277.4696 -22.2758)
		(stroke
			(width 0.06985)
			(type default)
		)
		(layer "F.Cu")
	)
	(gr_arc
		(start 277.529544 -31.496)
		(mid 277.587509 -31.78741)
		(end 277.752556 -32.03448)
		(stroke
			(width 0.06985)
			(type default)
		)
		(layer "F.Cu")
	)
	(gr_arc
		(start 277.5966 -21.63826)
		(mid 277.50261 -21.778917)
		(end 277.4696 -21.944838)
		(stroke
			(width 0.06985)
			(type default)
		)
		(layer "F.Cu")
	)
	(gr_line
		(start 277.5966 -21.63826)
		(end 277.795228 -21.439632)
		(stroke
			(width 0.06985)
			(type default)
		)
		(layer "F.Cu")
	)
	(gr_arc
		(start 277.67661 -27.407108)
		(mid 277.567752 -27.570026)
		(end 277.529544 -27.7622)
		(stroke
			(width 0.06985)
			(type default)
		)
		(layer "F.Cu")
	)
	(gr_line
		(start 277.67661 -27.407108)
		(end 277.725632 -27.358086)
		(stroke
			(width 0.06985)
			(type default)
		)
		(layer "F.Cu")
	)
	(gr_arc
		(start 277.725632 -27.358086)
		(mid 277.810768 -27.230582)
		(end 277.840694 -27.08021)
		(stroke
			(width 0.06985)
			(type default)
		)
		(layer "F.Cu")
	)
	(gr_line
		(start 277.752556 -32.03448)
		(end 277.849076 -32.131)
		(stroke
			(width 0.06985)
			(type default)
		)
		(layer "F.Cu")
	)
	(gr_arc
		(start 277.82393 -21.410676)
		(mid 277.909433 -21.282851)
		(end 277.9395 -21.132038)
		(stroke
			(width 0.06985)
			(type default)
		)
		(layer "F.Cu")
	)
	(gr_line
		(start 277.840694 -26.629868)
		(end 277.840694 -27.08021)
		(stroke
			(width 0.06985)
			(type default)
		)
		(layer "F.Cu")
	)
	(gr_line
		(start 277.840694 -23.174706)
		(end 277.840694 -24.953468)
		(stroke
			(width 0.06985)
			(type default)
		)
		(layer "F.Cu")
	)
	(gr_arc
		(start 277.9395 -22.9362)
		(mid 277.866362 -23.045622)
		(end 277.840694 -23.174706)
		(stroke
			(width 0.06985)
			(type default)
		)
		(layer "F.Cu")
	)
	(gr_line
		(start 277.9395 -21.960078)
		(end 277.9395 -22.9362)
		(stroke
			(width 0.06985)
			(type default)
		)
		(layer "F.Cu")
	)
	(gr_line
		(start 277.9395 -20.2438)
		(end 277.9395 -21.132038)
		(stroke
			(width 0.06985)
			(type default)
		)
		(layer "F.Cu")
	)
	(gr_line
		(start 277.9395 -19.531076)
		(end 277.9395 -20.2438)
		(stroke
			(width 0.06985)
			(type default)
		)
		(layer "F.Cu")
	)
	(gr_arc
		(start 278.0665 -21.6535)
		(mid 277.972515 -21.794159)
		(end 277.9395 -21.960078)
		(stroke
			(width 0.06985)
			(type default)
		)
		(layer "F.Cu")
	)
	(gr_line
		(start 278.095456 -21.624544)
		(end 278.271732 -21.448014)
		(stroke
			(width 0.06985)
			(type default)
		)
		(layer "F.Cu")
	)
	(gr_arc
		(start 278.2824 -19.185636)
		(mid 278.308811 -19.318413)
		(end 278.384 -19.431)
		(stroke
			(width 0.06985)
			(type default)
		)
		(layer "F.Cu")
	)
	(gr_arc
		(start 278.3586 -21.4122)
		(mid 278.311598 -21.421456)
		(end 278.271732 -21.448014)
		(stroke
			(width 0.06985)
			(type default)
		)
		(layer "F.Cu")
	)
	(gr_arc
		(start 278.3586 -21.4122)
		(mid 278.466363 -21.367563)
		(end 278.511 -21.2598)
		(stroke
			(width 0.06985)
			(type default)
		)
		(layer "F.Cu")
	)
	(gr_arc
		(start 278.511 -19.737578)
		(mid 278.47799 -19.571658)
		(end 278.384 -19.431)
		(stroke
			(width 0.06985)
			(type default)
		)
		(layer "F.Cu")
	)
	(gr_line
		(start 278.511 -19.737578)
		(end 278.511 -21.2598)
		(stroke
			(width 0.06985)
			(type default)
		)
		(layer "F.Cu")
	)
	(gr_arc
		(start 284.607 -185.293)
		(mid 284.650013 -185.284527)
		(end 284.686502 -185.260234)
		(stroke
			(width 0.06985)
			(type default)
		)
		(layer "F.Cu")
	)
	(gr_line
		(start 284.686502 -185.260234)
		(end 284.846014 -185.100468)
		(stroke
			(width 0.06985)
			(type default)
		)
		(layer "F.Cu")
	)
	(gr_line
		(start 284.846014 -185.100468)
		(end 285.388304 -184.558178)
		(stroke
			(width 0.06985)
			(type default)
		)
		(layer "F.Cu")
	)
	(gr_arc
		(start 285.584392 -184.361836)
		(mid 285.621731 -184.306018)
		(end 285.634938 -184.24017)
		(stroke
			(width 0.06985)
			(type default)
		)
		(layer "F.Cu")
	)
	(gr_arc
		(start 285.65856 -184.773316)
		(mid 285.538231 -184.953495)
		(end 285.496 -185.166)
		(stroke
			(width 0.06985)
			(type default)
		)
		(layer "F.Cu")
	)
	(gr_line
		(start 285.853124 -184.579006)
		(end 286.020002 -184.412128)
		(stroke
			(width 0.06985)
			(type default)
		)
		(layer "F.Cu")
	)
	(gr_arc
		(start 286.434784 -184.24017)
		(mid 286.210302 -184.284916)
		(end 286.020002 -184.412128)
		(stroke
			(width 0.06985)
			(type default)
		)
		(layer "F.Cu")
	)
	(gr_line
		(start 289.698176 -197.73519)
		(end 289.701732 -197.73519)
		(stroke
			(width 0.0508)
			(type default)
		)
		(layer "F.Cu")
	)
	(gr_line
		(start 289.701732 -197.73519)
		(end 290.150042 -198.1835)
		(stroke
			(width 0.0508)
			(type default)
		)
		(layer "F.Cu")
	)
	(gr_line
		(start 290.44138 -198.503032)
		(end 290.44138 -198.83247)
		(stroke
			(width 0.0508)
			(type default)
		)
		(layer "F.Cu")
	)
	(gr_line
		(start 290.44138 -198.503032)
		(end 290.581842 -198.36257)
		(stroke
			(width 0.0508)
			(type default)
		)
		(layer "F.Cu")
	)
	(gr_line
		(start 290.498022 -197.92061)
		(end 290.581842 -198.00443)
		(stroke
			(width 0.0508)
			(type default)
		)
		(layer "F.Cu")
	)
	(gr_line
		(start 290.498022 -197.73519)
		(end 290.498022 -197.92061)
		(stroke
			(width 0.0508)
			(type default)
		)
		(layer "F.Cu")
	)
	(gr_line
		(start 290.581842 -198.00443)
		(end 290.581842 -198.36257)
		(stroke
			(width 0.0508)
			(type default)
		)
		(layer "F.Cu")
	)
	(gr_line
		(start 292.097968 -200.935082)
		(end 292.453568 -200.579482)
		(stroke
			(width 0.0508)
			(type default)
		)
		(layer "F.Cu")
	)
	(gr_line
		(start 292.453568 -200.579482)
		(end 292.967918 -200.579482)
		(stroke
			(width 0.0508)
			(type default)
		)
		(layer "F.Cu")
	)
	(gr_line
		(start 292.670992 -185.522616)
		(end 293.1922 -185.001408)
		(stroke
			(width 0.0508)
			(type default)
		)
		(layer "F.Cu")
	)
	(gr_line
		(start 292.7096 -184.7596)
		(end 292.7096 -184.8104)
		(stroke
			(width 0.0508)
			(type default)
		)
		(layer "F.Cu")
	)
	(gr_line
		(start 292.7096 -184.7596)
		(end 292.84676 -184.62244)
		(stroke
			(width 0.0508)
			(type default)
		)
		(layer "F.Cu")
	)
	(gr_line
		(start 292.834822 -183.44007)
		(end 292.834822 -183.75503)
		(stroke
			(width 0.0508)
			(type default)
		)
		(layer "F.Cu")
	)
	(gr_line
		(start 292.898068 -200.935082)
		(end 293.187882 -200.935082)
		(stroke
			(width 0.0508)
			(type default)
		)
		(layer "F.Cu")
	)
	(gr_line
		(start 292.967918 -200.579482)
		(end 293.1668 -200.3806)
		(stroke
			(width 0.0508)
			(type default)
		)
		(layer "F.Cu")
	)
	(gr_line
		(start 293.187882 -200.935082)
		(end 293.2938 -201.041)
		(stroke
			(width 0.0508)
			(type default)
		)
		(layer "F.Cu")
	)
	(gr_line
		(start 293.1922 -184.96534)
		(end 293.1922 -185.001408)
		(stroke
			(width 0.0508)
			(type default)
		)
		(layer "F.Cu")
	)
	(gr_line
		(start 293.2938 -201.340212)
		(end 293.296848 -201.34326)
		(stroke
			(width 0.0508)
			(type default)
		)
		(layer "F.Cu")
	)
	(gr_line
		(start 293.2938 -201.041)
		(end 293.2938 -201.340212)
		(stroke
			(width 0.0508)
			(type default)
		)
		(layer "F.Cu")
	)
	(gr_line
		(start 293.6494 -80.36687)
		(end 293.913306 -80.10271)
		(stroke
			(width 0.06985)
			(type default)
		)
		(layer "F.Cu")
	)
	(gr_line
		(start 293.6494 -79.44993)
		(end 293.718488 -79.519018)
		(stroke
			(width 0.06985)
			(type default)
		)
		(layer "F.Cu")
	)
	(gr_line
		(start 293.878 -186.504834)
		(end 293.878 -186.563)
		(stroke
			(width 0.0508)
			(type default)
		)
		(layer "F.Cu")
	)
	(gr_line
		(start 293.878 -186.504834)
		(end 294.043608 -186.339226)
		(stroke
			(width 0.0508)
			(type default)
		)
		(layer "F.Cu")
	)
	(gr_line
		(start 293.906448 -185.852308)
		(end 294.042084 -185.852308)
		(stroke
			(width 0.0508)
			(type default)
		)
		(layer "F.Cu")
	)
	(gr_arc
		(start 294.106854 -80.0227)
		(mid 294.002114 -80.04344)
		(end 293.913306 -80.10271)
		(stroke
			(width 0.06985)
			(type default)
		)
		(layer "F.Cu")
	)
	(gr_line
		(start 294.434768 -184.24017)
		(end 294.559228 -184.36463)
		(stroke
			(width 0.0508)
			(type default)
		)
		(layer "F.Cu")
	)
	(gr_line
		(start 294.434768 -183.44007)
		(end 294.904668 -183.90997)
		(stroke
			(width 0.0508)
			(type default)
		)
		(layer "F.Cu")
	)
	(gr_line
		(start 294.904668 -183.90997)
		(end 294.904668 -184.02173)
		(stroke
			(width 0.0508)
			(type default)
		)
		(layer "F.Cu")
	)
	(gr_line
		(start 295.298114 -198.313802)
		(end 295.324022 -198.33971)
		(stroke
			(width 0.0508)
			(type default)
		)
		(layer "F.Cu")
	)
	(gr_line
		(start 295.298114 -197.73519)
		(end 295.298114 -198.313802)
		(stroke
			(width 0.0508)
			(type default)
		)
		(layer "F.Cu")
	)
	(gr_line
		(start 296.0116 -198.33971)
		(end 296.034968 -198.363078)
		(stroke
			(width 0.0508)
			(type default)
		)
		(layer "F.Cu")
	)
	(gr_line
		(start 296.0116 -197.838568)
		(end 296.0116 -198.33971)
		(stroke
			(width 0.0508)
			(type default)
		)
		(layer "F.Cu")
	)
	(gr_line
		(start 296.0116 -197.838568)
		(end 296.09796 -197.752208)
		(stroke
			(width 0.0508)
			(type default)
		)
		(layer "F.Cu")
	)
	(gr_line
		(start 296.0116 -184.953402)
		(end 296.249598 -185.1914)
		(stroke
			(width 0.0508)
			(type default)
		)
		(layer "F.Cu")
	)
	(gr_line
		(start 296.0116 -184.4294)
		(end 296.0116 -184.953402)
		(stroke
			(width 0.0508)
			(type default)
		)
		(layer "F.Cu")
	)
	(gr_line
		(start 296.0116 -184.4294)
		(end 296.034968 -184.406032)
		(stroke
			(width 0.0508)
			(type default)
		)
		(layer "F.Cu")
	)
	(gr_line
		(start 296.034968 -184.24017)
		(end 296.034968 -184.406032)
		(stroke
			(width 0.0508)
			(type default)
		)
		(layer "F.Cu")
	)
	(gr_line
		(start 296.034968 -183.44007)
		(end 296.418 -183.823102)
		(stroke
			(width 0.0508)
			(type default)
		)
		(layer "F.Cu")
	)
	(gr_line
		(start 296.09796 -197.73519)
		(end 296.09796 -197.752208)
		(stroke
			(width 0.0508)
			(type default)
		)
		(layer "F.Cu")
	)
	(gr_line
		(start 296.249598 -185.1914)
		(end 296.843196 -185.1914)
		(stroke
			(width 0.0508)
			(type default)
		)
		(layer "F.Cu")
	)
	(gr_line
		(start 296.418 -183.823102)
		(end 296.418 -184.785)
		(stroke
			(width 0.0508)
			(type default)
		)
		(layer "F.Cu")
	)
	(gr_line
		(start 296.843196 -185.1914)
		(end 296.997628 -185.345832)
		(stroke
			(width 0.0508)
			(type default)
		)
		(layer "F.Cu")
	)
	(gr_line
		(start 297.05681 -82.223864)
		(end 297.207432 -82.073496)
		(stroke
			(width 0.06985)
			(type default)
		)
		(layer "F.Cu")
	)
	(gr_line
		(start 297.123358 -73.645014)
		(end 297.123358 -73.69175)
		(stroke
			(width 0.06985)
			(type default)
		)
		(layer "F.Cu")
	)
	(gr_arc
		(start 297.207432 -82.073496)
		(mid 297.333804 -81.884227)
		(end 297.37812 -81.661)
		(stroke
			(width 0.06985)
			(type default)
		)
		(layer "F.Cu")
	)
	(gr_arc
		(start 297.342052 -73.116694)
		(mid 297.180142 -73.359104)
		(end 297.123358 -73.645014)
		(stroke
			(width 0.06985)
			(type default)
		)
		(layer "F.Cu")
	)
	(gr_line
		(start 297.342052 -73.116694)
		(end 297.532806 -72.92594)
		(stroke
			(width 0.06985)
			(type default)
		)
		(layer "F.Cu")
	)
	(gr_arc
		(start 297.72102 -81.661)
		(mid 297.777935 -81.947604)
		(end 297.940222 -82.19059)
		(stroke
			(width 0.06985)
			(type default)
		)
		(layer "F.Cu")
	)
	(gr_line
		(start 297.80357 -73.355962)
		(end 298.139358 -73.69175)
		(stroke
			(width 0.06985)
			(type default)
		)
		(layer "F.Cu")
	)
	(gr_arc
		(start 297.80357 -73.14057)
		(mid 297.758961 -73.248266)
		(end 297.80357 -73.355962)
		(stroke
			(width 0.06985)
			(type default)
		)
		(layer "F.Cu")
	)
	(gr_line
		(start 297.940222 -82.19059)
		(end 297.97375 -82.223864)
		(stroke
			(width 0.06985)
			(type default)
		)
		(layer "F.Cu")
	)
	(gr_line
		(start 299.23486 -174.64024)
		(end 299.244258 -174.64024)
		(stroke
			(width 0.06985)
			(type default)
		)
		(layer "F.Cu")
	)
	(gr_line
		(start 299.244258 -174.64024)
		(end 299.638212 -175.034194)
		(stroke
			(width 0.06985)
			(type default)
		)
		(layer "F.Cu")
	)
	(gr_line
		(start 300.03496 -174.644812)
		(end 300.435518 -175.04537)
		(stroke
			(width 0.06985)
			(type default)
		)
		(layer "F.Cu")
	)
	(gr_line
		(start 300.03496 -174.64024)
		(end 300.03496 -174.644812)
		(stroke
			(width 0.06985)
			(type default)
		)
		(layer "F.Cu")
	)
	(gr_line
		(start 300.834806 -173.84014)
		(end 300.861984 -173.84014)
		(stroke
			(width 0.06985)
			(type default)
		)
		(layer "F.Cu")
	)
	(gr_line
		(start 300.861984 -173.84014)
		(end 301.271178 -174.249334)
		(stroke
			(width 0.06985)
			(type default)
		)
		(layer "F.Cu")
	)
	(gr_line
		(start 301.271178 -174.249334)
		(end 302.470058 -174.249334)
		(stroke
			(width 0.06985)
			(type default)
		)
		(layer "F.Cu")
	)
	(gr_line
		(start 301.634906 -173.84014)
		(end 302.141382 -173.84014)
		(stroke
			(width 0.06985)
			(type default)
		)
		(layer "F.Cu")
	)
	(gr_arc
		(start 301.908464 -67.47129)
		(mid 302.431095 -67.367288)
		(end 302.874172 -67.07124)
		(stroke
			(width 0.06985)
			(type default)
		)
		(layer "F.Cu")
	)
	(gr_line
		(start 301.974758 -73.6092)
		(end 302.203612 -73.380346)
		(stroke
			(width 0.06985)
			(type default)
		)
		(layer "F.Cu")
	)
	(gr_line
		(start 302.141382 -173.84014)
		(end 302.23206 -173.749462)
		(stroke
			(width 0.06985)
			(type default)
		)
		(layer "F.Cu")
	)
	(gr_arc
		(start 302.203612 -73.380346)
		(mid 302.273538 -73.275698)
		(end 302.2981 -73.152254)
		(stroke
			(width 0.06985)
			(type default)
		)
		(layer "F.Cu")
	)
	(gr_line
		(start 302.470058 -174.249334)
		(end 303.005998 -173.713394)
		(stroke
			(width 0.06985)
			(type default)
		)
		(layer "F.Cu")
	)
	(gr_line
		(start 302.741076 -73.393554)
		(end 302.956722 -73.6092)
		(stroke
			(width 0.06985)
			(type default)
		)
		(layer "F.Cu")
	)
	(gr_arc
		(start 302.874172 -68.21424)
		(mid 302.431101 -67.91819)
		(end 301.908464 -67.81419)
		(stroke
			(width 0.06985)
			(type default)
		)
		(layer "F.Cu")
	)
	(gr_line
		(start 303.763172 -68.21424)
		(end 303.94402 -68.033392)
		(stroke
			(width 0.06985)
			(type default)
		)
		(layer "F.Cu")
	)
	(gr_line
		(start 303.763172 -67.07124)
		(end 303.957228 -67.265042)
		(stroke
			(width 0.06985)
			(type default)
		)
		(layer "F.Cu")
	)
	(gr_line
		(start 303.80305 -87.525352)
		(end 303.912016 -87.416132)
		(stroke
			(width 0.06985)
			(type default)
		)
		(layer "F.Cu")
	)
	(gr_arc
		(start 303.912016 -87.416132)
		(mid 304.033413 -87.234582)
		(end 304.0761 -87.0204)
		(stroke
			(width 0.06985)
			(type default)
		)
		(layer "F.Cu")
	)
	(gr_arc
		(start 303.957228 -67.265042)
		(mid 304.189703 -67.42047)
		(end 304.463958 -67.4751)
		(stroke
			(width 0.06985)
			(type default)
		)
		(layer "F.Cu")
	)
	(gr_arc
		(start 304.419 -87.0204)
		(mid 304.45649 -87.208874)
		(end 304.563272 -87.368634)
		(stroke
			(width 0.06985)
			(type default)
		)
		(layer "F.Cu")
	)
	(gr_arc
		(start 304.463958 -67.818)
		(mid 304.18258 -67.87401)
		(end 303.94402 -68.033392)
		(stroke
			(width 0.06985)
			(type default)
		)
		(layer "F.Cu")
	)
	(gr_line
		(start 304.563272 -87.368634)
		(end 304.71999 -87.525352)
		(stroke
			(width 0.06985)
			(type default)
		)
		(layer "F.Cu")
	)
	(gr_arc
		(start 304.771806 -67.4751)
		(mid 304.825267 -67.464466)
		(end 304.870612 -67.434206)
		(stroke
			(width 0.06985)
			(type default)
		)
		(layer "F.Cu")
	)
	(gr_arc
		(start 304.887884 -67.818)
		(mid 304.965548 -67.802552)
		(end 305.031394 -67.758564)
		(stroke
			(width 0.06985)
			(type default)
		)
		(layer "F.Cu")
	)
	(gr_arc
		(start 307.029104 -73.4822)
		(mid 307.128622 -73.462374)
		(end 307.213 -73.406)
		(stroke
			(width 0.06985)
			(type default)
		)
		(layer "F.Cu")
	)
	(gr_arc
		(start 307.064156 -70.2183)
		(mid 307.213439 -70.188566)
		(end 307.34 -70.104)
		(stroke
			(width 0.06985)
			(type default)
		)
		(layer "F.Cu")
	)
	(gr_line
		(start 307.071014 -79.82712)
		(end 307.10759 -79.832708)
		(stroke
			(width 0.06985)
			(type default)
		)
		(layer "F.Cu")
	)
	(gr_arc
		(start 307.090318 -76.6318)
		(mid 307.156719 -76.618616)
		(end 307.213 -76.581)
		(stroke
			(width 0.06985)
			(type default)
		)
		(layer "F.Cu")
	)
	(gr_arc
		(start 307.10759 -79.832708)
		(mid 307.232925 -79.822016)
		(end 307.34 -79.756)
		(stroke
			(width 0.06985)
			(type default)
		)
		(layer "F.Cu")
	)
	(gr_line
		(start 307.213 -80.264)
		(end 307.265832 -80.316832)
		(stroke
			(width 0.06985)
			(type default)
		)
		(layer "F.Cu")
	)
	(gr_arc
		(start 307.213 -77.089)
		(mid 307.086442 -77.004436)
		(end 306.937156 -76.9747)
		(stroke
			(width 0.06985)
			(type default)
		)
		(layer "F.Cu")
	)
	(gr_arc
		(start 307.213 -77.089)
		(mid 307.335946 -77.171153)
		(end 307.48097 -77.199998)
		(stroke
			(width 0.06985)
			(type default)
		)
		(layer "F.Cu")
	)
	(gr_line
		(start 307.213 -76.581)
		(end 307.25237 -76.54163)
		(stroke
			(width 0.06985)
			(type default)
		)
		(layer "F.Cu")
	)
	(gr_arc
		(start 307.213 -73.914)
		(mid 307.114527 -73.848202)
		(end 306.99837 -73.8251)
		(stroke
			(width 0.06985)
			(type default)
		)
		(layer "F.Cu")
	)
	(gr_arc
		(start 307.213 -73.914)
		(mid 307.308316 -73.977729)
		(end 307.420772 -74.000106)
		(stroke
			(width 0.06985)
			(type default)
		)
		(layer "F.Cu")
	)
	(gr_line
		(start 307.213 -73.406)
		(end 307.384958 -73.233788)
		(stroke
			(width 0.06985)
			(type default)
		)
		(layer "F.Cu")
	)
	(gr_arc
		(start 307.213 -70.612)
		(mid 307.156713 -70.57439)
		(end 307.090318 -70.5612)
		(stroke
			(width 0.06985)
			(type default)
		)
		(layer "F.Cu")
	)
	(gr_line
		(start 307.213 -70.612)
		(end 307.26507 -70.66407)
		(stroke
			(width 0.06985)
			(type default)
		)
		(layer "F.Cu")
	)
	(gr_arc
		(start 307.226716 -67.028568)
		(mid 307.356772 -67.002698)
		(end 307.467 -66.929)
		(stroke
			(width 0.06985)
			(type default)
		)
		(layer "F.Cu")
	)
	(gr_arc
		(start 307.26507 -70.66407)
		(mid 307.416009 -70.764815)
		(end 307.594 -70.800214)
		(stroke
			(width 0.06985)
			(type default)
		)
		(layer "F.Cu")
	)
	(gr_arc
		(start 307.265832 -80.316832)
		(mid 307.358132 -80.378489)
		(end 307.467 -80.400144)
		(stroke
			(width 0.06985)
			(type default)
		)
		(layer "F.Cu")
	)
	(gr_line
		(start 307.34 -70.104)
		(end 307.427376 -70.01637)
		(stroke
			(width 0.06985)
			(type default)
		)
		(layer "F.Cu")
	)
	(gr_arc
		(start 307.34 -67.437)
		(mid 307.267398 -67.388482)
		(end 307.181758 -67.371468)
		(stroke
			(width 0.06985)
			(type default)
		)
		(layer "F.Cu")
	)
	(gr_line
		(start 307.34 -67.437)
		(end 307.438806 -67.535806)
		(stroke
			(width 0.06985)
			(type default)
		)
		(layer "F.Cu")
	)
	(gr_line
		(start 307.420772 -74.000106)
		(end 308.675024 -74.000106)
		(stroke
			(width 0.06985)
			(type default)
		)
		(layer "F.Cu")
	)
	(gr_arc
		(start 307.438806 -67.535806)
		(mid 307.51001 -67.583383)
		(end 307.594 -67.600068)
		(stroke
			(width 0.06985)
			(type default)
		)
		(layer "F.Cu")
	)
	(gr_line
		(start 307.467 -80.400144)
		(end 308.675024 -80.400144)
		(stroke
			(width 0.06985)
			(type default)
		)
		(layer "F.Cu")
	)
	(gr_arc
		(start 307.467 -73.200006)
		(mid 307.422622 -73.20874)
		(end 307.384958 -73.233788)
		(stroke
			(width 0.06985)
			(type default)
		)
		(layer "F.Cu")
	)
	(gr_line
		(start 307.467 -73.200006)
		(end 308.675024 -73.200006)
		(stroke
			(width 0.06985)
			(type default)
		)
		(layer "F.Cu")
	)
	(gr_arc
		(start 307.467 -70.000114)
		(mid 307.445562 -70.004284)
		(end 307.427376 -70.01637)
		(stroke
			(width 0.06985)
			(type default)
		)
		(layer "F.Cu")
	)
	(gr_line
		(start 307.467 -70.000114)
		(end 308.675024 -70.000114)
		(stroke
			(width 0.06985)
			(type default)
		)
		(layer "F.Cu")
	)
	(gr_line
		(start 307.48097 -77.199998)
		(end 308.675024 -77.199998)
		(stroke
			(width 0.06985)
			(type default)
		)
		(layer "F.Cu")
	)
	(gr_arc
		(start 307.594 -76.400152)
		(mid 307.409123 -76.436926)
		(end 307.25237 -76.54163)
		(stroke
			(width 0.06985)
			(type default)
		)
		(layer "F.Cu")
	)
	(gr_line
		(start 307.594 -76.400152)
		(end 308.675024 -76.400152)
		(stroke
			(width 0.06985)
			(type default)
		)
		(layer "F.Cu")
	)
	(gr_line
		(start 307.594 -70.800214)
		(end 308.675024 -70.800214)
		(stroke
			(width 0.06985)
			(type default)
		)
		(layer "F.Cu")
	)
	(gr_line
		(start 307.594 -67.600068)
		(end 308.675024 -67.600068)
		(stroke
			(width 0.06985)
			(type default)
		)
		(layer "F.Cu")
	)
	(gr_arc
		(start 307.716428 -79.600044)
		(mid 307.512693 -79.640569)
		(end 307.34 -79.756)
		(stroke
			(width 0.06985)
			(type default)
		)
		(layer "F.Cu")
	)
	(gr_line
		(start 307.716428 -79.600044)
		(end 308.675024 -79.600044)
		(stroke
			(width 0.06985)
			(type default)
		)
		(layer "F.Cu")
	)
	(gr_arc
		(start 307.777896 -66.800222)
		(mid 307.609641 -66.833691)
		(end 307.467 -66.929)
		(stroke
			(width 0.06985)
			(type default)
		)
		(layer "F.Cu")
	)
	(gr_line
		(start 307.777896 -66.800222)
		(end 308.675024 -66.800222)
		(stroke
			(width 0.06985)
			(type default)
		)
		(layer "F.Cu")
	)
	(gr_line
		(start 313.125104 -82.00009)
		(end 314.251848 -82.00009)
		(stroke
			(width 0.06985)
			(type default)
		)
		(layer "F.Cu")
	)
	(gr_line
		(start 313.125104 -81.19999)
		(end 314.251848 -81.19999)
		(stroke
			(width 0.06985)
			(type default)
		)
		(layer "F.Cu")
	)
	(gr_line
		(start 313.125104 -78.800198)
		(end 314.251848 -78.800198)
		(stroke
			(width 0.06985)
			(type default)
		)
		(layer "F.Cu")
	)
	(gr_line
		(start 313.125104 -78.000098)
		(end 314.251848 -78.000098)
		(stroke
			(width 0.06985)
			(type default)
		)
		(layer "F.Cu")
	)
	(gr_line
		(start 313.125104 -75.600052)
		(end 314.251848 -75.600052)
		(stroke
			(width 0.06985)
			(type default)
		)
		(layer "F.Cu")
	)
	(gr_line
		(start 313.125104 -74.800206)
		(end 314.251848 -74.800206)
		(stroke
			(width 0.06985)
			(type default)
		)
		(layer "F.Cu")
	)
	(gr_line
		(start 313.125104 -72.40016)
		(end 314.251848 -72.40016)
		(stroke
			(width 0.06985)
			(type default)
		)
		(layer "F.Cu")
	)
	(gr_line
		(start 313.125104 -71.60006)
		(end 314.251848 -71.60006)
		(stroke
			(width 0.06985)
			(type default)
		)
		(layer "F.Cu")
	)
	(gr_line
		(start 313.125104 -69.200014)
		(end 314.251848 -69.200014)
		(stroke
			(width 0.06985)
			(type default)
		)
		(layer "F.Cu")
	)
	(gr_line
		(start 313.125104 -68.400168)
		(end 314.251848 -68.400168)
		(stroke
			(width 0.06985)
			(type default)
		)
		(layer "F.Cu")
	)
	(gr_arc
		(start 314.251848 -82.00009)
		(mid 314.305309 -81.989456)
		(end 314.350654 -81.959196)
		(stroke
			(width 0.06985)
			(type default)
		)
		(layer "F.Cu")
	)
	(gr_arc
		(start 314.251848 -78.800198)
		(mid 314.305309 -78.789564)
		(end 314.350654 -78.759304)
		(stroke
			(width 0.06985)
			(type default)
		)
		(layer "F.Cu")
	)
	(gr_arc
		(start 314.251848 -75.600052)
		(mid 314.305309 -75.589418)
		(end 314.350654 -75.559158)
		(stroke
			(width 0.06985)
			(type default)
		)
		(layer "F.Cu")
	)
	(gr_arc
		(start 314.251848 -72.40016)
		(mid 314.305309 -72.389526)
		(end 314.350654 -72.359266)
		(stroke
			(width 0.06985)
			(type default)
		)
		(layer "F.Cu")
	)
	(gr_arc
		(start 314.251848 -69.200014)
		(mid 314.305331 -69.189419)
		(end 314.350654 -69.15912)
		(stroke
			(width 0.06985)
			(type default)
		)
		(layer "F.Cu")
	)
	(gr_line
		(start 314.350654 -81.959196)
		(end 314.497466 -81.812384)
		(stroke
			(width 0.06985)
			(type default)
		)
		(layer "F.Cu")
	)
	(gr_arc
		(start 314.350654 -81.240884)
		(mid 314.305313 -81.210622)
		(end 314.251848 -81.19999)
		(stroke
			(width 0.06985)
			(type default)
		)
		(layer "F.Cu")
	)
	(gr_line
		(start 314.350654 -81.240884)
		(end 314.497466 -81.387696)
		(stroke
			(width 0.06985)
			(type default)
		)
		(layer "F.Cu")
	)
	(gr_line
		(start 314.350654 -78.759304)
		(end 314.497466 -78.612492)
		(stroke
			(width 0.06985)
			(type default)
		)
		(layer "F.Cu")
	)
	(gr_arc
		(start 314.350654 -78.040992)
		(mid 314.305313 -78.010729)
		(end 314.251848 -78.000098)
		(stroke
			(width 0.06985)
			(type default)
		)
		(layer "F.Cu")
	)
	(gr_line
		(start 314.350654 -78.040992)
		(end 314.497466 -78.187804)
		(stroke
			(width 0.06985)
			(type default)
		)
		(layer "F.Cu")
	)
	(gr_line
		(start 314.350654 -75.559158)
		(end 314.497212 -75.4126)
		(stroke
			(width 0.06985)
			(type default)
		)
		(layer "F.Cu")
	)
	(gr_arc
		(start 314.350654 -74.8411)
		(mid 314.305313 -74.810835)
		(end 314.251848 -74.800206)
		(stroke
			(width 0.06985)
			(type default)
		)
		(layer "F.Cu")
	)
	(gr_line
		(start 314.350654 -74.8411)
		(end 314.497466 -74.987912)
		(stroke
			(width 0.06985)
			(type default)
		)
		(layer "F.Cu")
	)
	(gr_line
		(start 314.350654 -72.359266)
		(end 314.497466 -72.212454)
		(stroke
			(width 0.06985)
			(type default)
		)
		(layer "F.Cu")
	)
	(gr_arc
		(start 314.350654 -71.640954)
		(mid 314.305311 -71.610699)
		(end 314.251848 -71.60006)
		(stroke
			(width 0.06985)
			(type default)
		)
		(layer "F.Cu")
	)
	(gr_line
		(start 314.350654 -71.640954)
		(end 314.497466 -71.787766)
		(stroke
			(width 0.06985)
			(type default)
		)
		(layer "F.Cu")
	)
	(gr_line
		(start 314.350654 -69.15912)
		(end 314.497466 -69.012308)
		(stroke
			(width 0.06985)
			(type default)
		)
		(layer "F.Cu")
	)
	(gr_arc
		(start 314.350654 -68.441062)
		(mid 314.305321 -68.410772)
		(end 314.251848 -68.400168)
		(stroke
			(width 0.06985)
			(type default)
		)
		(layer "F.Cu")
	)
	(gr_line
		(start 314.350654 -68.441062)
		(end 314.497212 -68.58762)
		(stroke
			(width 0.06985)
			(type default)
		)
		(layer "F.Cu")
	)
	(gr_arc
		(start 314.497212 -68.58762)
		(mid 314.542552 -68.617892)
		(end 314.596018 -68.628514)
		(stroke
			(width 0.06985)
			(type default)
		)
		(layer "F.Cu")
	)
	(gr_arc
		(start 314.497466 -81.387696)
		(mid 314.542799 -81.417986)
		(end 314.596272 -81.42859)
		(stroke
			(width 0.06985)
			(type default)
		)
		(layer "F.Cu")
	)
	(gr_arc
		(start 314.497466 -78.187804)
		(mid 314.542799 -78.218094)
		(end 314.596272 -78.228698)
		(stroke
			(width 0.06985)
			(type default)
		)
		(layer "F.Cu")
	)
	(gr_arc
		(start 314.497466 -74.987912)
		(mid 314.542799 -75.018202)
		(end 314.596272 -75.028806)
		(stroke
			(width 0.06985)
			(type default)
		)
		(layer "F.Cu")
	)
	(gr_arc
		(start 314.497466 -71.787766)
		(mid 314.542799 -71.818056)
		(end 314.596272 -71.82866)
		(stroke
			(width 0.06985)
			(type default)
		)
		(layer "F.Cu")
	)
	(gr_arc
		(start 314.596018 -75.371706)
		(mid 314.542544 -75.382314)
		(end 314.497212 -75.4126)
		(stroke
			(width 0.06985)
			(type default)
		)
		(layer "F.Cu")
	)
	(gr_arc
		(start 314.596272 -81.77149)
		(mid 314.542807 -81.782112)
		(end 314.497466 -81.812384)
		(stroke
			(width 0.06985)
			(type default)
		)
		(layer "F.Cu")
	)
	(gr_arc
		(start 314.596272 -78.571598)
		(mid 314.542807 -78.58222)
		(end 314.497466 -78.612492)
		(stroke
			(width 0.06985)
			(type default)
		)
		(layer "F.Cu")
	)
	(gr_arc
		(start 314.596272 -72.17156)
		(mid 314.542805 -72.18218)
		(end 314.497466 -72.212454)
		(stroke
			(width 0.06985)
			(type default)
		)
		(layer "F.Cu")
	)
	(gr_arc
		(start 314.596272 -68.971414)
		(mid 314.542811 -68.982048)
		(end 314.497466 -69.012308)
		(stroke
			(width 0.06985)
			(type default)
		)
		(layer "F.Cu")
	)
	(gr_arc
		(start 315.47562 -68.628514)
		(mid 315.599761 -68.603847)
		(end 315.704982 -68.533518)
		(stroke
			(width 0.06985)
			(type default)
		)
		(layer "F.Cu")
	)
	(gr_line
		(start 315.704982 -68.533518)
		(end 316.0395 -68.199)
		(stroke
			(width 0.06985)
			(type default)
		)
		(layer "F.Cu")
	)
	(gr_arc
		(start 316.0395 -69.215)
		(mid 315.769719 -69.034738)
		(end 315.45149 -68.971414)
		(stroke
			(width 0.06985)
			(type default)
		)
		(layer "F.Cu")
	)
	(gr_line
		(start 316.9285 -69.215)
		(end 317.3222 -69.215)
		(stroke
			(width 0.06985)
			(type default)
		)
		(layer "F.Cu")
	)
	(gr_line
		(start 316.9285 -68.199)
		(end 317.3222 -68.199)
		(stroke
			(width 0.06985)
			(type default)
		)
		(layer "F.Cu")
	)
	(gr_arc
		(start 317.1444 -72.3392)
		(mid 317.326804 -72.303011)
		(end 317.481458 -72.199754)
		(stroke
			(width 0.06985)
			(type default)
		)
		(layer "F.Cu")
	)
	(gr_arc
		(start 317.3222 -69.215)
		(mid 317.420983 -69.174083)
		(end 317.4619 -69.0753)
		(stroke
			(width 0.06985)
			(type default)
		)
		(layer "F.Cu")
	)
	(gr_arc
		(start 317.459614 -72.812656)
		(mid 317.314991 -72.716029)
		(end 317.1444 -72.6821)
		(stroke
			(width 0.06985)
			(type default)
		)
		(layer "F.Cu")
	)
	(gr_line
		(start 317.459614 -72.812656)
		(end 317.671958 -73.025)
		(stroke
			(width 0.06985)
			(type default)
		)
		(layer "F.Cu")
	)
	(gr_line
		(start 317.4619 -69.01815)
		(end 317.4619 -69.0753)
		(stroke
			(width 0.06985)
			(type default)
		)
		(layer "F.Cu")
	)
	(gr_arc
		(start 317.4619 -68.39585)
		(mid 317.502817 -68.494633)
		(end 317.6016 -68.53555)
		(stroke
			(width 0.06985)
			(type default)
		)
		(layer "F.Cu")
	)
	(gr_arc
		(start 317.4619 -68.3387)
		(mid 317.420983 -68.239917)
		(end 317.3222 -68.199)
		(stroke
			(width 0.06985)
			(type default)
		)
		(layer "F.Cu")
	)
	(gr_line
		(start 317.4619 -68.3387)
		(end 317.4619 -68.39585)
		(stroke
			(width 0.06985)
			(type default)
		)
		(layer "F.Cu")
	)
	(gr_line
		(start 317.481458 -72.199754)
		(end 317.671958 -72.009)
		(stroke
			(width 0.06985)
			(type default)
		)
		(layer "F.Cu")
	)
	(gr_arc
		(start 317.6016 -68.87845)
		(mid 317.502835 -68.91937)
		(end 317.4619 -69.01815)
		(stroke
			(width 0.06985)
			(type default)
		)
		(layer "F.Cu")
	)
	(gr_arc
		(start 317.754 -81.6991)
		(mid 317.994963 -81.65117)
		(end 318.199262 -81.514696)
		(stroke
			(width 0.06985)
			(type default)
		)
		(layer "F.Cu")
	)
	(gr_arc
		(start 317.8556 -78.6765)
		(mid 318.143457 -78.619148)
		(end 318.387476 -78.456028)
		(stroke
			(width 0.06985)
			(type default)
		)
		(layer "F.Cu")
	)
	(gr_arc
		(start 318.018922 -79.087218)
		(mid 317.944004 -79.037064)
		(end 317.8556 -79.0194)
		(stroke
			(width 0.06985)
			(type default)
		)
		(layer "F.Cu")
	)
	(gr_line
		(start 318.018922 -79.087218)
		(end 318.383158 -79.4512)
		(stroke
			(width 0.06985)
			(type default)
		)
		(layer "F.Cu")
	)
	(gr_arc
		(start 318.04737 -82.163666)
		(mid 317.912779 -82.073666)
		(end 317.754 -82.042)
		(stroke
			(width 0.06985)
			(type default)
		)
		(layer "F.Cu")
	)
	(gr_line
		(start 318.04737 -82.163666)
		(end 318.306958 -82.423)
		(stroke
			(width 0.06985)
			(type default)
		)
		(layer "F.Cu")
	)
	(gr_line
		(start 318.199262 -81.514696)
		(end 318.306958 -81.407)
		(stroke
			(width 0.06985)
			(type default)
		)
		(layer "F.Cu")
	)
	(gr_arc
		(start 318.378332 -68.53555)
		(mid 318.431793 -68.524916)
		(end 318.477138 -68.494656)
		(stroke
			(width 0.06985)
			(type default)
		)
		(layer "F.Cu")
	)
	(gr_line
		(start 318.387476 -78.456028)
		(end 318.408558 -78.4352)
		(stroke
			(width 0.06985)
			(type default)
		)
		(layer "F.Cu")
	)
	(gr_arc
		(start 318.477138 -68.919344)
		(mid 318.431793 -68.889096)
		(end 318.378332 -68.87845)
		(stroke
			(width 0.06985)
			(type default)
		)
		(layer "F.Cu")
	)
	(gr_line
		(start 318.477138 -68.919344)
		(end 318.755776 -69.197982)
		(stroke
			(width 0.06985)
			(type default)
		)
		(layer "F.Cu")
	)
	(gr_line
		(start 318.477138 -68.494656)
		(end 318.755776 -68.216018)
		(stroke
			(width 0.06985)
			(type default)
		)
		(layer "F.Cu")
	)
	(gr_arc
		(start 319.7098 -75.4888)
		(mid 319.892636 -75.452432)
		(end 320.04762 -75.348846)
		(stroke
			(width 0.06985)
			(type default)
		)
		(layer "F.Cu")
	)
	(gr_arc
		(start 319.908682 -75.91425)
		(mid 319.817448 -75.853197)
		(end 319.7098 -75.8317)
		(stroke
			(width 0.06985)
			(type default)
		)
		(layer "F.Cu")
	)
	(gr_line
		(start 319.908682 -75.91425)
		(end 320.186558 -76.191872)
		(stroke
			(width 0.06985)
			(type default)
		)
		(layer "F.Cu")
	)
	(gr_line
		(start 320.04762 -75.348846)
		(end 320.186558 -75.209908)
		(stroke
			(width 0.06985)
			(type default)
		)
		(layer "F.Cu")
	)
	(gr_line
		(start 335.8896 -134.655814)
		(end 335.8896 -135.4074)
		(stroke
			(width 0.06985)
			(type default)
		)
		(layer "F.Cu")
	)
	(gr_arc
		(start 335.915 -134.5946)
		(mid 335.896234 -134.622685)
		(end 335.8896 -134.655814)
		(stroke
			(width 0.06985)
			(type default)
		)
		(layer "F.Cu")
	)
	(gr_arc
		(start 336.0166 -133.711188)
		(mid 336.05291 -133.893733)
		(end 336.1563 -134.0485)
		(stroke
			(width 0.06985)
			(type default)
		)
		(layer "F.Cu")
	)
	(gr_line
		(start 336.0166 -133.2484)
		(end 336.0166 -133.711188)
		(stroke
			(width 0.06985)
			(type default)
		)
		(layer "F.Cu")
	)
	(gr_arc
		(start 336.12963 -134.5057)
		(mid 336.013474 -134.528805)
		(end 335.915 -134.5946)
		(stroke
			(width 0.06985)
			(type default)
		)
		(layer "F.Cu")
	)
	(gr_arc
		(start 336.1563 -134.0485)
		(mid 336.21288 -134.095225)
		(end 336.277204 -134.130542)
		(stroke
			(width 0.06985)
			(type default)
		)
		(layer "F.Cu")
	)
	(gr_arc
		(start 336.277204 -134.130542)
		(mid 336.353019 -134.154631)
		(end 336.432144 -134.1628)
		(stroke
			(width 0.06985)
			(type default)
		)
		(layer "F.Cu")
	)
	(gr_arc
		(start 337.53044 -139.82827)
		(mid 337.556991 -139.940412)
		(end 337.63077 -140.02893)
		(stroke
			(width 0.06985)
			(type default)
		)
		(layer "F.Cu")
	)
	(gr_line
		(start 337.53044 -139.40917)
		(end 337.53044 -139.82827)
		(stroke
			(width 0.06985)
			(type default)
		)
		(layer "F.Cu")
	)
	(gr_arc
		(start 337.53044 -138.18743)
		(mid 337.557013 -138.299555)
		(end 337.63077 -138.38809)
		(stroke
			(width 0.06985)
			(type default)
		)
		(layer "F.Cu")
	)
	(gr_line
		(start 337.53044 -137.76833)
		(end 337.53044 -138.18743)
		(stroke
			(width 0.06985)
			(type default)
		)
		(layer "F.Cu")
	)
	(gr_arc
		(start 337.63077 -139.20851)
		(mid 337.556962 -139.29702)
		(end 337.53044 -139.40917)
		(stroke
			(width 0.06985)
			(type default)
		)
		(layer "F.Cu")
	)
	(gr_arc
		(start 337.63077 -139.20851)
		(mid 337.70453 -139.119984)
		(end 337.7311 -139.00785)
		(stroke
			(width 0.06985)
			(type default)
		)
		(layer "F.Cu")
	)
	(gr_arc
		(start 337.63077 -137.56767)
		(mid 337.556983 -137.656184)
		(end 337.53044 -137.76833)
		(stroke
			(width 0.06985)
			(type default)
		)
		(layer "F.Cu")
	)
	(gr_arc
		(start 337.63077 -137.56767)
		(mid 337.70453 -137.479144)
		(end 337.7311 -137.36701)
		(stroke
			(width 0.06985)
			(type default)
		)
		(layer "F.Cu")
	)
	(gr_arc
		(start 337.7311 -140.22959)
		(mid 337.704576 -140.117433)
		(end 337.63077 -140.02893)
		(stroke
			(width 0.06985)
			(type default)
		)
		(layer "F.Cu")
	)
	(gr_arc
		(start 337.7311 -138.58875)
		(mid 337.704576 -138.476593)
		(end 337.63077 -138.38809)
		(stroke
			(width 0.06985)
			(type default)
		)
		(layer "F.Cu")
	)
	(gr_line
		(start 338.074 -139.35329)
		(end 338.074 -139.88415)
		(stroke
			(width 0.06985)
			(type default)
		)
		(layer "F.Cu")
	)
	(gr_line
		(start 338.074 -137.71245)
		(end 338.074 -138.24331)
		(stroke
			(width 0.06985)
			(type default)
		)
		(layer "F.Cu")
	)
	(gr_line
		(start 340.53272 -146.748246)
		(end 340.53272 -147.856448)
		(stroke
			(width 0.06985)
			(type default)
		)
		(layer "F.Cu")
	)
	(gr_arc
		(start 341.032592 -147.12696)
		(mid 340.878743 -146.353315)
		(end 340.440518 -145.697448)
		(stroke
			(width 0.06985)
			(type default)
		)
		(layer "F.Cu")
	)
	(gr_line
		(start 341.032592 -147.12696)
		(end 341.032592 -147.856448)
		(stroke
			(width 0.06985)
			(type default)
		)
		(layer "F.Cu")
	)
	(gr_line
		(start 343.3826 -135.4074)
		(end 343.5096 -135.5344)
		(stroke
			(width 0.06985)
			(type default)
		)
		(layer "F.Cu")
	)
	(gr_arc
		(start 343.3826 -134.7724)
		(mid 343.251087 -135.0899)
		(end 343.3826 -135.4074)
		(stroke
			(width 0.06985)
			(type default)
		)
		(layer "F.Cu")
	)
	(gr_arc
		(start 343.3826 -133.533388)
		(mid 343.41888 -133.71595)
		(end 343.5223 -133.8707)
		(stroke
			(width 0.06985)
			(type default)
		)
		(layer "F.Cu")
	)
	(gr_line
		(start 343.3826 -133.2484)
		(end 343.3826 -133.533388)
		(stroke
			(width 0.06985)
			(type default)
		)
		(layer "F.Cu")
	)
	(gr_line
		(start 343.5223 -133.8707)
		(end 343.730834 -134.079234)
		(stroke
			(width 0.06985)
			(type default)
		)
		(layer "F.Cu")
	)
	(gr_arc
		(start 343.730834 -134.079234)
		(mid 343.926002 -134.212019)
		(end 344.156284 -134.263892)
		(stroke
			(width 0.06985)
			(type default)
		)
		(layer "F.Cu")
	)
	(gr_arc
		(start 343.781126 -134.6073)
		(mid 343.565436 -134.650203)
		(end 343.3826 -134.7724)
		(stroke
			(width 0.06985)
			(type default)
		)
		(layer "F.Cu")
	)
	(gr_line
		(start 343.781126 -134.6073)
		(end 343.832434 -134.6073)
		(stroke
			(width 0.06985)
			(type default)
		)
		(layer "F.Cu")
	)
	(gr_arc
		(start 344.156284 -134.263892)
		(mid 344.167077 -134.264238)
		(end 344.177874 -134.2644)
		(stroke
			(width 0.06985)
			(type default)
		)
		(layer "F.Cu")
	)
	(gr_line
		(start 344.402918 -152.226772)
		(end 344.507058 -152.226772)
		(stroke
			(width 0.06985)
			(type default)
		)
		(layer "F.Cu")
	)
	(gr_line
		(start 344.402918 -151.726646)
		(end 345.326716 -151.726646)
		(stroke
			(width 0.06985)
			(type default)
		)
		(layer "F.Cu")
	)
	(gr_line
		(start 344.402918 -151.226774)
		(end 345.444318 -151.226774)
		(stroke
			(width 0.06985)
			(type default)
		)
		(layer "F.Cu")
	)
	(gr_line
		(start 344.402918 -150.226522)
		(end 345.017852 -150.226522)
		(stroke
			(width 0.06985)
			(type default)
		)
		(layer "F.Cu")
	)
	(gr_line
		(start 344.402918 -149.72665)
		(end 345.295474 -149.72665)
		(stroke
			(width 0.06985)
			(type default)
		)
		(layer "F.Cu")
	)
	(gr_line
		(start 344.402918 -149.226524)
		(end 344.587576 -149.226524)
		(stroke
			(width 0.06985)
			(type default)
		)
		(layer "F.Cu")
	)
	(gr_line
		(start 344.491818 -152.726644)
		(end 344.817192 -152.726644)
		(stroke
			(width 0.06985)
			(type default)
		)
		(layer "F.Cu")
	)
	(gr_line
		(start 344.491818 -148.726652)
		(end 345.010994 -148.726652)
		(stroke
			(width 0.06985)
			(type default)
		)
		(layer "F.Cu")
	)
	(gr_arc
		(start 345.017852 -150.226522)
		(mid 345.524266 -150.125777)
		(end 345.953588 -149.838918)
		(stroke
			(width 0.06985)
			(type default)
		)
		(layer "F.Cu")
	)
	(gr_arc
		(start 345.295474 -149.72665)
		(mid 345.558991 -149.67424)
		(end 345.782392 -149.524974)
		(stroke
			(width 0.06985)
			(type default)
		)
		(layer "F.Cu")
	)
	(gr_arc
		(start 345.770962 -148.23821)
		(mid 345.831469 -148.140128)
		(end 345.841828 -148.025358)
		(stroke
			(width 0.06985)
			(type default)
		)
		(layer "F.Cu")
	)
	(gr_arc
		(start 345.888056 -151.410416)
		(mid 345.684452 -151.274465)
		(end 345.444318 -151.226774)
		(stroke
			(width 0.06985)
			(type default)
		)
		(layer "F.Cu")
	)
	(gr_line
		(start 345.888056 -151.410416)
		(end 346.162376 -151.68499)
		(stroke
			(width 0.06985)
			(type default)
		)
		(layer "F.Cu")
	)
	(gr_arc
		(start 345.912694 -147.812506)
		(mid 345.85222 -147.910592)
		(end 345.841828 -148.025358)
		(stroke
			(width 0.06985)
			(type default)
		)
		(layer "F.Cu")
	)
	(gr_line
		(start 345.912694 -147.812506)
		(end 346.209112 -147.516342)
		(stroke
			(width 0.06985)
			(type default)
		)
		(layer "F.Cu")
	)
	(gr_line
		(start 345.953588 -152.825958)
		(end 345.959684 -152.828498)
		(stroke
			(width 0.06985)
			(type default)
		)
		(layer "F.Cu")
	)
	(gr_line
		(start 345.953588 -149.838918)
		(end 346.024962 -149.767544)
		(stroke
			(width 0.06985)
			(type default)
		)
		(layer "F.Cu")
	)
	(gr_line
		(start 345.959684 -152.828498)
		(end 345.962478 -152.829768)
		(stroke
			(width 0.06985)
			(type default)
		)
		(layer "F.Cu")
	)
	(gr_arc
		(start 345.995752 -152.00376)
		(mid 345.688796 -151.798658)
		(end 345.326716 -151.726646)
		(stroke
			(width 0.06985)
			(type default)
		)
		(layer "F.Cu")
	)
	(gr_line
		(start 346.162376 -151.68499)
		(end 346.21089 -151.733504)
		(stroke
			(width 0.06985)
			(type default)
		)
		(layer "F.Cu")
	)
	(gr_line
		(start 346.25788 -148.236686)
		(end 346.849954 -147.644612)
		(stroke
			(width 0.06985)
			(type default)
		)
		(layer "F.Cu")
	)
	(gr_arc
		(start 346.421964 -147.445476)
		(mid 346.307201 -147.455852)
		(end 346.209112 -147.516342)
		(stroke
			(width 0.06985)
			(type default)
		)
		(layer "F.Cu")
	)
	(gr_arc
		(start 346.421964 -147.445476)
		(mid 346.536747 -147.434952)
		(end 346.634816 -147.374356)
		(stroke
			(width 0.06985)
			(type default)
		)
		(layer "F.Cu")
	)
	(gr_arc
		(start 346.931234 -147.078192)
		(mid 346.991741 -146.98011)
		(end 347.0021 -146.86534)
		(stroke
			(width 0.06985)
			(type default)
		)
		(layer "F.Cu")
	)
	(gr_arc
		(start 347.07322 -146.652488)
		(mid 347.012642 -146.750552)
		(end 347.0021 -146.86534)
		(stroke
			(width 0.06985)
			(type default)
		)
		(layer "F.Cu")
	)
	(gr_line
		(start 347.07322 -146.652488)
		(end 347.369384 -146.35607)
		(stroke
			(width 0.06985)
			(type default)
		)
		(layer "F.Cu")
	)
	(gr_arc
		(start 347.196918 -149.170644)
		(mid 347.449431 -149.120383)
		(end 347.663516 -148.97735)
		(stroke
			(width 0.06985)
			(type default)
		)
		(layer "F.Cu")
	)
	(gr_line
		(start 347.202506 -147.29206)
		(end 348.010226 -146.48434)
		(stroke
			(width 0.06985)
			(type default)
		)
		(layer "F.Cu")
	)
	(gr_arc
		(start 347.271594 -152.149048)
		(mid 347.636696 -152.076451)
		(end 347.946218 -151.869648)
		(stroke
			(width 0.06985)
			(type default)
		)
		(layer "F.Cu")
	)
	(gr_arc
		(start 347.412564 -154.279854)
		(mid 347.500089 -154.338305)
		(end 347.603318 -154.358848)
		(stroke
			(width 0.06985)
			(type default)
		)
		(layer "F.Cu")
	)
	(gr_line
		(start 347.414342 -154.766772)
		(end 347.946218 -155.298648)
		(stroke
			(width 0.06985)
			(type default)
		)
		(layer "F.Cu")
	)
	(gr_arc
		(start 347.53423 -152.600914)
		(mid 347.413747 -152.520317)
		(end 347.271594 -152.491948)
		(stroke
			(width 0.06985)
			(type default)
		)
		(layer "F.Cu")
	)
	(gr_line
		(start 347.53423 -152.600914)
		(end 347.946218 -153.012648)
		(stroke
			(width 0.06985)
			(type default)
		)
		(layer "F.Cu")
	)
	(gr_arc
		(start 347.582236 -146.285204)
		(mid 347.467452 -146.295549)
		(end 347.369384 -146.35607)
		(stroke
			(width 0.06985)
			(type default)
		)
		(layer "F.Cu")
	)
	(gr_arc
		(start 347.582236 -146.285204)
		(mid 347.697019 -146.27468)
		(end 347.795088 -146.214084)
		(stroke
			(width 0.06985)
			(type default)
		)
		(layer "F.Cu")
	)
	(gr_line
		(start 347.603318 -154.358848)
		(end 347.743018 -154.358848)
		(stroke
			(width 0.06985)
			(type default)
		)
		(layer "F.Cu")
	)
	(gr_line
		(start 347.663516 -148.97735)
		(end 347.946218 -148.694648)
		(stroke
			(width 0.06985)
			(type default)
		)
		(layer "F.Cu")
	)
	(gr_arc
		(start 347.743018 -154.358848)
		(mid 347.886707 -154.299329)
		(end 347.946218 -154.155648)
		(stroke
			(width 0.06985)
			(type default)
		)
		(layer "F.Cu")
	)
	(gr_arc
		(start 347.832934 -149.724364)
		(mid 347.599395 -149.568319)
		(end 347.323918 -149.513544)
		(stroke
			(width 0.06985)
			(type default)
		)
		(layer "F.Cu")
	)
	(gr_line
		(start 347.832934 -149.724364)
		(end 347.946218 -149.837648)
		(stroke
			(width 0.06985)
			(type default)
		)
		(layer "F.Cu")
	)
	(gr_arc
		(start 348.091506 -145.91792)
		(mid 348.152013 -145.819838)
		(end 348.162372 -145.705068)
		(stroke
			(width 0.06985)
			(type default)
		)
		(layer "F.Cu")
	)
	(gr_arc
		(start 348.233492 -145.492216)
		(mid 348.172908 -145.590277)
		(end 348.162372 -145.705068)
		(stroke
			(width 0.06985)
			(type default)
		)
		(layer "F.Cu")
	)
	(gr_line
		(start 348.233492 -145.492216)
		(end 348.529656 -145.195798)
		(stroke
			(width 0.06985)
			(type default)
		)
		(layer "F.Cu")
	)
	(gr_line
		(start 348.362778 -146.131788)
		(end 348.953582 -145.540984)
		(stroke
			(width 0.06985)
			(type default)
		)
		(layer "F.Cu")
	)
	(gr_arc
		(start 348.742508 -145.124932)
		(mid 348.627732 -145.135289)
		(end 348.529656 -145.195798)
		(stroke
			(width 0.06985)
			(type default)
		)
		(layer "F.Cu")
	)
	(gr_arc
		(start 348.742508 -145.124932)
		(mid 348.857266 -145.114539)
		(end 348.95536 -145.054066)
		(stroke
			(width 0.06985)
			(type default)
		)
		(layer "F.Cu")
	)
	(gr_line
		(start 348.835218 -155.298648)
		(end 349.16237 -154.971496)
		(stroke
			(width 0.06985)
			(type default)
		)
		(layer "F.Cu")
	)
	(gr_line
		(start 348.835218 -154.155648)
		(end 349.16237 -154.4828)
		(stroke
			(width 0.06985)
			(type default)
		)
		(layer "F.Cu")
	)
	(gr_line
		(start 348.835218 -153.012648)
		(end 349.16237 -152.685496)
		(stroke
			(width 0.06985)
			(type default)
		)
		(layer "F.Cu")
	)
	(gr_line
		(start 348.835218 -151.869648)
		(end 349.16237 -152.1968)
		(stroke
			(width 0.06985)
			(type default)
		)
		(layer "F.Cu")
	)
	(gr_line
		(start 348.835218 -149.837648)
		(end 349.018352 -149.837648)
		(stroke
			(width 0.06985)
			(type default)
		)
		(layer "F.Cu")
	)
	(gr_line
		(start 348.835218 -148.694648)
		(end 349.037148 -148.694648)
		(stroke
			(width 0.06985)
			(type default)
		)
		(layer "F.Cu")
	)
	(gr_line
		(start 349.018352 -149.837648)
		(end 349.354902 -149.501098)
		(stroke
			(width 0.06985)
			(type default)
		)
		(layer "F.Cu")
	)
	(gr_line
		(start 349.037148 -148.694648)
		(end 349.354902 -149.012402)
		(stroke
			(width 0.06985)
			(type default)
		)
		(layer "F.Cu")
	)
	(gr_arc
		(start 349.43034 -141.563344)
		(mid 349.456918 -141.675465)
		(end 349.53067 -141.764004)
		(stroke
			(width 0.06985)
			(type default)
		)
		(layer "F.Cu")
	)
	(gr_line
		(start 349.43034 -141.144244)
		(end 349.43034 -141.563344)
		(stroke
			(width 0.06985)
			(type default)
		)
		(layer "F.Cu")
	)
	(gr_arc
		(start 349.43034 -139.922504)
		(mid 349.456903 -140.034636)
		(end 349.53067 -140.123164)
		(stroke
			(width 0.06985)
			(type default)
		)
		(layer "F.Cu")
	)
	(gr_line
		(start 349.43034 -139.503404)
		(end 349.43034 -139.922504)
		(stroke
			(width 0.06985)
			(type default)
		)
		(layer "F.Cu")
	)
	(gr_arc
		(start 349.43034 -138.281664)
		(mid 349.456889 -138.393808)
		(end 349.53067 -138.482324)
		(stroke
			(width 0.06985)
			(type default)
		)
		(layer "F.Cu")
	)
	(gr_line
		(start 349.43034 -137.862564)
		(end 349.43034 -138.281664)
		(stroke
			(width 0.06985)
			(type default)
		)
		(layer "F.Cu")
	)
	(gr_arc
		(start 349.53067 -140.943584)
		(mid 349.456888 -141.032099)
		(end 349.43034 -141.144244)
		(stroke
			(width 0.06985)
			(type default)
		)
		(layer "F.Cu")
	)
	(gr_arc
		(start 349.53067 -140.943584)
		(mid 349.60443 -140.855058)
		(end 349.631 -140.742924)
		(stroke
			(width 0.06985)
			(type default)
		)
		(layer "F.Cu")
	)
	(gr_arc
		(start 349.53067 -139.302744)
		(mid 349.456874 -139.391256)
		(end 349.43034 -139.503404)
		(stroke
			(width 0.06985)
			(type default)
		)
		(layer "F.Cu")
	)
	(gr_arc
		(start 349.53067 -139.302744)
		(mid 349.60443 -139.214218)
		(end 349.631 -139.102084)
		(stroke
			(width 0.06985)
			(type default)
		)
		(layer "F.Cu")
	)
	(gr_arc
		(start 349.53067 -137.661904)
		(mid 349.45686 -137.750413)
		(end 349.43034 -137.862564)
		(stroke
			(width 0.06985)
			(type default)
		)
		(layer "F.Cu")
	)
	(gr_arc
		(start 349.53067 -137.661904)
		(mid 349.60443 -137.573378)
		(end 349.631 -137.461244)
		(stroke
			(width 0.06985)
			(type default)
		)
		(layer "F.Cu")
	)
	(gr_arc
		(start 349.631 -141.964664)
		(mid 349.604476 -141.852507)
		(end 349.53067 -141.764004)
		(stroke
			(width 0.06985)
			(type default)
		)
		(layer "F.Cu")
	)
	(gr_arc
		(start 349.631 -140.323824)
		(mid 349.604476 -140.211667)
		(end 349.53067 -140.123164)
		(stroke
			(width 0.06985)
			(type default)
		)
		(layer "F.Cu")
	)
	(gr_arc
		(start 349.631 -138.682984)
		(mid 349.604476 -138.570827)
		(end 349.53067 -138.482324)
		(stroke
			(width 0.06985)
			(type default)
		)
		(layer "F.Cu")
	)
	(gr_line
		(start 349.81515 -154.959304)
		(end 350.010984 -155.155138)
		(stroke
			(width 0.06985)
			(type default)
		)
		(layer "F.Cu")
	)
	(gr_line
		(start 349.81515 -154.470862)
		(end 350.010984 -154.275028)
		(stroke
			(width 0.06985)
			(type default)
		)
		(layer "F.Cu")
	)
	(gr_line
		(start 349.9739 -141.088364)
		(end 349.9739 -141.619224)
		(stroke
			(width 0.06985)
			(type default)
		)
		(layer "F.Cu")
	)
	(gr_line
		(start 349.9739 -139.447524)
		(end 349.9739 -139.978384)
		(stroke
			(width 0.06985)
			(type default)
		)
		(layer "F.Cu")
	)
	(gr_line
		(start 349.9739 -137.806684)
		(end 349.9739 -138.337544)
		(stroke
			(width 0.06985)
			(type default)
		)
		(layer "F.Cu")
	)
	(gr_line
		(start 350.526858 -152.688798)
		(end 350.75495 -152.91689)
		(stroke
			(width 0.06985)
			(type default)
		)
		(layer "F.Cu")
	)
	(gr_line
		(start 350.526858 -152.200102)
		(end 350.75495 -151.97201)
		(stroke
			(width 0.06985)
			(type default)
		)
		(layer "F.Cu")
	)
	(gr_line
		(start 350.87941 -147.62353)
		(end 351.107502 -147.851622)
		(stroke
			(width 0.06985)
			(type default)
		)
		(layer "F.Cu")
	)
	(gr_line
		(start 351.596198 -147.851622)
		(end 351.82429 -147.62353)
		(stroke
			(width 0.06985)
			(type default)
		)
		(layer "F.Cu")
	)
	(gr_line
		(start 11.146282 -98.493326)
		(end 11.169904 -98.516948)
		(stroke
			(width 0.0508)
			(type default)
		)
		(layer "B.Cu")
	)
	(gr_line
		(start 11.169904 -100.845366)
		(end 11.379454 -101.05517)
		(stroke
			(width 0.0508)
			(type default)
		)
		(layer "B.Cu")
	)
	(gr_line
		(start 11.169904 -98.516948)
		(end 11.169904 -99.956366)
		(stroke
			(width 0.0508)
			(type default)
		)
		(layer "B.Cu")
	)
	(gr_arc
		(start 11.423904 -101.162104)
		(mid 11.412312 -101.104218)
		(end 11.379454 -101.05517)
		(stroke
			(width 0.0508)
			(type default)
		)
		(layer "B.Cu")
	)
	(gr_line
		(start 11.423904 -101.162104)
		(end 11.423904 -101.20503)
		(stroke
			(width 0.0508)
			(type default)
		)
		(layer "B.Cu")
	)
	(gr_arc
		(start 11.773662 -101.43236)
		(mid 11.768475 -101.491313)
		(end 11.766804 -101.55047)
		(stroke
			(width 0.0508)
			(type default)
		)
		(layer "B.Cu")
	)
	(gr_arc
		(start 11.80592 -101.272848)
		(mid 11.786525 -101.351944)
		(end 11.773662 -101.43236)
		(stroke
			(width 0.0508)
			(type default)
		)
		(layer "B.Cu")
	)
	(gr_arc
		(start 12.058904 -100.845366)
		(mid 11.905397 -101.043116)
		(end 11.80592 -101.272848)
		(stroke
			(width 0.0508)
			(type default)
		)
		(layer "B.Cu")
	)
	(gr_line
		(start 12.058904 -99.956366)
		(end 12.060682 -99.954588)
		(stroke
			(width 0.0508)
			(type default)
		)
		(layer "B.Cu")
	)
	(gr_line
		(start 12.060682 -98.495104)
		(end 12.060682 -99.954588)
		(stroke
			(width 0.0508)
			(type default)
		)
		(layer "B.Cu")
	)
	(gr_arc
		(start 13.582904 -98.649282)
		(mid 13.563569 -98.55208)
		(end 13.508482 -98.469704)
		(stroke
			(width 0.0508)
			(type default)
		)
		(layer "B.Cu")
	)
	(gr_line
		(start 13.582904 -98.649282)
		(end 13.582904 -99.956366)
		(stroke
			(width 0.0508)
			(type default)
		)
		(layer "B.Cu")
	)
	(gr_arc
		(start 13.749782 -101.24821)
		(mid 13.706389 -101.030202)
		(end 13.582904 -100.845366)
		(stroke
			(width 0.0508)
			(type default)
		)
		(layer "B.Cu")
	)
	(gr_arc
		(start 14.123162 -101.055932)
		(mid 14.100581 -101.089727)
		(end 14.092682 -101.129592)
		(stroke
			(width 0.0508)
			(type default)
		)
		(layer "B.Cu")
	)
	(gr_line
		(start 14.123162 -101.055932)
		(end 14.193774 -100.985066)
		(stroke
			(width 0.0508)
			(type default)
		)
		(layer "B.Cu")
	)
	(gr_line
		(start 14.193774 -100.985066)
		(end 14.23543 -100.943156)
		(stroke
			(width 0.0508)
			(type default)
		)
		(layer "B.Cu")
	)
	(gr_line
		(start 14.448282 -98.520504)
		(end 14.471904 -98.544126)
		(stroke
			(width 0.0508)
			(type default)
		)
		(layer "B.Cu")
	)
	(gr_arc
		(start 14.471904 -100.845366)
		(mid 14.343933 -100.870727)
		(end 14.23543 -100.943156)
		(stroke
			(width 0.0508)
			(type default)
		)
		(layer "B.Cu")
	)
	(gr_line
		(start 14.471904 -98.544126)
		(end 14.471904 -99.956366)
		(stroke
			(width 0.0508)
			(type default)
		)
		(layer "B.Cu")
	)
	(gr_arc
		(start 15.995904 -98.613468)
		(mid 15.983162 -98.549412)
		(end 15.946882 -98.495104)
		(stroke
			(width 0.0508)
			(type default)
		)
		(layer "B.Cu")
	)
	(gr_line
		(start 15.995904 -98.613468)
		(end 15.995904 -99.956366)
		(stroke
			(width 0.0508)
			(type default)
		)
		(layer "B.Cu")
	)
	(gr_arc
		(start 16.22044 -101.290882)
		(mid 16.143929 -101.0501)
		(end 15.995904 -100.845366)
		(stroke
			(width 0.0508)
			(type default)
		)
		(layer "B.Cu")
	)
	(gr_arc
		(start 16.22298 -101.308154)
		(mid 16.221757 -101.299511)
		(end 16.22044 -101.290882)
		(stroke
			(width 0.0508)
			(type default)
		)
		(layer "B.Cu")
	)
	(gr_arc
		(start 16.227806 -101.36124)
		(mid 16.225841 -101.334656)
		(end 16.22298 -101.308154)
		(stroke
			(width 0.0508)
			(type default)
		)
		(layer "B.Cu")
	)
	(gr_arc
		(start 16.229584 -101.4095)
		(mid 16.229065 -101.385356)
		(end 16.227806 -101.36124)
		(stroke
			(width 0.0508)
			(type default)
		)
		(layer "B.Cu")
	)
	(gr_arc
		(start 16.701262 -101.029008)
		(mid 16.605953 -101.171648)
		(end 16.572484 -101.339904)
		(stroke
			(width 0.0508)
			(type default)
		)
		(layer "B.Cu")
	)
	(gr_line
		(start 16.701262 -101.029008)
		(end 16.884904 -100.845366)
		(stroke
			(width 0.0508)
			(type default)
		)
		(layer "B.Cu")
	)
	(gr_line
		(start 16.884904 -98.522282)
		(end 16.884904 -99.956366)
		(stroke
			(width 0.0508)
			(type default)
		)
		(layer "B.Cu")
	)
	(gr_line
		(start 16.884904 -98.522282)
		(end 16.886682 -98.520504)
		(stroke
			(width 0.0508)
			(type default)
		)
		(layer "B.Cu")
	)
	(gr_line
		(start 18.281904 -100.845366)
		(end 18.379948 -100.94341)
		(stroke
			(width 0.0508)
			(type default)
		)
		(layer "B.Cu")
	)
	(gr_arc
		(start 18.281904 -98.603054)
		(mid 18.275756 -98.572144)
		(end 18.258282 -98.545904)
		(stroke
			(width 0.0508)
			(type default)
		)
		(layer "B.Cu")
	)
	(gr_line
		(start 18.281904 -98.603054)
		(end 18.281904 -99.956366)
		(stroke
			(width 0.0508)
			(type default)
		)
		(layer "B.Cu")
	)
	(gr_arc
		(start 18.563082 -101.385624)
		(mid 18.51548 -101.146314)
		(end 18.379948 -100.94341)
		(stroke
			(width 0.0508)
			(type default)
		)
		(layer "B.Cu")
	)
	(gr_arc
		(start 18.905982 -101.47173)
		(mid 18.905958 -101.478334)
		(end 18.905982 -101.484938)
		(stroke
			(width 0.0508)
			(type default)
		)
		(layer "B.Cu")
	)
	(gr_line
		(start 18.908522 -101.442774)
		(end 18.91157 -101.407976)
		(stroke
			(width 0.0508)
			(type default)
		)
		(layer "B.Cu")
	)
	(gr_arc
		(start 18.94586 -101.28758)
		(mid 18.922899 -101.346123)
		(end 18.91157 -101.407976)
		(stroke
			(width 0.0508)
			(type default)
		)
		(layer "B.Cu")
	)
	(gr_line
		(start 18.94586 -101.28758)
		(end 19.170904 -100.845366)
		(stroke
			(width 0.0508)
			(type default)
		)
		(layer "B.Cu")
	)
	(gr_line
		(start 19.170904 -98.918014)
		(end 19.170904 -99.956366)
		(stroke
			(width 0.0508)
			(type default)
		)
		(layer "B.Cu")
	)
	(gr_arc
		(start 19.325082 -98.545904)
		(mid 19.21095 -98.716614)
		(end 19.170904 -98.918014)
		(stroke
			(width 0.0508)
			(type default)
		)
		(layer "B.Cu")
	)
	(gr_arc
		(start 19.686016 -106.6292)
		(mid 19.820009 -106.598708)
		(end 19.924776 -106.50982)
		(stroke
			(width 0.0508)
			(type default)
		)
		(layer "B.Cu")
	)
	(gr_line
		(start 20.031456 -106.9721)
		(end 20.600416 -106.9721)
		(stroke
			(width 0.0508)
			(type default)
		)
		(layer "B.Cu")
	)
	(gr_arc
		(start 20.163536 -106.39044)
		(mid 20.029606 -106.421027)
		(end 19.924776 -106.50982)
		(stroke
			(width 0.0508)
			(type default)
		)
		(layer "B.Cu")
	)
	(gr_line
		(start 20.163536 -106.39044)
		(end 20.468336 -106.39044)
		(stroke
			(width 0.0508)
			(type default)
		)
		(layer "B.Cu")
	)
	(gr_arc
		(start 20.707096 -106.50982)
		(mid 20.602322 -106.420911)
		(end 20.468336 -106.39044)
		(stroke
			(width 0.0508)
			(type default)
		)
		(layer "B.Cu")
	)
	(gr_arc
		(start 20.707096 -106.50982)
		(mid 20.81191 -106.598614)
		(end 20.945856 -106.6292)
		(stroke
			(width 0.0508)
			(type default)
		)
		(layer "B.Cu")
	)
	(gr_arc
		(start 21.250656 -106.6292)
		(mid 21.384649 -106.598708)
		(end 21.489416 -106.50982)
		(stroke
			(width 0.0508)
			(type default)
		)
		(layer "B.Cu")
	)
	(gr_line
		(start 21.596096 -106.9721)
		(end 22.165056 -106.9721)
		(stroke
			(width 0.0508)
			(type default)
		)
		(layer "B.Cu")
	)
	(gr_arc
		(start 21.728176 -106.39044)
		(mid 21.594234 -106.421013)
		(end 21.489416 -106.50982)
		(stroke
			(width 0.0508)
			(type default)
		)
		(layer "B.Cu")
	)
	(gr_line
		(start 21.728176 -106.39044)
		(end 22.032976 -106.39044)
		(stroke
			(width 0.0508)
			(type default)
		)
		(layer "B.Cu")
	)
	(gr_arc
		(start 22.271736 -106.50982)
		(mid 22.166958 -106.420933)
		(end 22.032976 -106.39044)
		(stroke
			(width 0.0508)
			(type default)
		)
		(layer "B.Cu")
	)
	(gr_arc
		(start 22.271736 -106.50982)
		(mid 22.37655 -106.598614)
		(end 22.510496 -106.6292)
		(stroke
			(width 0.0508)
			(type default)
		)
		(layer "B.Cu")
	)
	(gr_arc
		(start 22.815296 -106.6292)
		(mid 22.949289 -106.598708)
		(end 23.054056 -106.50982)
		(stroke
			(width 0.0508)
			(type default)
		)
		(layer "B.Cu")
	)
	(gr_line
		(start 23.160736 -106.9721)
		(end 23.729696 -106.9721)
		(stroke
			(width 0.0508)
			(type default)
		)
		(layer "B.Cu")
	)
	(gr_arc
		(start 23.292816 -106.39044)
		(mid 23.158892 -106.421035)
		(end 23.054056 -106.50982)
		(stroke
			(width 0.0508)
			(type default)
		)
		(layer "B.Cu")
	)
	(gr_line
		(start 23.292816 -106.39044)
		(end 23.597616 -106.39044)
		(stroke
			(width 0.0508)
			(type default)
		)
		(layer "B.Cu")
	)
	(gr_arc
		(start 23.836376 -106.50982)
		(mid 23.7316 -106.420919)
		(end 23.597616 -106.39044)
		(stroke
			(width 0.0508)
			(type default)
		)
		(layer "B.Cu")
	)
	(gr_arc
		(start 23.836376 -106.50982)
		(mid 23.94119 -106.598614)
		(end 24.075136 -106.6292)
		(stroke
			(width 0.0508)
			(type default)
		)
		(layer "B.Cu")
	)
	(gr_arc
		(start 24.799544 -104.01808)
		(mid 24.69473 -103.929286)
		(end 24.560784 -103.8987)
		(stroke
			(width 0.0508)
			(type default)
		)
		(layer "B.Cu")
	)
	(gr_arc
		(start 24.799544 -104.01808)
		(mid 24.904321 -104.106974)
		(end 25.038304 -104.13746)
		(stroke
			(width 0.0508)
			(type default)
		)
		(layer "B.Cu")
	)
	(gr_line
		(start 24.906224 -103.5558)
		(end 25.475184 -103.5558)
		(stroke
			(width 0.0508)
			(type default)
		)
		(layer "B.Cu")
	)
	(gr_line
		(start 25.038304 -104.13746)
		(end 25.343104 -104.13746)
		(stroke
			(width 0.0508)
			(type default)
		)
		(layer "B.Cu")
	)
	(gr_arc
		(start 25.343104 -104.13746)
		(mid 25.477052 -104.106895)
		(end 25.581864 -104.01808)
		(stroke
			(width 0.0508)
			(type default)
		)
		(layer "B.Cu")
	)
	(gr_arc
		(start 25.777952 -106.6292)
		(mid 25.911945 -106.598708)
		(end 26.016712 -106.50982)
		(stroke
			(width 0.0508)
			(type default)
		)
		(layer "B.Cu")
	)
	(gr_arc
		(start 25.820624 -103.8987)
		(mid 25.686631 -103.929192)
		(end 25.581864 -104.01808)
		(stroke
			(width 0.0508)
			(type default)
		)
		(layer "B.Cu")
	)
	(gr_line
		(start 26.123392 -106.9721)
		(end 26.692352 -106.9721)
		(stroke
			(width 0.0508)
			(type default)
		)
		(layer "B.Cu")
	)
	(gr_arc
		(start 26.255472 -106.39044)
		(mid 26.121486 -106.420924)
		(end 26.016712 -106.50982)
		(stroke
			(width 0.0508)
			(type default)
		)
		(layer "B.Cu")
	)
	(gr_line
		(start 26.255472 -106.39044)
		(end 26.560272 -106.39044)
		(stroke
			(width 0.0508)
			(type default)
		)
		(layer "B.Cu")
	)
	(gr_arc
		(start 26.364184 -104.01808)
		(mid 26.25937 -103.929286)
		(end 26.125424 -103.8987)
		(stroke
			(width 0.0508)
			(type default)
		)
		(layer "B.Cu")
	)
	(gr_arc
		(start 26.364184 -104.01808)
		(mid 26.468957 -104.106996)
		(end 26.602944 -104.13746)
		(stroke
			(width 0.0508)
			(type default)
		)
		(layer "B.Cu")
	)
	(gr_line
		(start 26.470864 -103.5558)
		(end 27.039824 -103.5558)
		(stroke
			(width 0.0508)
			(type default)
		)
		(layer "B.Cu")
	)
	(gr_line
		(start 26.602944 -104.13746)
		(end 26.907744 -104.13746)
		(stroke
			(width 0.0508)
			(type default)
		)
		(layer "B.Cu")
	)
	(gr_arc
		(start 26.799032 -106.50982)
		(mid 26.694253 -106.420935)
		(end 26.560272 -106.39044)
		(stroke
			(width 0.0508)
			(type default)
		)
		(layer "B.Cu")
	)
	(gr_arc
		(start 26.799032 -106.50982)
		(mid 26.903827 -106.598708)
		(end 27.037792 -106.6292)
		(stroke
			(width 0.0508)
			(type default)
		)
		(layer "B.Cu")
	)
	(gr_arc
		(start 26.907744 -104.13746)
		(mid 27.04168 -104.10688)
		(end 27.146504 -104.01808)
		(stroke
			(width 0.0508)
			(type default)
		)
		(layer "B.Cu")
	)
	(gr_arc
		(start 27.385264 -103.8987)
		(mid 27.251271 -103.929192)
		(end 27.146504 -104.01808)
		(stroke
			(width 0.0508)
			(type default)
		)
		(layer "B.Cu")
	)
	(gr_arc
		(start 28.322524 -106.6292)
		(mid 28.456517 -106.598708)
		(end 28.561284 -106.50982)
		(stroke
			(width 0.0508)
			(type default)
		)
		(layer "B.Cu")
	)
	(gr_line
		(start 28.667964 -106.9721)
		(end 29.236924 -106.9721)
		(stroke
			(width 0.0508)
			(type default)
		)
		(layer "B.Cu")
	)
	(gr_arc
		(start 28.800044 -106.39044)
		(mid 28.666111 -106.421024)
		(end 28.561284 -106.50982)
		(stroke
			(width 0.0508)
			(type default)
		)
		(layer "B.Cu")
	)
	(gr_line
		(start 28.800044 -106.39044)
		(end 29.104844 -106.39044)
		(stroke
			(width 0.0508)
			(type default)
		)
		(layer "B.Cu")
	)
	(gr_arc
		(start 29.343604 -106.50982)
		(mid 29.23883 -106.420908)
		(end 29.104844 -106.39044)
		(stroke
			(width 0.0508)
			(type default)
		)
		(layer "B.Cu")
	)
	(gr_arc
		(start 29.343604 -106.50982)
		(mid 29.448418 -106.598614)
		(end 29.582364 -106.6292)
		(stroke
			(width 0.0508)
			(type default)
		)
		(layer "B.Cu")
	)
	(gr_line
		(start 39.591996 -83.047078)
		(end 39.83609 -82.802984)
		(stroke
			(width 0.0508)
			(type default)
		)
		(layer "B.Cu")
	)
	(gr_line
		(start 39.591996 -82.070194)
		(end 39.83609 -82.314288)
		(stroke
			(width 0.0508)
			(type default)
		)
		(layer "B.Cu")
	)
	(gr_line
		(start 39.591996 -80.722978)
		(end 39.83609 -80.478884)
		(stroke
			(width 0.0508)
			(type default)
		)
		(layer "B.Cu")
	)
	(gr_line
		(start 39.591996 -79.746094)
		(end 39.83609 -79.990188)
		(stroke
			(width 0.0508)
			(type default)
		)
		(layer "B.Cu")
	)
	(gr_line
		(start 42.111422 -74.754486)
		(end 42.398696 -75.04176)
		(stroke
			(width 0.0508)
			(type default)
		)
		(layer "B.Cu")
	)
	(gr_arc
		(start 42.11193 -78.539086)
		(mid 42.141685 -78.610926)
		(end 42.21353 -78.640686)
		(stroke
			(width 0.0508)
			(type default)
		)
		(layer "B.Cu")
	)
	(gr_line
		(start 42.11193 -78.094586)
		(end 42.11193 -78.539086)
		(stroke
			(width 0.0508)
			(type default)
		)
		(layer "B.Cu")
	)
	(gr_line
		(start 42.11193 -77.205586)
		(end 42.203624 -77.113892)
		(stroke
			(width 0.0508)
			(type default)
		)
		(layer "B.Cu")
	)
	(gr_arc
		(start 42.203624 -77.113892)
		(mid 42.369972 -76.86484)
		(end 42.428414 -76.571094)
		(stroke
			(width 0.0508)
			(type default)
		)
		(layer "B.Cu")
	)
	(gr_line
		(start 42.21353 -78.640686)
		(end 42.34688 -78.640686)
		(stroke
			(width 0.0508)
			(type default)
		)
		(layer "B.Cu")
	)
	(gr_arc
		(start 42.428414 -75.113642)
		(mid 42.420695 -75.074747)
		(end 42.398696 -75.04176)
		(stroke
			(width 0.0508)
			(type default)
		)
		(layer "B.Cu")
	)
	(gr_arc
		(start 42.44848 -78.742286)
		(mid 42.418722 -78.670444)
		(end 42.34688 -78.640686)
		(stroke
			(width 0.0508)
			(type default)
		)
		(layer "B.Cu")
	)
	(gr_arc
		(start 42.771314 -76.344526)
		(mid 42.863964 -76.810531)
		(end 43.12793 -77.205586)
		(stroke
			(width 0.0508)
			(type default)
		)
		(layer "B.Cu")
	)
	(gr_arc
		(start 42.801032 -75.04176)
		(mid 42.779049 -75.074753)
		(end 42.771314 -75.113642)
		(stroke
			(width 0.0508)
			(type default)
		)
		(layer "B.Cu")
	)
	(gr_line
		(start 42.801032 -75.04176)
		(end 43.088306 -74.754486)
		(stroke
			(width 0.0508)
			(type default)
		)
		(layer "B.Cu")
	)
	(gr_arc
		(start 42.89298 -78.640686)
		(mid 42.821146 -78.67045)
		(end 42.79138 -78.742286)
		(stroke
			(width 0.0508)
			(type default)
		)
		(layer "B.Cu")
	)
	(gr_line
		(start 42.89298 -78.640686)
		(end 43.02633 -78.640686)
		(stroke
			(width 0.0508)
			(type default)
		)
		(layer "B.Cu")
	)
	(gr_arc
		(start 43.02633 -78.640686)
		(mid 43.098172 -78.610928)
		(end 43.12793 -78.539086)
		(stroke
			(width 0.0508)
			(type default)
		)
		(layer "B.Cu")
	)
	(gr_line
		(start 43.12793 -78.094586)
		(end 43.12793 -78.539086)
		(stroke
			(width 0.0508)
			(type default)
		)
		(layer "B.Cu")
	)
	(gr_line
		(start 44.511468 -74.906886)
		(end 44.798742 -75.19416)
		(stroke
			(width 0.0508)
			(type default)
		)
		(layer "B.Cu")
	)
	(gr_line
		(start 44.52493 -78.412086)
		(end 44.735242 -78.622398)
		(stroke
			(width 0.0508)
			(type default)
		)
		(layer "B.Cu")
	)
	(gr_line
		(start 44.52493 -78.094586)
		(end 44.52493 -78.412086)
		(stroke
			(width 0.0508)
			(type default)
		)
		(layer "B.Cu")
	)
	(gr_line
		(start 44.52493 -77.205586)
		(end 44.68876 -77.041756)
		(stroke
			(width 0.0508)
			(type default)
		)
		(layer "B.Cu")
	)
	(gr_arc
		(start 44.68876 -77.041756)
		(mid 44.792172 -76.887128)
		(end 44.82846 -76.704698)
		(stroke
			(width 0.0508)
			(type default)
		)
		(layer "B.Cu")
	)
	(gr_arc
		(start 44.82846 -75.266042)
		(mid 44.820741 -75.227147)
		(end 44.798742 -75.19416)
		(stroke
			(width 0.0508)
			(type default)
		)
		(layer "B.Cu")
	)
	(gr_arc
		(start 45.17136 -76.507086)
		(mid 45.23187 -76.81089)
		(end 45.404024 -77.068426)
		(stroke
			(width 0.0508)
			(type default)
		)
		(layer "B.Cu")
	)
	(gr_arc
		(start 45.201078 -75.19416)
		(mid 45.179085 -75.22715)
		(end 45.17136 -75.266042)
		(stroke
			(width 0.0508)
			(type default)
		)
		(layer "B.Cu")
	)
	(gr_line
		(start 45.201078 -75.19416)
		(end 45.488352 -74.906886)
		(stroke
			(width 0.0508)
			(type default)
		)
		(layer "B.Cu")
	)
	(gr_line
		(start 45.223684 -78.622398)
		(end 45.54093 -78.305152)
		(stroke
			(width 0.0508)
			(type default)
		)
		(layer "B.Cu")
	)
	(gr_line
		(start 45.404024 -77.068426)
		(end 45.54093 -77.205586)
		(stroke
			(width 0.0508)
			(type default)
		)
		(layer "B.Cu")
	)
	(gr_line
		(start 45.54093 -78.094586)
		(end 45.54093 -78.305152)
		(stroke
			(width 0.0508)
			(type default)
		)
		(layer "B.Cu")
	)
	(gr_arc
		(start 48.989996 -86.769194)
		(mid 49.298938 -86.975606)
		(end 49.66335 -87.048086)
		(stroke
			(width 0.0508)
			(type default)
		)
		(layer "B.Cu")
	)
	(gr_line
		(start 48.989996 -84.913978)
		(end 49.172114 -84.732114)
		(stroke
			(width 0.0508)
			(type default)
		)
		(layer "B.Cu")
	)
	(gr_line
		(start 48.989996 -83.937094)
		(end 49.172114 -84.118958)
		(stroke
			(width 0.0508)
			(type default)
		)
		(layer "B.Cu")
	)
	(gr_arc
		(start 49.172114 -84.118958)
		(mid 49.321615 -84.218944)
		(end 49.497996 -84.254086)
		(stroke
			(width 0.0508)
			(type default)
		)
		(layer "B.Cu")
	)
	(gr_arc
		(start 49.497996 -84.596986)
		(mid 49.321629 -84.632161)
		(end 49.172114 -84.732114)
		(stroke
			(width 0.0508)
			(type default)
		)
		(layer "B.Cu")
	)
	(gr_arc
		(start 49.847246 -87.390986)
		(mid 49.383303 -87.48327)
		(end 48.989996 -87.746078)
		(stroke
			(width 0.0508)
			(type default)
		)
		(layer "B.Cu")
	)
	(gr_line
		(start 50.87493 -77.59192)
		(end 51.114198 -77.831188)
		(stroke
			(width 0.0508)
			(type default)
		)
		(layer "B.Cu")
	)
	(gr_line
		(start 50.87493 -77.205586)
		(end 50.87493 -77.59192)
		(stroke
			(width 0.0508)
			(type default)
		)
		(layer "B.Cu")
	)
	(gr_line
		(start 50.87493 -76.316586)
		(end 51.151536 -76.03998)
		(stroke
			(width 0.0508)
			(type default)
		)
		(layer "B.Cu")
	)
	(gr_line
		(start 50.911506 -74.906886)
		(end 51.19878 -75.19416)
		(stroke
			(width 0.0508)
			(type default)
		)
		(layer "B.Cu")
	)
	(gr_arc
		(start 51.151536 -76.03998)
		(mid 51.208481 -75.954661)
		(end 51.228498 -75.854052)
		(stroke
			(width 0.0508)
			(type default)
		)
		(layer "B.Cu")
	)
	(gr_arc
		(start 51.228498 -75.266042)
		(mid 51.220779 -75.227147)
		(end 51.19878 -75.19416)
		(stroke
			(width 0.0508)
			(type default)
		)
		(layer "B.Cu")
	)
	(gr_arc
		(start 51.571398 -75.851766)
		(mid 51.621428 -76.103328)
		(end 51.76393 -76.316586)
		(stroke
			(width 0.0508)
			(type default)
		)
		(layer "B.Cu")
	)
	(gr_arc
		(start 51.601116 -75.19416)
		(mid 51.579115 -75.227148)
		(end 51.571398 -75.266042)
		(stroke
			(width 0.0508)
			(type default)
		)
		(layer "B.Cu")
	)
	(gr_line
		(start 51.601116 -75.19416)
		(end 51.88839 -74.906886)
		(stroke
			(width 0.0508)
			(type default)
		)
		(layer "B.Cu")
	)
	(gr_line
		(start 51.602894 -77.831188)
		(end 51.76393 -77.670152)
		(stroke
			(width 0.0508)
			(type default)
		)
		(layer "B.Cu")
	)
	(gr_line
		(start 51.76393 -77.205586)
		(end 51.76393 -77.670152)
		(stroke
			(width 0.0508)
			(type default)
		)
		(layer "B.Cu")
	)
	(gr_arc
		(start 53.28793 -77.650086)
		(mid 53.317688 -77.721928)
		(end 53.38953 -77.751686)
		(stroke
			(width 0.0508)
			(type default)
		)
		(layer "B.Cu")
	)
	(gr_line
		(start 53.28793 -77.205586)
		(end 53.28793 -77.650086)
		(stroke
			(width 0.0508)
			(type default)
		)
		(layer "B.Cu")
	)
	(gr_line
		(start 53.28793 -76.316586)
		(end 53.546502 -76.058014)
		(stroke
			(width 0.0508)
			(type default)
		)
		(layer "B.Cu")
	)
	(gr_line
		(start 53.311298 -74.906886)
		(end 53.598572 -75.19416)
		(stroke
			(width 0.0508)
			(type default)
		)
		(layer "B.Cu")
	)
	(gr_line
		(start 53.38953 -77.751686)
		(end 53.52288 -77.751686)
		(stroke
			(width 0.0508)
			(type default)
		)
		(layer "B.Cu")
	)
	(gr_arc
		(start 53.546502 -76.058014)
		(mid 53.607058 -75.96748)
		(end 53.62829 -75.860656)
		(stroke
			(width 0.0508)
			(type default)
		)
		(layer "B.Cu")
	)
	(gr_arc
		(start 53.62448 -77.853286)
		(mid 53.594716 -77.78146)
		(end 53.52288 -77.751686)
		(stroke
			(width 0.0508)
			(type default)
		)
		(layer "B.Cu")
	)
	(gr_arc
		(start 53.62829 -75.266042)
		(mid 53.620571 -75.227147)
		(end 53.598572 -75.19416)
		(stroke
			(width 0.0508)
			(type default)
		)
		(layer "B.Cu")
	)
	(gr_arc
		(start 53.97119 -75.745086)
		(mid 54.015128 -75.965591)
		(end 54.1401 -76.152502)
		(stroke
			(width 0.0508)
			(type default)
		)
		(layer "B.Cu")
	)
	(gr_arc
		(start 54.000908 -75.19416)
		(mid 53.978909 -75.227148)
		(end 53.97119 -75.266042)
		(stroke
			(width 0.0508)
			(type default)
		)
		(layer "B.Cu")
	)
	(gr_line
		(start 54.000908 -75.19416)
		(end 54.288182 -74.906886)
		(stroke
			(width 0.0508)
			(type default)
		)
		(layer "B.Cu")
	)
	(gr_arc
		(start 54.06898 -77.751686)
		(mid 53.997138 -77.781444)
		(end 53.96738 -77.853286)
		(stroke
			(width 0.0508)
			(type default)
		)
		(layer "B.Cu")
	)
	(gr_line
		(start 54.06898 -77.751686)
		(end 54.20233 -77.751686)
		(stroke
			(width 0.0508)
			(type default)
		)
		(layer "B.Cu")
	)
	(gr_line
		(start 54.1401 -76.152502)
		(end 54.30393 -76.316586)
		(stroke
			(width 0.0508)
			(type default)
		)
		(layer "B.Cu")
	)
	(gr_arc
		(start 54.20233 -77.751686)
		(mid 54.274148 -77.721917)
		(end 54.30393 -77.650086)
		(stroke
			(width 0.0508)
			(type default)
		)
		(layer "B.Cu")
	)
	(gr_line
		(start 54.30393 -77.205586)
		(end 54.30393 -77.650086)
		(stroke
			(width 0.0508)
			(type default)
		)
		(layer "B.Cu")
	)
	(gr_arc
		(start 61.436758 -92.995242)
		(mid 61.509981 -92.878954)
		(end 61.52134 -92.742004)
		(stroke
			(width 0.0508)
			(type default)
		)
		(layer "B.Cu")
	)
	(gr_arc
		(start 61.605668 -92.488766)
		(mid 61.532588 -92.605086)
		(end 61.52134 -92.742004)
		(stroke
			(width 0.0508)
			(type default)
		)
		(layer "B.Cu")
	)
	(gr_line
		(start 61.605668 -92.488766)
		(end 61.821314 -92.27312)
		(stroke
			(width 0.0508)
			(type default)
		)
		(layer "B.Cu")
	)
	(gr_line
		(start 61.923676 -92.993464)
		(end 62.326012 -92.591128)
		(stroke
			(width 0.0508)
			(type default)
		)
		(layer "B.Cu")
	)
	(gr_arc
		(start 62.074552 -92.188792)
		(mid 61.937651 -92.200067)
		(end 61.821314 -92.27312)
		(stroke
			(width 0.0508)
			(type default)
		)
		(layer "B.Cu")
	)
	(gr_arc
		(start 62.074552 -92.188792)
		(mid 62.2115 -92.177428)
		(end 62.32779 -92.10421)
		(stroke
			(width 0.0508)
			(type default)
		)
		(layer "B.Cu")
	)
	(gr_arc
		(start 65.244726 -89.187274)
		(mid 65.317786 -89.070949)
		(end 65.329054 -88.934036)
		(stroke
			(width 0.0508)
			(type default)
		)
		(layer "B.Cu")
	)
	(gr_arc
		(start 65.413382 -88.680798)
		(mid 65.34027 -88.797115)
		(end 65.329054 -88.934036)
		(stroke
			(width 0.0508)
			(type default)
		)
		(layer "B.Cu")
	)
	(gr_line
		(start 65.413382 -88.680798)
		(end 65.629028 -88.465406)
		(stroke
			(width 0.0508)
			(type default)
		)
		(layer "B.Cu")
	)
	(gr_line
		(start 65.731644 -89.185496)
		(end 66.133726 -88.783414)
		(stroke
			(width 0.0508)
			(type default)
		)
		(layer "B.Cu")
	)
	(gr_arc
		(start 65.882266 -88.380824)
		(mid 65.745306 -88.392167)
		(end 65.629028 -88.465406)
		(stroke
			(width 0.0508)
			(type default)
		)
		(layer "B.Cu")
	)
	(gr_arc
		(start 65.882266 -88.380824)
		(mid 66.019191 -88.369594)
		(end 66.135504 -88.296496)
		(stroke
			(width 0.0508)
			(type default)
		)
		(layer "B.Cu")
	)
	(gr_arc
		(start 66.35115 -88.08085)
		(mid 66.42421 -87.964525)
		(end 66.435478 -87.827612)
		(stroke
			(width 0.0508)
			(type default)
		)
		(layer "B.Cu")
	)
	(gr_arc
		(start 66.519806 -87.574374)
		(mid 66.446719 -87.690692)
		(end 66.435478 -87.827612)
		(stroke
			(width 0.0508)
			(type default)
		)
		(layer "B.Cu")
	)
	(gr_line
		(start 66.519806 -87.574374)
		(end 66.735452 -87.358982)
		(stroke
			(width 0.0508)
			(type default)
		)
		(layer "B.Cu")
	)
	(gr_line
		(start 66.838068 -88.079072)
		(end 67.24015 -87.67699)
		(stroke
			(width 0.0508)
			(type default)
		)
		(layer "B.Cu")
	)
	(gr_arc
		(start 66.98869 -87.274654)
		(mid 66.851777 -87.285912)
		(end 66.735452 -87.358982)
		(stroke
			(width 0.0508)
			(type default)
		)
		(layer "B.Cu")
	)
	(gr_arc
		(start 66.98869 -87.274654)
		(mid 67.125638 -87.26329)
		(end 67.241928 -87.190072)
		(stroke
			(width 0.0508)
			(type default)
		)
		(layer "B.Cu")
	)
	(gr_arc
		(start 67.45732 -86.97468)
		(mid 67.530543 -86.858392)
		(end 67.541902 -86.721442)
		(stroke
			(width 0.0508)
			(type default)
		)
		(layer "B.Cu")
	)
	(gr_arc
		(start 67.62623 -86.468204)
		(mid 67.553108 -86.584519)
		(end 67.541902 -86.721442)
		(stroke
			(width 0.0508)
			(type default)
		)
		(layer "B.Cu")
	)
	(gr_line
		(start 67.62623 -86.468204)
		(end 67.841876 -86.252558)
		(stroke
			(width 0.0508)
			(type default)
		)
		(layer "B.Cu")
	)
	(gr_line
		(start 67.944238 -86.972902)
		(end 68.346574 -86.570566)
		(stroke
			(width 0.0508)
			(type default)
		)
		(layer "B.Cu")
	)
	(gr_arc
		(start 68.095114 -86.16823)
		(mid 67.958194 -86.179477)
		(end 67.841876 -86.252558)
		(stroke
			(width 0.0508)
			(type default)
		)
		(layer "B.Cu")
	)
	(gr_arc
		(start 68.095114 -86.16823)
		(mid 68.232062 -86.156866)
		(end 68.348352 -86.083648)
		(stroke
			(width 0.0508)
			(type default)
		)
		(layer "B.Cu")
	)
	(gr_line
		(start 68.954396 -81.921604)
		(end 69.356478 -81.519522)
		(stroke
			(width 0.0508)
			(type default)
		)
		(layer "B.Cu")
	)
	(gr_arc
		(start 69.205856 -82.324194)
		(mid 69.068949 -82.335465)
		(end 68.952618 -82.408522)
		(stroke
			(width 0.0508)
			(type default)
		)
		(layer "B.Cu")
	)
	(gr_arc
		(start 69.205856 -82.324194)
		(mid 69.342781 -82.312964)
		(end 69.459094 -82.239866)
		(stroke
			(width 0.0508)
			(type default)
		)
		(layer "B.Cu")
	)
	(gr_line
		(start 69.459094 -82.239866)
		(end 69.674486 -82.02422)
		(stroke
			(width 0.0508)
			(type default)
		)
		(layer "B.Cu")
	)
	(gr_arc
		(start 69.674486 -82.02422)
		(mid 69.747709 -81.907932)
		(end 69.759068 -81.770982)
		(stroke
			(width 0.0508)
			(type default)
		)
		(layer "B.Cu")
	)
	(gr_arc
		(start 69.843396 -81.517744)
		(mid 69.770299 -81.634062)
		(end 69.759068 -81.770982)
		(stroke
			(width 0.0508)
			(type default)
		)
		(layer "B.Cu")
	)
	(gr_line
		(start 70.06082 -80.81518)
		(end 70.462902 -80.413098)
		(stroke
			(width 0.0508)
			(type default)
		)
		(layer "B.Cu")
	)
	(gr_arc
		(start 70.31228 -81.21777)
		(mid 70.175371 -81.229033)
		(end 70.059042 -81.302098)
		(stroke
			(width 0.0508)
			(type default)
		)
		(layer "B.Cu")
	)
	(gr_arc
		(start 70.31228 -81.21777)
		(mid 70.449205 -81.20654)
		(end 70.565518 -81.133442)
		(stroke
			(width 0.0508)
			(type default)
		)
		(layer "B.Cu")
	)
	(gr_line
		(start 70.565518 -81.133442)
		(end 70.78091 -80.917796)
		(stroke
			(width 0.0508)
			(type default)
		)
		(layer "B.Cu")
	)
	(gr_arc
		(start 70.78091 -80.917796)
		(mid 70.85397 -80.801471)
		(end 70.865238 -80.664558)
		(stroke
			(width 0.0508)
			(type default)
		)
		(layer "B.Cu")
	)
	(gr_arc
		(start 70.94982 -80.41132)
		(mid 70.876631 -80.527612)
		(end 70.865238 -80.664558)
		(stroke
			(width 0.0508)
			(type default)
		)
		(layer "B.Cu")
	)
	(gr_line
		(start 71.16699 -79.70901)
		(end 71.569326 -79.306674)
		(stroke
			(width 0.0508)
			(type default)
		)
		(layer "B.Cu")
	)
	(gr_arc
		(start 71.41845 -80.111346)
		(mid 71.281495 -80.122696)
		(end 71.165212 -80.195928)
		(stroke
			(width 0.0508)
			(type default)
		)
		(layer "B.Cu")
	)
	(gr_arc
		(start 71.41845 -80.111346)
		(mid 71.555375 -80.100116)
		(end 71.671688 -80.027018)
		(stroke
			(width 0.0508)
			(type default)
		)
		(layer "B.Cu")
	)
	(gr_line
		(start 71.671688 -80.027018)
		(end 71.887334 -79.811626)
		(stroke
			(width 0.0508)
			(type default)
		)
		(layer "B.Cu")
	)
	(gr_arc
		(start 71.887334 -79.811626)
		(mid 71.960434 -79.695182)
		(end 71.971662 -79.558134)
		(stroke
			(width 0.0508)
			(type default)
		)
		(layer "B.Cu")
	)
	(gr_arc
		(start 72.056244 -79.304896)
		(mid 71.983039 -79.421187)
		(end 71.971662 -79.558134)
		(stroke
			(width 0.0508)
			(type default)
		)
		(layer "B.Cu")
	)
	(gr_line
		(start 73.000362 -254.679958)
		(end 73.000362 -256.50444)
		(stroke
			(width 0.0508)
			(type default)
		)
		(layer "B.Cu")
	)
	(gr_arc
		(start 73.162414 -254.288798)
		(mid 73.042481 -254.468257)
		(end 73.000362 -254.679958)
		(stroke
			(width 0.0508)
			(type default)
		)
		(layer "B.Cu")
	)
	(gr_arc
		(start 73.162414 -254.288798)
		(mid 73.198155 -254.235308)
		(end 73.210674 -254.172212)
		(stroke
			(width 0.0508)
			(type default)
		)
		(layer "B.Cu")
	)
	(gr_arc
		(start 73.22439 -254.124206)
		(mid 73.214169 -254.147248)
		(end 73.210674 -254.172212)
		(stroke
			(width 0.0508)
			(type default)
		)
		(layer "B.Cu")
	)
	(gr_line
		(start 73.22439 -254.124206)
		(end 73.230486 -254.1143)
		(stroke
			(width 0.0508)
			(type default)
		)
		(layer "B.Cu")
	)
	(gr_arc
		(start 73.230486 -254.1143)
		(mid 73.234008 -254.101037)
		(end 73.235312 -254.087376)
		(stroke
			(width 0.0508)
			(type default)
		)
		(layer "B.Cu")
	)
	(gr_line
		(start 73.235312 -254.012192)
		(end 73.235312 -254.087376)
		(stroke
			(width 0.0508)
			(type default)
		)
		(layer "B.Cu")
	)
	(gr_line
		(start 73.235312 -245.29288)
		(end 73.235312 -245.86184)
		(stroke
			(width 0.0508)
			(type default)
		)
		(layer "B.Cu")
	)
	(gr_line
		(start 73.235312 -243.72824)
		(end 73.235312 -244.2972)
		(stroke
			(width 0.0508)
			(type default)
		)
		(layer "B.Cu")
	)
	(gr_line
		(start 73.235312 -242.1636)
		(end 73.235312 -242.73256)
		(stroke
			(width 0.0508)
			(type default)
		)
		(layer "B.Cu")
	)
	(gr_line
		(start 73.235312 -235.82376)
		(end 73.235312 -236.39272)
		(stroke
			(width 0.0508)
			(type default)
		)
		(layer "B.Cu")
	)
	(gr_line
		(start 73.235312 -234.25912)
		(end 73.235312 -234.82808)
		(stroke
			(width 0.0508)
			(type default)
		)
		(layer "B.Cu")
	)
	(gr_line
		(start 73.235312 -232.69448)
		(end 73.235312 -233.26344)
		(stroke
			(width 0.0508)
			(type default)
		)
		(layer "B.Cu")
	)
	(gr_line
		(start 73.235312 -226.35464)
		(end 73.235312 -226.9236)
		(stroke
			(width 0.0508)
			(type default)
		)
		(layer "B.Cu")
	)
	(gr_arc
		(start 73.578212 -253.666752)
		(mid 73.590387 -253.79054)
		(end 73.626472 -253.909576)
		(stroke
			(width 0.0508)
			(type default)
		)
		(layer "B.Cu")
	)
	(gr_arc
		(start 73.578212 -244.94744)
		(mid 73.608796 -245.081371)
		(end 73.697592 -245.1862)
		(stroke
			(width 0.0508)
			(type default)
		)
		(layer "B.Cu")
	)
	(gr_arc
		(start 73.578212 -243.3828)
		(mid 73.608781 -243.516743)
		(end 73.697592 -243.62156)
		(stroke
			(width 0.0508)
			(type default)
		)
		(layer "B.Cu")
	)
	(gr_arc
		(start 73.578212 -241.81816)
		(mid 73.608803 -241.952085)
		(end 73.697592 -242.05692)
		(stroke
			(width 0.0508)
			(type default)
		)
		(layer "B.Cu")
	)
	(gr_arc
		(start 73.578212 -235.47832)
		(mid 73.608788 -235.612257)
		(end 73.697592 -235.71708)
		(stroke
			(width 0.0508)
			(type default)
		)
		(layer "B.Cu")
	)
	(gr_arc
		(start 73.578212 -233.91368)
		(mid 73.60881 -234.047599)
		(end 73.697592 -234.15244)
		(stroke
			(width 0.0508)
			(type default)
		)
		(layer "B.Cu")
	)
	(gr_arc
		(start 73.578212 -232.34904)
		(mid 73.608796 -232.482971)
		(end 73.697592 -232.5878)
		(stroke
			(width 0.0508)
			(type default)
		)
		(layer "B.Cu")
	)
	(gr_arc
		(start 73.578212 -226.0092)
		(mid 73.608781 -226.143143)
		(end 73.697592 -226.24796)
		(stroke
			(width 0.0508)
			(type default)
		)
		(layer "B.Cu")
	)
	(gr_line
		(start 73.626472 -253.909576)
		(end 73.813924 -254.362712)
		(stroke
			(width 0.0508)
			(type default)
		)
		(layer "B.Cu")
	)
	(gr_arc
		(start 73.697592 -245.96852)
		(mid 73.608698 -246.073298)
		(end 73.578212 -246.20728)
		(stroke
			(width 0.0508)
			(type default)
		)
		(layer "B.Cu")
	)
	(gr_arc
		(start 73.697592 -245.96852)
		(mid 73.786386 -245.863706)
		(end 73.816972 -245.72976)
		(stroke
			(width 0.0508)
			(type default)
		)
		(layer "B.Cu")
	)
	(gr_arc
		(start 73.697592 -244.40388)
		(mid 73.608683 -244.508655)
		(end 73.578212 -244.64264)
		(stroke
			(width 0.0508)
			(type default)
		)
		(layer "B.Cu")
	)
	(gr_arc
		(start 73.697592 -244.40388)
		(mid 73.786386 -244.299066)
		(end 73.816972 -244.16512)
		(stroke
			(width 0.0508)
			(type default)
		)
		(layer "B.Cu")
	)
	(gr_arc
		(start 73.697592 -242.83924)
		(mid 73.608705 -242.944019)
		(end 73.578212 -243.078)
		(stroke
			(width 0.0508)
			(type default)
		)
		(layer "B.Cu")
	)
	(gr_arc
		(start 73.697592 -242.83924)
		(mid 73.786386 -242.734426)
		(end 73.816972 -242.60048)
		(stroke
			(width 0.0508)
			(type default)
		)
		(layer "B.Cu")
	)
	(gr_arc
		(start 73.697592 -236.4994)
		(mid 73.60869 -236.604176)
		(end 73.578212 -236.73816)
		(stroke
			(width 0.0508)
			(type default)
		)
		(layer "B.Cu")
	)
	(gr_arc
		(start 73.697592 -236.4994)
		(mid 73.786386 -236.394586)
		(end 73.816972 -236.26064)
		(stroke
			(width 0.0508)
			(type default)
		)
		(layer "B.Cu")
	)
	(gr_arc
		(start 73.697592 -234.93476)
		(mid 73.608712 -235.039541)
		(end 73.578212 -235.17352)
		(stroke
			(width 0.0508)
			(type default)
		)
		(layer "B.Cu")
	)
	(gr_arc
		(start 73.697592 -234.93476)
		(mid 73.786386 -234.829946)
		(end 73.816972 -234.696)
		(stroke
			(width 0.0508)
			(type default)
		)
		(layer "B.Cu")
	)
	(gr_arc
		(start 73.697592 -233.37012)
		(mid 73.608698 -233.474898)
		(end 73.578212 -233.60888)
		(stroke
			(width 0.0508)
			(type default)
		)
		(layer "B.Cu")
	)
	(gr_arc
		(start 73.697592 -233.37012)
		(mid 73.786386 -233.265306)
		(end 73.816972 -233.13136)
		(stroke
			(width 0.0508)
			(type default)
		)
		(layer "B.Cu")
	)
	(gr_arc
		(start 73.697592 -227.03028)
		(mid 73.608683 -227.135055)
		(end 73.578212 -227.26904)
		(stroke
			(width 0.0508)
			(type default)
		)
		(layer "B.Cu")
	)
	(gr_arc
		(start 73.697592 -227.03028)
		(mid 73.786386 -226.925466)
		(end 73.816972 -226.79152)
		(stroke
			(width 0.0508)
			(type default)
		)
		(layer "B.Cu")
	)
	(gr_arc
		(start 73.816972 -245.42496)
		(mid 73.78648 -245.290967)
		(end 73.697592 -245.1862)
		(stroke
			(width 0.0508)
			(type default)
		)
		(layer "B.Cu")
	)
	(gr_line
		(start 73.816972 -245.42496)
		(end 73.816972 -245.72976)
		(stroke
			(width 0.0508)
			(type default)
		)
		(layer "B.Cu")
	)
	(gr_arc
		(start 73.816972 -243.86032)
		(mid 73.78648 -243.726327)
		(end 73.697592 -243.62156)
		(stroke
			(width 0.0508)
			(type default)
		)
		(layer "B.Cu")
	)
	(gr_line
		(start 73.816972 -243.86032)
		(end 73.816972 -244.16512)
		(stroke
			(width 0.0508)
			(type default)
		)
		(layer "B.Cu")
	)
	(gr_arc
		(start 73.816972 -242.29568)
		(mid 73.78648 -242.161687)
		(end 73.697592 -242.05692)
		(stroke
			(width 0.0508)
			(type default)
		)
		(layer "B.Cu")
	)
	(gr_line
		(start 73.816972 -242.29568)
		(end 73.816972 -242.60048)
		(stroke
			(width 0.0508)
			(type default)
		)
		(layer "B.Cu")
	)
	(gr_arc
		(start 73.816972 -235.95584)
		(mid 73.78648 -235.821847)
		(end 73.697592 -235.71708)
		(stroke
			(width 0.0508)
			(type default)
		)
		(layer "B.Cu")
	)
	(gr_line
		(start 73.816972 -235.95584)
		(end 73.816972 -236.26064)
		(stroke
			(width 0.0508)
			(type default)
		)
		(layer "B.Cu")
	)
	(gr_arc
		(start 73.816972 -234.3912)
		(mid 73.78648 -234.257207)
		(end 73.697592 -234.15244)
		(stroke
			(width 0.0508)
			(type default)
		)
		(layer "B.Cu")
	)
	(gr_line
		(start 73.816972 -234.3912)
		(end 73.816972 -234.696)
		(stroke
			(width 0.0508)
			(type default)
		)
		(layer "B.Cu")
	)
	(gr_arc
		(start 73.816972 -232.82656)
		(mid 73.78648 -232.692567)
		(end 73.697592 -232.5878)
		(stroke
			(width 0.0508)
			(type default)
		)
		(layer "B.Cu")
	)
	(gr_line
		(start 73.816972 -232.82656)
		(end 73.816972 -233.13136)
		(stroke
			(width 0.0508)
			(type default)
		)
		(layer "B.Cu")
	)
	(gr_arc
		(start 73.816972 -226.48672)
		(mid 73.78648 -226.352727)
		(end 73.697592 -226.24796)
		(stroke
			(width 0.0508)
			(type default)
		)
		(layer "B.Cu")
	)
	(gr_line
		(start 73.816972 -226.48672)
		(end 73.816972 -226.79152)
		(stroke
			(width 0.0508)
			(type default)
		)
		(layer "B.Cu")
	)
	(gr_arc
		(start 73.999852 -254.811784)
		(mid 73.951531 -254.568766)
		(end 73.813924 -254.362712)
		(stroke
			(width 0.0508)
			(type default)
		)
		(layer "B.Cu")
	)
	(gr_line
		(start 73.999852 -254.811784)
		(end 73.999852 -256.50444)
		(stroke
			(width 0.0508)
			(type default)
		)
		(layer "B.Cu")
	)
	(gr_line
		(start 76.157074 -36.659312)
		(end 76.366116 -36.450524)
		(stroke
			(width 0.0508)
			(type default)
		)
		(layer "B.Cu")
	)
	(gr_arc
		(start 76.366116 -36.450524)
		(mid 76.391483 -36.419557)
		(end 76.410312 -36.38423)
		(stroke
			(width 0.0508)
			(type default)
		)
		(layer "B.Cu")
	)
	(gr_line
		(start 76.410312 -36.38423)
		(end 76.458826 -36.266628)
		(stroke
			(width 0.0508)
			(type default)
		)
		(layer "B.Cu")
	)
	(gr_arc
		(start 76.458826 -36.266628)
		(mid 76.47022 -36.228765)
		(end 76.474066 -36.189412)
		(stroke
			(width 0.0508)
			(type default)
		)
		(layer "B.Cu")
	)
	(gr_arc
		(start 76.816966 -36.415726)
		(mid 76.832414 -36.49339)
		(end 76.876402 -36.559236)
		(stroke
			(width 0.0508)
			(type default)
		)
		(layer "B.Cu")
	)
	(gr_line
		(start 76.876402 -36.559236)
		(end 76.917042 -36.599876)
		(stroke
			(width 0.0508)
			(type default)
		)
		(layer "B.Cu")
	)
	(gr_arc
		(start 76.917042 -36.599876)
		(mid 76.982885 -36.643871)
		(end 77.060552 -36.659312)
		(stroke
			(width 0.0508)
			(type default)
		)
		(layer "B.Cu")
	)
	(gr_arc
		(start 76.956412 -256.4003)
		(mid 76.967619 -256.456674)
		(end 76.999592 -256.50444)
		(stroke
			(width 0.0508)
			(type default)
		)
		(layer "B.Cu")
	)
	(gr_line
		(start 76.956412 -254.31877)
		(end 76.956412 -256.4003)
		(stroke
			(width 0.0508)
			(type default)
		)
		(layer "B.Cu")
	)
	(gr_line
		(start 77.060552 -36.659312)
		(end 77.133958 -36.659312)
		(stroke
			(width 0.0508)
			(type default)
		)
		(layer "B.Cu")
	)
	(gr_arc
		(start 77.127862 -253.90475)
		(mid 77.000965 -254.094709)
		(end 76.956412 -254.31877)
		(stroke
			(width 0.0508)
			(type default)
		)
		(layer "B.Cu")
	)
	(gr_arc
		(start 77.127862 -253.90475)
		(mid 77.254503 -253.715119)
		(end 77.299058 -253.491492)
		(stroke
			(width 0.0508)
			(type default)
		)
		(layer "B.Cu")
	)
	(gr_arc
		(start 77.299058 -253.491492)
		(mid 77.299185 -253.491111)
		(end 77.299312 -253.49073)
		(stroke
			(width 0.0508)
			(type default)
		)
		(layer "B.Cu")
	)
	(gr_line
		(start 77.299312 -248.030492)
		(end 77.299312 -248.599452)
		(stroke
			(width 0.0508)
			(type default)
		)
		(layer "B.Cu")
	)
	(gr_line
		(start 77.299312 -246.465852)
		(end 77.299312 -247.034812)
		(stroke
			(width 0.0508)
			(type default)
		)
		(layer "B.Cu")
	)
	(gr_line
		(start 77.299312 -240.126012)
		(end 77.299312 -240.694972)
		(stroke
			(width 0.0508)
			(type default)
		)
		(layer "B.Cu")
	)
	(gr_line
		(start 77.299312 -238.561372)
		(end 77.299312 -239.130332)
		(stroke
			(width 0.0508)
			(type default)
		)
		(layer "B.Cu")
	)
	(gr_line
		(start 77.299312 -236.996732)
		(end 77.299312 -237.565692)
		(stroke
			(width 0.0508)
			(type default)
		)
		(layer "B.Cu")
	)
	(gr_line
		(start 77.299312 -229.667308)
		(end 77.299312 -230.236268)
		(stroke
			(width 0.0508)
			(type default)
		)
		(layer "B.Cu")
	)
	(gr_line
		(start 77.299312 -228.102668)
		(end 77.299312 -228.671628)
		(stroke
			(width 0.0508)
			(type default)
		)
		(layer "B.Cu")
	)
	(gr_arc
		(start 77.642212 -253.31674)
		(mid 77.652759 -253.4322)
		(end 77.684122 -253.543816)
		(stroke
			(width 0.0508)
			(type default)
		)
		(layer "B.Cu")
	)
	(gr_arc
		(start 77.642212 -247.685052)
		(mid 77.672703 -247.819033)
		(end 77.761592 -247.923812)
		(stroke
			(width 0.0508)
			(type default)
		)
		(layer "B.Cu")
	)
	(gr_arc
		(start 77.642212 -246.120412)
		(mid 77.672725 -246.254376)
		(end 77.761592 -246.359172)
		(stroke
			(width 0.0508)
			(type default)
		)
		(layer "B.Cu")
	)
	(gr_arc
		(start 77.642212 -239.780572)
		(mid 77.67271 -239.914547)
		(end 77.761592 -240.019332)
		(stroke
			(width 0.0508)
			(type default)
		)
		(layer "B.Cu")
	)
	(gr_arc
		(start 77.642212 -238.215932)
		(mid 77.672696 -238.349919)
		(end 77.761592 -238.454692)
		(stroke
			(width 0.0508)
			(type default)
		)
		(layer "B.Cu")
	)
	(gr_arc
		(start 77.642212 -236.651292)
		(mid 77.672718 -236.785262)
		(end 77.761592 -236.890052)
		(stroke
			(width 0.0508)
			(type default)
		)
		(layer "B.Cu")
	)
	(gr_arc
		(start 77.642212 -229.321868)
		(mid 77.672806 -229.45579)
		(end 77.761592 -229.560628)
		(stroke
			(width 0.0508)
			(type default)
		)
		(layer "B.Cu")
	)
	(gr_arc
		(start 77.642212 -227.757228)
		(mid 77.672791 -227.891162)
		(end 77.761592 -227.995988)
		(stroke
			(width 0.0508)
			(type default)
		)
		(layer "B.Cu")
	)
	(gr_line
		(start 77.684122 -253.543816)
		(end 77.958442 -254.259588)
		(stroke
			(width 0.0508)
			(type default)
		)
		(layer "B.Cu")
	)
	(gr_line
		(start 77.686408 -41.6052)
		(end 77.973682 -41.317926)
		(stroke
			(width 0.0508)
			(type default)
		)
		(layer "B.Cu")
	)
	(gr_arc
		(start 77.761592 -248.706132)
		(mid 77.672702 -248.810911)
		(end 77.642212 -248.944892)
		(stroke
			(width 0.0508)
			(type default)
		)
		(layer "B.Cu")
	)
	(gr_arc
		(start 77.761592 -248.706132)
		(mid 77.85048 -248.601337)
		(end 77.880972 -248.467372)
		(stroke
			(width 0.0508)
			(type default)
		)
		(layer "B.Cu")
	)
	(gr_arc
		(start 77.761592 -247.141492)
		(mid 77.672687 -247.246268)
		(end 77.642212 -247.380252)
		(stroke
			(width 0.0508)
			(type default)
		)
		(layer "B.Cu")
	)
	(gr_arc
		(start 77.761592 -247.141492)
		(mid 77.85048 -247.036697)
		(end 77.880972 -246.902732)
		(stroke
			(width 0.0508)
			(type default)
		)
		(layer "B.Cu")
	)
	(gr_arc
		(start 77.761592 -240.801652)
		(mid 77.672709 -240.906432)
		(end 77.642212 -241.040412)
		(stroke
			(width 0.0508)
			(type default)
		)
		(layer "B.Cu")
	)
	(gr_arc
		(start 77.761592 -240.801652)
		(mid 77.85048 -240.696857)
		(end 77.880972 -240.562892)
		(stroke
			(width 0.0508)
			(type default)
		)
		(layer "B.Cu")
	)
	(gr_arc
		(start 77.761592 -239.237012)
		(mid 77.672695 -239.341789)
		(end 77.642212 -239.475772)
		(stroke
			(width 0.0508)
			(type default)
		)
		(layer "B.Cu")
	)
	(gr_arc
		(start 77.761592 -239.237012)
		(mid 77.85048 -239.132217)
		(end 77.880972 -238.998252)
		(stroke
			(width 0.0508)
			(type default)
		)
		(layer "B.Cu")
	)
	(gr_arc
		(start 77.761592 -237.672372)
		(mid 77.67268 -237.777146)
		(end 77.642212 -237.911132)
		(stroke
			(width 0.0508)
			(type default)
		)
		(layer "B.Cu")
	)
	(gr_arc
		(start 77.761592 -237.672372)
		(mid 77.85048 -237.567577)
		(end 77.880972 -237.433612)
		(stroke
			(width 0.0508)
			(type default)
		)
		(layer "B.Cu")
	)
	(gr_arc
		(start 77.761592 -230.342948)
		(mid 77.672708 -230.447728)
		(end 77.642212 -230.581708)
		(stroke
			(width 0.0508)
			(type default)
		)
		(layer "B.Cu")
	)
	(gr_arc
		(start 77.761592 -230.342948)
		(mid 77.850386 -230.238134)
		(end 77.880972 -230.104188)
		(stroke
			(width 0.0508)
			(type default)
		)
		(layer "B.Cu")
	)
	(gr_arc
		(start 77.761592 -228.778308)
		(mid 77.672693 -228.883085)
		(end 77.642212 -229.017068)
		(stroke
			(width 0.0508)
			(type default)
		)
		(layer "B.Cu")
	)
	(gr_arc
		(start 77.761592 -228.778308)
		(mid 77.850386 -228.673494)
		(end 77.880972 -228.539548)
		(stroke
			(width 0.0508)
			(type default)
		)
		(layer "B.Cu")
	)
	(gr_arc
		(start 77.880972 -248.162572)
		(mid 77.85048 -248.028579)
		(end 77.761592 -247.923812)
		(stroke
			(width 0.0508)
			(type default)
		)
		(layer "B.Cu")
	)
	(gr_line
		(start 77.880972 -248.162572)
		(end 77.880972 -248.467372)
		(stroke
			(width 0.0508)
			(type default)
		)
		(layer "B.Cu")
	)
	(gr_arc
		(start 77.880972 -246.597932)
		(mid 77.85048 -246.463939)
		(end 77.761592 -246.359172)
		(stroke
			(width 0.0508)
			(type default)
		)
		(layer "B.Cu")
	)
	(gr_line
		(start 77.880972 -246.597932)
		(end 77.880972 -246.902732)
		(stroke
			(width 0.0508)
			(type default)
		)
		(layer "B.Cu")
	)
	(gr_arc
		(start 77.880972 -240.258092)
		(mid 77.85048 -240.124099)
		(end 77.761592 -240.019332)
		(stroke
			(width 0.0508)
			(type default)
		)
		(layer "B.Cu")
	)
	(gr_line
		(start 77.880972 -240.258092)
		(end 77.880972 -240.562892)
		(stroke
			(width 0.0508)
			(type default)
		)
		(layer "B.Cu")
	)
	(gr_arc
		(start 77.880972 -238.693452)
		(mid 77.85048 -238.559459)
		(end 77.761592 -238.454692)
		(stroke
			(width 0.0508)
			(type default)
		)
		(layer "B.Cu")
	)
	(gr_line
		(start 77.880972 -238.693452)
		(end 77.880972 -238.998252)
		(stroke
			(width 0.0508)
			(type default)
		)
		(layer "B.Cu")
	)
	(gr_arc
		(start 77.880972 -237.128812)
		(mid 77.85048 -236.994819)
		(end 77.761592 -236.890052)
		(stroke
			(width 0.0508)
			(type default)
		)
		(layer "B.Cu")
	)
	(gr_line
		(start 77.880972 -237.128812)
		(end 77.880972 -237.433612)
		(stroke
			(width 0.0508)
			(type default)
		)
		(layer "B.Cu")
	)
	(gr_arc
		(start 77.880972 -229.799388)
		(mid 77.85048 -229.665395)
		(end 77.761592 -229.560628)
		(stroke
			(width 0.0508)
			(type default)
		)
		(layer "B.Cu")
	)
	(gr_line
		(start 77.880972 -229.799388)
		(end 77.880972 -230.104188)
		(stroke
			(width 0.0508)
			(type default)
		)
		(layer "B.Cu")
	)
	(gr_arc
		(start 77.880972 -228.234748)
		(mid 77.85048 -228.100755)
		(end 77.761592 -227.995988)
		(stroke
			(width 0.0508)
			(type default)
		)
		(layer "B.Cu")
	)
	(gr_line
		(start 77.880972 -228.234748)
		(end 77.880972 -228.539548)
		(stroke
			(width 0.0508)
			(type default)
		)
		(layer "B.Cu")
	)
	(gr_arc
		(start 77.973682 -41.317926)
		(mid 77.995679 -41.284937)
		(end 78.0034 -41.246044)
		(stroke
			(width 0.0508)
			(type default)
		)
		(layer "B.Cu")
	)
	(gr_arc
		(start 78.000352 -254.486664)
		(mid 77.989814 -254.371203)
		(end 77.958442 -254.259588)
		(stroke
			(width 0.0508)
			(type default)
		)
		(layer "B.Cu")
	)
	(gr_line
		(start 78.000352 -254.486664)
		(end 78.000352 -256.50444)
		(stroke
			(width 0.0508)
			(type default)
		)
		(layer "B.Cu")
	)
	(gr_arc
		(start 78.3463 -41.246044)
		(mid 78.354019 -41.284939)
		(end 78.376018 -41.317926)
		(stroke
			(width 0.0508)
			(type default)
		)
		(layer "B.Cu")
	)
	(gr_line
		(start 78.376018 -41.317926)
		(end 78.663292 -41.6052)
		(stroke
			(width 0.0508)
			(type default)
		)
		(layer "B.Cu")
	)
	(gr_line
		(start 79.604108 -39.624)
		(end 79.753206 -39.474902)
		(stroke
			(width 0.0508)
			(type default)
		)
		(layer "B.Cu")
	)
	(gr_arc
		(start 79.753206 -39.474902)
		(mid 79.839872 -39.345197)
		(end 79.8703 -39.1922)
		(stroke
			(width 0.0508)
			(type default)
		)
		(layer "B.Cu")
	)
	(gr_arc
		(start 80.2132 -39.1922)
		(mid 80.224931 -39.251312)
		(end 80.258412 -39.30142)
		(stroke
			(width 0.0508)
			(type default)
		)
		(layer "B.Cu")
	)
	(gr_line
		(start 80.258412 -39.30142)
		(end 80.580992 -39.624)
		(stroke
			(width 0.0508)
			(type default)
		)
		(layer "B.Cu")
	)
	(gr_line
		(start 80.3021 -247.550432)
		(end 80.3021 -248.119392)
		(stroke
			(width 0.0508)
			(type default)
		)
		(layer "B.Cu")
	)
	(gr_line
		(start 80.3021 -245.985792)
		(end 80.3021 -246.554752)
		(stroke
			(width 0.0508)
			(type default)
		)
		(layer "B.Cu")
	)
	(gr_line
		(start 80.3021 -244.421152)
		(end 80.3021 -244.990112)
		(stroke
			(width 0.0508)
			(type default)
		)
		(layer "B.Cu")
	)
	(gr_line
		(start 80.3021 -238.081312)
		(end 80.3021 -238.650272)
		(stroke
			(width 0.0508)
			(type default)
		)
		(layer "B.Cu")
	)
	(gr_line
		(start 80.3021 -236.516672)
		(end 80.3021 -237.085632)
		(stroke
			(width 0.0508)
			(type default)
		)
		(layer "B.Cu")
	)
	(gr_line
		(start 80.3021 -234.952032)
		(end 80.3021 -235.520992)
		(stroke
			(width 0.0508)
			(type default)
		)
		(layer "B.Cu")
	)
	(gr_line
		(start 80.3021 -228.612192)
		(end 80.3021 -229.181152)
		(stroke
			(width 0.0508)
			(type default)
		)
		(layer "B.Cu")
	)
	(gr_arc
		(start 80.645 -247.204992)
		(mid 80.675505 -247.338963)
		(end 80.76438 -247.443752)
		(stroke
			(width 0.0508)
			(type default)
		)
		(layer "B.Cu")
	)
	(gr_arc
		(start 80.645 -245.640352)
		(mid 80.67549 -245.774335)
		(end 80.76438 -245.879112)
		(stroke
			(width 0.0508)
			(type default)
		)
		(layer "B.Cu")
	)
	(gr_arc
		(start 80.645 -244.075712)
		(mid 80.675512 -244.209677)
		(end 80.76438 -244.314472)
		(stroke
			(width 0.0508)
			(type default)
		)
		(layer "B.Cu")
	)
	(gr_arc
		(start 80.645 -237.735872)
		(mid 80.675497 -237.869849)
		(end 80.76438 -237.974632)
		(stroke
			(width 0.0508)
			(type default)
		)
		(layer "B.Cu")
	)
	(gr_arc
		(start 80.645 -236.171232)
		(mid 80.675483 -236.30522)
		(end 80.76438 -236.409992)
		(stroke
			(width 0.0508)
			(type default)
		)
		(layer "B.Cu")
	)
	(gr_arc
		(start 80.645 -234.606592)
		(mid 80.675505 -234.740563)
		(end 80.76438 -234.845352)
		(stroke
			(width 0.0508)
			(type default)
		)
		(layer "B.Cu")
	)
	(gr_arc
		(start 80.645 -228.266752)
		(mid 80.67549 -228.400735)
		(end 80.76438 -228.505512)
		(stroke
			(width 0.0508)
			(type default)
		)
		(layer "B.Cu")
	)
	(gr_arc
		(start 80.76438 -248.226072)
		(mid 80.675471 -248.330848)
		(end 80.645 -248.464832)
		(stroke
			(width 0.0508)
			(type default)
		)
		(layer "B.Cu")
	)
	(gr_arc
		(start 80.76438 -248.226072)
		(mid 80.853268 -248.121277)
		(end 80.88376 -247.987312)
		(stroke
			(width 0.0508)
			(type default)
		)
		(layer "B.Cu")
	)
	(gr_arc
		(start 80.76438 -246.661432)
		(mid 80.675494 -246.766212)
		(end 80.645 -246.900192)
		(stroke
			(width 0.0508)
			(type default)
		)
		(layer "B.Cu")
	)
	(gr_arc
		(start 80.76438 -246.661432)
		(mid 80.853268 -246.556637)
		(end 80.88376 -246.422672)
		(stroke
			(width 0.0508)
			(type default)
		)
		(layer "B.Cu")
	)
	(gr_arc
		(start 80.76438 -245.096792)
		(mid 80.675479 -245.201569)
		(end 80.645 -245.335552)
		(stroke
			(width 0.0508)
			(type default)
		)
		(layer "B.Cu")
	)
	(gr_arc
		(start 80.76438 -245.096792)
		(mid 80.853268 -244.991997)
		(end 80.88376 -244.858032)
		(stroke
			(width 0.0508)
			(type default)
		)
		(layer "B.Cu")
	)
	(gr_arc
		(start 80.76438 -238.756952)
		(mid 80.675501 -238.861733)
		(end 80.645 -238.995712)
		(stroke
			(width 0.0508)
			(type default)
		)
		(layer "B.Cu")
	)
	(gr_arc
		(start 80.76438 -238.756952)
		(mid 80.853268 -238.652157)
		(end 80.88376 -238.518192)
		(stroke
			(width 0.0508)
			(type default)
		)
		(layer "B.Cu")
	)
	(gr_arc
		(start 80.76438 -237.192312)
		(mid 80.675486 -237.29709)
		(end 80.645 -237.431072)
		(stroke
			(width 0.0508)
			(type default)
		)
		(layer "B.Cu")
	)
	(gr_arc
		(start 80.76438 -237.192312)
		(mid 80.853268 -237.087517)
		(end 80.88376 -236.953552)
		(stroke
			(width 0.0508)
			(type default)
		)
		(layer "B.Cu")
	)
	(gr_arc
		(start 80.76438 -235.627672)
		(mid 80.675471 -235.732448)
		(end 80.645 -235.866432)
		(stroke
			(width 0.0508)
			(type default)
		)
		(layer "B.Cu")
	)
	(gr_arc
		(start 80.76438 -235.627672)
		(mid 80.853268 -235.522877)
		(end 80.88376 -235.388912)
		(stroke
			(width 0.0508)
			(type default)
		)
		(layer "B.Cu")
	)
	(gr_arc
		(start 80.76438 -229.287832)
		(mid 80.675494 -229.392612)
		(end 80.645 -229.526592)
		(stroke
			(width 0.0508)
			(type default)
		)
		(layer "B.Cu")
	)
	(gr_arc
		(start 80.76438 -229.287832)
		(mid 80.853268 -229.183037)
		(end 80.88376 -229.049072)
		(stroke
			(width 0.0508)
			(type default)
		)
		(layer "B.Cu")
	)
	(gr_arc
		(start 80.870044 -36.6522)
		(mid 80.908939 -36.644481)
		(end 80.941926 -36.622482)
		(stroke
			(width 0.0508)
			(type default)
		)
		(layer "B.Cu")
	)
	(gr_arc
		(start 80.88376 -247.682512)
		(mid 80.853268 -247.548519)
		(end 80.76438 -247.443752)
		(stroke
			(width 0.0508)
			(type default)
		)
		(layer "B.Cu")
	)
	(gr_line
		(start 80.88376 -247.682512)
		(end 80.88376 -247.987312)
		(stroke
			(width 0.0508)
			(type default)
		)
		(layer "B.Cu")
	)
	(gr_arc
		(start 80.88376 -246.117872)
		(mid 80.853268 -245.983879)
		(end 80.76438 -245.879112)
		(stroke
			(width 0.0508)
			(type default)
		)
		(layer "B.Cu")
	)
	(gr_line
		(start 80.88376 -246.117872)
		(end 80.88376 -246.422672)
		(stroke
			(width 0.0508)
			(type default)
		)
		(layer "B.Cu")
	)
	(gr_arc
		(start 80.88376 -244.553232)
		(mid 80.853268 -244.419239)
		(end 80.76438 -244.314472)
		(stroke
			(width 0.0508)
			(type default)
		)
		(layer "B.Cu")
	)
	(gr_line
		(start 80.88376 -244.553232)
		(end 80.88376 -244.858032)
		(stroke
			(width 0.0508)
			(type default)
		)
		(layer "B.Cu")
	)
	(gr_arc
		(start 80.88376 -238.213392)
		(mid 80.853268 -238.079399)
		(end 80.76438 -237.974632)
		(stroke
			(width 0.0508)
			(type default)
		)
		(layer "B.Cu")
	)
	(gr_line
		(start 80.88376 -238.213392)
		(end 80.88376 -238.518192)
		(stroke
			(width 0.0508)
			(type default)
		)
		(layer "B.Cu")
	)
	(gr_arc
		(start 80.88376 -236.648752)
		(mid 80.853268 -236.514759)
		(end 80.76438 -236.409992)
		(stroke
			(width 0.0508)
			(type default)
		)
		(layer "B.Cu")
	)
	(gr_line
		(start 80.88376 -236.648752)
		(end 80.88376 -236.953552)
		(stroke
			(width 0.0508)
			(type default)
		)
		(layer "B.Cu")
	)
	(gr_arc
		(start 80.88376 -235.084112)
		(mid 80.853268 -234.950119)
		(end 80.76438 -234.845352)
		(stroke
			(width 0.0508)
			(type default)
		)
		(layer "B.Cu")
	)
	(gr_line
		(start 80.88376 -235.084112)
		(end 80.88376 -235.388912)
		(stroke
			(width 0.0508)
			(type default)
		)
		(layer "B.Cu")
	)
	(gr_arc
		(start 80.88376 -228.744272)
		(mid 80.853268 -228.610279)
		(end 80.76438 -228.505512)
		(stroke
			(width 0.0508)
			(type default)
		)
		(layer "B.Cu")
	)
	(gr_line
		(start 80.88376 -228.744272)
		(end 80.88376 -229.049072)
		(stroke
			(width 0.0508)
			(type default)
		)
		(layer "B.Cu")
	)
	(gr_arc
		(start 80.941926 -37.024818)
		(mid 80.908937 -37.002821)
		(end 80.870044 -36.9951)
		(stroke
			(width 0.0508)
			(type default)
		)
		(layer "B.Cu")
	)
	(gr_line
		(start 80.941926 -37.024818)
		(end 81.2292 -37.312092)
		(stroke
			(width 0.0508)
			(type default)
		)
		(layer "B.Cu")
	)
	(gr_line
		(start 80.941926 -36.622482)
		(end 81.2292 -36.335208)
		(stroke
			(width 0.0508)
			(type default)
		)
		(layer "B.Cu")
	)
	(gr_arc
		(start 80.978502 -256.45237)
		(mid 80.984124 -256.480551)
		(end 81.000092 -256.50444)
		(stroke
			(width 0.0508)
			(type default)
		)
		(layer "B.Cu")
	)
	(gr_line
		(start 80.978502 -254.270764)
		(end 80.978502 -256.45237)
		(stroke
			(width 0.0508)
			(type default)
		)
		(layer "B.Cu")
	)
	(gr_arc
		(start 81.15808 -253.836932)
		(mid 81.025165 -254.035996)
		(end 80.978502 -254.270764)
		(stroke
			(width 0.0508)
			(type default)
		)
		(layer "B.Cu")
	)
	(gr_arc
		(start 81.15808 -253.836932)
		(mid 81.291155 -253.637772)
		(end 81.337912 -253.402846)
		(stroke
			(width 0.0508)
			(type default)
		)
		(layer "B.Cu")
	)
	(gr_arc
		(start 81.680812 -253.491746)
		(mid 81.727581 -253.726661)
		(end 81.860644 -253.925832)
		(stroke
			(width 0.0508)
			(type default)
		)
		(layer "B.Cu")
	)
	(gr_arc
		(start 81.999582 -256.50444)
		(mid 82.029639 -256.459457)
		(end 82.040222 -256.406396)
		(stroke
			(width 0.0508)
			(type default)
		)
		(layer "B.Cu")
	)
	(gr_arc
		(start 82.040222 -254.359664)
		(mid 81.993559 -254.124894)
		(end 81.860644 -253.925832)
		(stroke
			(width 0.0508)
			(type default)
		)
		(layer "B.Cu")
	)
	(gr_line
		(start 82.040222 -254.359664)
		(end 82.040222 -256.406396)
		(stroke
			(width 0.0508)
			(type default)
		)
		(layer "B.Cu")
	)
	(gr_arc
		(start 82.760312 -34.8996)
		(mid 82.799191 -34.891853)
		(end 82.832194 -34.869882)
		(stroke
			(width 0.0508)
			(type default)
		)
		(layer "B.Cu")
	)
	(gr_arc
		(start 82.83194 -35.272218)
		(mid 82.798946 -35.250235)
		(end 82.760058 -35.2425)
		(stroke
			(width 0.0508)
			(type default)
		)
		(layer "B.Cu")
	)
	(gr_line
		(start 82.83194 -35.272218)
		(end 83.0834 -35.523678)
		(stroke
			(width 0.0508)
			(type default)
		)
		(layer "B.Cu")
	)
	(gr_line
		(start 82.832194 -34.869882)
		(end 83.0834 -34.618676)
		(stroke
			(width 0.0508)
			(type default)
		)
		(layer "B.Cu")
	)
	(gr_line
		(start 82.911188 -38.711378)
		(end 82.911188 -38.736778)
		(stroke
			(width 0.0508)
			(type default)
		)
		(layer "B.Cu")
	)
	(gr_arc
		(start 82.911188 -37.848032)
		(mid 82.988716 -38.035175)
		(end 83.175856 -38.1127)
		(stroke
			(width 0.0508)
			(type default)
		)
		(layer "B.Cu")
	)
	(gr_line
		(start 82.911188 -37.831776)
		(end 82.911188 -37.848032)
		(stroke
			(width 0.0508)
			(type default)
		)
		(layer "B.Cu")
	)
	(gr_arc
		(start 83.166966 -38.4556)
		(mid 82.986104 -38.530516)
		(end 82.911188 -38.711378)
		(stroke
			(width 0.0508)
			(type default)
		)
		(layer "B.Cu")
	)
	(gr_line
		(start 83.288124 -244.947186)
		(end 83.288124 -245.516146)
		(stroke
			(width 0.0508)
			(type default)
		)
		(layer "B.Cu")
	)
	(gr_line
		(start 83.288124 -243.382546)
		(end 83.288124 -243.951506)
		(stroke
			(width 0.0508)
			(type default)
		)
		(layer "B.Cu")
	)
	(gr_line
		(start 83.288124 -241.817906)
		(end 83.288124 -242.386866)
		(stroke
			(width 0.0508)
			(type default)
		)
		(layer "B.Cu")
	)
	(gr_line
		(start 83.288124 -240.253266)
		(end 83.288124 -240.822226)
		(stroke
			(width 0.0508)
			(type default)
		)
		(layer "B.Cu")
	)
	(gr_line
		(start 83.288124 -233.913426)
		(end 83.288124 -234.482386)
		(stroke
			(width 0.0508)
			(type default)
		)
		(layer "B.Cu")
	)
	(gr_line
		(start 83.288124 -232.348786)
		(end 83.288124 -232.917746)
		(stroke
			(width 0.0508)
			(type default)
		)
		(layer "B.Cu")
	)
	(gr_line
		(start 83.288124 -230.784146)
		(end 83.288124 -231.353106)
		(stroke
			(width 0.0508)
			(type default)
		)
		(layer "B.Cu")
	)
	(gr_arc
		(start 83.631024 -244.601746)
		(mid 83.661604 -244.735683)
		(end 83.750404 -244.840506)
		(stroke
			(width 0.0508)
			(type default)
		)
		(layer "B.Cu")
	)
	(gr_arc
		(start 83.631024 -243.037106)
		(mid 83.661589 -243.171055)
		(end 83.750404 -243.275866)
		(stroke
			(width 0.0508)
			(type default)
		)
		(layer "B.Cu")
	)
	(gr_arc
		(start 83.631024 -241.472466)
		(mid 83.661611 -241.606397)
		(end 83.750404 -241.711226)
		(stroke
			(width 0.0508)
			(type default)
		)
		(layer "B.Cu")
	)
	(gr_arc
		(start 83.631024 -239.907826)
		(mid 83.661596 -240.041769)
		(end 83.750404 -240.146586)
		(stroke
			(width 0.0508)
			(type default)
		)
		(layer "B.Cu")
	)
	(gr_arc
		(start 83.631024 -233.567986)
		(mid 83.661618 -233.701911)
		(end 83.750404 -233.806746)
		(stroke
			(width 0.0508)
			(type default)
		)
		(layer "B.Cu")
	)
	(gr_arc
		(start 83.631024 -232.003346)
		(mid 83.661604 -232.137283)
		(end 83.750404 -232.242106)
		(stroke
			(width 0.0508)
			(type default)
		)
		(layer "B.Cu")
	)
	(gr_arc
		(start 83.631024 -230.438706)
		(mid 83.661589 -230.572655)
		(end 83.750404 -230.677466)
		(stroke
			(width 0.0508)
			(type default)
		)
		(layer "B.Cu")
	)
	(gr_arc
		(start 83.750404 -245.622826)
		(mid 83.661508 -245.727603)
		(end 83.631024 -245.861586)
		(stroke
			(width 0.0508)
			(type default)
		)
		(layer "B.Cu")
	)
	(gr_arc
		(start 83.750404 -245.622826)
		(mid 83.839198 -245.518012)
		(end 83.869784 -245.384066)
		(stroke
			(width 0.0508)
			(type default)
		)
		(layer "B.Cu")
	)
	(gr_arc
		(start 83.750404 -244.058186)
		(mid 83.661493 -244.16296)
		(end 83.631024 -244.296946)
		(stroke
			(width 0.0508)
			(type default)
		)
		(layer "B.Cu")
	)
	(gr_arc
		(start 83.750404 -244.058186)
		(mid 83.839198 -243.953372)
		(end 83.869784 -243.819426)
		(stroke
			(width 0.0508)
			(type default)
		)
		(layer "B.Cu")
	)
	(gr_arc
		(start 83.750404 -242.493546)
		(mid 83.661516 -242.598325)
		(end 83.631024 -242.732306)
		(stroke
			(width 0.0508)
			(type default)
		)
		(layer "B.Cu")
	)
	(gr_arc
		(start 83.750404 -242.493546)
		(mid 83.839198 -242.388732)
		(end 83.869784 -242.254786)
		(stroke
			(width 0.0508)
			(type default)
		)
		(layer "B.Cu")
	)
	(gr_arc
		(start 83.750404 -240.928906)
		(mid 83.661501 -241.033682)
		(end 83.631024 -241.167666)
		(stroke
			(width 0.0508)
			(type default)
		)
		(layer "B.Cu")
	)
	(gr_arc
		(start 83.750404 -240.928906)
		(mid 83.839198 -240.824092)
		(end 83.869784 -240.690146)
		(stroke
			(width 0.0508)
			(type default)
		)
		(layer "B.Cu")
	)
	(gr_arc
		(start 83.750404 -234.589066)
		(mid 83.661523 -234.693846)
		(end 83.631024 -234.827826)
		(stroke
			(width 0.0508)
			(type default)
		)
		(layer "B.Cu")
	)
	(gr_arc
		(start 83.750404 -234.589066)
		(mid 83.839198 -234.484252)
		(end 83.869784 -234.350306)
		(stroke
			(width 0.0508)
			(type default)
		)
		(layer "B.Cu")
	)
	(gr_arc
		(start 83.750404 -233.024426)
		(mid 83.661508 -233.129203)
		(end 83.631024 -233.263186)
		(stroke
			(width 0.0508)
			(type default)
		)
		(layer "B.Cu")
	)
	(gr_arc
		(start 83.750404 -233.024426)
		(mid 83.839198 -232.919612)
		(end 83.869784 -232.785666)
		(stroke
			(width 0.0508)
			(type default)
		)
		(layer "B.Cu")
	)
	(gr_arc
		(start 83.750404 -231.459786)
		(mid 83.661493 -231.56456)
		(end 83.631024 -231.698546)
		(stroke
			(width 0.0508)
			(type default)
		)
		(layer "B.Cu")
	)
	(gr_arc
		(start 83.750404 -231.459786)
		(mid 83.839198 -231.354972)
		(end 83.869784 -231.221026)
		(stroke
			(width 0.0508)
			(type default)
		)
		(layer "B.Cu")
	)
	(gr_arc
		(start 83.852766 -38.1127)
		(mid 83.996472 -38.053196)
		(end 84.055966 -37.9095)
		(stroke
			(width 0.0508)
			(type default)
		)
		(layer "B.Cu")
	)
	(gr_arc
		(start 83.869784 -245.079266)
		(mid 83.839292 -244.945273)
		(end 83.750404 -244.840506)
		(stroke
			(width 0.0508)
			(type default)
		)
		(layer "B.Cu")
	)
	(gr_line
		(start 83.869784 -245.079266)
		(end 83.869784 -245.384066)
		(stroke
			(width 0.0508)
			(type default)
		)
		(layer "B.Cu")
	)
	(gr_arc
		(start 83.869784 -243.514626)
		(mid 83.839292 -243.380633)
		(end 83.750404 -243.275866)
		(stroke
			(width 0.0508)
			(type default)
		)
		(layer "B.Cu")
	)
	(gr_line
		(start 83.869784 -243.514626)
		(end 83.869784 -243.819426)
		(stroke
			(width 0.0508)
			(type default)
		)
		(layer "B.Cu")
	)
	(gr_arc
		(start 83.869784 -241.949986)
		(mid 83.839292 -241.815993)
		(end 83.750404 -241.711226)
		(stroke
			(width 0.0508)
			(type default)
		)
		(layer "B.Cu")
	)
	(gr_line
		(start 83.869784 -241.949986)
		(end 83.869784 -242.254786)
		(stroke
			(width 0.0508)
			(type default)
		)
		(layer "B.Cu")
	)
	(gr_arc
		(start 83.869784 -240.385346)
		(mid 83.839292 -240.251353)
		(end 83.750404 -240.146586)
		(stroke
			(width 0.0508)
			(type default)
		)
		(layer "B.Cu")
	)
	(gr_line
		(start 83.869784 -240.385346)
		(end 83.869784 -240.690146)
		(stroke
			(width 0.0508)
			(type default)
		)
		(layer "B.Cu")
	)
	(gr_arc
		(start 83.869784 -234.045506)
		(mid 83.839292 -233.911513)
		(end 83.750404 -233.806746)
		(stroke
			(width 0.0508)
			(type default)
		)
		(layer "B.Cu")
	)
	(gr_line
		(start 83.869784 -234.045506)
		(end 83.869784 -234.350306)
		(stroke
			(width 0.0508)
			(type default)
		)
		(layer "B.Cu")
	)
	(gr_arc
		(start 83.869784 -232.480866)
		(mid 83.839292 -232.346873)
		(end 83.750404 -232.242106)
		(stroke
			(width 0.0508)
			(type default)
		)
		(layer "B.Cu")
	)
	(gr_line
		(start 83.869784 -232.480866)
		(end 83.869784 -232.785666)
		(stroke
			(width 0.0508)
			(type default)
		)
		(layer "B.Cu")
	)
	(gr_arc
		(start 83.869784 -230.916226)
		(mid 83.839292 -230.782233)
		(end 83.750404 -230.677466)
		(stroke
			(width 0.0508)
			(type default)
		)
		(layer "B.Cu")
	)
	(gr_line
		(start 83.869784 -230.916226)
		(end 83.869784 -231.221026)
		(stroke
			(width 0.0508)
			(type default)
		)
		(layer "B.Cu")
	)
	(gr_line
		(start 84.055966 -37.7444)
		(end 84.055966 -37.9095)
		(stroke
			(width 0.0508)
			(type default)
		)
		(layer "B.Cu")
	)
	(gr_arc
		(start 84.08416 -38.650926)
		(mid 84.02695 -38.51281)
		(end 83.888834 -38.4556)
		(stroke
			(width 0.0508)
			(type default)
		)
		(layer "B.Cu")
	)
	(gr_line
		(start 84.08416 -38.650926)
		(end 84.08416 -38.760654)
		(stroke
			(width 0.0508)
			(type default)
		)
		(layer "B.Cu")
	)
	(gr_arc
		(start 84.406486 -33.1343)
		(mid 84.713727 -33.073171)
		(end 84.974176 -32.899096)
		(stroke
			(width 0.0508)
			(type default)
		)
		(layer "B.Cu")
	)
	(gr_line
		(start 84.974176 -32.899096)
		(end 84.9884 -32.884872)
		(stroke
			(width 0.0508)
			(type default)
		)
		(layer "B.Cu")
	)
	(gr_arc
		(start 84.9884 -33.789874)
		(mid 84.642054 -33.558453)
		(end 84.233512 -33.4772)
		(stroke
			(width 0.0508)
			(type default)
		)
		(layer "B.Cu")
	)
	(gr_line
		(start 84.999322 -254.51435)
		(end 84.999322 -256.50444)
		(stroke
			(width 0.0508)
			(type default)
		)
		(layer "B.Cu")
	)
	(gr_arc
		(start 85.16366 -254.117348)
		(mid 85.04203 -254.299516)
		(end 84.999322 -254.51435)
		(stroke
			(width 0.0508)
			(type default)
		)
		(layer "B.Cu")
	)
	(gr_arc
		(start 85.16366 -254.117348)
		(mid 85.285498 -253.9351)
		(end 85.328252 -253.720092)
		(stroke
			(width 0.0508)
			(type default)
		)
		(layer "B.Cu")
	)
	(gr_arc
		(start 85.671152 -253.769876)
		(mid 85.713903 -253.98489)
		(end 85.835744 -254.167132)
		(stroke
			(width 0.0508)
			(type default)
		)
		(layer "B.Cu")
	)
	(gr_arc
		(start 86.000082 -254.56388)
		(mid 85.957372 -254.349162)
		(end 85.835744 -254.167132)
		(stroke
			(width 0.0508)
			(type default)
		)
		(layer "B.Cu")
	)
	(gr_line
		(start 86.000082 -254.56388)
		(end 86.000082 -256.50444)
		(stroke
			(width 0.0508)
			(type default)
		)
		(layer "B.Cu")
	)
	(gr_line
		(start 86.868 -25.908)
		(end 87.134446 -25.641554)
		(stroke
			(width 0.06985)
			(type default)
		)
		(layer "B.Cu")
	)
	(gr_arc
		(start 87.134446 -25.641554)
		(mid 87.247412 -25.472455)
		(end 87.2871 -25.273)
		(stroke
			(width 0.06985)
			(type default)
		)
		(layer "B.Cu")
	)
	(gr_line
		(start 87.288624 -239.191292)
		(end 87.288624 -239.760252)
		(stroke
			(width 0.0508)
			(type default)
		)
		(layer "B.Cu")
	)
	(gr_line
		(start 87.288624 -237.626652)
		(end 87.288624 -238.195612)
		(stroke
			(width 0.0508)
			(type default)
		)
		(layer "B.Cu")
	)
	(gr_line
		(start 87.288624 -236.062012)
		(end 87.288624 -236.630972)
		(stroke
			(width 0.0508)
			(type default)
		)
		(layer "B.Cu")
	)
	(gr_line
		(start 87.288624 -229.722172)
		(end 87.288624 -230.291132)
		(stroke
			(width 0.0508)
			(type default)
		)
		(layer "B.Cu")
	)
	(gr_line
		(start 87.288624 -228.157532)
		(end 87.288624 -228.726492)
		(stroke
			(width 0.0508)
			(type default)
		)
		(layer "B.Cu")
	)
	(gr_line
		(start 87.288624 -226.592892)
		(end 87.288624 -227.161852)
		(stroke
			(width 0.0508)
			(type default)
		)
		(layer "B.Cu")
	)
	(gr_line
		(start 87.288624 -221.446598)
		(end 87.288624 -222.015558)
		(stroke
			(width 0.0508)
			(type default)
		)
		(layer "B.Cu")
	)
	(gr_arc
		(start 87.63 -25.294844)
		(mid 87.696008 -25.62669)
		(end 87.884 -25.908)
		(stroke
			(width 0.06985)
			(type default)
		)
		(layer "B.Cu")
	)
	(gr_arc
		(start 87.631524 -238.845852)
		(mid 87.662106 -238.979787)
		(end 87.750904 -239.084612)
		(stroke
			(width 0.0508)
			(type default)
		)
		(layer "B.Cu")
	)
	(gr_arc
		(start 87.631524 -237.281212)
		(mid 87.662091 -237.415159)
		(end 87.750904 -237.519972)
		(stroke
			(width 0.0508)
			(type default)
		)
		(layer "B.Cu")
	)
	(gr_arc
		(start 87.631524 -235.716572)
		(mid 87.662113 -235.850501)
		(end 87.750904 -235.955332)
		(stroke
			(width 0.0508)
			(type default)
		)
		(layer "B.Cu")
	)
	(gr_arc
		(start 87.631524 -229.376732)
		(mid 87.662098 -229.510673)
		(end 87.750904 -229.615492)
		(stroke
			(width 0.0508)
			(type default)
		)
		(layer "B.Cu")
	)
	(gr_arc
		(start 87.631524 -227.812092)
		(mid 87.662084 -227.946045)
		(end 87.750904 -228.050852)
		(stroke
			(width 0.0508)
			(type default)
		)
		(layer "B.Cu")
	)
	(gr_arc
		(start 87.631524 -226.247452)
		(mid 87.662106 -226.381387)
		(end 87.750904 -226.486212)
		(stroke
			(width 0.0508)
			(type default)
		)
		(layer "B.Cu")
	)
	(gr_arc
		(start 87.631524 -221.101158)
		(mid 87.662018 -221.235137)
		(end 87.750904 -221.339918)
		(stroke
			(width 0.0508)
			(type default)
		)
		(layer "B.Cu")
	)
	(gr_arc
		(start 87.750904 -239.866932)
		(mid 87.66201 -239.97171)
		(end 87.631524 -240.105692)
		(stroke
			(width 0.0508)
			(type default)
		)
		(layer "B.Cu")
	)
	(gr_arc
		(start 87.750904 -239.866932)
		(mid 87.839698 -239.762118)
		(end 87.870284 -239.628172)
		(stroke
			(width 0.0508)
			(type default)
		)
		(layer "B.Cu")
	)
	(gr_arc
		(start 87.750904 -238.302292)
		(mid 87.661996 -238.407067)
		(end 87.631524 -238.541052)
		(stroke
			(width 0.0508)
			(type default)
		)
		(layer "B.Cu")
	)
	(gr_arc
		(start 87.750904 -238.302292)
		(mid 87.839698 -238.197478)
		(end 87.870284 -238.063532)
		(stroke
			(width 0.0508)
			(type default)
		)
		(layer "B.Cu")
	)
	(gr_arc
		(start 87.750904 -236.737652)
		(mid 87.662018 -236.842431)
		(end 87.631524 -236.976412)
		(stroke
			(width 0.0508)
			(type default)
		)
		(layer "B.Cu")
	)
	(gr_arc
		(start 87.750904 -236.737652)
		(mid 87.839698 -236.632838)
		(end 87.870284 -236.498892)
		(stroke
			(width 0.0508)
			(type default)
		)
		(layer "B.Cu")
	)
	(gr_arc
		(start 87.750904 -230.397812)
		(mid 87.662003 -230.502588)
		(end 87.631524 -230.636572)
		(stroke
			(width 0.0508)
			(type default)
		)
		(layer "B.Cu")
	)
	(gr_arc
		(start 87.750904 -230.397812)
		(mid 87.839698 -230.292998)
		(end 87.870284 -230.159052)
		(stroke
			(width 0.0508)
			(type default)
		)
		(layer "B.Cu")
	)
	(gr_arc
		(start 87.750904 -228.833172)
		(mid 87.661988 -228.937945)
		(end 87.631524 -229.071932)
		(stroke
			(width 0.0508)
			(type default)
		)
		(layer "B.Cu")
	)
	(gr_arc
		(start 87.750904 -228.833172)
		(mid 87.839698 -228.728358)
		(end 87.870284 -228.594412)
		(stroke
			(width 0.0508)
			(type default)
		)
		(layer "B.Cu")
	)
	(gr_arc
		(start 87.750904 -227.268532)
		(mid 87.66201 -227.37331)
		(end 87.631524 -227.507292)
		(stroke
			(width 0.0508)
			(type default)
		)
		(layer "B.Cu")
	)
	(gr_arc
		(start 87.750904 -227.268532)
		(mid 87.839698 -227.163718)
		(end 87.870284 -227.029772)
		(stroke
			(width 0.0508)
			(type default)
		)
		(layer "B.Cu")
	)
	(gr_arc
		(start 87.750904 -222.122238)
		(mid 87.662013 -222.227016)
		(end 87.631524 -222.360998)
		(stroke
			(width 0.0508)
			(type default)
		)
		(layer "B.Cu")
	)
	(gr_arc
		(start 87.750904 -222.122238)
		(mid 87.839792 -222.017443)
		(end 87.870284 -221.883478)
		(stroke
			(width 0.0508)
			(type default)
		)
		(layer "B.Cu")
	)
	(gr_arc
		(start 87.870284 -239.323372)
		(mid 87.839792 -239.189379)
		(end 87.750904 -239.084612)
		(stroke
			(width 0.0508)
			(type default)
		)
		(layer "B.Cu")
	)
	(gr_line
		(start 87.870284 -239.323372)
		(end 87.870284 -239.628172)
		(stroke
			(width 0.0508)
			(type default)
		)
		(layer "B.Cu")
	)
	(gr_arc
		(start 87.870284 -237.758732)
		(mid 87.839792 -237.624739)
		(end 87.750904 -237.519972)
		(stroke
			(width 0.0508)
			(type default)
		)
		(layer "B.Cu")
	)
	(gr_line
		(start 87.870284 -237.758732)
		(end 87.870284 -238.063532)
		(stroke
			(width 0.0508)
			(type default)
		)
		(layer "B.Cu")
	)
	(gr_arc
		(start 87.870284 -236.194092)
		(mid 87.839792 -236.060099)
		(end 87.750904 -235.955332)
		(stroke
			(width 0.0508)
			(type default)
		)
		(layer "B.Cu")
	)
	(gr_line
		(start 87.870284 -236.194092)
		(end 87.870284 -236.498892)
		(stroke
			(width 0.0508)
			(type default)
		)
		(layer "B.Cu")
	)
	(gr_arc
		(start 87.870284 -229.854252)
		(mid 87.839792 -229.720259)
		(end 87.750904 -229.615492)
		(stroke
			(width 0.0508)
			(type default)
		)
		(layer "B.Cu")
	)
	(gr_line
		(start 87.870284 -229.854252)
		(end 87.870284 -230.159052)
		(stroke
			(width 0.0508)
			(type default)
		)
		(layer "B.Cu")
	)
	(gr_arc
		(start 87.870284 -228.289612)
		(mid 87.839792 -228.155619)
		(end 87.750904 -228.050852)
		(stroke
			(width 0.0508)
			(type default)
		)
		(layer "B.Cu")
	)
	(gr_line
		(start 87.870284 -228.289612)
		(end 87.870284 -228.594412)
		(stroke
			(width 0.0508)
			(type default)
		)
		(layer "B.Cu")
	)
	(gr_arc
		(start 87.870284 -226.724972)
		(mid 87.839792 -226.590979)
		(end 87.750904 -226.486212)
		(stroke
			(width 0.0508)
			(type default)
		)
		(layer "B.Cu")
	)
	(gr_line
		(start 87.870284 -226.724972)
		(end 87.870284 -227.029772)
		(stroke
			(width 0.0508)
			(type default)
		)
		(layer "B.Cu")
	)
	(gr_arc
		(start 87.870284 -221.578678)
		(mid 87.839792 -221.444685)
		(end 87.750904 -221.339918)
		(stroke
			(width 0.0508)
			(type default)
		)
		(layer "B.Cu")
	)
	(gr_line
		(start 87.870284 -221.578678)
		(end 87.870284 -221.883478)
		(stroke
			(width 0.0508)
			(type default)
		)
		(layer "B.Cu")
	)
	(gr_line
		(start 88.999822 -254.455676)
		(end 88.999822 -256.50444)
		(stroke
			(width 0.0508)
			(type default)
		)
		(layer "B.Cu")
	)
	(gr_arc
		(start 89.055448 -254.321818)
		(mid 89.014338 -254.383219)
		(end 88.999822 -254.455676)
		(stroke
			(width 0.0508)
			(type default)
		)
		(layer "B.Cu")
	)
	(gr_line
		(start 89.055448 -254.321818)
		(end 89.0778 -254.299466)
		(stroke
			(width 0.0508)
			(type default)
		)
		(layer "B.Cu")
	)
	(gr_arc
		(start 89.154254 -254.248158)
		(mid 89.113482 -254.270019)
		(end 89.0778 -254.299466)
		(stroke
			(width 0.0508)
			(type default)
		)
		(layer "B.Cu")
	)
	(gr_line
		(start 89.154254 -254.248158)
		(end 89.171272 -254.241046)
		(stroke
			(width 0.0508)
			(type default)
		)
		(layer "B.Cu")
	)
	(gr_arc
		(start 89.171272 -254.241046)
		(mid 89.195777 -254.228092)
		(end 89.217246 -254.210566)
		(stroke
			(width 0.0508)
			(type default)
		)
		(layer "B.Cu")
	)
	(gr_line
		(start 89.217246 -254.210566)
		(end 89.237312 -254.1905)
		(stroke
			(width 0.0508)
			(type default)
		)
		(layer "B.Cu")
	)
	(gr_arc
		(start 89.237312 -254.1905)
		(mid 89.304978 -254.08923)
		(end 89.328752 -253.969774)
		(stroke
			(width 0.0508)
			(type default)
		)
		(layer "B.Cu")
	)
	(gr_arc
		(start 89.671652 -253.952756)
		(mid 89.719847 -254.069153)
		(end 89.836244 -254.117348)
		(stroke
			(width 0.0508)
			(type default)
		)
		(layer "B.Cu")
	)
	(gr_line
		(start 89.768172 -239.747552)
		(end 89.768172 -240.316512)
		(stroke
			(width 0.0508)
			(type default)
		)
		(layer "B.Cu")
	)
	(gr_line
		(start 89.768172 -233.993944)
		(end 89.768172 -234.545124)
		(stroke
			(width 0.0508)
			(type default)
		)
		(layer "B.Cu")
	)
	(gr_line
		(start 89.768172 -232.429304)
		(end 89.768172 -232.980484)
		(stroke
			(width 0.0508)
			(type default)
		)
		(layer "B.Cu")
	)
	(gr_line
		(start 89.768172 -230.864664)
		(end 89.768172 -231.415844)
		(stroke
			(width 0.0508)
			(type default)
		)
		(layer "B.Cu")
	)
	(gr_line
		(start 89.768172 -229.300024)
		(end 89.768172 -229.851204)
		(stroke
			(width 0.0508)
			(type default)
		)
		(layer "B.Cu")
	)
	(gr_line
		(start 89.768172 -222.960184)
		(end 89.768172 -223.511364)
		(stroke
			(width 0.0508)
			(type default)
		)
		(layer "B.Cu")
	)
	(gr_line
		(start 89.768172 -221.395544)
		(end 89.768172 -221.946724)
		(stroke
			(width 0.0508)
			(type default)
		)
		(layer "B.Cu")
	)
	(gr_arc
		(start 90.000582 -254.28194)
		(mid 89.952464 -254.165646)
		(end 89.836244 -254.117348)
		(stroke
			(width 0.0508)
			(type default)
		)
		(layer "B.Cu")
	)
	(gr_line
		(start 90.000582 -254.28194)
		(end 90.000582 -256.50444)
		(stroke
			(width 0.0508)
			(type default)
		)
		(layer "B.Cu")
	)
	(gr_arc
		(start 90.111072 -239.402112)
		(mid 90.141643 -239.536055)
		(end 90.230452 -239.640872)
		(stroke
			(width 0.0508)
			(type default)
		)
		(layer "B.Cu")
	)
	(gr_line
		(start 90.113612 -234.885738)
		(end 90.230452 -234.660694)
		(stroke
			(width 0.0508)
			(type default)
		)
		(layer "B.Cu")
	)
	(gr_line
		(start 90.113612 -233.65333)
		(end 90.230452 -233.878374)
		(stroke
			(width 0.0508)
			(type default)
		)
		(layer "B.Cu")
	)
	(gr_line
		(start 90.113612 -233.321098)
		(end 90.230452 -233.096054)
		(stroke
			(width 0.0508)
			(type default)
		)
		(layer "B.Cu")
	)
	(gr_line
		(start 90.113612 -232.08869)
		(end 90.230452 -232.313734)
		(stroke
			(width 0.0508)
			(type default)
		)
		(layer "B.Cu")
	)
	(gr_line
		(start 90.113612 -231.756458)
		(end 90.230452 -231.531414)
		(stroke
			(width 0.0508)
			(type default)
		)
		(layer "B.Cu")
	)
	(gr_line
		(start 90.113612 -230.52405)
		(end 90.230452 -230.749094)
		(stroke
			(width 0.0508)
			(type default)
		)
		(layer "B.Cu")
	)
	(gr_line
		(start 90.113612 -230.191818)
		(end 90.230452 -229.966774)
		(stroke
			(width 0.0508)
			(type default)
		)
		(layer "B.Cu")
	)
	(gr_line
		(start 90.113612 -228.95941)
		(end 90.230452 -229.184454)
		(stroke
			(width 0.0508)
			(type default)
		)
		(layer "B.Cu")
	)
	(gr_line
		(start 90.113612 -223.851978)
		(end 90.230452 -223.626934)
		(stroke
			(width 0.0508)
			(type default)
		)
		(layer "B.Cu")
	)
	(gr_line
		(start 90.113612 -222.61957)
		(end 90.230452 -222.844614)
		(stroke
			(width 0.0508)
			(type default)
		)
		(layer "B.Cu")
	)
	(gr_line
		(start 90.113612 -222.287338)
		(end 90.230452 -222.062294)
		(stroke
			(width 0.0508)
			(type default)
		)
		(layer "B.Cu")
	)
	(gr_line
		(start 90.113612 -221.05493)
		(end 90.230452 -221.279974)
		(stroke
			(width 0.0508)
			(type default)
		)
		(layer "B.Cu")
	)
	(gr_arc
		(start 90.230452 -240.423192)
		(mid 90.141679 -240.528026)
		(end 90.111072 -240.661952)
		(stroke
			(width 0.0508)
			(type default)
		)
		(layer "B.Cu")
	)
	(gr_arc
		(start 90.230452 -240.423192)
		(mid 90.319246 -240.318378)
		(end 90.349832 -240.184432)
		(stroke
			(width 0.0508)
			(type default)
		)
		(layer "B.Cu")
	)
	(gr_arc
		(start 90.230452 -234.660694)
		(mid 90.319246 -234.55588)
		(end 90.349832 -234.421934)
		(stroke
			(width 0.0508)
			(type default)
		)
		(layer "B.Cu")
	)
	(gr_arc
		(start 90.230452 -233.096054)
		(mid 90.319246 -232.99124)
		(end 90.349832 -232.857294)
		(stroke
			(width 0.0508)
			(type default)
		)
		(layer "B.Cu")
	)
	(gr_arc
		(start 90.230452 -231.531414)
		(mid 90.319246 -231.4266)
		(end 90.349832 -231.292654)
		(stroke
			(width 0.0508)
			(type default)
		)
		(layer "B.Cu")
	)
	(gr_arc
		(start 90.230452 -229.966774)
		(mid 90.319246 -229.86196)
		(end 90.349832 -229.728014)
		(stroke
			(width 0.0508)
			(type default)
		)
		(layer "B.Cu")
	)
	(gr_arc
		(start 90.230452 -223.626934)
		(mid 90.319246 -223.52212)
		(end 90.349832 -223.388174)
		(stroke
			(width 0.0508)
			(type default)
		)
		(layer "B.Cu")
	)
	(gr_arc
		(start 90.230452 -222.062294)
		(mid 90.319246 -221.95748)
		(end 90.349832 -221.823534)
		(stroke
			(width 0.0508)
			(type default)
		)
		(layer "B.Cu")
	)
	(gr_arc
		(start 90.349832 -239.879632)
		(mid 90.319246 -239.745714)
		(end 90.230452 -239.640872)
		(stroke
			(width 0.0508)
			(type default)
		)
		(layer "B.Cu")
	)
	(gr_line
		(start 90.349832 -239.879632)
		(end 90.349832 -240.184432)
		(stroke
			(width 0.0508)
			(type default)
		)
		(layer "B.Cu")
	)
	(gr_arc
		(start 90.349832 -234.117134)
		(mid 90.31934 -233.983141)
		(end 90.230452 -233.878374)
		(stroke
			(width 0.0508)
			(type default)
		)
		(layer "B.Cu")
	)
	(gr_line
		(start 90.349832 -234.117134)
		(end 90.349832 -234.421934)
		(stroke
			(width 0.0508)
			(type default)
		)
		(layer "B.Cu")
	)
	(gr_arc
		(start 90.349832 -232.552494)
		(mid 90.31934 -232.418501)
		(end 90.230452 -232.313734)
		(stroke
			(width 0.0508)
			(type default)
		)
		(layer "B.Cu")
	)
	(gr_line
		(start 90.349832 -232.552494)
		(end 90.349832 -232.857294)
		(stroke
			(width 0.0508)
			(type default)
		)
		(layer "B.Cu")
	)
	(gr_arc
		(start 90.349832 -230.987854)
		(mid 90.31934 -230.853861)
		(end 90.230452 -230.749094)
		(stroke
			(width 0.0508)
			(type default)
		)
		(layer "B.Cu")
	)
	(gr_line
		(start 90.349832 -230.987854)
		(end 90.349832 -231.292654)
		(stroke
			(width 0.0508)
			(type default)
		)
		(layer "B.Cu")
	)
	(gr_arc
		(start 90.349832 -229.423214)
		(mid 90.31934 -229.289221)
		(end 90.230452 -229.184454)
		(stroke
			(width 0.0508)
			(type default)
		)
		(layer "B.Cu")
	)
	(gr_line
		(start 90.349832 -229.423214)
		(end 90.349832 -229.728014)
		(stroke
			(width 0.0508)
			(type default)
		)
		(layer "B.Cu")
	)
	(gr_arc
		(start 90.349832 -223.083374)
		(mid 90.31934 -222.949381)
		(end 90.230452 -222.844614)
		(stroke
			(width 0.0508)
			(type default)
		)
		(layer "B.Cu")
	)
	(gr_line
		(start 90.349832 -223.083374)
		(end 90.349832 -223.388174)
		(stroke
			(width 0.0508)
			(type default)
		)
		(layer "B.Cu")
	)
	(gr_arc
		(start 90.349832 -221.518734)
		(mid 90.31934 -221.384741)
		(end 90.230452 -221.279974)
		(stroke
			(width 0.0508)
			(type default)
		)
		(layer "B.Cu")
	)
	(gr_line
		(start 90.349832 -221.518734)
		(end 90.349832 -221.823534)
		(stroke
			(width 0.0508)
			(type default)
		)
		(layer "B.Cu")
	)
	(gr_line
		(start 91.966542 -38.909752)
		(end 92.13977 -38.909752)
		(stroke
			(width 0.0508)
			(type default)
		)
		(layer "B.Cu")
	)
	(gr_arc
		(start 91.9861 -42.1132)
		(mid 92.399596 -42.030951)
		(end 92.750132 -41.796716)
		(stroke
			(width 0.0508)
			(type default)
		)
		(layer "B.Cu")
	)
	(gr_arc
		(start 92.024708 -41.7703)
		(mid 92.107441 -41.753861)
		(end 92.177616 -41.707054)
		(stroke
			(width 0.04445)
			(type default)
		)
		(layer "B.Cu")
	)
	(gr_line
		(start 92.108528 -38.566852)
		(end 92.534994 -38.993318)
		(stroke
			(width 0.0508)
			(type default)
		)
		(layer "B.Cu")
	)
	(gr_line
		(start 92.13977 -38.909752)
		(end 92.621608 -39.39159)
		(stroke
			(width 0.0508)
			(type default)
		)
		(layer "B.Cu")
	)
	(gr_line
		(start 92.177616 -41.707054)
		(end 92.423234 -41.461436)
		(stroke
			(width 0.04445)
			(type default)
		)
		(layer "B.Cu")
	)
	(gr_line
		(start 92.534994 -38.993318)
		(end 92.600526 -38.993318)
		(stroke
			(width 0.04445)
			(type default)
		)
		(layer "B.Cu")
	)
	(gr_arc
		(start 92.579698 -41.396666)
		(mid 92.495026 -41.413486)
		(end 92.423234 -41.461436)
		(stroke
			(width 0.04445)
			(type default)
		)
		(layer "B.Cu")
	)
	(gr_line
		(start 92.579698 -41.396666)
		(end 93.279468 -41.396666)
		(stroke
			(width 0.04445)
			(type default)
		)
		(layer "B.Cu")
	)
	(gr_line
		(start 92.604082 -38.993318)
		(end 93.152722 -38.993318)
		(stroke
			(width 0.04445)
			(type default)
		)
		(layer "B.Cu")
	)
	(gr_line
		(start 92.623386 -39.393368)
		(end 92.625418 -39.3954)
		(stroke
			(width 0.0508)
			(type default)
		)
		(layer "B.Cu")
	)
	(gr_line
		(start 92.625418 -39.3954)
		(end 92.74556 -39.3954)
		(stroke
			(width 0.0508)
			(type default)
		)
		(layer "B.Cu")
	)
	(gr_line
		(start 93.152722 -38.993318)
		(end 93.556582 -39.397178)
		(stroke
			(width 0.04445)
			(type default)
		)
		(layer "B.Cu")
	)
	(gr_arc
		(start 93.250766 -40.5892)
		(mid 93.1093 -40.494645)
		(end 92.94241 -40.461438)
		(stroke
			(width 0.0508)
			(type default)
		)
		(layer "B.Cu")
	)
	(gr_line
		(start 93.250766 -40.5892)
		(end 93.482414 -40.820848)
		(stroke
			(width 0.0508)
			(type default)
		)
		(layer "B.Cu")
	)
	(gr_line
		(start 93.28785 -40.118538)
		(end 93.343984 -40.118538)
		(stroke
			(width 0.0508)
			(type default)
		)
		(layer "B.Cu")
	)
	(gr_arc
		(start 93.298772 -42.74058)
		(mid 93.368729 -42.753519)
		(end 93.432376 -42.721784)
		(stroke
			(width 0.0508)
			(type default)
		)
		(layer "B.Cu")
	)
	(gr_arc
		(start 93.35516 -31.9024)
		(mid 93.404927 -32.152597)
		(end 93.546676 -32.36468)
		(stroke
			(width 0.06985)
			(type default)
		)
		(layer "B.Cu")
	)
	(gr_arc
		(start 93.35516 -31.3436)
		(mid 93.463239 -31.181848)
		(end 93.50121 -30.991048)
		(stroke
			(width 0.06985)
			(type default)
		)
		(layer "B.Cu")
	)
	(gr_arc
		(start 93.382084 -41.439338)
		(mid 93.335017 -41.407802)
		(end 93.279468 -41.396666)
		(stroke
			(width 0.04445)
			(type default)
		)
		(layer "B.Cu")
	)
	(gr_line
		(start 93.382084 -41.439338)
		(end 93.472 -41.529)
		(stroke
			(width 0.04445)
			(type default)
		)
		(layer "B.Cu")
	)
	(gr_line
		(start 93.406722 -43.247056)
		(end 93.550486 -43.39082)
		(stroke
			(width 0.0508)
			(type default)
		)
		(layer "B.Cu")
	)
	(gr_line
		(start 93.432376 -42.721784)
		(end 93.556836 -42.597324)
		(stroke
			(width 0.0508)
			(type default)
		)
		(layer "B.Cu")
	)
	(gr_arc
		(start 93.540834 -40.200072)
		(mid 93.450513 -40.139747)
		(end 93.343984 -40.118538)
		(stroke
			(width 0.0508)
			(type default)
		)
		(layer "B.Cu")
	)
	(gr_line
		(start 93.546676 -32.36468)
		(end 93.799406 -32.61741)
		(stroke
			(width 0.06985)
			(type default)
		)
		(layer "B.Cu")
	)
	(gr_arc
		(start 93.55455 -41.72839)
		(mid 93.533139 -41.620467)
		(end 93.472 -41.529)
		(stroke
			(width 0.04445)
			(type default)
		)
		(layer "B.Cu")
	)
	(gr_line
		(start 93.55455 -41.72839)
		(end 93.55455 -41.80459)
		(stroke
			(width 0.04445)
			(type default)
		)
		(layer "B.Cu")
	)
	(gr_arc
		(start 93.554804 -40.9956)
		(mid 93.535995 -40.901019)
		(end 93.482414 -40.820848)
		(stroke
			(width 0.0508)
			(type default)
		)
		(layer "B.Cu")
	)
	(gr_arc
		(start 93.84411 -30.991048)
		(mid 93.882074 -31.18185)
		(end 93.99016 -31.3436)
		(stroke
			(width 0.06985)
			(type default)
		)
		(layer "B.Cu")
	)
	(gr_arc
		(start 93.99016 -31.904178)
		(mid 94.067131 -32.291138)
		(end 94.286324 -32.619188)
		(stroke
			(width 0.06985)
			(type default)
		)
		(layer "B.Cu")
	)
	(gr_line
		(start 93.99016 -31.9024)
		(end 93.99016 -31.904178)
		(stroke
			(width 0.06985)
			(type default)
		)
		(layer "B.Cu")
	)
	(gr_arc
		(start 94.339156 -246.381016)
		(mid 94.455444 -246.454248)
		(end 94.592394 -246.465598)
		(stroke
			(width 0.0508)
			(type default)
		)
		(layer "B.Cu")
	)
	(gr_line
		(start 94.340934 -246.867934)
		(end 94.74327 -247.27027)
		(stroke
			(width 0.0508)
			(type default)
		)
		(layer "B.Cu")
	)
	(gr_arc
		(start 94.845632 -246.549926)
		(mid 94.729307 -246.476866)
		(end 94.592394 -246.465598)
		(stroke
			(width 0.0508)
			(type default)
		)
		(layer "B.Cu")
	)
	(gr_line
		(start 94.845632 -246.549926)
		(end 95.061278 -246.765572)
		(stroke
			(width 0.0508)
			(type default)
		)
		(layer "B.Cu")
	)
	(gr_arc
		(start 94.87916 -31.9024)
		(mid 94.99522 -32.486344)
		(end 95.325946 -32.981392)
		(stroke
			(width 0.06985)
			(type default)
		)
		(layer "B.Cu")
	)
	(gr_arc
		(start 94.87916 -31.3436)
		(mid 94.994014 -31.171709)
		(end 95.034354 -30.96895)
		(stroke
			(width 0.06985)
			(type default)
		)
		(layer "B.Cu")
	)
	(gr_arc
		(start 95.145606 -247.01881)
		(mid 95.134376 -246.881885)
		(end 95.061278 -246.765572)
		(stroke
			(width 0.0508)
			(type default)
		)
		(layer "B.Cu")
	)
	(gr_arc
		(start 95.145606 -247.01881)
		(mid 95.15698 -247.155752)
		(end 95.230188 -247.272048)
		(stroke
			(width 0.0508)
			(type default)
		)
		(layer "B.Cu")
	)
	(gr_line
		(start 95.1484 -35.40506)
		(end 95.150178 -35.403282)
		(stroke
			(width 0.0508)
			(type default)
		)
		(layer "B.Cu")
	)
	(gr_line
		(start 95.150178 -36.20008)
		(end 95.396812 -35.953446)
		(stroke
			(width 0.04445)
			(type default)
		)
		(layer "B.Cu")
	)
	(gr_line
		(start 95.150178 -35.287966)
		(end 95.150178 -35.403282)
		(stroke
			(width 0.0508)
			(type default)
		)
		(layer "B.Cu")
	)
	(gr_arc
		(start 95.217488 -35.125406)
		(mid 95.167653 -35.199989)
		(end 95.150178 -35.287966)
		(stroke
			(width 0.0508)
			(type default)
		)
		(layer "B.Cu")
	)
	(gr_line
		(start 95.217488 -35.125406)
		(end 95.291402 -35.050984)
		(stroke
			(width 0.0508)
			(type default)
		)
		(layer "B.Cu")
	)
	(gr_line
		(start 95.291402 -35.050984)
		(end 95.29191 -35.05073)
		(stroke
			(width 0.0508)
			(type default)
		)
		(layer "B.Cu")
	)
	(gr_line
		(start 95.29191 -35.05073)
		(end 95.43923 -34.903664)
		(stroke
			(width 0.0508)
			(type default)
		)
		(layer "B.Cu")
	)
	(gr_line
		(start 95.325946 -32.981392)
		(end 95.393256 -33.048448)
		(stroke
			(width 0.06985)
			(type default)
		)
		(layer "B.Cu")
	)
	(gr_arc
		(start 95.377254 -31.013146)
		(mid 95.412866 -31.191976)
		(end 95.51416 -31.3436)
		(stroke
			(width 0.06985)
			(type default)
		)
		(layer "B.Cu")
	)
	(gr_line
		(start 95.396812 -35.953446)
		(end 95.413322 -35.936682)
		(stroke
			(width 0.04445)
			(type default)
		)
		(layer "B.Cu")
	)
	(gr_arc
		(start 95.413322 -35.936682)
		(mid 95.513273 -35.78717)
		(end 95.54845 -35.6108)
		(stroke
			(width 0.04445)
			(type default)
		)
		(layer "B.Cu")
	)
	(gr_arc
		(start 95.43923 -34.903664)
		(mid 95.469337 -34.870188)
		(end 95.495872 -34.833814)
		(stroke
			(width 0.0508)
			(type default)
		)
		(layer "B.Cu")
	)
	(gr_arc
		(start 95.495872 -34.833814)
		(mid 95.533652 -34.763364)
		(end 95.558102 -34.687256)
		(stroke
			(width 0.0508)
			(type default)
		)
		(layer "B.Cu")
	)
	(gr_arc
		(start 95.51416 -32.473392)
		(mid 95.552849 -32.667892)
		(end 95.663004 -32.832802)
		(stroke
			(width 0.06985)
			(type default)
		)
		(layer "B.Cu")
	)
	(gr_line
		(start 95.51416 -31.9024)
		(end 95.51416 -32.473392)
		(stroke
			(width 0.06985)
			(type default)
		)
		(layer "B.Cu")
	)
	(gr_line
		(start 95.54845 -35.30727)
		(end 95.54845 -35.6108)
		(stroke
			(width 0.04445)
			(type default)
		)
		(layer "B.Cu")
	)
	(gr_arc
		(start 95.551498 -34.445194)
		(mid 95.508419 -34.345719)
		(end 95.442024 -34.260028)
		(stroke
			(width 0.0508)
			(type default)
		)
		(layer "B.Cu")
	)
	(gr_arc
		(start 95.558102 -34.687256)
		(mid 95.566223 -34.639169)
		(end 95.569024 -34.590482)
		(stroke
			(width 0.0508)
			(type default)
		)
		(layer "B.Cu")
	)
	(gr_arc
		(start 95.569024 -34.566606)
		(mid 95.564567 -34.505278)
		(end 95.551498 -34.445194)
		(stroke
			(width 0.0508)
			(type default)
		)
		(layer "B.Cu")
	)
	(gr_line
		(start 95.569024 -34.566606)
		(end 95.569024 -34.590482)
		(stroke
			(width 0.0508)
			(type default)
		)
		(layer "B.Cu")
	)
	(gr_arc
		(start 95.656908 -35.045396)
		(mid 95.576627 -35.165545)
		(end 95.54845 -35.30727)
		(stroke
			(width 0.04445)
			(type default)
		)
		(layer "B.Cu")
	)
	(gr_line
		(start 95.656908 -35.045396)
		(end 95.733108 -34.969196)
		(stroke
			(width 0.04445)
			(type default)
		)
		(layer "B.Cu")
	)
	(gr_line
		(start 95.670624 -34.003488)
		(end 95.674434 -34.007044)
		(stroke
			(width 0.0508)
			(type default)
		)
		(layer "B.Cu")
	)
	(gr_arc
		(start 95.733108 -34.969196)
		(mid 95.799642 -34.869546)
		(end 95.823024 -34.752026)
		(stroke
			(width 0.04445)
			(type default)
		)
		(layer "B.Cu")
	)
	(gr_arc
		(start 95.823024 -34.3662)
		(mid 95.784438 -34.171853)
		(end 95.674434 -34.007044)
		(stroke
			(width 0.04445)
			(type default)
		)
		(layer "B.Cu")
	)
	(gr_line
		(start 95.823024 -34.3662)
		(end 95.823024 -34.752026)
		(stroke
			(width 0.04445)
			(type default)
		)
		(layer "B.Cu")
	)
	(gr_arc
		(start 95.9485 -35.4076)
		(mid 95.993236 -35.353276)
		(end 96.026986 -35.291522)
		(stroke
			(width 0.04445)
			(type default)
		)
		(layer "B.Cu")
	)
	(gr_arc
		(start 96.014794 -33.749742)
		(mid 95.964704 -33.639907)
		(end 95.89008 -33.545018)
		(stroke
			(width 0.0508)
			(type default)
		)
		(layer "B.Cu")
	)
	(gr_arc
		(start 96.026986 -35.291522)
		(mid 96.050061 -35.218937)
		(end 96.057974 -35.143186)
		(stroke
			(width 0.04445)
			(type default)
		)
		(layer "B.Cu")
	)
	(gr_line
		(start 96.038924 -34.204402)
		(end 96.057974 -34.223452)
		(stroke
			(width 0.0508)
			(type default)
		)
		(layer "B.Cu")
	)
	(gr_arc
		(start 96.038924 -33.904428)
		(mid 96.032843 -33.826152)
		(end 96.014794 -33.749742)
		(stroke
			(width 0.0508)
			(type default)
		)
		(layer "B.Cu")
	)
	(gr_line
		(start 96.038924 -33.904428)
		(end 96.038924 -34.204402)
		(stroke
			(width 0.0508)
			(type default)
		)
		(layer "B.Cu")
	)
	(gr_line
		(start 96.057974 -34.976816)
		(end 96.057974 -35.143186)
		(stroke
			(width 0.04445)
			(type default)
		)
		(layer "B.Cu")
	)
	(gr_line
		(start 96.057974 -34.223452)
		(end 96.057974 -34.976816)
		(stroke
			(width 0.0508)
			(type default)
		)
		(layer "B.Cu")
	)
	(gr_arc
		(start 96.104456 -35.827462)
		(mid 95.990308 -35.998436)
		(end 95.950278 -36.20008)
		(stroke
			(width 0.04445)
			(type default)
		)
		(layer "B.Cu")
	)
	(gr_line
		(start 96.104456 -35.827462)
		(end 96.246442 -35.68573)
		(stroke
			(width 0.04445)
			(type default)
		)
		(layer "B.Cu")
	)
	(gr_line
		(start 96.161352 -33.33115)
		(end 96.239584 -33.409382)
		(stroke
			(width 0.06985)
			(type default)
		)
		(layer "B.Cu")
	)
	(gr_line
		(start 96.246442 -35.68573)
		(end 96.25076 -35.681412)
		(stroke
			(width 0.04445)
			(type default)
		)
		(layer "B.Cu")
	)
	(gr_arc
		(start 96.25076 -35.681412)
		(mid 96.326883 -35.567431)
		(end 96.35363 -35.433)
		(stroke
			(width 0.04445)
			(type default)
		)
		(layer "B.Cu")
	)
	(gr_line
		(start 96.311974 -34.95421)
		(end 96.35363 -34.995866)
		(stroke
			(width 0.04445)
			(type default)
		)
		(layer "B.Cu")
	)
	(gr_arc
		(start 96.311974 -33.584134)
		(mid 96.293142 -33.489569)
		(end 96.239584 -33.409382)
		(stroke
			(width 0.0508)
			(type default)
		)
		(layer "B.Cu")
	)
	(gr_line
		(start 96.311974 -33.584134)
		(end 96.311974 -34.95421)
		(stroke
			(width 0.04445)
			(type default)
		)
		(layer "B.Cu")
	)
	(gr_line
		(start 96.35363 -34.995866)
		(end 96.35363 -35.433)
		(stroke
			(width 0.04445)
			(type default)
		)
		(layer "B.Cu")
	)
	(gr_line
		(start 96.40316 -31.3436)
		(end 96.541082 -31.205678)
		(stroke
			(width 0.06985)
			(type default)
		)
		(layer "B.Cu")
	)
	(gr_arc
		(start 96.541082 -31.205678)
		(mid 96.568515 -31.164527)
		(end 96.578166 -31.116016)
		(stroke
			(width 0.06985)
			(type default)
		)
		(layer "B.Cu")
	)
	(gr_arc
		(start 96.667066 -32.539432)
		(mid 96.598445 -32.194681)
		(end 96.40316 -31.9024)
		(stroke
			(width 0.06985)
			(type default)
		)
		(layer "B.Cu")
	)
	(gr_arc
		(start 96.921066 -31.060898)
		(mid 96.951502 -31.21389)
		(end 97.03816 -31.3436)
		(stroke
			(width 0.06985)
			(type default)
		)
		(layer "B.Cu")
	)
	(gr_line
		(start 96.999552 -254.375158)
		(end 96.999552 -256.50444)
		(stroke
			(width 0.0508)
			(type default)
		)
		(layer "B.Cu")
	)
	(gr_line
		(start 97.009966 -31.970472)
		(end 97.009966 -32.193992)
		(stroke
			(width 0.06985)
			(type default)
		)
		(layer "B.Cu")
	)
	(gr_arc
		(start 97.03816 -31.9024)
		(mid 97.017292 -31.933632)
		(end 97.009966 -31.970472)
		(stroke
			(width 0.06985)
			(type default)
		)
		(layer "B.Cu")
	)
	(gr_arc
		(start 97.155 -254)
		(mid 97.039934 -254.172107)
		(end 96.999552 -254.375158)
		(stroke
			(width 0.0508)
			(type default)
		)
		(layer "B.Cu")
	)
	(gr_arc
		(start 97.155 -254)
		(mid 97.29189 -253.795129)
		(end 97.339912 -253.553468)
		(stroke
			(width 0.0508)
			(type default)
		)
		(layer "B.Cu")
	)
	(gr_arc
		(start 97.263966 -34.8996)
		(mid 97.305091 -35.106348)
		(end 97.422208 -35.281616)
		(stroke
			(width 0.06985)
			(type default)
		)
		(layer "B.Cu")
	)
	(gr_line
		(start 97.263966 -34.80816)
		(end 97.263966 -34.8996)
		(stroke
			(width 0.06985)
			(type default)
		)
		(layer "B.Cu")
	)
	(gr_line
		(start 97.422208 -35.281616)
		(end 97.540826 -35.400234)
		(stroke
			(width 0.06985)
			(type default)
		)
		(layer "B.Cu")
	)
	(gr_line
		(start 97.550224 -36.069524)
		(end 97.550224 -36.20008)
		(stroke
			(width 0.04445)
			(type default)
		)
		(layer "B.Cu")
	)
	(gr_arc
		(start 97.606866 -34.415476)
		(mid 97.607371 -34.438993)
		(end 97.608898 -34.462466)
		(stroke
			(width 0.06985)
			(type default)
		)
		(layer "B.Cu")
	)
	(gr_arc
		(start 97.608898 -34.46272)
		(mid 97.615455 -34.51138)
		(end 97.626424 -34.55924)
		(stroke
			(width 0.06985)
			(type default)
		)
		(layer "B.Cu")
	)
	(gr_arc
		(start 97.626424 -34.55924)
		(mid 97.638822 -34.59799)
		(end 97.65411 -34.635694)
		(stroke
			(width 0.06985)
			(type default)
		)
		(layer "B.Cu")
	)
	(gr_arc
		(start 97.62998 -35.876992)
		(mid 97.570957 -35.965326)
		(end 97.550224 -36.069524)
		(stroke
			(width 0.04445)
			(type default)
		)
		(layer "B.Cu")
	)
	(gr_line
		(start 97.62998 -35.876992)
		(end 97.831402 -35.67557)
		(stroke
			(width 0.04445)
			(type default)
		)
		(layer "B.Cu")
	)
	(gr_arc
		(start 97.65411 -34.635694)
		(mid 97.66028 -34.648988)
		(end 97.66681 -34.66211)
		(stroke
			(width 0.06985)
			(type default)
		)
		(layer "B.Cu")
	)
	(gr_arc
		(start 97.66681 -34.66211)
		(mid 97.669947 -34.668226)
		(end 97.67316 -34.674302)
		(stroke
			(width 0.06985)
			(type default)
		)
		(layer "B.Cu")
	)
	(gr_arc
		(start 97.67316 -34.674302)
		(mid 97.675429 -34.678249)
		(end 97.677732 -34.682176)
		(stroke
			(width 0.06985)
			(type default)
		)
		(layer "B.Cu")
	)
	(gr_arc
		(start 97.677732 -34.682176)
		(mid 97.679626 -34.685358)
		(end 97.681542 -34.688526)
		(stroke
			(width 0.06985)
			(type default)
		)
		(layer "B.Cu")
	)
	(gr_arc
		(start 97.681542 -34.688526)
		(mid 97.692743 -34.706663)
		(end 97.704656 -34.72434)
		(stroke
			(width 0.06985)
			(type default)
		)
		(layer "B.Cu")
	)
	(gr_arc
		(start 97.682812 -253.775464)
		(mid 97.724063 -253.982897)
		(end 97.841562 -254.15875)
		(stroke
			(width 0.0508)
			(type default)
		)
		(layer "B.Cu")
	)
	(gr_arc
		(start 97.704656 -34.72434)
		(mid 97.704783 -34.724594)
		(end 97.70491 -34.724848)
		(stroke
			(width 0.06985)
			(type default)
		)
		(layer "B.Cu")
	)
	(gr_arc
		(start 97.70491 -34.724848)
		(mid 97.709435 -34.731231)
		(end 97.714054 -34.737548)
		(stroke
			(width 0.06985)
			(type default)
		)
		(layer "B.Cu")
	)
	(gr_arc
		(start 97.714054 -34.737548)
		(mid 97.715574 -34.739456)
		(end 97.717102 -34.741358)
		(stroke
			(width 0.06985)
			(type default)
		)
		(layer "B.Cu")
	)
	(gr_arc
		(start 97.717102 -34.741358)
		(mid 97.734586 -34.763035)
		(end 97.75317 -34.783776)
		(stroke
			(width 0.06985)
			(type default)
		)
		(layer "B.Cu")
	)
	(gr_arc
		(start 97.75317 -34.783776)
		(mid 97.75859 -34.789404)
		(end 97.764092 -34.794952)
		(stroke
			(width 0.06985)
			(type default)
		)
		(layer "B.Cu")
	)
	(gr_line
		(start 97.764092 -34.794952)
		(end 97.845626 -34.876486)
		(stroke
			(width 0.06985)
			(type default)
		)
		(layer "B.Cu")
	)
	(gr_arc
		(start 97.831402 -35.67557)
		(mid 97.91242 -35.554382)
		(end 97.940876 -35.41141)
		(stroke
			(width 0.04445)
			(type default)
		)
		(layer "B.Cu")
	)
	(gr_line
		(start 97.92716 -31.3436)
		(end 97.953576 -31.317184)
		(stroke
			(width 0.06985)
			(type default)
		)
		(layer "B.Cu")
	)
	(gr_arc
		(start 97.940876 -35.106356)
		(mid 97.91609 -34.98196)
		(end 97.845626 -34.876486)
		(stroke
			(width 0.04445)
			(type default)
		)
		(layer "B.Cu")
	)
	(gr_line
		(start 97.940876 -35.106356)
		(end 97.940876 -35.41141)
		(stroke
			(width 0.04445)
			(type default)
		)
		(layer "B.Cu")
	)
	(gr_arc
		(start 97.953576 -31.317184)
		(mid 97.981009 -31.276033)
		(end 97.99066 -31.227522)
		(stroke
			(width 0.06985)
			(type default)
		)
		(layer "B.Cu")
	)
	(gr_line
		(start 97.99066 -31.137098)
		(end 97.99066 -31.227522)
		(stroke
			(width 0.06985)
			(type default)
		)
		(layer "B.Cu")
	)
	(gr_arc
		(start 98.000312 -254.542036)
		(mid 97.959052 -254.334608)
		(end 97.841562 -254.15875)
		(stroke
			(width 0.0508)
			(type default)
		)
		(layer "B.Cu")
	)
	(gr_line
		(start 98.000312 -254.542036)
		(end 98.000312 -256.50444)
		(stroke
			(width 0.0508)
			(type default)
		)
		(layer "B.Cu")
	)
	(gr_arc
		(start 98.025966 -32.140906)
		(mid 98.000262 -32.011839)
		(end 97.92716 -31.9024)
		(stroke
			(width 0.06985)
			(type default)
		)
		(layer "B.Cu")
	)
	(gr_arc
		(start 98.33356 -30.791658)
		(mid 98.392968 -31.090362)
		(end 98.56216 -31.3436)
		(stroke
			(width 0.06985)
			(type default)
		)
		(layer "B.Cu")
	)
	(gr_line
		(start 98.341942 -35.195002)
		(end 98.341942 -35.401504)
		(stroke
			(width 0.06985)
			(type default)
		)
		(layer "B.Cu")
	)
	(gr_line
		(start 98.350324 -36.07435)
		(end 98.350324 -36.20008)
		(stroke
			(width 0.04445)
			(type default)
		)
		(layer "B.Cu")
	)
	(gr_arc
		(start 98.426778 -35.889692)
		(mid 98.370169 -35.974414)
		(end 98.350324 -36.07435)
		(stroke
			(width 0.04445)
			(type default)
		)
		(layer "B.Cu")
	)
	(gr_line
		(start 98.426778 -35.889692)
		(end 98.610928 -35.705542)
		(stroke
			(width 0.04445)
			(type default)
		)
		(layer "B.Cu")
	)
	(gr_arc
		(start 98.455734 -32.008826)
		(mid 98.391416 -32.105085)
		(end 98.368866 -32.21863)
		(stroke
			(width 0.06985)
			(type default)
		)
		(layer "B.Cu")
	)
	(gr_line
		(start 98.455734 -32.008826)
		(end 98.56216 -31.9024)
		(stroke
			(width 0.06985)
			(type default)
		)
		(layer "B.Cu")
	)
	(gr_arc
		(start 98.610928 -35.705542)
		(mid 98.713949 -35.551365)
		(end 98.75012 -35.3695)
		(stroke
			(width 0.04445)
			(type default)
		)
		(layer "B.Cu")
	)
	(gr_line
		(start 98.75012 -34.91484)
		(end 98.75012 -35.3695)
		(stroke
			(width 0.04445)
			(type default)
		)
		(layer "B.Cu")
	)
	(gr_line
		(start 99.45116 -31.9024)
		(end 99.711764 -32.163004)
		(stroke
			(width 0.06985)
			(type default)
		)
		(layer "B.Cu")
	)
	(gr_line
		(start 99.45116 -31.3436)
		(end 99.60864 -31.186374)
		(stroke
			(width 0.06985)
			(type default)
		)
		(layer "B.Cu")
	)
	(gr_arc
		(start 99.60864 -31.186374)
		(mid 99.708305 -31.037076)
		(end 99.74326 -30.861)
		(stroke
			(width 0.06985)
			(type default)
		)
		(layer "B.Cu")
	)
	(gr_arc
		(start 99.796346 -32.289496)
		(mid 99.760261 -32.222102)
		(end 99.711764 -32.163004)
		(stroke
			(width 0.06985)
			(type default)
		)
		(layer "B.Cu")
	)
	(gr_arc
		(start 99.796346 -32.289496)
		(mid 99.832491 -32.357186)
		(end 99.881182 -32.416496)
		(stroke
			(width 0.06985)
			(type default)
		)
		(layer "B.Cu")
	)
	(gr_line
		(start 99.95027 -36.078668)
		(end 99.95027 -36.20008)
		(stroke
			(width 0.04445)
			(type default)
		)
		(layer "B.Cu")
	)
	(gr_arc
		(start 99.95154 -35.39236)
		(mid 99.998146 -35.322545)
		(end 100.014532 -35.240214)
		(stroke
			(width 0.06985)
			(type default)
		)
		(layer "B.Cu")
	)
	(gr_arc
		(start 100.023676 -35.901376)
		(mid 99.969325 -35.982718)
		(end 99.95027 -36.078668)
		(stroke
			(width 0.04445)
			(type default)
		)
		(layer "B.Cu")
	)
	(gr_line
		(start 100.023676 -35.901376)
		(end 100.21824 -35.706812)
		(stroke
			(width 0.04445)
			(type default)
		)
		(layer "B.Cu")
	)
	(gr_arc
		(start 100.051616 -32.94507)
		(mid 100.024183 -32.986221)
		(end 100.014532 -33.034732)
		(stroke
			(width 0.06985)
			(type default)
		)
		(layer "B.Cu")
	)
	(gr_line
		(start 100.051616 -32.94507)
		(end 100.05187 -32.944816)
		(stroke
			(width 0.06985)
			(type default)
		)
		(layer "B.Cu")
	)
	(gr_line
		(start 100.05441 -32.824166)
		(end 100.05441 -32.942276)
		(stroke
			(width 0.06985)
			(type default)
		)
		(layer "B.Cu")
	)
	(gr_arc
		(start 100.08616 -32.03321)
		(mid 100.105108 -32.128468)
		(end 100.159058 -32.209232)
		(stroke
			(width 0.06985)
			(type default)
		)
		(layer "B.Cu")
	)
	(gr_line
		(start 100.08616 -31.9024)
		(end 100.08616 -32.03321)
		(stroke
			(width 0.06985)
			(type default)
		)
		(layer "B.Cu")
	)
	(gr_line
		(start 100.08616 -31.20644)
		(end 100.08616 -31.3436)
		(stroke
			(width 0.06985)
			(type default)
		)
		(layer "B.Cu")
	)
	(gr_arc
		(start 100.21824 -35.706812)
		(mid 100.321249 -35.552633)
		(end 100.357432 -35.37077)
		(stroke
			(width 0.04445)
			(type default)
		)
		(layer "B.Cu")
	)
	(gr_line
		(start 100.357432 -35.052)
		(end 100.357432 -35.37077)
		(stroke
			(width 0.04445)
			(type default)
		)
		(layer "B.Cu")
	)
	(gr_line
		(start 100.357432 -33.167066)
		(end 100.357432 -33.285176)
		(stroke
			(width 0.06985)
			(type default)
		)
		(layer "B.Cu")
	)
	(gr_arc
		(start 100.39731 -33.0708)
		(mid 100.367798 -33.114967)
		(end 100.357432 -33.167066)
		(stroke
			(width 0.06985)
			(type default)
		)
		(layer "B.Cu")
	)
	(gr_line
		(start 100.565712 -211.512912)
		(end 100.565712 -212.081872)
		(stroke
			(width 0.0508)
			(type default)
		)
		(layer "B.Cu")
	)
	(gr_line
		(start 100.565712 -209.948272)
		(end 100.565712 -210.517232)
		(stroke
			(width 0.0508)
			(type default)
		)
		(layer "B.Cu")
	)
	(gr_line
		(start 100.565712 -208.383632)
		(end 100.565712 -208.952592)
		(stroke
			(width 0.0508)
			(type default)
		)
		(layer "B.Cu")
	)
	(gr_line
		(start 100.565712 -206.818992)
		(end 100.565712 -207.387952)
		(stroke
			(width 0.0508)
			(type default)
		)
		(layer "B.Cu")
	)
	(gr_line
		(start 100.565712 -202.41895)
		(end 100.565712 -202.98791)
		(stroke
			(width 0.0508)
			(type default)
		)
		(layer "B.Cu")
	)
	(gr_line
		(start 100.565712 -200.85431)
		(end 100.565712 -201.42327)
		(stroke
			(width 0.0508)
			(type default)
		)
		(layer "B.Cu")
	)
	(gr_line
		(start 100.565712 -199.28967)
		(end 100.565712 -199.85863)
		(stroke
			(width 0.0508)
			(type default)
		)
		(layer "B.Cu")
	)
	(gr_line
		(start 100.62845 -35.268916)
		(end 100.757482 -35.397948)
		(stroke
			(width 0.06985)
			(type default)
		)
		(layer "B.Cu")
	)
	(gr_line
		(start 100.62845 -34.996374)
		(end 100.62845 -35.268916)
		(stroke
			(width 0.06985)
			(type default)
		)
		(layer "B.Cu")
	)
	(gr_line
		(start 100.62845 -34.996374)
		(end 100.712778 -34.912046)
		(stroke
			(width 0.06985)
			(type default)
		)
		(layer "B.Cu")
	)
	(gr_arc
		(start 100.712778 -34.912046)
		(mid 100.726909 -34.895233)
		(end 100.737924 -34.876232)
		(stroke
			(width 0.06985)
			(type default)
		)
		(layer "B.Cu")
	)
	(gr_arc
		(start 100.738178 -34.875724)
		(mid 100.738051 -34.875978)
		(end 100.737924 -34.876232)
		(stroke
			(width 0.06985)
			(type default)
		)
		(layer "B.Cu")
	)
	(gr_arc
		(start 100.738178 -34.875724)
		(mid 100.747207 -34.849465)
		(end 100.75037 -34.821876)
		(stroke
			(width 0.06985)
			(type default)
		)
		(layer "B.Cu")
	)
	(gr_line
		(start 100.75037 -36.20008)
		(end 100.988876 -35.961574)
		(stroke
			(width 0.04445)
			(type default)
		)
		(layer "B.Cu")
	)
	(gr_arc
		(start 100.908612 -211.167472)
		(mid 100.939208 -211.301393)
		(end 101.027992 -211.406232)
		(stroke
			(width 0.0508)
			(type default)
		)
		(layer "B.Cu")
	)
	(gr_arc
		(start 100.908612 -209.602832)
		(mid 100.939193 -209.736765)
		(end 101.027992 -209.841592)
		(stroke
			(width 0.0508)
			(type default)
		)
		(layer "B.Cu")
	)
	(gr_arc
		(start 100.908612 -208.038192)
		(mid 100.939178 -208.172137)
		(end 101.027992 -208.276952)
		(stroke
			(width 0.0508)
			(type default)
		)
		(layer "B.Cu")
	)
	(gr_arc
		(start 100.908612 -206.473552)
		(mid 100.9392 -206.607479)
		(end 101.027992 -206.712312)
		(stroke
			(width 0.0508)
			(type default)
		)
		(layer "B.Cu")
	)
	(gr_arc
		(start 100.908612 -202.07351)
		(mid 100.939185 -202.20745)
		(end 101.027992 -202.31227)
		(stroke
			(width 0.0508)
			(type default)
		)
		(layer "B.Cu")
	)
	(gr_arc
		(start 100.908612 -200.50887)
		(mid 100.939207 -200.642792)
		(end 101.027992 -200.74763)
		(stroke
			(width 0.0508)
			(type default)
		)
		(layer "B.Cu")
	)
	(gr_arc
		(start 100.908612 -198.94423)
		(mid 100.939192 -199.078164)
		(end 101.027992 -199.18299)
		(stroke
			(width 0.0508)
			(type default)
		)
		(layer "B.Cu")
	)
	(gr_line
		(start 100.97516 -31.360618)
		(end 101.067362 -31.268416)
		(stroke
			(width 0.06985)
			(type default)
		)
		(layer "B.Cu")
	)
	(gr_arc
		(start 100.988876 -35.961574)
		(mid 101.069725 -35.840615)
		(end 101.098096 -35.697922)
		(stroke
			(width 0.04445)
			(type default)
		)
		(layer "B.Cu")
	)
	(gr_arc
		(start 101.027992 -212.188552)
		(mid 100.939109 -212.293332)
		(end 100.908612 -212.427312)
		(stroke
			(width 0.0508)
			(type default)
		)
		(layer "B.Cu")
	)
	(gr_arc
		(start 101.027992 -212.188552)
		(mid 101.116786 -212.083738)
		(end 101.147372 -211.949792)
		(stroke
			(width 0.0508)
			(type default)
		)
		(layer "B.Cu")
	)
	(gr_arc
		(start 101.027992 -210.623912)
		(mid 100.939095 -210.728689)
		(end 100.908612 -210.862672)
		(stroke
			(width 0.0508)
			(type default)
		)
		(layer "B.Cu")
	)
	(gr_arc
		(start 101.027992 -210.623912)
		(mid 101.116786 -210.519098)
		(end 101.147372 -210.385152)
		(stroke
			(width 0.0508)
			(type default)
		)
		(layer "B.Cu")
	)
	(gr_arc
		(start 101.027992 -209.059272)
		(mid 100.93908 -209.164046)
		(end 100.908612 -209.298032)
		(stroke
			(width 0.0508)
			(type default)
		)
		(layer "B.Cu")
	)
	(gr_arc
		(start 101.027992 -209.059272)
		(mid 101.116786 -208.954458)
		(end 101.147372 -208.820512)
		(stroke
			(width 0.0508)
			(type default)
		)
		(layer "B.Cu")
	)
	(gr_arc
		(start 101.027992 -207.494632)
		(mid 100.939102 -207.599411)
		(end 100.908612 -207.733392)
		(stroke
			(width 0.0508)
			(type default)
		)
		(layer "B.Cu")
	)
	(gr_arc
		(start 101.027992 -207.494632)
		(mid 101.116786 -207.389818)
		(end 101.147372 -207.255872)
		(stroke
			(width 0.0508)
			(type default)
		)
		(layer "B.Cu")
	)
	(gr_arc
		(start 101.027992 -203.09459)
		(mid 100.939086 -203.199366)
		(end 100.908612 -203.33335)
		(stroke
			(width 0.0508)
			(type default)
		)
		(layer "B.Cu")
	)
	(gr_arc
		(start 101.027992 -203.09459)
		(mid 101.116786 -202.989776)
		(end 101.147372 -202.85583)
		(stroke
			(width 0.0508)
			(type default)
		)
		(layer "B.Cu")
	)
	(gr_arc
		(start 101.027992 -201.52995)
		(mid 100.939109 -201.63473)
		(end 100.908612 -201.76871)
		(stroke
			(width 0.0508)
			(type default)
		)
		(layer "B.Cu")
	)
	(gr_arc
		(start 101.027992 -201.52995)
		(mid 101.116786 -201.425136)
		(end 101.147372 -201.29119)
		(stroke
			(width 0.0508)
			(type default)
		)
		(layer "B.Cu")
	)
	(gr_arc
		(start 101.027992 -199.96531)
		(mid 100.939094 -200.070087)
		(end 100.908612 -200.20407)
		(stroke
			(width 0.0508)
			(type default)
		)
		(layer "B.Cu")
	)
	(gr_arc
		(start 101.027992 -199.96531)
		(mid 101.116786 -199.860496)
		(end 101.147372 -199.72655)
		(stroke
			(width 0.0508)
			(type default)
		)
		(layer "B.Cu")
	)
	(gr_arc
		(start 101.067362 -31.268416)
		(mid 101.1213 -31.187787)
		(end 101.14026 -31.092648)
		(stroke
			(width 0.06985)
			(type default)
		)
		(layer "B.Cu")
	)
	(gr_arc
		(start 101.098096 -35.697922)
		(mid 101.142865 -35.562306)
		(end 101.15804 -35.4203)
		(stroke
			(width 0.04445)
			(type default)
		)
		(layer "B.Cu")
	)
	(gr_arc
		(start 101.147372 -211.644992)
		(mid 101.11688 -211.510999)
		(end 101.027992 -211.406232)
		(stroke
			(width 0.0508)
			(type default)
		)
		(layer "B.Cu")
	)
	(gr_line
		(start 101.147372 -211.644992)
		(end 101.147372 -211.949792)
		(stroke
			(width 0.0508)
			(type default)
		)
		(layer "B.Cu")
	)
	(gr_arc
		(start 101.147372 -210.080352)
		(mid 101.11688 -209.946359)
		(end 101.027992 -209.841592)
		(stroke
			(width 0.0508)
			(type default)
		)
		(layer "B.Cu")
	)
	(gr_line
		(start 101.147372 -210.080352)
		(end 101.147372 -210.385152)
		(stroke
			(width 0.0508)
			(type default)
		)
		(layer "B.Cu")
	)
	(gr_arc
		(start 101.147372 -208.515712)
		(mid 101.11688 -208.381719)
		(end 101.027992 -208.276952)
		(stroke
			(width 0.0508)
			(type default)
		)
		(layer "B.Cu")
	)
	(gr_line
		(start 101.147372 -208.515712)
		(end 101.147372 -208.820512)
		(stroke
			(width 0.0508)
			(type default)
		)
		(layer "B.Cu")
	)
	(gr_arc
		(start 101.147372 -206.951072)
		(mid 101.11688 -206.817079)
		(end 101.027992 -206.712312)
		(stroke
			(width 0.0508)
			(type default)
		)
		(layer "B.Cu")
	)
	(gr_line
		(start 101.147372 -206.951072)
		(end 101.147372 -207.255872)
		(stroke
			(width 0.0508)
			(type default)
		)
		(layer "B.Cu")
	)
	(gr_arc
		(start 101.147372 -202.55103)
		(mid 101.11688 -202.417037)
		(end 101.027992 -202.31227)
		(stroke
			(width 0.0508)
			(type default)
		)
		(layer "B.Cu")
	)
	(gr_line
		(start 101.147372 -202.55103)
		(end 101.147372 -202.85583)
		(stroke
			(width 0.0508)
			(type default)
		)
		(layer "B.Cu")
	)
	(gr_arc
		(start 101.147372 -200.98639)
		(mid 101.11688 -200.852397)
		(end 101.027992 -200.74763)
		(stroke
			(width 0.0508)
			(type default)
		)
		(layer "B.Cu")
	)
	(gr_line
		(start 101.147372 -200.98639)
		(end 101.147372 -201.29119)
		(stroke
			(width 0.0508)
			(type default)
		)
		(layer "B.Cu")
	)
	(gr_arc
		(start 101.147372 -199.42175)
		(mid 101.11688 -199.287757)
		(end 101.027992 -199.18299)
		(stroke
			(width 0.0508)
			(type default)
		)
		(layer "B.Cu")
	)
	(gr_line
		(start 101.147372 -199.42175)
		(end 101.147372 -199.72655)
		(stroke
			(width 0.0508)
			(type default)
		)
		(layer "B.Cu")
	)
	(gr_arc
		(start 101.15804 -35.10788)
		(mid 101.13906 -35.062104)
		(end 101.09327 -35.04311)
		(stroke
			(width 0.06985)
			(type default)
		)
		(layer "B.Cu")
	)
	(gr_line
		(start 101.15804 -35.10788)
		(end 101.15804 -35.4203)
		(stroke
			(width 0.04445)
			(type default)
		)
		(layer "B.Cu")
	)
	(gr_arc
		(start 101.22916 -32.532574)
		(mid 101.163117 -32.200749)
		(end 100.97516 -31.919418)
		(stroke
			(width 0.06985)
			(type default)
		)
		(layer "B.Cu")
	)
	(gr_arc
		(start 101.48316 -31.157672)
		(mid 101.497174 -31.227922)
		(end 101.537008 -31.287466)
		(stroke
			(width 0.06985)
			(type default)
		)
		(layer "B.Cu")
	)
	(gr_line
		(start 101.537008 -31.287466)
		(end 101.61016 -31.360618)
		(stroke
			(width 0.06985)
			(type default)
		)
		(layer "B.Cu")
	)
	(gr_line
		(start 101.57206 -32.011366)
		(end 101.57206 -32.187134)
		(stroke
			(width 0.06985)
			(type default)
		)
		(layer "B.Cu")
	)
	(gr_arc
		(start 101.57206 -32.005778)
		(mid 101.57203 -32.008572)
		(end 101.57206 -32.011366)
		(stroke
			(width 0.06985)
			(type default)
		)
		(layer "B.Cu")
	)
	(gr_arc
		(start 101.61016 -31.919418)
		(mid 101.582991 -31.95902)
		(end 101.57206 -32.005778)
		(stroke
			(width 0.06985)
			(type default)
		)
		(layer "B.Cu")
	)
	(gr_line
		(start 102.350062 -34.654998)
		(end 102.350062 -35.39998)
		(stroke
			(width 0.06985)
			(type default)
		)
		(layer "B.Cu")
	)
	(gr_line
		(start 102.350316 -36.20008)
		(end 102.55631 -35.994086)
		(stroke
			(width 0.04445)
			(type default)
		)
		(layer "B.Cu")
	)
	(gr_line
		(start 102.49916 -31.3436)
		(end 102.570788 -31.271972)
		(stroke
			(width 0.06985)
			(type default)
		)
		(layer "B.Cu")
	)
	(gr_arc
		(start 102.55631 -35.994086)
		(mid 102.69968 -35.779537)
		(end 102.750112 -35.526472)
		(stroke
			(width 0.04445)
			(type default)
		)
		(layer "B.Cu")
	)
	(gr_line
		(start 102.570788 -31.271972)
		(end 102.616254 -31.164022)
		(stroke
			(width 0.06985)
			(type default)
		)
		(layer "B.Cu")
	)
	(gr_arc
		(start 102.616254 -31.164022)
		(mid 102.617442 -31.160863)
		(end 102.61854 -31.157672)
		(stroke
			(width 0.06985)
			(type default)
		)
		(layer "B.Cu")
	)
	(gr_arc
		(start 102.61854 -31.157672)
		(mid 102.624223 -31.13654)
		(end 102.62616 -31.114746)
		(stroke
			(width 0.06985)
			(type default)
		)
		(layer "B.Cu")
	)
	(gr_line
		(start 102.724712 -34.021014)
		(end 102.724712 -34.026094)
		(stroke
			(width 0.06985)
			(type default)
		)
		(layer "B.Cu")
	)
	(gr_line
		(start 102.724712 -34.021014)
		(end 102.749858 -33.995868)
		(stroke
			(width 0.06985)
			(type default)
		)
		(layer "B.Cu")
	)
	(gr_arc
		(start 102.749858 -33.995868)
		(mid 102.767356 -33.970346)
		(end 102.774496 -33.940242)
		(stroke
			(width 0.06985)
			(type default)
		)
		(layer "B.Cu")
	)
	(gr_line
		(start 102.750112 -34.704782)
		(end 102.750112 -35.526472)
		(stroke
			(width 0.04445)
			(type default)
		)
		(layer "B.Cu")
	)
	(gr_arc
		(start 102.774496 -33.940242)
		(mid 102.77465 -33.937958)
		(end 102.77475 -33.93567)
		(stroke
			(width 0.06985)
			(type default)
		)
		(layer "B.Cu")
	)
	(gr_arc
		(start 102.77475 -32.567626)
		(mid 102.703092 -32.207615)
		(end 102.49916 -31.9024)
		(stroke
			(width 0.06985)
			(type default)
		)
		(layer "B.Cu")
	)
	(gr_arc
		(start 102.902766 -34.336482)
		(mid 102.789805 -34.505445)
		(end 102.750112 -34.704782)
		(stroke
			(width 0.04445)
			(type default)
		)
		(layer "B.Cu")
	)
	(gr_arc
		(start 102.96906 -30.945074)
		(mid 103.011981 -31.160755)
		(end 103.13416 -31.3436)
		(stroke
			(width 0.06985)
			(type default)
		)
		(layer "B.Cu")
	)
	(gr_arc
		(start 103.067612 -34.171636)
		(mid 103.104622 -34.116149)
		(end 103.11765 -34.050732)
		(stroke
			(width 0.06985)
			(type default)
		)
		(layer "B.Cu")
	)
	(gr_line
		(start 103.11765 -31.942278)
		(end 103.11765 -32.222186)
		(stroke
			(width 0.06985)
			(type default)
		)
		(layer "B.Cu")
	)
	(gr_arc
		(start 103.13416 -31.9024)
		(mid 103.121935 -31.920696)
		(end 103.11765 -31.942278)
		(stroke
			(width 0.06985)
			(type default)
		)
		(layer "B.Cu")
	)
	(gr_line
		(start 103.150162 -36.07435)
		(end 103.150162 -36.20008)
		(stroke
			(width 0.04445)
			(type default)
		)
		(layer "B.Cu")
	)
	(gr_line
		(start 103.150162 -35.400234)
		(end 103.160322 -35.389566)
		(stroke
			(width 0.06985)
			(type default)
		)
		(layer "B.Cu")
	)
	(gr_line
		(start 103.160322 -35.389566)
		(end 103.170228 -35.379914)
		(stroke
			(width 0.06985)
			(type default)
		)
		(layer "B.Cu")
	)
	(gr_arc
		(start 103.170228 -35.379914)
		(mid 103.187782 -35.357715)
		(end 103.199946 -35.332162)
		(stroke
			(width 0.06985)
			(type default)
		)
		(layer "B.Cu")
	)
	(gr_arc
		(start 103.199946 -35.332162)
		(mid 103.201903 -35.325478)
		(end 103.203502 -35.3187)
		(stroke
			(width 0.06985)
			(type default)
		)
		(layer "B.Cu")
	)
	(gr_arc
		(start 103.203502 -35.3187)
		(mid 103.2043 -35.315661)
		(end 103.205026 -35.312604)
		(stroke
			(width 0.06985)
			(type default)
		)
		(layer "B.Cu")
	)
	(gr_arc
		(start 103.205026 -35.312604)
		(mid 103.206649 -35.301605)
		(end 103.207312 -35.290506)
		(stroke
			(width 0.06985)
			(type default)
		)
		(layer "B.Cu")
	)
	(gr_line
		(start 103.207312 -35.054032)
		(end 103.207312 -35.290506)
		(stroke
			(width 0.06985)
			(type default)
		)
		(layer "B.Cu")
	)
	(gr_arc
		(start 103.226616 -35.889692)
		(mid 103.170007 -35.974414)
		(end 103.150162 -36.07435)
		(stroke
			(width 0.04445)
			(type default)
		)
		(layer "B.Cu")
	)
	(gr_line
		(start 103.226616 -35.889692)
		(end 103.43261 -35.683698)
		(stroke
			(width 0.04445)
			(type default)
		)
		(layer "B.Cu")
	)
	(gr_arc
		(start 103.244396 -34.96437)
		(mid 103.216963 -35.005521)
		(end 103.207312 -35.054032)
		(stroke
			(width 0.06985)
			(type default)
		)
		(layer "B.Cu")
	)
	(gr_line
		(start 103.244396 -34.96437)
		(end 103.308912 -34.899854)
		(stroke
			(width 0.06985)
			(type default)
		)
		(layer "B.Cu")
	)
	(gr_line
		(start 103.335074 -34.837624)
		(end 103.345234 -34.812732)
		(stroke
			(width 0.06985)
			(type default)
		)
		(layer "B.Cu")
	)
	(gr_line
		(start 103.43261 -35.683698)
		(end 103.432864 -35.683698)
		(stroke
			(width 0.04445)
			(type default)
		)
		(layer "B.Cu")
	)
	(gr_line
		(start 103.432864 -35.683698)
		(end 103.433118 -35.683444)
		(stroke
			(width 0.04445)
			(type default)
		)
		(layer "B.Cu")
	)
	(gr_arc
		(start 103.433118 -35.683444)
		(mid 103.519794 -35.553741)
		(end 103.550212 -35.400742)
		(stroke
			(width 0.04445)
			(type default)
		)
		(layer "B.Cu")
	)
	(gr_line
		(start 103.550212 -35.213798)
		(end 103.550212 -35.400742)
		(stroke
			(width 0.04445)
			(type default)
		)
		(layer "B.Cu")
	)
	(gr_arc
		(start 103.621332 -35.042094)
		(mid 103.568694 -35.120872)
		(end 103.550212 -35.213798)
		(stroke
			(width 0.04445)
			(type default)
		)
		(layer "B.Cu")
	)
	(gr_line
		(start 103.63581 -35.007296)
		(end 103.768652 -34.874454)
		(stroke
			(width 0.06985)
			(type default)
		)
		(layer "B.Cu")
	)
	(gr_arc
		(start 104.02316 -31.3436)
		(mid 104.169936 -31.156641)
		(end 104.26827 -30.940248)
		(stroke
			(width 0.06985)
			(type default)
		)
		(layer "B.Cu")
	)
	(gr_arc
		(start 104.15016 -32.208978)
		(mid 104.117154 -32.043055)
		(end 104.02316 -31.9024)
		(stroke
			(width 0.06985)
			(type default)
		)
		(layer "B.Cu")
	)
	(gr_arc
		(start 104.26827 -30.940248)
		(mid 104.303386 -30.791182)
		(end 104.31526 -30.638496)
		(stroke
			(width 0.06985)
			(type default)
		)
		(layer "B.Cu")
	)
	(gr_arc
		(start 104.65816 -31.9024)
		(mid 104.535987 -32.085245)
		(end 104.49306 -32.300926)
		(stroke
			(width 0.06985)
			(type default)
		)
		(layer "B.Cu")
	)
	(gr_line
		(start 104.65816 -30.983936)
		(end 104.65816 -31.3436)
		(stroke
			(width 0.06985)
			(type default)
		)
		(layer "B.Cu")
	)
	(gr_line
		(start 106.304842 -103.872792)
		(end 106.304842 -103.96982)
		(stroke
			(width 0.0508)
			(type default)
		)
		(layer "B.Cu")
	)
	(gr_arc
		(start 106.49077 -103.42372)
		(mid 106.353174 -103.629776)
		(end 106.304842 -103.872792)
		(stroke
			(width 0.0508)
			(type default)
		)
		(layer "B.Cu")
	)
	(gr_line
		(start 106.49077 -103.42372)
		(end 106.619294 -103.295196)
		(stroke
			(width 0.0508)
			(type default)
		)
		(layer "B.Cu")
	)
	(gr_arc
		(start 106.619294 -103.295196)
		(mid 106.698295 -103.198858)
		(end 106.756962 -103.088948)
		(stroke
			(width 0.0508)
			(type default)
		)
		(layer "B.Cu")
	)
	(gr_line
		(start 106.756962 -103.088948)
		(end 106.849672 -102.865174)
		(stroke
			(width 0.0508)
			(type default)
		)
		(layer "B.Cu")
	)
	(gr_arc
		(start 106.83367 -103.866188)
		(mid 106.696064 -104.072242)
		(end 106.647742 -104.31526)
		(stroke
			(width 0.0508)
			(type default)
		)
		(layer "B.Cu")
	)
	(gr_line
		(start 106.83367 -103.866188)
		(end 106.849672 -103.850186)
		(stroke
			(width 0.0508)
			(type default)
		)
		(layer "B.Cu")
	)
	(gr_line
		(start 106.849672 -102.850188)
		(end 106.849672 -102.865174)
		(stroke
			(width 0.0508)
			(type default)
		)
		(layer "B.Cu")
	)
	(gr_line
		(start 107.245658 -104.021636)
		(end 107.246674 -104.02062)
		(stroke
			(width 0.0508)
			(type default)
		)
		(layer "B.Cu")
	)
	(gr_line
		(start 107.246674 -104.02062)
		(end 107.267248 -104.000554)
		(stroke
			(width 0.0508)
			(type default)
		)
		(layer "B.Cu")
	)
	(gr_arc
		(start 107.267248 -104.000554)
		(mid 107.327144 -103.92746)
		(end 107.371642 -103.84409)
		(stroke
			(width 0.0508)
			(type default)
		)
		(layer "B.Cu")
	)
	(gr_line
		(start 107.371642 -103.84409)
		(end 107.688888 -103.128318)
		(stroke
			(width 0.0508)
			(type default)
		)
		(layer "B.Cu")
	)
	(gr_arc
		(start 107.48645 -104.265984)
		(mid 107.675068 -104.064207)
		(end 107.84967 -103.850186)
		(stroke
			(width 0.0508)
			(type default)
		)
		(layer "B.Cu")
	)
	(gr_arc
		(start 107.803696 -102.961186)
		(mid 107.738589 -103.03946)
		(end 107.688888 -103.128318)
		(stroke
			(width 0.0508)
			(type default)
		)
		(layer "B.Cu")
	)
	(gr_arc
		(start 107.803696 -102.961186)
		(mid 107.837724 -102.91026)
		(end 107.84967 -102.850188)
		(stroke
			(width 0.0508)
			(type default)
		)
		(layer "B.Cu")
	)
	(gr_line
		(start 108.020612 -206.3115)
		(end 108.100876 -206.344774)
		(stroke
			(width 0.0508)
			(type default)
		)
		(layer "B.Cu")
	)
	(gr_arc
		(start 108.020612 -205.4225)
		(mid 108.257835 -205.267479)
		(end 108.450634 -205.059788)
		(stroke
			(width 0.0508)
			(type default)
		)
		(layer "B.Cu")
	)
	(gr_line
		(start 108.020612 -203.708)
		(end 108.020612 -204.5335)
		(stroke
			(width 0.0508)
			(type default)
		)
		(layer "B.Cu")
	)
	(gr_arc
		(start 108.100876 -206.344774)
		(mid 108.129637 -206.353509)
		(end 108.15955 -206.356458)
		(stroke
			(width 0.0508)
			(type default)
		)
		(layer "B.Cu")
	)
	(gr_arc
		(start 108.280962 -206.40675)
		(mid 108.225253 -206.369554)
		(end 108.15955 -206.356458)
		(stroke
			(width 0.0508)
			(type default)
		)
		(layer "B.Cu")
	)
	(gr_line
		(start 108.280962 -206.40675)
		(end 108.686346 -206.812134)
		(stroke
			(width 0.0508)
			(type default)
		)
		(layer "B.Cu")
	)
	(gr_arc
		(start 108.450634 -205.059788)
		(mid 108.62204 -204.722125)
		(end 108.681012 -204.34808)
		(stroke
			(width 0.0508)
			(type default)
		)
		(layer "B.Cu")
	)
	(gr_arc
		(start 108.5723 -103.43769)
		(mid 108.457927 -103.608876)
		(end 108.417868 -103.810816)
		(stroke
			(width 0.0508)
			(type default)
		)
		(layer "B.Cu")
	)
	(gr_line
		(start 108.5723 -103.43769)
		(end 108.77296 -103.23703)
		(stroke
			(width 0.0508)
			(type default)
		)
		(layer "B.Cu")
	)
	(gr_line
		(start 108.681012 -203.99248)
		(end 108.681012 -204.34808)
		(stroke
			(width 0.0508)
			(type default)
		)
		(layer "B.Cu")
	)
	(gr_arc
		(start 108.745782 -207.270096)
		(mid 108.76123 -207.34776)
		(end 108.805218 -207.413606)
		(stroke
			(width 0.0508)
			(type default)
		)
		(layer "B.Cu")
	)
	(gr_arc
		(start 108.745782 -206.955644)
		(mid 108.730344 -206.877974)
		(end 108.686346 -206.812134)
		(stroke
			(width 0.0508)
			(type default)
		)
		(layer "B.Cu")
	)
	(gr_arc
		(start 108.77296 -103.23703)
		(mid 108.82053 -103.172838)
		(end 108.847382 -103.097584)
		(stroke
			(width 0.0508)
			(type default)
		)
		(layer "B.Cu")
	)
	(gr_arc
		(start 108.847382 -103.097584)
		(mid 108.849068 -103.086591)
		(end 108.849668 -103.075486)
		(stroke
			(width 0.0508)
			(type default)
		)
		(layer "B.Cu")
	)
	(gr_arc
		(start 108.849668 -103.850186)
		(mid 108.786822 -103.876235)
		(end 108.760768 -103.939086)
		(stroke
			(width 0.0508)
			(type default)
		)
		(layer "B.Cu")
	)
	(gr_line
		(start 108.849668 -102.850188)
		(end 108.849668 -103.075486)
		(stroke
			(width 0.0508)
			(type default)
		)
		(layer "B.Cu")
	)
	(gr_line
		(start 109.023658 -204.33538)
		(end 109.023912 -204.33538)
		(stroke
			(width 0.0508)
			(type default)
		)
		(layer "B.Cu")
	)
	(gr_arc
		(start 109.023658 -204.33538)
		(mid 109.104525 -204.741443)
		(end 109.334554 -205.085696)
		(stroke
			(width 0.0508)
			(type default)
		)
		(layer "B.Cu")
	)
	(gr_arc
		(start 109.078268 -104.972358)
		(mid 109.07923 -104.990113)
		(end 109.082078 -105.007664)
		(stroke
			(width 0.0508)
			(type default)
		)
		(layer "B.Cu")
	)
	(gr_arc
		(start 109.088682 -207.127856)
		(mid 109.10413 -207.20552)
		(end 109.148118 -207.271366)
		(stroke
			(width 0.0508)
			(type default)
		)
		(layer "B.Cu")
	)
	(gr_arc
		(start 109.13491 -104.285542)
		(mid 109.092609 -104.402781)
		(end 109.078268 -104.526588)
		(stroke
			(width 0.0508)
			(type default)
		)
		(layer "B.Cu")
	)
	(gr_line
		(start 109.13491 -104.285542)
		(end 109.17809 -104.19842)
		(stroke
			(width 0.0508)
			(type default)
		)
		(layer "B.Cu")
	)
	(gr_arc
		(start 109.148118 -206.568294)
		(mid 109.104123 -206.634137)
		(end 109.088682 -206.711804)
		(stroke
			(width 0.0508)
			(type default)
		)
		(layer "B.Cu")
	)
	(gr_line
		(start 109.148118 -206.568294)
		(end 109.345476 -206.370936)
		(stroke
			(width 0.0508)
			(type default)
		)
		(layer "B.Cu")
	)
	(gr_arc
		(start 109.17809 -104.19842)
		(mid 109.254609 -104.083996)
		(end 109.281468 -103.948992)
		(stroke
			(width 0.0508)
			(type default)
		)
		(layer "B.Cu")
	)
	(gr_line
		(start 109.281468 -103.895398)
		(end 109.281468 -103.948992)
		(stroke
			(width 0.0508)
			(type default)
		)
		(layer "B.Cu")
	)
	(gr_line
		(start 109.281468 -103.768906)
		(end 109.281468 -103.892858)
		(stroke
			(width 0.0508)
			(type default)
		)
		(layer "B.Cu")
	)
	(gr_line
		(start 109.334554 -205.085696)
		(end 109.671612 -205.4225)
		(stroke
			(width 0.0508)
			(type default)
		)
		(layer "B.Cu")
	)
	(gr_arc
		(start 109.421168 -104.94264)
		(mid 109.421768 -104.95324)
		(end 109.423454 -104.963722)
		(stroke
			(width 0.0508)
			(type default)
		)
		(layer "B.Cu")
	)
	(gr_arc
		(start 109.467396 -103.319834)
		(mid 109.329799 -103.525889)
		(end 109.281468 -103.768906)
		(stroke
			(width 0.0508)
			(type default)
		)
		(layer "B.Cu")
	)
	(gr_line
		(start 109.467396 -103.319834)
		(end 109.787944 -102.999286)
		(stroke
			(width 0.0508)
			(type default)
		)
		(layer "B.Cu")
	)
	(gr_arc
		(start 109.488986 -206.3115)
		(mid 109.411322 -206.326948)
		(end 109.345476 -206.370936)
		(stroke
			(width 0.0508)
			(type default)
		)
		(layer "B.Cu")
	)
	(gr_line
		(start 109.488986 -206.3115)
		(end 109.671612 -206.3115)
		(stroke
			(width 0.0508)
			(type default)
		)
		(layer "B.Cu")
	)
	(gr_arc
		(start 109.503718 -104.368092)
		(mid 109.448951 -104.490837)
		(end 109.421168 -104.622346)
		(stroke
			(width 0.0508)
			(type default)
		)
		(layer "B.Cu")
	)
	(gr_line
		(start 109.503718 -104.368092)
		(end 109.603794 -104.238298)
		(stroke
			(width 0.0508)
			(type default)
		)
		(layer "B.Cu")
	)
	(gr_line
		(start 109.544612 -223.3295)
		(end 109.544612 -224.282)
		(stroke
			(width 0.0508)
			(type default)
		)
		(layer "B.Cu")
	)
	(gr_line
		(start 109.544612 -222.4405)
		(end 109.603794 -222.4405)
		(stroke
			(width 0.0508)
			(type default)
		)
		(layer "B.Cu")
	)
	(gr_line
		(start 109.544612 -221.5515)
		(end 109.690662 -221.5515)
		(stroke
			(width 0.0508)
			(type default)
		)
		(layer "B.Cu")
	)
	(gr_line
		(start 109.603794 -104.238298)
		(end 109.618272 -104.238298)
		(stroke
			(width 0.0508)
			(type default)
		)
		(layer "B.Cu")
	)
	(gr_line
		(start 109.618272 -104.238298)
		(end 109.794294 -104.062276)
		(stroke
			(width 0.0508)
			(type default)
		)
		(layer "B.Cu")
	)
	(gr_line
		(start 109.671612 -203.708)
		(end 109.671612 -204.5335)
		(stroke
			(width 0.0508)
			(type default)
		)
		(layer "B.Cu")
	)
	(gr_arc
		(start 109.690662 -221.5515)
		(mid 109.825661 -221.524629)
		(end 109.94009 -221.448122)
		(stroke
			(width 0.0508)
			(type default)
		)
		(layer "B.Cu")
	)
	(gr_arc
		(start 109.775244 -222.48368)
		(mid 109.692188 -222.45149)
		(end 109.603794 -222.4405)
		(stroke
			(width 0.0508)
			(type default)
		)
		(layer "B.Cu")
	)
	(gr_line
		(start 109.775244 -222.48368)
		(end 109.857286 -222.527622)
		(stroke
			(width 0.0508)
			(type default)
		)
		(layer "B.Cu")
	)
	(gr_arc
		(start 109.787944 -102.999286)
		(mid 109.833652 -102.930879)
		(end 109.849666 -102.850188)
		(stroke
			(width 0.0508)
			(type default)
		)
		(layer "B.Cu")
	)
	(gr_arc
		(start 109.794294 -104.062276)
		(mid 109.835281 -104.000979)
		(end 109.849666 -103.928672)
		(stroke
			(width 0.0508)
			(type default)
		)
		(layer "B.Cu")
	)
	(gr_line
		(start 109.849666 -103.850186)
		(end 109.849666 -103.928672)
		(stroke
			(width 0.0508)
			(type default)
		)
		(layer "B.Cu")
	)
	(gr_line
		(start 109.94009 -221.448122)
		(end 110.096554 -221.291658)
		(stroke
			(width 0.0508)
			(type default)
		)
		(layer "B.Cu")
	)
	(gr_arc
		(start 110.096554 -221.291658)
		(mid 110.126109 -221.258269)
		(end 110.151418 -221.221554)
		(stroke
			(width 0.0508)
			(type default)
		)
		(layer "B.Cu")
	)
	(gr_arc
		(start 110.151418 -221.221554)
		(mid 110.163155 -221.198826)
		(end 110.171992 -221.174818)
		(stroke
			(width 0.0508)
			(type default)
		)
		(layer "B.Cu")
	)
	(gr_arc
		(start 110.181136 -221.155768)
		(mid 110.17586 -221.164955)
		(end 110.171992 -221.174818)
		(stroke
			(width 0.0508)
			(type default)
		)
		(layer "B.Cu")
	)
	(gr_line
		(start 110.181136 -221.155768)
		(end 110.186978 -221.146878)
		(stroke
			(width 0.0508)
			(type default)
		)
		(layer "B.Cu")
	)
	(gr_arc
		(start 110.186978 -221.146878)
		(mid 110.197099 -221.129932)
		(end 110.20552 -221.11208)
		(stroke
			(width 0.0508)
			(type default)
		)
		(layer "B.Cu")
	)
	(gr_arc
		(start 110.192312 -223.087438)
		(mid 110.102235 -222.761171)
		(end 109.857286 -222.527622)
		(stroke
			(width 0.0508)
			(type default)
		)
		(layer "B.Cu")
	)
	(gr_line
		(start 110.20552 -221.11208)
		(end 110.253018 -220.997272)
		(stroke
			(width 0.0508)
			(type default)
		)
		(layer "B.Cu")
	)
	(gr_arc
		(start 110.253018 -220.997272)
		(mid 110.261199 -220.972927)
		(end 110.266226 -220.947742)
		(stroke
			(width 0.0508)
			(type default)
		)
		(layer "B.Cu")
	)
	(gr_arc
		(start 110.266226 -220.947742)
		(mid 110.267737 -220.933681)
		(end 110.268258 -220.919548)
		(stroke
			(width 0.0508)
			(type default)
		)
		(layer "B.Cu")
	)
	(gr_arc
		(start 110.330742 -104.107234)
		(mid 110.329577 -104.143937)
		(end 110.330742 -104.18064)
		(stroke
			(width 0.0508)
			(type default)
		)
		(layer "B.Cu")
	)
	(gr_line
		(start 110.330742 -103.748332)
		(end 110.335314 -104.107742)
		(stroke
			(width 0.0508)
			(type default)
		)
		(layer "B.Cu")
	)
	(gr_arc
		(start 110.335314 -104.107742)
		(mid 110.333044 -104.107346)
		(end 110.330742 -104.107234)
		(stroke
			(width 0.0508)
			(type default)
		)
		(layer "B.Cu")
	)
	(gr_arc
		(start 110.51667 -103.29926)
		(mid 110.379087 -103.505318)
		(end 110.330742 -103.748332)
		(stroke
			(width 0.0508)
			(type default)
		)
		(layer "B.Cu")
	)
	(gr_line
		(start 110.51667 -103.29926)
		(end 110.808516 -103.007414)
		(stroke
			(width 0.0508)
			(type default)
		)
		(layer "B.Cu")
	)
	(gr_arc
		(start 110.567978 -222.970852)
		(mid 110.5435 -223.051407)
		(end 110.535212 -223.13519)
		(stroke
			(width 0.0508)
			(type default)
		)
		(layer "B.Cu")
	)
	(gr_line
		(start 110.567978 -222.970852)
		(end 110.603284 -222.885254)
		(stroke
			(width 0.0508)
			(type default)
		)
		(layer "B.Cu")
	)
	(gr_arc
		(start 110.611412 -221.293436)
		(mid 110.614639 -221.318635)
		(end 110.624112 -221.342204)
		(stroke
			(width 0.0508)
			(type default)
		)
		(layer "B.Cu")
	)
	(gr_line
		(start 110.611412 -221.264988)
		(end 110.611412 -221.293436)
		(stroke
			(width 0.0508)
			(type default)
		)
		(layer "B.Cu")
	)
	(gr_arc
		(start 110.624112 -221.342204)
		(mid 110.658192 -221.384795)
		(end 110.704376 -221.413832)
		(stroke
			(width 0.0508)
			(type default)
		)
		(layer "B.Cu")
	)
	(gr_line
		(start 110.704376 -221.413832)
		(end 111.001556 -221.537022)
		(stroke
			(width 0.0508)
			(type default)
		)
		(layer "B.Cu")
	)
	(gr_line
		(start 110.716314 -104.047544)
		(end 110.72876 -104.030018)
		(stroke
			(width 0.0508)
			(type default)
		)
		(layer "B.Cu")
	)
	(gr_line
		(start 110.761526 -103.99141)
		(end 110.830614 -103.922322)
		(stroke
			(width 0.0508)
			(type default)
		)
		(layer "B.Cu")
	)
	(gr_arc
		(start 110.808516 -103.007414)
		(mid 110.838967 -102.96198)
		(end 110.849664 -102.908354)
		(stroke
			(width 0.0508)
			(type default)
		)
		(layer "B.Cu")
	)
	(gr_arc
		(start 110.819692 -222.621094)
		(mid 110.691937 -222.737157)
		(end 110.603284 -222.885254)
		(stroke
			(width 0.0508)
			(type default)
		)
		(layer "B.Cu")
	)
	(gr_line
		(start 110.819692 -222.621094)
		(end 110.86465 -222.590868)
		(stroke
			(width 0.0508)
			(type default)
		)
		(layer "B.Cu")
	)
	(gr_arc
		(start 110.830614 -103.922322)
		(mid 110.844689 -103.901491)
		(end 110.849664 -103.876856)
		(stroke
			(width 0.0508)
			(type default)
		)
		(layer "B.Cu")
	)
	(gr_line
		(start 110.849664 -103.850186)
		(end 110.849664 -103.876856)
		(stroke
			(width 0.0508)
			(type default)
		)
		(layer "B.Cu")
	)
	(gr_line
		(start 110.849664 -102.850188)
		(end 110.849664 -102.908354)
		(stroke
			(width 0.0508)
			(type default)
		)
		(layer "B.Cu")
	)
	(gr_arc
		(start 110.975902 -222.531432)
		(mid 110.9188 -222.558387)
		(end 110.86465 -222.590868)
		(stroke
			(width 0.0508)
			(type default)
		)
		(layer "B.Cu")
	)
	(gr_line
		(start 110.975902 -222.531432)
		(end 111.195612 -222.4405)
		(stroke
			(width 0.0508)
			(type default)
		)
		(layer "B.Cu")
	)
	(gr_line
		(start 111.000032 -254.768604)
		(end 111.000032 -256.50444)
		(stroke
			(width 0.0508)
			(type default)
		)
		(layer "B.Cu")
	)
	(gr_arc
		(start 111.001556 -221.537022)
		(mid 111.037547 -221.547873)
		(end 111.074962 -221.5515)
		(stroke
			(width 0.0508)
			(type default)
		)
		(layer "B.Cu")
	)
	(gr_line
		(start 111.074962 -221.5515)
		(end 111.195612 -221.5515)
		(stroke
			(width 0.0508)
			(type default)
		)
		(layer "B.Cu")
	)
	(gr_arc
		(start 111.177578 -104.357678)
		(mid 111.120446 -104.443221)
		(end 111.100362 -104.544114)
		(stroke
			(width 0.0508)
			(type default)
		)
		(layer "B.Cu")
	)
	(gr_line
		(start 111.177578 -104.357678)
		(end 111.254794 -104.280462)
		(stroke
			(width 0.0508)
			(type default)
		)
		(layer "B.Cu")
	)
	(gr_line
		(start 111.195612 -223.3295)
		(end 111.195612 -224.282)
		(stroke
			(width 0.0508)
			(type default)
		)
		(layer "B.Cu")
	)
	(gr_arc
		(start 111.254794 -104.280462)
		(mid 111.257983 -104.276791)
		(end 111.261144 -104.273096)
		(stroke
			(width 0.0508)
			(type default)
		)
		(layer "B.Cu")
	)
	(gr_arc
		(start 111.261144 -104.273096)
		(mid 111.318151 -104.193569)
		(end 111.362236 -104.106218)
		(stroke
			(width 0.0508)
			(type default)
		)
		(layer "B.Cu")
	)
	(gr_arc
		(start 111.298736 -254.047498)
		(mid 111.077664 -254.378342)
		(end 111.000032 -254.768604)
		(stroke
			(width 0.0508)
			(type default)
		)
		(layer "B.Cu")
	)
	(gr_arc
		(start 111.298736 -254.047498)
		(mid 111.386336 -253.916395)
		(end 111.4171 -253.761748)
		(stroke
			(width 0.0508)
			(type default)
		)
		(layer "B.Cu")
	)
	(gr_line
		(start 111.31804 -209.487008)
		(end 111.31804 -209.487262)
		(stroke
			(width 0.0508)
			(type default)
		)
		(layer "B.Cu")
	)
	(gr_line
		(start 111.322612 -203.7334)
		(end 111.416338 -203.7334)
		(stroke
			(width 0.0508)
			(type default)
		)
		(layer "B.Cu")
	)
	(gr_arc
		(start 111.362236 -104.106218)
		(mid 111.398093 -103.987666)
		(end 111.410242 -103.86441)
		(stroke
			(width 0.0508)
			(type default)
		)
		(layer "B.Cu")
	)
	(gr_line
		(start 111.410242 -103.710232)
		(end 111.410242 -103.86441)
		(stroke
			(width 0.0508)
			(type default)
		)
		(layer "B.Cu")
	)
	(gr_arc
		(start 111.484918 -104.556306)
		(mid 111.454126 -104.602197)
		(end 111.443262 -104.656382)
		(stroke
			(width 0.0508)
			(type default)
		)
		(layer "B.Cu")
	)
	(gr_line
		(start 111.484918 -104.556306)
		(end 111.52632 -104.51465)
		(stroke
			(width 0.0508)
			(type default)
		)
		(layer "B.Cu")
	)
	(gr_line
		(start 111.52632 -104.51465)
		(end 111.659162 -104.381808)
		(stroke
			(width 0.0508)
			(type default)
		)
		(layer "B.Cu")
	)
	(gr_arc
		(start 111.559848 -203.792836)
		(mid 111.494005 -203.748841)
		(end 111.416338 -203.7334)
		(stroke
			(width 0.0508)
			(type default)
		)
		(layer "B.Cu")
	)
	(gr_line
		(start 111.559848 -203.792836)
		(end 111.822992 -204.05598)
		(stroke
			(width 0.0508)
			(type default)
		)
		(layer "B.Cu")
	)
	(gr_arc
		(start 111.59617 -103.26116)
		(mid 111.458587 -103.467218)
		(end 111.410242 -103.710232)
		(stroke
			(width 0.0508)
			(type default)
		)
		(layer "B.Cu")
	)
	(gr_line
		(start 111.59617 -103.26116)
		(end 111.794036 -103.063294)
		(stroke
			(width 0.0508)
			(type default)
		)
		(layer "B.Cu")
	)
	(gr_line
		(start 111.76 -254.042164)
		(end 111.835438 -254.117602)
		(stroke
			(width 0.0508)
			(type default)
		)
		(layer "B.Cu")
	)
	(gr_arc
		(start 111.794036 -103.063294)
		(mid 111.835228 -103.001646)
		(end 111.849662 -102.928928)
		(stroke
			(width 0.0508)
			(type default)
		)
		(layer "B.Cu")
	)
	(gr_line
		(start 111.825278 -104.09047)
		(end 111.839248 -104.036114)
		(stroke
			(width 0.0508)
			(type default)
		)
		(layer "B.Cu")
	)
	(gr_line
		(start 111.849662 -103.850186)
		(end 111.849662 -103.95458)
		(stroke
			(width 0.0508)
			(type default)
		)
		(layer "B.Cu")
	)
	(gr_line
		(start 111.849662 -102.850188)
		(end 111.849662 -102.928928)
		(stroke
			(width 0.0508)
			(type default)
		)
		(layer "B.Cu")
	)
	(gr_arc
		(start 111.882428 -204.19949)
		(mid 111.86698 -204.121826)
		(end 111.822992 -204.05598)
		(stroke
			(width 0.0508)
			(type default)
		)
		(layer "B.Cu")
	)
	(gr_arc
		(start 111.999522 -254.281686)
		(mid 111.951463 -254.165661)
		(end 111.835438 -254.117602)
		(stroke
			(width 0.0508)
			(type default)
		)
		(layer "B.Cu")
	)
	(gr_line
		(start 111.999522 -254.281686)
		(end 111.999522 -256.50444)
		(stroke
			(width 0.0508)
			(type default)
		)
		(layer "B.Cu")
	)
	(gr_line
		(start 112.256062 -103.70693)
		(end 112.256062 -103.84663)
		(stroke
			(width 0.0508)
			(type default)
		)
		(layer "B.Cu")
	)
	(gr_arc
		(start 112.284764 -204.346048)
		(mid 112.240761 -204.41189)
		(end 112.225328 -204.489558)
		(stroke
			(width 0.0508)
			(type default)
		)
		(layer "B.Cu")
	)
	(gr_line
		(start 112.284764 -204.346048)
		(end 112.843564 -203.787248)
		(stroke
			(width 0.0508)
			(type default)
		)
		(layer "B.Cu")
	)
	(gr_arc
		(start 112.44199 -103.257858)
		(mid 112.304402 -103.463915)
		(end 112.256062 -103.70693)
		(stroke
			(width 0.0508)
			(type default)
		)
		(layer "B.Cu")
	)
	(gr_line
		(start 112.44199 -103.257858)
		(end 112.84966 -102.850188)
		(stroke
			(width 0.0508)
			(type default)
		)
		(layer "B.Cu")
	)
	(gr_arc
		(start 112.631728 -104.02697)
		(mid 112.607208 -104.107906)
		(end 112.598962 -104.19207)
		(stroke
			(width 0.0508)
			(type default)
		)
		(layer "B.Cu")
	)
	(gr_line
		(start 112.631728 -104.02697)
		(end 112.667288 -103.941372)
		(stroke
			(width 0.0508)
			(type default)
		)
		(layer "B.Cu")
	)
	(gr_arc
		(start 112.7506 -103.85806)
		(mid 112.700652 -103.891426)
		(end 112.667288 -103.941372)
		(stroke
			(width 0.0508)
			(type default)
		)
		(layer "B.Cu")
	)
	(gr_arc
		(start 112.789716 -103.850186)
		(mid 112.76977 -103.852199)
		(end 112.7506 -103.85806)
		(stroke
			(width 0.0508)
			(type default)
		)
		(layer "B.Cu")
	)
	(gr_line
		(start 112.789716 -103.850186)
		(end 112.84966 -103.850186)
		(stroke
			(width 0.0508)
			(type default)
		)
		(layer "B.Cu")
	)
	(gr_line
		(start 112.846612 -224.282)
		(end 112.965738 -224.282)
		(stroke
			(width 0.0508)
			(type default)
		)
		(layer "B.Cu")
	)
	(gr_arc
		(start 112.965738 -224.282)
		(mid 113.043413 -224.266569)
		(end 113.109248 -224.222564)
		(stroke
			(width 0.0508)
			(type default)
		)
		(layer "B.Cu")
	)
	(gr_arc
		(start 112.973612 -203.7334)
		(mid 112.90322 -203.747367)
		(end 112.843564 -203.787248)
		(stroke
			(width 0.0508)
			(type default)
		)
		(layer "B.Cu")
	)
	(gr_line
		(start 113.109248 -224.222564)
		(end 113.460276 -223.871536)
		(stroke
			(width 0.0508)
			(type default)
		)
		(layer "B.Cu")
	)
	(gr_arc
		(start 113.272316 -104.023668)
		(mid 113.357988 -103.91111)
		(end 113.388394 -103.77297)
		(stroke
			(width 0.0508)
			(type default)
		)
		(layer "B.Cu")
	)
	(gr_arc
		(start 113.403888 -103.70947)
		(mid 113.395327 -103.741021)
		(end 113.388394 -103.77297)
		(stroke
			(width 0.0508)
			(type default)
		)
		(layer "B.Cu")
	)
	(gr_arc
		(start 113.459514 -103.578406)
		(mid 113.428019 -103.642375)
		(end 113.403888 -103.70947)
		(stroke
			(width 0.0508)
			(type default)
		)
		(layer "B.Cu")
	)
	(gr_line
		(start 113.459514 -103.578406)
		(end 113.677446 -103.192834)
		(stroke
			(width 0.0508)
			(type default)
		)
		(layer "B.Cu")
	)
	(gr_arc
		(start 113.460276 -223.871536)
		(mid 113.504265 -223.805691)
		(end 113.519712 -223.728026)
		(stroke
			(width 0.0508)
			(type default)
		)
		(layer "B.Cu")
	)
	(gr_arc
		(start 113.50879 -105.29443)
		(mid 113.501877 -105.28207)
		(end 113.49482 -105.269792)
		(stroke
			(width 0.0508)
			(type default)
		)
		(layer "B.Cu")
	)
	(gr_line
		(start 113.519712 -223.410526)
		(end 113.519712 -223.728026)
		(stroke
			(width 0.0508)
			(type default)
		)
		(layer "B.Cu")
	)
	(gr_line
		(start 113.54562 -104.230678)
		(end 113.545874 -104.230678)
		(stroke
			(width 0.0508)
			(type default)
		)
		(layer "B.Cu")
	)
	(gr_line
		(start 113.602516 -104.165908)
		(end 113.685828 -104.082596)
		(stroke
			(width 0.0508)
			(type default)
		)
		(layer "B.Cu")
	)
	(gr_arc
		(start 113.640616 -217.089736)
		(mid 113.650989 -217.141831)
		(end 113.680494 -217.186002)
		(stroke
			(width 0.0508)
			(type default)
		)
		(layer "B.Cu")
	)
	(gr_line
		(start 113.640616 -216.662)
		(end 113.640616 -217.089736)
		(stroke
			(width 0.0508)
			(type default)
		)
		(layer "B.Cu")
	)
	(gr_line
		(start 113.640616 -212.520784)
		(end 113.640616 -213.106)
		(stroke
			(width 0.0508)
			(type default)
		)
		(layer "B.Cu")
	)
	(gr_arc
		(start 113.672874 -212.44306)
		(mid 113.648993 -212.478706)
		(end 113.640616 -212.520784)
		(stroke
			(width 0.0508)
			(type default)
		)
		(layer "B.Cu")
	)
	(gr_line
		(start 113.672874 -212.44306)
		(end 113.686844 -212.42909)
		(stroke
			(width 0.0508)
			(type default)
		)
		(layer "B.Cu")
	)
	(gr_arc
		(start 113.677446 -103.192834)
		(mid 113.69524 -103.159048)
		(end 113.710974 -103.124254)
		(stroke
			(width 0.0508)
			(type default)
		)
		(layer "B.Cu")
	)
	(gr_line
		(start 113.685828 -104.082596)
		(end 113.686844 -104.080056)
		(stroke
			(width 0.0508)
			(type default)
		)
		(layer "B.Cu")
	)
	(gr_arc
		(start 113.686844 -212.42909)
		(mid 113.710698 -212.393438)
		(end 113.719102 -212.351366)
		(stroke
			(width 0.0508)
			(type default)
		)
		(layer "B.Cu")
	)
	(gr_arc
		(start 113.686844 -104.080056)
		(mid 113.708334 -104.056515)
		(end 113.727484 -104.031034)
		(stroke
			(width 0.0508)
			(type default)
		)
		(layer "B.Cu")
	)
	(gr_line
		(start 113.710974 -103.124254)
		(end 113.806986 -102.89286)
		(stroke
			(width 0.0508)
			(type default)
		)
		(layer "B.Cu")
	)
	(gr_arc
		(start 113.720372 -217.282268)
		(mid 113.710009 -217.230168)
		(end 113.680494 -217.186002)
		(stroke
			(width 0.0508)
			(type default)
		)
		(layer "B.Cu")
	)
	(gr_line
		(start 113.727484 -104.031034)
		(end 113.849658 -103.850186)
		(stroke
			(width 0.0508)
			(type default)
		)
		(layer "B.Cu")
	)
	(gr_line
		(start 113.806986 -102.89286)
		(end 113.849658 -102.850188)
		(stroke
			(width 0.0508)
			(type default)
		)
		(layer "B.Cu")
	)
	(gr_line
		(start 113.862104 -223.778826)
		(end 113.862612 -223.791526)
		(stroke
			(width 0.0508)
			(type default)
		)
		(layer "B.Cu")
	)
	(gr_line
		(start 113.862104 -223.778826)
		(end 113.862612 -223.778826)
		(stroke
			(width 0.0508)
			(type default)
		)
		(layer "B.Cu")
	)
	(gr_line
		(start 113.862104 -223.753426)
		(end 113.862612 -223.753426)
		(stroke
			(width 0.0508)
			(type default)
		)
		(layer "B.Cu")
	)
	(gr_line
		(start 113.862358 -223.771206)
		(end 113.862612 -223.778826)
		(stroke
			(width 0.0508)
			(type default)
		)
		(layer "B.Cu")
	)
	(gr_arc
		(start 113.862612 -223.791526)
		(mid 113.87806 -223.86919)
		(end 113.922048 -223.935036)
		(stroke
			(width 0.0508)
			(type default)
		)
		(layer "B.Cu")
	)
	(gr_line
		(start 113.922048 -223.935036)
		(end 114.209576 -224.222564)
		(stroke
			(width 0.0508)
			(type default)
		)
		(layer "B.Cu")
	)
	(gr_arc
		(start 114.062002 -212.351366)
		(mid 114.070389 -212.39344)
		(end 114.09426 -212.42909)
		(stroke
			(width 0.0508)
			(type default)
		)
		(layer "B.Cu")
	)
	(gr_line
		(start 114.09426 -212.42909)
		(end 114.10823 -212.44306)
		(stroke
			(width 0.0508)
			(type default)
		)
		(layer "B.Cu")
	)
	(gr_arc
		(start 114.10188 -217.177112)
		(mid 114.073313 -217.219883)
		(end 114.063272 -217.27033)
		(stroke
			(width 0.0508)
			(type default)
		)
		(layer "B.Cu")
	)
	(gr_arc
		(start 114.10188 -217.177112)
		(mid 114.130457 -217.134343)
		(end 114.140488 -217.083894)
		(stroke
			(width 0.0508)
			(type default)
		)
		(layer "B.Cu")
	)
	(gr_line
		(start 114.140488 -216.662)
		(end 114.140488 -217.083894)
		(stroke
			(width 0.0508)
			(type default)
		)
		(layer "B.Cu")
	)
	(gr_arc
		(start 114.140488 -212.520784)
		(mid 114.132126 -212.478694)
		(end 114.10823 -212.44306)
		(stroke
			(width 0.0508)
			(type default)
		)
		(layer "B.Cu")
	)
	(gr_line
		(start 114.140488 -212.520784)
		(end 114.140488 -213.106)
		(stroke
			(width 0.0508)
			(type default)
		)
		(layer "B.Cu")
	)
	(gr_arc
		(start 114.209576 -224.222564)
		(mid 114.275419 -224.266559)
		(end 114.353086 -224.282)
		(stroke
			(width 0.0508)
			(type default)
		)
		(layer "B.Cu")
	)
	(gr_line
		(start 114.267742 -104.073452)
		(end 114.267742 -104.098598)
		(stroke
			(width 0.0508)
			(type default)
		)
		(layer "B.Cu")
	)
	(gr_line
		(start 114.353086 -224.282)
		(end 114.497612 -224.282)
		(stroke
			(width 0.0508)
			(type default)
		)
		(layer "B.Cu")
	)
	(gr_arc
		(start 114.640614 -217.247216)
		(mid 114.649001 -217.28929)
		(end 114.672872 -217.32494)
		(stroke
			(width 0.0508)
			(type default)
		)
		(layer "B.Cu")
	)
	(gr_line
		(start 114.640614 -216.662)
		(end 114.640614 -217.247216)
		(stroke
			(width 0.0508)
			(type default)
		)
		(layer "B.Cu")
	)
	(gr_line
		(start 114.640614 -212.520784)
		(end 114.640614 -213.106)
		(stroke
			(width 0.0508)
			(type default)
		)
		(layer "B.Cu")
	)
	(gr_line
		(start 114.672872 -217.32494)
		(end 114.686842 -217.33891)
		(stroke
			(width 0.0508)
			(type default)
		)
		(layer "B.Cu")
	)
	(gr_arc
		(start 114.672872 -212.44306)
		(mid 114.648998 -212.478708)
		(end 114.640614 -212.520784)
		(stroke
			(width 0.0508)
			(type default)
		)
		(layer "B.Cu")
	)
	(gr_line
		(start 114.672872 -212.44306)
		(end 114.686842 -212.42909)
		(stroke
			(width 0.0508)
			(type default)
		)
		(layer "B.Cu")
	)
	(gr_arc
		(start 114.686842 -212.42909)
		(mid 114.710723 -212.393444)
		(end 114.7191 -212.351366)
		(stroke
			(width 0.0508)
			(type default)
		)
		(layer "B.Cu")
	)
	(gr_arc
		(start 114.717576 -102.987094)
		(mid 114.384572 -103.485521)
		(end 114.267742 -104.073452)
		(stroke
			(width 0.0508)
			(type default)
		)
		(layer "B.Cu")
	)
	(gr_line
		(start 114.717576 -102.987094)
		(end 114.864642 -102.840282)
		(stroke
			(width 0.0508)
			(type default)
		)
		(layer "B.Cu")
	)
	(gr_arc
		(start 114.7191 -217.416634)
		(mid 114.710723 -217.374554)
		(end 114.686842 -217.33891)
		(stroke
			(width 0.0508)
			(type default)
		)
		(layer "B.Cu")
	)
	(gr_arc
		(start 114.864642 -103.830882)
		(mid 114.676642 -104.112192)
		(end 114.610642 -104.444038)
		(stroke
			(width 0.0508)
			(type default)
		)
		(layer "B.Cu")
	)
	(gr_line
		(start 115.000532 -254.273558)
		(end 115.000532 -256.50444)
		(stroke
			(width 0.0508)
			(type default)
		)
		(layer "B.Cu")
	)
	(gr_arc
		(start 115.062 -212.351366)
		(mid 115.070377 -212.393446)
		(end 115.094258 -212.42909)
		(stroke
			(width 0.0508)
			(type default)
		)
		(layer "B.Cu")
	)
	(gr_arc
		(start 115.094258 -217.33891)
		(mid 115.070377 -217.374556)
		(end 115.062 -217.416634)
		(stroke
			(width 0.0508)
			(type default)
		)
		(layer "B.Cu")
	)
	(gr_line
		(start 115.094258 -217.33891)
		(end 115.108228 -217.32494)
		(stroke
			(width 0.0508)
			(type default)
		)
		(layer "B.Cu")
	)
	(gr_line
		(start 115.094258 -212.42909)
		(end 115.108228 -212.44306)
		(stroke
			(width 0.0508)
			(type default)
		)
		(layer "B.Cu")
	)
	(gr_arc
		(start 115.108228 -217.32494)
		(mid 115.132102 -217.289292)
		(end 115.140486 -217.247216)
		(stroke
			(width 0.0508)
			(type default)
		)
		(layer "B.Cu")
	)
	(gr_arc
		(start 115.136422 -253.94539)
		(mid 115.035839 -254.095959)
		(end 115.000532 -254.273558)
		(stroke
			(width 0.0508)
			(type default)
		)
		(layer "B.Cu")
	)
	(gr_arc
		(start 115.136422 -253.94539)
		(mid 115.236972 -253.794811)
		(end 115.272312 -253.617222)
		(stroke
			(width 0.0508)
			(type default)
		)
		(layer "B.Cu")
	)
	(gr_line
		(start 115.140486 -216.662)
		(end 115.140486 -217.247216)
		(stroke
			(width 0.0508)
			(type default)
		)
		(layer "B.Cu")
	)
	(gr_arc
		(start 115.140486 -212.520784)
		(mid 115.132099 -212.47871)
		(end 115.108228 -212.44306)
		(stroke
			(width 0.0508)
			(type default)
		)
		(layer "B.Cu")
	)
	(gr_line
		(start 115.140486 -212.520784)
		(end 115.140486 -213.106)
		(stroke
			(width 0.0508)
			(type default)
		)
		(layer "B.Cu")
	)
	(gr_line
		(start 115.189 -186.848242)
		(end 115.189 -187.417202)
		(stroke
			(width 0.0508)
			(type default)
		)
		(layer "B.Cu")
	)
	(gr_line
		(start 115.189 -185.283602)
		(end 115.189 -185.852562)
		(stroke
			(width 0.0508)
			(type default)
		)
		(layer "B.Cu")
	)
	(gr_line
		(start 115.189 -183.718962)
		(end 115.189 -184.287922)
		(stroke
			(width 0.0508)
			(type default)
		)
		(layer "B.Cu")
	)
	(gr_line
		(start 115.189 -173.797722)
		(end 115.189 -174.366682)
		(stroke
			(width 0.0508)
			(type default)
		)
		(layer "B.Cu")
	)
	(gr_line
		(start 115.189 -172.233082)
		(end 115.189 -172.802042)
		(stroke
			(width 0.0508)
			(type default)
		)
		(layer "B.Cu")
	)
	(gr_line
		(start 115.189 -170.668442)
		(end 115.189 -171.237402)
		(stroke
			(width 0.0508)
			(type default)
		)
		(layer "B.Cu")
	)
	(gr_line
		(start 115.189 -148.29663)
		(end 115.189 -148.86559)
		(stroke
			(width 0.0508)
			(type default)
		)
		(layer "B.Cu")
	)
	(gr_arc
		(start 115.400074 -104.095296)
		(mid 115.45497 -104.013138)
		(end 115.474242 -103.916226)
		(stroke
			(width 0.0508)
			(type default)
		)
		(layer "B.Cu")
	)
	(gr_line
		(start 115.474242 -103.740712)
		(end 115.474242 -103.916226)
		(stroke
			(width 0.0508)
			(type default)
		)
		(layer "B.Cu")
	)
	(gr_arc
		(start 115.5319 -186.502802)
		(mid 115.562469 -186.636745)
		(end 115.65128 -186.741562)
		(stroke
			(width 0.0508)
			(type default)
		)
		(layer "B.Cu")
	)
	(gr_arc
		(start 115.5319 -184.938162)
		(mid 115.562491 -185.072087)
		(end 115.65128 -185.176922)
		(stroke
			(width 0.0508)
			(type default)
		)
		(layer "B.Cu")
	)
	(gr_arc
		(start 115.5319 -183.373522)
		(mid 115.562476 -183.507459)
		(end 115.65128 -183.612282)
		(stroke
			(width 0.0508)
			(type default)
		)
		(layer "B.Cu")
	)
	(gr_arc
		(start 115.5319 -173.452282)
		(mid 115.562498 -173.586201)
		(end 115.65128 -173.691042)
		(stroke
			(width 0.0508)
			(type default)
		)
		(layer "B.Cu")
	)
	(gr_arc
		(start 115.5319 -171.887642)
		(mid 115.562484 -172.021573)
		(end 115.65128 -172.126402)
		(stroke
			(width 0.0508)
			(type default)
		)
		(layer "B.Cu")
	)
	(gr_arc
		(start 115.5319 -170.323002)
		(mid 115.562469 -170.456945)
		(end 115.65128 -170.561762)
		(stroke
			(width 0.0508)
			(type default)
		)
		(layer "B.Cu")
	)
	(gr_arc
		(start 115.5319 -147.95119)
		(mid 115.562464 -148.085137)
		(end 115.65128 -148.18995)
		(stroke
			(width 0.0508)
			(type default)
		)
		(layer "B.Cu")
	)
	(gr_arc
		(start 115.615212 -253.635256)
		(mid 115.663523 -253.87828)
		(end 115.80114 -254.084328)
		(stroke
			(width 0.0508)
			(type default)
		)
		(layer "B.Cu")
	)
	(gr_arc
		(start 115.65128 -187.523882)
		(mid 115.562375 -187.628658)
		(end 115.5319 -187.762642)
		(stroke
			(width 0.0508)
			(type default)
		)
		(layer "B.Cu")
	)
	(gr_arc
		(start 115.65128 -187.523882)
		(mid 115.740074 -187.419068)
		(end 115.77066 -187.285122)
		(stroke
			(width 0.0508)
			(type default)
		)
		(layer "B.Cu")
	)
	(gr_arc
		(start 115.65128 -185.959242)
		(mid 115.562397 -186.064023)
		(end 115.5319 -186.198002)
		(stroke
			(width 0.0508)
			(type default)
		)
		(layer "B.Cu")
	)
	(gr_arc
		(start 115.65128 -185.959242)
		(mid 115.740074 -185.854428)
		(end 115.77066 -185.720482)
		(stroke
			(width 0.0508)
			(type default)
		)
		(layer "B.Cu")
	)
	(gr_arc
		(start 115.65128 -184.394602)
		(mid 115.562382 -184.49938)
		(end 115.5319 -184.633362)
		(stroke
			(width 0.0508)
			(type default)
		)
		(layer "B.Cu")
	)
	(gr_arc
		(start 115.65128 -184.394602)
		(mid 115.740074 -184.289788)
		(end 115.77066 -184.155842)
		(stroke
			(width 0.0508)
			(type default)
		)
		(layer "B.Cu")
	)
	(gr_arc
		(start 115.65128 -174.473362)
		(mid 115.562405 -174.578144)
		(end 115.5319 -174.712122)
		(stroke
			(width 0.0508)
			(type default)
		)
		(layer "B.Cu")
	)
	(gr_arc
		(start 115.65128 -174.473362)
		(mid 115.740074 -174.368548)
		(end 115.77066 -174.234602)
		(stroke
			(width 0.0508)
			(type default)
		)
		(layer "B.Cu")
	)
	(gr_arc
		(start 115.65128 -172.908722)
		(mid 115.56239 -173.013501)
		(end 115.5319 -173.147482)
		(stroke
			(width 0.0508)
			(type default)
		)
		(layer "B.Cu")
	)
	(gr_arc
		(start 115.65128 -172.908722)
		(mid 115.740074 -172.803908)
		(end 115.77066 -172.669962)
		(stroke
			(width 0.0508)
			(type default)
		)
		(layer "B.Cu")
	)
	(gr_arc
		(start 115.65128 -171.344082)
		(mid 115.562375 -171.448858)
		(end 115.5319 -171.582842)
		(stroke
			(width 0.0508)
			(type default)
		)
		(layer "B.Cu")
	)
	(gr_arc
		(start 115.65128 -171.344082)
		(mid 115.740074 -171.239268)
		(end 115.77066 -171.105322)
		(stroke
			(width 0.0508)
			(type default)
		)
		(layer "B.Cu")
	)
	(gr_arc
		(start 115.65128 -148.97227)
		(mid 115.562371 -149.077045)
		(end 115.5319 -149.21103)
		(stroke
			(width 0.0508)
			(type default)
		)
		(layer "B.Cu")
	)
	(gr_arc
		(start 115.65128 -148.97227)
		(mid 115.740074 -148.867456)
		(end 115.77066 -148.73351)
		(stroke
			(width 0.0508)
			(type default)
		)
		(layer "B.Cu")
	)
	(gr_arc
		(start 115.66017 -103.29164)
		(mid 115.522581 -103.497697)
		(end 115.474242 -103.740712)
		(stroke
			(width 0.0508)
			(type default)
		)
		(layer "B.Cu")
	)
	(gr_line
		(start 115.66017 -103.29164)
		(end 115.71732 -103.23449)
		(stroke
			(width 0.0508)
			(type default)
		)
		(layer "B.Cu")
	)
	(gr_line
		(start 115.709192 -104.258618)
		(end 115.716812 -104.263698)
		(stroke
			(width 0.0508)
			(type default)
		)
		(layer "B.Cu")
	)
	(gr_line
		(start 115.709192 -104.258618)
		(end 115.785646 -104.194864)
		(stroke
			(width 0.0508)
			(type default)
		)
		(layer "B.Cu")
	)
	(gr_arc
		(start 115.71732 -103.23449)
		(mid 115.83817 -103.053626)
		(end 115.880642 -102.840282)
		(stroke
			(width 0.0508)
			(type default)
		)
		(layer "B.Cu")
	)
	(gr_arc
		(start 115.77066 -186.980322)
		(mid 115.740168 -186.846329)
		(end 115.65128 -186.741562)
		(stroke
			(width 0.0508)
			(type default)
		)
		(layer "B.Cu")
	)
	(gr_line
		(start 115.77066 -186.980322)
		(end 115.77066 -187.285122)
		(stroke
			(width 0.0508)
			(type default)
		)
		(layer "B.Cu")
	)
	(gr_arc
		(start 115.77066 -185.415682)
		(mid 115.740168 -185.281689)
		(end 115.65128 -185.176922)
		(stroke
			(width 0.0508)
			(type default)
		)
		(layer "B.Cu")
	)
	(gr_line
		(start 115.77066 -185.415682)
		(end 115.77066 -185.720482)
		(stroke
			(width 0.0508)
			(type default)
		)
		(layer "B.Cu")
	)
	(gr_arc
		(start 115.77066 -183.851042)
		(mid 115.740168 -183.717049)
		(end 115.65128 -183.612282)
		(stroke
			(width 0.0508)
			(type default)
		)
		(layer "B.Cu")
	)
	(gr_line
		(start 115.77066 -183.851042)
		(end 115.77066 -184.155842)
		(stroke
			(width 0.0508)
			(type default)
		)
		(layer "B.Cu")
	)
	(gr_arc
		(start 115.77066 -173.929802)
		(mid 115.740168 -173.795809)
		(end 115.65128 -173.691042)
		(stroke
			(width 0.0508)
			(type default)
		)
		(layer "B.Cu")
	)
	(gr_line
		(start 115.77066 -173.929802)
		(end 115.77066 -174.234602)
		(stroke
			(width 0.0508)
			(type default)
		)
		(layer "B.Cu")
	)
	(gr_arc
		(start 115.77066 -172.365162)
		(mid 115.740168 -172.231169)
		(end 115.65128 -172.126402)
		(stroke
			(width 0.0508)
			(type default)
		)
		(layer "B.Cu")
	)
	(gr_line
		(start 115.77066 -172.365162)
		(end 115.77066 -172.669962)
		(stroke
			(width 0.0508)
			(type default)
		)
		(layer "B.Cu")
	)
	(gr_arc
		(start 115.77066 -170.800522)
		(mid 115.740168 -170.666529)
		(end 115.65128 -170.561762)
		(stroke
			(width 0.0508)
			(type default)
		)
		(layer "B.Cu")
	)
	(gr_line
		(start 115.77066 -170.800522)
		(end 115.77066 -171.105322)
		(stroke
			(width 0.0508)
			(type default)
		)
		(layer "B.Cu")
	)
	(gr_arc
		(start 115.77066 -148.42871)
		(mid 115.740168 -148.294717)
		(end 115.65128 -148.18995)
		(stroke
			(width 0.0508)
			(type default)
		)
		(layer "B.Cu")
	)
	(gr_line
		(start 115.77066 -148.42871)
		(end 115.77066 -148.73351)
		(stroke
			(width 0.0508)
			(type default)
		)
		(layer "B.Cu")
	)
	(gr_line
		(start 115.80114 -254.084328)
		(end 115.814094 -254.097282)
		(stroke
			(width 0.0508)
			(type default)
		)
		(layer "B.Cu")
	)
	(gr_line
		(start 115.880642 -103.830882)
		(end 115.880642 -103.965248)
		(stroke
			(width 0.0508)
			(type default)
		)
		(layer "B.Cu")
	)
	(gr_line
		(start 115.894612 -206.3115)
		(end 116.3066 -206.3115)
		(stroke
			(width 0.0508)
			(type default)
		)
		(layer "B.Cu")
	)
	(gr_arc
		(start 115.894612 -205.4225)
		(mid 116.09407 -205.382825)
		(end 116.263166 -205.269846)
		(stroke
			(width 0.0508)
			(type default)
		)
		(layer "B.Cu")
	)
	(gr_line
		(start 115.894612 -203.7334)
		(end 115.894612 -204.5335)
		(stroke
			(width 0.0508)
			(type default)
		)
		(layer "B.Cu")
	)
	(gr_arc
		(start 116.000022 -254.546354)
		(mid 115.951701 -254.303336)
		(end 115.814094 -254.097282)
		(stroke
			(width 0.0508)
			(type default)
		)
		(layer "B.Cu")
	)
	(gr_line
		(start 116.000022 -254.546354)
		(end 116.000022 -256.50444)
		(stroke
			(width 0.0508)
			(type default)
		)
		(layer "B.Cu")
	)
	(gr_line
		(start 116.263166 -205.269846)
		(end 116.301012 -205.232)
		(stroke
			(width 0.0508)
			(type default)
		)
		(layer "B.Cu")
	)
	(gr_arc
		(start 116.301012 -205.232)
		(mid 116.428544 -205.06693)
		(end 116.510562 -204.87513)
		(stroke
			(width 0.0508)
			(type default)
		)
		(layer "B.Cu")
	)
	(gr_arc
		(start 116.5098 -206.5147)
		(mid 116.450284 -206.371016)
		(end 116.3066 -206.3115)
		(stroke
			(width 0.0508)
			(type default)
		)
		(layer "B.Cu")
	)
	(gr_arc
		(start 116.510562 -204.87513)
		(mid 116.512108 -204.869294)
		(end 116.51361 -204.863446)
		(stroke
			(width 0.0508)
			(type default)
		)
		(layer "B.Cu")
	)
	(gr_arc
		(start 116.51361 -204.863446)
		(mid 116.535023 -204.757331)
		(end 116.542312 -204.649324)
		(stroke
			(width 0.0508)
			(type default)
		)
		(layer "B.Cu")
	)
	(gr_arc
		(start 116.64061 -217.24747)
		(mid 116.648989 -217.289548)
		(end 116.672868 -217.325194)
		(stroke
			(width 0.0508)
			(type default)
		)
		(layer "B.Cu")
	)
	(gr_line
		(start 116.64061 -216.662)
		(end 116.64061 -217.24747)
		(stroke
			(width 0.0508)
			(type default)
		)
		(layer "B.Cu")
	)
	(gr_line
		(start 116.64061 -212.52053)
		(end 116.64061 -213.106)
		(stroke
			(width 0.0508)
			(type default)
		)
		(layer "B.Cu")
	)
	(gr_line
		(start 116.672868 -217.325194)
		(end 116.686838 -217.339164)
		(stroke
			(width 0.0508)
			(type default)
		)
		(layer "B.Cu")
	)
	(gr_arc
		(start 116.672868 -212.442806)
		(mid 116.648987 -212.478452)
		(end 116.64061 -212.52053)
		(stroke
			(width 0.0508)
			(type default)
		)
		(layer "B.Cu")
	)
	(gr_line
		(start 116.672868 -212.442806)
		(end 116.686838 -212.428836)
		(stroke
			(width 0.0508)
			(type default)
		)
		(layer "B.Cu")
	)
	(gr_arc
		(start 116.686838 -212.428836)
		(mid 116.710709 -212.393187)
		(end 116.719096 -212.351112)
		(stroke
			(width 0.0508)
			(type default)
		)
		(layer "B.Cu")
	)
	(gr_arc
		(start 116.719096 -217.416888)
		(mid 116.710709 -217.374814)
		(end 116.686838 -217.339164)
		(stroke
			(width 0.0508)
			(type default)
		)
		(layer "B.Cu")
	)
	(gr_arc
		(start 116.885212 -204.4954)
		(mid 116.901241 -204.74043)
		(end 116.948966 -204.981302)
		(stroke
			(width 0.0508)
			(type default)
		)
		(layer "B.Cu")
	)
	(gr_arc
		(start 116.948966 -204.981302)
		(mid 116.966702 -205.043473)
		(end 116.986558 -205.105)
		(stroke
			(width 0.0508)
			(type default)
		)
		(layer "B.Cu")
	)
	(gr_arc
		(start 116.986558 -205.105)
		(mid 117.224147 -205.337596)
		(end 117.545612 -205.4225)
		(stroke
			(width 0.0508)
			(type default)
		)
		(layer "B.Cu")
	)
	(gr_line
		(start 117.037612 -223.3295)
		(end 117.037612 -224.282)
		(stroke
			(width 0.0508)
			(type default)
		)
		(layer "B.Cu")
	)
	(gr_line
		(start 117.037612 -222.4405)
		(end 117.084856 -222.4405)
		(stroke
			(width 0.0508)
			(type default)
		)
		(layer "B.Cu")
	)
	(gr_line
		(start 117.037612 -221.5515)
		(end 117.245638 -221.5515)
		(stroke
			(width 0.0508)
			(type default)
		)
		(layer "B.Cu")
	)
	(gr_arc
		(start 117.061996 -212.350858)
		(mid 117.070372 -212.393058)
		(end 117.094254 -212.428836)
		(stroke
			(width 0.0508)
			(type default)
		)
		(layer "B.Cu")
	)
	(gr_arc
		(start 117.094254 -217.339164)
		(mid 117.070377 -217.374947)
		(end 117.061996 -217.417142)
		(stroke
			(width 0.0508)
			(type default)
		)
		(layer "B.Cu")
	)
	(gr_line
		(start 117.094254 -217.339164)
		(end 117.108478 -217.32494)
		(stroke
			(width 0.0508)
			(type default)
		)
		(layer "B.Cu")
	)
	(gr_line
		(start 117.094254 -212.428836)
		(end 117.108478 -212.44306)
		(stroke
			(width 0.0508)
			(type default)
		)
		(layer "B.Cu")
	)
	(gr_arc
		(start 117.108478 -217.32494)
		(mid 117.13233 -217.289149)
		(end 117.140736 -217.246962)
		(stroke
			(width 0.0508)
			(type default)
		)
		(layer "B.Cu")
	)
	(gr_arc
		(start 117.113558 -222.446088)
		(mid 117.099481 -222.441885)
		(end 117.084856 -222.4405)
		(stroke
			(width 0.0508)
			(type default)
		)
		(layer "B.Cu")
	)
	(gr_line
		(start 117.113558 -222.446088)
		(end 117.408198 -222.568008)
		(stroke
			(width 0.0508)
			(type default)
		)
		(layer "B.Cu")
	)
	(gr_line
		(start 117.140736 -216.662)
		(end 117.140736 -217.246962)
		(stroke
			(width 0.0508)
			(type default)
		)
		(layer "B.Cu")
	)
	(gr_arc
		(start 117.140736 -212.521038)
		(mid 117.132316 -212.478864)
		(end 117.108478 -212.44306)
		(stroke
			(width 0.0508)
			(type default)
		)
		(layer "B.Cu")
	)
	(gr_line
		(start 117.140736 -212.521038)
		(end 117.140736 -213.106)
		(stroke
			(width 0.0508)
			(type default)
		)
		(layer "B.Cu")
	)
	(gr_arc
		(start 117.241574 -206.3115)
		(mid 116.966599 -206.425399)
		(end 116.8527 -206.700374)
		(stroke
			(width 0.0508)
			(type default)
		)
		(layer "B.Cu")
	)
	(gr_line
		(start 117.241574 -206.3115)
		(end 117.545612 -206.3115)
		(stroke
			(width 0.0508)
			(type default)
		)
		(layer "B.Cu")
	)
	(gr_arc
		(start 117.245638 -221.5515)
		(mid 117.323302 -221.536052)
		(end 117.389148 -221.492064)
		(stroke
			(width 0.0508)
			(type default)
		)
		(layer "B.Cu")
	)
	(gr_line
		(start 117.389148 -221.492064)
		(end 117.551454 -221.329758)
		(stroke
			(width 0.0508)
			(type default)
		)
		(layer "B.Cu")
	)
	(gr_arc
		(start 117.395244 -103.9622)
		(mid 117.390935 -104.041448)
		(end 117.395244 -104.120696)
		(stroke
			(width 0.0508)
			(type default)
		)
		(layer "B.Cu")
	)
	(gr_line
		(start 117.395244 -103.641652)
		(end 117.395244 -103.775256)
		(stroke
			(width 0.0508)
			(type default)
		)
		(layer "B.Cu")
	)
	(gr_arc
		(start 117.447568 -103.411274)
		(mid 117.408495 -103.52353)
		(end 117.395244 -103.641652)
		(stroke
			(width 0.0508)
			(type default)
		)
		(layer "B.Cu")
	)
	(gr_line
		(start 117.447568 -103.411274)
		(end 117.547898 -103.201978)
		(stroke
			(width 0.0508)
			(type default)
		)
		(layer "B.Cu")
	)
	(gr_arc
		(start 117.494558 -222.625666)
		(mid 117.454227 -222.592566)
		(end 117.408198 -222.568008)
		(stroke
			(width 0.0508)
			(type default)
		)
		(layer "B.Cu")
	)
	(gr_line
		(start 117.518942 -186.884818)
		(end 117.518942 -187.453778)
		(stroke
			(width 0.0508)
			(type default)
		)
		(layer "B.Cu")
	)
	(gr_line
		(start 117.518942 -185.320178)
		(end 117.518942 -185.889138)
		(stroke
			(width 0.0508)
			(type default)
		)
		(layer "B.Cu")
	)
	(gr_line
		(start 117.518942 -183.755538)
		(end 117.518942 -184.324498)
		(stroke
			(width 0.0508)
			(type default)
		)
		(layer "B.Cu")
	)
	(gr_line
		(start 117.518942 -182.190898)
		(end 117.518942 -182.759858)
		(stroke
			(width 0.0508)
			(type default)
		)
		(layer "B.Cu")
	)
	(gr_line
		(start 117.518942 -176.017682)
		(end 117.518942 -176.586642)
		(stroke
			(width 0.0508)
			(type default)
		)
		(layer "B.Cu")
	)
	(gr_line
		(start 117.518942 -174.453042)
		(end 117.518942 -175.022002)
		(stroke
			(width 0.0508)
			(type default)
		)
		(layer "B.Cu")
	)
	(gr_line
		(start 117.518942 -172.888402)
		(end 117.518942 -173.457362)
		(stroke
			(width 0.0508)
			(type default)
		)
		(layer "B.Cu")
	)
	(gr_line
		(start 117.545612 -203.7334)
		(end 117.545612 -204.5335)
		(stroke
			(width 0.0508)
			(type default)
		)
		(layer "B.Cu")
	)
	(gr_arc
		(start 117.551454 -221.329758)
		(mid 117.595449 -221.263915)
		(end 117.61089 -221.186248)
		(stroke
			(width 0.0508)
			(type default)
		)
		(layer "B.Cu")
	)
	(gr_arc
		(start 117.55247 -222.71228)
		(mid 117.527783 -222.666116)
		(end 117.494558 -222.625666)
		(stroke
			(width 0.0508)
			(type default)
		)
		(layer "B.Cu")
	)
	(gr_line
		(start 117.55247 -222.71228)
		(end 117.643148 -222.93072)
		(stroke
			(width 0.0508)
			(type default)
		)
		(layer "B.Cu")
	)
	(gr_arc
		(start 117.60327 -103.124)
		(mid 117.572265 -103.160632)
		(end 117.547898 -103.201978)
		(stroke
			(width 0.0508)
			(type default)
		)
		(layer "B.Cu")
	)
	(gr_arc
		(start 117.60327 -103.124)
		(mid 117.625056 -103.101155)
		(end 117.645688 -103.077264)
		(stroke
			(width 0.0508)
			(type default)
		)
		(layer "B.Cu")
	)
	(gr_line
		(start 117.640608 -216.682828)
		(end 117.710712 -216.752932)
		(stroke
			(width 0.0508)
			(type default)
		)
		(layer "B.Cu")
	)
	(gr_line
		(start 117.640608 -216.662)
		(end 117.640608 -216.682828)
		(stroke
			(width 0.0508)
			(type default)
		)
		(layer "B.Cu")
	)
	(gr_line
		(start 117.640608 -212.52053)
		(end 117.640608 -213.106)
		(stroke
			(width 0.0508)
			(type default)
		)
		(layer "B.Cu")
	)
	(gr_line
		(start 117.645688 -103.077264)
		(end 117.734588 -102.968552)
		(stroke
			(width 0.0508)
			(type default)
		)
		(layer "B.Cu")
	)
	(gr_arc
		(start 117.672866 -212.442806)
		(mid 117.649008 -212.478457)
		(end 117.640608 -212.52053)
		(stroke
			(width 0.0508)
			(type default)
		)
		(layer "B.Cu")
	)
	(gr_line
		(start 117.672866 -212.442806)
		(end 117.686836 -212.428836)
		(stroke
			(width 0.0508)
			(type default)
		)
		(layer "B.Cu")
	)
	(gr_arc
		(start 117.685312 -223.141794)
		(mid 117.674648 -223.034175)
		(end 117.643148 -222.93072)
		(stroke
			(width 0.0508)
			(type default)
		)
		(layer "B.Cu")
	)
	(gr_arc
		(start 117.686836 -212.428836)
		(mid 117.710717 -212.39319)
		(end 117.719094 -212.351112)
		(stroke
			(width 0.0508)
			(type default)
		)
		(layer "B.Cu")
	)
	(gr_line
		(start 117.719094 -212.350858)
		(end 117.719094 -212.351112)
		(stroke
			(width 0.0508)
			(type default)
		)
		(layer "B.Cu")
	)
	(gr_line
		(start 117.734588 -102.968552)
		(end 117.740938 -102.960932)
		(stroke
			(width 0.0508)
			(type default)
		)
		(layer "B.Cu")
	)
	(gr_arc
		(start 117.7544 -102.945946)
		(mid 117.747485 -102.953274)
		(end 117.740938 -102.960932)
		(stroke
			(width 0.0508)
			(type default)
		)
		(layer "B.Cu")
	)
	(gr_line
		(start 117.7544 -102.945946)
		(end 117.850158 -102.850188)
		(stroke
			(width 0.0508)
			(type default)
		)
		(layer "B.Cu")
	)
	(gr_arc
		(start 117.861842 -186.539378)
		(mid 117.892435 -186.673304)
		(end 117.981222 -186.778138)
		(stroke
			(width 0.0508)
			(type default)
		)
		(layer "B.Cu")
	)
	(gr_arc
		(start 117.861842 -184.974738)
		(mid 117.89242 -185.108676)
		(end 117.981222 -185.213498)
		(stroke
			(width 0.0508)
			(type default)
		)
		(layer "B.Cu")
	)
	(gr_arc
		(start 117.861842 -183.410098)
		(mid 117.892405 -183.544048)
		(end 117.981222 -183.648858)
		(stroke
			(width 0.0508)
			(type default)
		)
		(layer "B.Cu")
	)
	(gr_arc
		(start 117.861842 -181.845458)
		(mid 117.892427 -181.97939)
		(end 117.981222 -182.084218)
		(stroke
			(width 0.0508)
			(type default)
		)
		(layer "B.Cu")
	)
	(gr_arc
		(start 117.861842 -175.672242)
		(mid 117.892421 -175.806179)
		(end 117.981222 -175.911002)
		(stroke
			(width 0.0508)
			(type default)
		)
		(layer "B.Cu")
	)
	(gr_arc
		(start 117.861842 -174.107602)
		(mid 117.892407 -174.24155)
		(end 117.981222 -174.346362)
		(stroke
			(width 0.0508)
			(type default)
		)
		(layer "B.Cu")
	)
	(gr_arc
		(start 117.861842 -172.542962)
		(mid 117.892429 -172.676893)
		(end 117.981222 -172.781722)
		(stroke
			(width 0.0508)
			(type default)
		)
		(layer "B.Cu")
	)
	(gr_arc
		(start 117.95379 -220.923104)
		(mid 117.969242 -221.000765)
		(end 118.013226 -221.066614)
		(stroke
			(width 0.0508)
			(type default)
		)
		(layer "B.Cu")
	)
	(gr_arc
		(start 117.981222 -187.560458)
		(mid 117.892333 -187.665236)
		(end 117.861842 -187.799218)
		(stroke
			(width 0.0508)
			(type default)
		)
		(layer "B.Cu")
	)
	(gr_arc
		(start 117.981222 -187.560458)
		(mid 118.070016 -187.455644)
		(end 118.100602 -187.321698)
		(stroke
			(width 0.0508)
			(type default)
		)
		(layer "B.Cu")
	)
	(gr_arc
		(start 117.981222 -185.995818)
		(mid 117.892318 -186.100593)
		(end 117.861842 -186.234578)
		(stroke
			(width 0.0508)
			(type default)
		)
		(layer "B.Cu")
	)
	(gr_arc
		(start 117.981222 -185.995818)
		(mid 118.070016 -185.891004)
		(end 118.100602 -185.757058)
		(stroke
			(width 0.0508)
			(type default)
		)
		(layer "B.Cu")
	)
	(gr_arc
		(start 117.981222 -184.431178)
		(mid 117.892303 -184.53595)
		(end 117.861842 -184.669938)
		(stroke
			(width 0.0508)
			(type default)
		)
		(layer "B.Cu")
	)
	(gr_arc
		(start 117.981222 -184.431178)
		(mid 118.070016 -184.326364)
		(end 118.100602 -184.192418)
		(stroke
			(width 0.0508)
			(type default)
		)
		(layer "B.Cu")
	)
	(gr_arc
		(start 117.981222 -182.866538)
		(mid 117.892325 -182.971314)
		(end 117.861842 -183.105298)
		(stroke
			(width 0.0508)
			(type default)
		)
		(layer "B.Cu")
	)
	(gr_arc
		(start 117.981222 -182.866538)
		(mid 118.070016 -182.761724)
		(end 118.100602 -182.627778)
		(stroke
			(width 0.0508)
			(type default)
		)
		(layer "B.Cu")
	)
	(gr_arc
		(start 117.981222 -176.693322)
		(mid 117.892319 -176.798097)
		(end 117.861842 -176.932082)
		(stroke
			(width 0.0508)
			(type default)
		)
		(layer "B.Cu")
	)
	(gr_arc
		(start 117.981222 -176.693322)
		(mid 118.070016 -176.588508)
		(end 118.100602 -176.454562)
		(stroke
			(width 0.0508)
			(type default)
		)
		(layer "B.Cu")
	)
	(gr_arc
		(start 117.981222 -175.128682)
		(mid 117.892305 -175.233454)
		(end 117.861842 -175.367442)
		(stroke
			(width 0.0508)
			(type default)
		)
		(layer "B.Cu")
	)
	(gr_arc
		(start 117.981222 -175.128682)
		(mid 118.070016 -175.023868)
		(end 118.100602 -174.889922)
		(stroke
			(width 0.0508)
			(type default)
		)
		(layer "B.Cu")
	)
	(gr_arc
		(start 117.981222 -173.564042)
		(mid 117.892327 -173.668819)
		(end 117.861842 -173.802802)
		(stroke
			(width 0.0508)
			(type default)
		)
		(layer "B.Cu")
	)
	(gr_arc
		(start 117.981222 -173.564042)
		(mid 118.070016 -173.459228)
		(end 118.100602 -173.325282)
		(stroke
			(width 0.0508)
			(type default)
		)
		(layer "B.Cu")
	)
	(gr_line
		(start 118.013226 -221.066614)
		(end 118.438676 -221.492064)
		(stroke
			(width 0.0508)
			(type default)
		)
		(layer "B.Cu")
	)
	(gr_arc
		(start 118.070884 -222.931736)
		(mid 118.038982 -223.036951)
		(end 118.028212 -223.146366)
		(stroke
			(width 0.0508)
			(type default)
		)
		(layer "B.Cu")
	)
	(gr_line
		(start 118.070884 -222.931736)
		(end 118.143782 -222.75546)
		(stroke
			(width 0.0508)
			(type default)
		)
		(layer "B.Cu")
	)
	(gr_arc
		(start 118.090188 -216.712546)
		(mid 118.063114 -216.75297)
		(end 118.053612 -216.800684)
		(stroke
			(width 0.0508)
			(type default)
		)
		(layer "B.Cu")
	)
	(gr_line
		(start 118.090188 -216.712546)
		(end 118.140734 -216.662)
		(stroke
			(width 0.0508)
			(type default)
		)
		(layer "B.Cu")
	)
	(gr_line
		(start 118.094252 -212.428836)
		(end 118.108476 -212.44306)
		(stroke
			(width 0.0508)
			(type default)
		)
		(layer "B.Cu")
	)
	(gr_arc
		(start 118.100602 -187.016898)
		(mid 118.07011 -186.882905)
		(end 117.981222 -186.778138)
		(stroke
			(width 0.0508)
			(type default)
		)
		(layer "B.Cu")
	)
	(gr_line
		(start 118.100602 -187.016898)
		(end 118.100602 -187.321698)
		(stroke
			(width 0.0508)
			(type default)
		)
		(layer "B.Cu")
	)
	(gr_arc
		(start 118.100602 -185.452258)
		(mid 118.07011 -185.318265)
		(end 117.981222 -185.213498)
		(stroke
			(width 0.0508)
			(type default)
		)
		(layer "B.Cu")
	)
	(gr_line
		(start 118.100602 -185.452258)
		(end 118.100602 -185.757058)
		(stroke
			(width 0.0508)
			(type default)
		)
		(layer "B.Cu")
	)
	(gr_arc
		(start 118.100602 -183.887618)
		(mid 118.07011 -183.753625)
		(end 117.981222 -183.648858)
		(stroke
			(width 0.0508)
			(type default)
		)
		(layer "B.Cu")
	)
	(gr_line
		(start 118.100602 -183.887618)
		(end 118.100602 -184.192418)
		(stroke
			(width 0.0508)
			(type default)
		)
		(layer "B.Cu")
	)
	(gr_arc
		(start 118.100602 -182.322978)
		(mid 118.07011 -182.188985)
		(end 117.981222 -182.084218)
		(stroke
			(width 0.0508)
			(type default)
		)
		(layer "B.Cu")
	)
	(gr_line
		(start 118.100602 -182.322978)
		(end 118.100602 -182.627778)
		(stroke
			(width 0.0508)
			(type default)
		)
		(layer "B.Cu")
	)
	(gr_arc
		(start 118.100602 -176.149762)
		(mid 118.07011 -176.015769)
		(end 117.981222 -175.911002)
		(stroke
			(width 0.0508)
			(type default)
		)
		(layer "B.Cu")
	)
	(gr_line
		(start 118.100602 -176.149762)
		(end 118.100602 -176.454562)
		(stroke
			(width 0.0508)
			(type default)
		)
		(layer "B.Cu")
	)
	(gr_arc
		(start 118.100602 -174.585122)
		(mid 118.07011 -174.451129)
		(end 117.981222 -174.346362)
		(stroke
			(width 0.0508)
			(type default)
		)
		(layer "B.Cu")
	)
	(gr_line
		(start 118.100602 -174.585122)
		(end 118.100602 -174.889922)
		(stroke
			(width 0.0508)
			(type default)
		)
		(layer "B.Cu")
	)
	(gr_arc
		(start 118.100602 -173.020482)
		(mid 118.07011 -172.886489)
		(end 117.981222 -172.781722)
		(stroke
			(width 0.0508)
			(type default)
		)
		(layer "B.Cu")
	)
	(gr_line
		(start 118.100602 -173.020482)
		(end 118.100602 -173.325282)
		(stroke
			(width 0.0508)
			(type default)
		)
		(layer "B.Cu")
	)
	(gr_arc
		(start 118.140734 -212.521038)
		(mid 118.132358 -212.478838)
		(end 118.108476 -212.44306)
		(stroke
			(width 0.0508)
			(type default)
		)
		(layer "B.Cu")
	)
	(gr_line
		(start 118.140734 -212.521038)
		(end 118.140734 -213.106)
		(stroke
			(width 0.0508)
			(type default)
		)
		(layer "B.Cu")
	)
	(gr_arc
		(start 118.228872 -222.62846)
		(mid 118.18007 -222.687768)
		(end 118.143782 -222.75546)
		(stroke
			(width 0.0508)
			(type default)
		)
		(layer "B.Cu")
	)
	(gr_arc
		(start 118.304818 -104.216708)
		(mid 118.365625 -104.133831)
		(end 118.387114 -104.03332)
		(stroke
			(width 0.0508)
			(type default)
		)
		(layer "B.Cu")
	)
	(gr_arc
		(start 118.356126 -222.543624)
		(mid 118.288313 -222.579764)
		(end 118.228872 -222.62846)
		(stroke
			(width 0.0508)
			(type default)
		)
		(layer "B.Cu")
	)
	(gr_line
		(start 118.356126 -222.543624)
		(end 118.58625 -222.44812)
		(stroke
			(width 0.0508)
			(type default)
		)
		(layer "B.Cu")
	)
	(gr_line
		(start 118.387114 -103.76662)
		(end 118.387114 -104.03332)
		(stroke
			(width 0.0508)
			(type default)
		)
		(layer "B.Cu")
	)
	(gr_arc
		(start 118.438676 -221.492064)
		(mid 118.504521 -221.536052)
		(end 118.582186 -221.5515)
		(stroke
			(width 0.0508)
			(type default)
		)
		(layer "B.Cu")
	)
	(gr_arc
		(start 118.573042 -103.317548)
		(mid 118.43544 -103.523601)
		(end 118.387114 -103.76662)
		(stroke
			(width 0.0508)
			(type default)
		)
		(layer "B.Cu")
	)
	(gr_line
		(start 118.573042 -103.317548)
		(end 118.715536 -103.175054)
		(stroke
			(width 0.0508)
			(type default)
		)
		(layer "B.Cu")
	)
	(gr_line
		(start 118.582186 -221.5515)
		(end 118.688612 -221.5515)
		(stroke
			(width 0.0508)
			(type default)
		)
		(layer "B.Cu")
	)
	(gr_arc
		(start 118.624858 -222.4405)
		(mid 118.605178 -222.442402)
		(end 118.58625 -222.44812)
		(stroke
			(width 0.0508)
			(type default)
		)
		(layer "B.Cu")
	)
	(gr_line
		(start 118.624858 -222.4405)
		(end 118.688612 -222.4405)
		(stroke
			(width 0.0508)
			(type default)
		)
		(layer "B.Cu")
	)
	(gr_line
		(start 118.629684 -104.365806)
		(end 118.664228 -104.331262)
		(stroke
			(width 0.0508)
			(type default)
		)
		(layer "B.Cu")
	)
	(gr_arc
		(start 118.664228 -104.331262)
		(mid 118.678444 -104.316377)
		(end 118.692168 -104.301036)
		(stroke
			(width 0.0508)
			(type default)
		)
		(layer "B.Cu")
	)
	(gr_line
		(start 118.688612 -223.3295)
		(end 118.688612 -224.282)
		(stroke
			(width 0.0508)
			(type default)
		)
		(layer "B.Cu")
	)
	(gr_arc
		(start 118.692168 -104.301036)
		(mid 118.809234 -104.105983)
		(end 118.850156 -103.88219)
		(stroke
			(width 0.0508)
			(type default)
		)
		(layer "B.Cu")
	)
	(gr_arc
		(start 118.715536 -103.175054)
		(mid 118.815182 -103.026018)
		(end 118.850156 -102.850188)
		(stroke
			(width 0.0508)
			(type default)
		)
		(layer "B.Cu")
	)
	(gr_line
		(start 118.850156 -103.850186)
		(end 118.850156 -103.88219)
		(stroke
			(width 0.0508)
			(type default)
		)
		(layer "B.Cu")
	)
	(gr_line
		(start 118.999762 -254.536194)
		(end 118.999762 -256.50444)
		(stroke
			(width 0.0508)
			(type default)
		)
		(layer "B.Cu")
	)
	(gr_arc
		(start 119.167656 -254.130302)
		(mid 119.043402 -254.316574)
		(end 118.999762 -254.536194)
		(stroke
			(width 0.0508)
			(type default)
		)
		(layer "B.Cu")
	)
	(gr_line
		(start 119.167656 -254.130302)
		(end 119.16791 -254.130048)
		(stroke
			(width 0.0508)
			(type default)
		)
		(layer "B.Cu")
	)
	(gr_arc
		(start 119.16791 -254.130048)
		(mid 119.292502 -253.943722)
		(end 119.336312 -253.723902)
		(stroke
			(width 0.0508)
			(type default)
		)
		(layer "B.Cu")
	)
	(gr_line
		(start 119.196612 -203.7334)
		(end 119.239538 -203.7334)
		(stroke
			(width 0.0508)
			(type default)
		)
		(layer "B.Cu")
	)
	(gr_arc
		(start 119.383048 -203.792836)
		(mid 119.317205 -203.748841)
		(end 119.239538 -203.7334)
		(stroke
			(width 0.0508)
			(type default)
		)
		(layer "B.Cu")
	)
	(gr_line
		(start 119.383048 -203.792836)
		(end 119.772176 -204.181964)
		(stroke
			(width 0.0508)
			(type default)
		)
		(layer "B.Cu")
	)
	(gr_arc
		(start 119.679212 -253.645924)
		(mid 119.72092 -253.855693)
		(end 119.83974 -254.033528)
		(stroke
			(width 0.0508)
			(type default)
		)
		(layer "B.Cu")
	)
	(gr_arc
		(start 119.831612 -204.325474)
		(mid 119.816164 -204.24781)
		(end 119.772176 -204.181964)
		(stroke
			(width 0.0508)
			(type default)
		)
		(layer "B.Cu")
	)
	(gr_arc
		(start 120.000522 -254.421386)
		(mid 119.958729 -254.211459)
		(end 119.83974 -254.033528)
		(stroke
			(width 0.0508)
			(type default)
		)
		(layer "B.Cu")
	)
	(gr_line
		(start 120.000522 -254.421386)
		(end 120.000522 -256.50444)
		(stroke
			(width 0.0508)
			(type default)
		)
		(layer "B.Cu")
	)
	(gr_arc
		(start 120.233948 -204.245464)
		(mid 120.189954 -204.311308)
		(end 120.174512 -204.388974)
		(stroke
			(width 0.0508)
			(type default)
		)
		(layer "B.Cu")
	)
	(gr_line
		(start 120.233948 -204.245464)
		(end 120.686576 -203.792836)
		(stroke
			(width 0.0508)
			(type default)
		)
		(layer "B.Cu")
	)
	(gr_line
		(start 120.339612 -224.282)
		(end 120.484138 -224.282)
		(stroke
			(width 0.0508)
			(type default)
		)
		(layer "B.Cu")
	)
	(gr_arc
		(start 120.484138 -224.282)
		(mid 120.561813 -224.266569)
		(end 120.627648 -224.222564)
		(stroke
			(width 0.0508)
			(type default)
		)
		(layer "B.Cu")
	)
	(gr_line
		(start 120.627648 -224.222564)
		(end 120.915176 -223.935036)
		(stroke
			(width 0.0508)
			(type default)
		)
		(layer "B.Cu")
	)
	(gr_arc
		(start 120.830086 -203.7334)
		(mid 120.752427 -203.748856)
		(end 120.686576 -203.792836)
		(stroke
			(width 0.0508)
			(type default)
		)
		(layer "B.Cu")
	)
	(gr_line
		(start 120.830086 -203.7334)
		(end 120.847612 -203.7334)
		(stroke
			(width 0.0508)
			(type default)
		)
		(layer "B.Cu")
	)
	(gr_arc
		(start 120.915176 -223.935036)
		(mid 120.959165 -223.869191)
		(end 120.974612 -223.791526)
		(stroke
			(width 0.0508)
			(type default)
		)
		(layer "B.Cu")
	)
	(gr_arc
		(start 121.317512 -223.702626)
		(mid 121.33296 -223.78029)
		(end 121.376948 -223.846136)
		(stroke
			(width 0.0508)
			(type default)
		)
		(layer "B.Cu")
	)
	(gr_line
		(start 121.376948 -223.846136)
		(end 121.753376 -224.222564)
		(stroke
			(width 0.0508)
			(type default)
		)
		(layer "B.Cu")
	)
	(gr_arc
		(start 121.753376 -224.222564)
		(mid 121.819219 -224.266559)
		(end 121.896886 -224.282)
		(stroke
			(width 0.0508)
			(type default)
		)
		(layer "B.Cu")
	)
	(gr_line
		(start 121.896886 -224.282)
		(end 121.990612 -224.282)
		(stroke
			(width 0.0508)
			(type default)
		)
		(layer "B.Cu")
	)
	(gr_line
		(start 122.850148 -91.849702)
		(end 122.856752 -91.856306)
		(stroke
			(width 0.0508)
			(type default)
		)
		(layer "B.Cu")
	)
	(gr_line
		(start 122.850148 -90.849704)
		(end 122.966734 -90.849704)
		(stroke
			(width 0.0508)
			(type default)
		)
		(layer "B.Cu")
	)
	(gr_line
		(start 122.850148 -89.849706)
		(end 122.925332 -89.849706)
		(stroke
			(width 0.0508)
			(type default)
		)
		(layer "B.Cu")
	)
	(gr_line
		(start 122.850148 -84.849716)
		(end 123.141232 -84.558632)
		(stroke
			(width 0.0508)
			(type default)
		)
		(layer "B.Cu")
	)
	(gr_line
		(start 122.850148 -83.849718)
		(end 123.257818 -83.442048)
		(stroke
			(width 0.0508)
			(type default)
		)
		(layer "B.Cu")
	)
	(gr_line
		(start 122.850148 -82.84972)
		(end 122.98426 -82.715862)
		(stroke
			(width 0.0508)
			(type default)
		)
		(layer "B.Cu")
	)
	(gr_arc
		(start 122.855482 -93.828362)
		(mid 122.86274 -93.864802)
		(end 122.883422 -93.895672)
		(stroke
			(width 0.0508)
			(type default)
		)
		(layer "B.Cu")
	)
	(gr_arc
		(start 122.856752 -91.856306)
		(mid 122.95309 -91.935307)
		(end 123.063 -91.993974)
		(stroke
			(width 0.0508)
			(type default)
		)
		(layer "B.Cu")
	)
	(gr_arc
		(start 122.86107 -92.54236)
		(mid 122.830171 -92.684022)
		(end 122.850402 -92.827602)
		(stroke
			(width 0.0508)
			(type default)
		)
		(layer "B.Cu")
	)
	(gr_line
		(start 122.883422 -93.895672)
		(end 123.155964 -94.168214)
		(stroke
			(width 0.0508)
			(type default)
		)
		(layer "B.Cu")
	)
	(gr_arc
		(start 122.936 -80.952086)
		(mid 122.933022 -80.937117)
		(end 122.92457 -80.9244)
		(stroke
			(width 0.0508)
			(type default)
		)
		(layer "B.Cu")
	)
	(gr_line
		(start 122.936 -80.952086)
		(end 122.936 -81.788)
		(stroke
			(width 0.0508)
			(type default)
		)
		(layer "B.Cu")
	)
	(gr_line
		(start 123.000262 -254.547624)
		(end 123.000262 -256.50444)
		(stroke
			(width 0.0508)
			(type default)
		)
		(layer "B.Cu")
	)
	(gr_line
		(start 123.063 -91.993974)
		(end 123.272296 -92.080588)
		(stroke
			(width 0.0508)
			(type default)
		)
		(layer "B.Cu")
	)
	(gr_arc
		(start 123.14936 -254.187452)
		(mid 123.03903 -254.352722)
		(end 123.000262 -254.547624)
		(stroke
			(width 0.0508)
			(type default)
		)
		(layer "B.Cu")
	)
	(gr_arc
		(start 123.14936 -254.187452)
		(mid 123.259877 -254.021956)
		(end 123.298712 -253.826772)
		(stroke
			(width 0.0508)
			(type default)
		)
		(layer "B.Cu")
	)
	(gr_arc
		(start 123.166124 -90.932254)
		(mid 123.074642 -90.871158)
		(end 122.966734 -90.849704)
		(stroke
			(width 0.0508)
			(type default)
		)
		(layer "B.Cu")
	)
	(gr_line
		(start 123.166124 -90.932254)
		(end 123.360942 -91.127072)
		(stroke
			(width 0.0508)
			(type default)
		)
		(layer "B.Cu")
	)
	(gr_arc
		(start 123.175014 -92.412058)
		(mid 122.991111 -92.412271)
		(end 122.86107 -92.54236)
		(stroke
			(width 0.0508)
			(type default)
		)
		(layer "B.Cu")
	)
	(gr_arc
		(start 123.23953 -94.310708)
		(mid 123.20686 -94.234117)
		(end 123.155964 -94.168214)
		(stroke
			(width 0.0508)
			(type default)
		)
		(layer "B.Cu")
	)
	(gr_line
		(start 123.298712 -250.833128)
		(end 123.298712 -251.402088)
		(stroke
			(width 0.0508)
			(type default)
		)
		(layer "B.Cu")
	)
	(gr_line
		(start 123.298712 -249.268488)
		(end 123.298712 -249.837448)
		(stroke
			(width 0.0508)
			(type default)
		)
		(layer "B.Cu")
	)
	(gr_line
		(start 123.298712 -247.703848)
		(end 123.298712 -248.272808)
		(stroke
			(width 0.0508)
			(type default)
		)
		(layer "B.Cu")
	)
	(gr_line
		(start 123.298712 -246.139208)
		(end 123.298712 -246.708168)
		(stroke
			(width 0.0508)
			(type default)
		)
		(layer "B.Cu")
	)
	(gr_arc
		(start 123.360942 -91.127072)
		(mid 123.566996 -91.264673)
		(end 123.810014 -91.313)
		(stroke
			(width 0.0508)
			(type default)
		)
		(layer "B.Cu")
	)
	(gr_arc
		(start 123.374404 -90.035634)
		(mid 123.168354 -89.898019)
		(end 122.925332 -89.849706)
		(stroke
			(width 0.0508)
			(type default)
		)
		(layer "B.Cu")
	)
	(gr_line
		(start 123.374404 -90.035634)
		(end 123.55449 -90.21572)
		(stroke
			(width 0.0508)
			(type default)
		)
		(layer "B.Cu")
	)
	(gr_line
		(start 123.391168 -94.771718)
		(end 123.392438 -94.77375)
		(stroke
			(width 0.0508)
			(type default)
		)
		(layer "B.Cu")
	)
	(gr_arc
		(start 123.541028 -83.3247)
		(mid 123.387741 -83.355191)
		(end 123.257818 -83.442048)
		(stroke
			(width 0.0508)
			(type default)
		)
		(layer "B.Cu")
	)
	(gr_line
		(start 123.541028 -83.3247)
		(end 123.72213 -83.3247)
		(stroke
			(width 0.0508)
			(type default)
		)
		(layer "B.Cu")
	)
	(gr_arc
		(start 123.55449 -90.21572)
		(mid 123.717668 -90.324662)
		(end 123.91009 -90.36304)
		(stroke
			(width 0.0508)
			(type default)
		)
		(layer "B.Cu")
	)
	(gr_arc
		(start 123.58497 -81.632552)
		(mid 123.594881 -81.682313)
		(end 123.62307 -81.7245)
		(stroke
			(width 0.0508)
			(type default)
		)
		(layer "B.Cu")
	)
	(gr_line
		(start 123.58497 -81.099406)
		(end 123.58497 -81.632552)
		(stroke
			(width 0.0508)
			(type default)
		)
		(layer "B.Cu")
	)
	(gr_arc
		(start 123.62307 -81.7245)
		(mid 123.665254 -81.752692)
		(end 123.715018 -81.7626)
		(stroke
			(width 0.0508)
			(type default)
		)
		(layer "B.Cu")
	)
	(gr_arc
		(start 123.63577 -80.976724)
		(mid 123.598193 -81.03302)
		(end 123.58497 -81.099406)
		(stroke
			(width 0.0508)
			(type default)
		)
		(layer "B.Cu")
	)
	(gr_arc
		(start 123.641612 -253.576074)
		(mid 123.641772 -253.583697)
		(end 123.64212 -253.591314)
		(stroke
			(width 0.0508)
			(type default)
		)
		(layer "B.Cu")
	)
	(gr_arc
		(start 123.641612 -250.487688)
		(mid 123.672116 -250.621659)
		(end 123.760992 -250.726448)
		(stroke
			(width 0.0508)
			(type default)
		)
		(layer "B.Cu")
	)
	(gr_arc
		(start 123.641612 -248.923048)
		(mid 123.672101 -249.057031)
		(end 123.760992 -249.161808)
		(stroke
			(width 0.0508)
			(type default)
		)
		(layer "B.Cu")
	)
	(gr_arc
		(start 123.641612 -247.358408)
		(mid 123.672124 -247.492373)
		(end 123.760992 -247.597168)
		(stroke
			(width 0.0508)
			(type default)
		)
		(layer "B.Cu")
	)
	(gr_arc
		(start 123.641612 -245.793768)
		(mid 123.672109 -245.927745)
		(end 123.760992 -246.032528)
		(stroke
			(width 0.0508)
			(type default)
		)
		(layer "B.Cu")
	)
	(gr_line
		(start 123.644152 -253.632462)
		(end 123.647962 -253.709678)
		(stroke
			(width 0.0508)
			(type default)
		)
		(layer "B.Cu")
	)
	(gr_arc
		(start 123.647962 -253.709678)
		(mid 123.66657 -253.833744)
		(end 123.709176 -253.95174)
		(stroke
			(width 0.0508)
			(type default)
		)
		(layer "B.Cu")
	)
	(gr_arc
		(start 123.698 -84.328)
		(mid 123.396669 -84.387931)
		(end 123.141232 -84.558632)
		(stroke
			(width 0.0508)
			(type default)
		)
		(layer "B.Cu")
	)
	(gr_line
		(start 123.698 -84.328)
		(end 123.922028 -84.328)
		(stroke
			(width 0.0508)
			(type default)
		)
		(layer "B.Cu")
	)
	(gr_line
		(start 123.709176 -253.95174)
		(end 123.937776 -254.430784)
		(stroke
			(width 0.0508)
			(type default)
		)
		(layer "B.Cu")
	)
	(gr_line
		(start 123.715018 -81.7626)
		(end 123.73737 -81.7626)
		(stroke
			(width 0.0508)
			(type default)
		)
		(layer "B.Cu")
	)
	(gr_arc
		(start 123.758452 -80.925924)
		(mid 123.692058 -80.939119)
		(end 123.63577 -80.976724)
		(stroke
			(width 0.0508)
			(type default)
		)
		(layer "B.Cu")
	)
	(gr_line
		(start 123.758452 -80.925924)
		(end 123.853448 -80.925924)
		(stroke
			(width 0.0508)
			(type default)
		)
		(layer "B.Cu")
	)
	(gr_arc
		(start 123.760992 -251.508768)
		(mid 123.672115 -251.613549)
		(end 123.641612 -251.747528)
		(stroke
			(width 0.0508)
			(type default)
		)
		(layer "B.Cu")
	)
	(gr_arc
		(start 123.760992 -251.508768)
		(mid 123.84988 -251.403973)
		(end 123.880372 -251.270008)
		(stroke
			(width 0.0508)
			(type default)
		)
		(layer "B.Cu")
	)
	(gr_arc
		(start 123.760992 -249.944128)
		(mid 123.672101 -250.048906)
		(end 123.641612 -250.182888)
		(stroke
			(width 0.0508)
			(type default)
		)
		(layer "B.Cu")
	)
	(gr_arc
		(start 123.760992 -249.944128)
		(mid 123.84988 -249.839333)
		(end 123.880372 -249.705368)
		(stroke
			(width 0.0508)
			(type default)
		)
		(layer "B.Cu")
	)
	(gr_arc
		(start 123.760992 -248.379488)
		(mid 123.672086 -248.484264)
		(end 123.641612 -248.618248)
		(stroke
			(width 0.0508)
			(type default)
		)
		(layer "B.Cu")
	)
	(gr_arc
		(start 123.760992 -248.379488)
		(mid 123.84988 -248.274693)
		(end 123.880372 -248.140728)
		(stroke
			(width 0.0508)
			(type default)
		)
		(layer "B.Cu")
	)
	(gr_arc
		(start 123.760992 -246.814848)
		(mid 123.672108 -246.919628)
		(end 123.641612 -247.053608)
		(stroke
			(width 0.0508)
			(type default)
		)
		(layer "B.Cu")
	)
	(gr_arc
		(start 123.760992 -246.814848)
		(mid 123.84988 -246.710053)
		(end 123.880372 -246.576088)
		(stroke
			(width 0.0508)
			(type default)
		)
		(layer "B.Cu")
	)
	(gr_line
		(start 123.80341 -92.601288)
		(end 123.80341 -92.601542)
		(stroke
			(width 0.0508)
			(type default)
		)
		(layer "B.Cu")
	)
	(gr_line
		(start 123.80722 -92.258642)
		(end 124.140468 -92.258642)
		(stroke
			(width 0.0508)
			(type default)
		)
		(layer "B.Cu")
	)
	(gr_line
		(start 123.810014 -91.313)
		(end 123.92152 -91.313)
		(stroke
			(width 0.0508)
			(type default)
		)
		(layer "B.Cu")
	)
	(gr_arc
		(start 123.81357 -82.3722)
		(mid 123.364747 -82.46157)
		(end 122.98426 -82.715862)
		(stroke
			(width 0.0508)
			(type default)
		)
		(layer "B.Cu")
	)
	(gr_line
		(start 123.81357 -82.3722)
		(end 124.04217 -82.3722)
		(stroke
			(width 0.0508)
			(type default)
		)
		(layer "B.Cu")
	)
	(gr_arc
		(start 123.825 -84.793582)
		(mid 123.97333 -84.764077)
		(end 124.099066 -84.680044)
		(stroke
			(width 0.0508)
			(type default)
		)
		(layer "B.Cu")
	)
	(gr_line
		(start 123.850146 -90.849704)
		(end 124.023882 -90.92184)
		(stroke
			(width 0.0508)
			(type default)
		)
		(layer "B.Cu")
	)
	(gr_line
		(start 123.850146 -89.849706)
		(end 123.938792 -89.849706)
		(stroke
			(width 0.0508)
			(type default)
		)
		(layer "B.Cu")
	)
	(gr_line
		(start 123.850146 -83.849718)
		(end 124.005594 -83.693762)
		(stroke
			(width 0.0508)
			(type default)
		)
		(layer "B.Cu")
	)
	(gr_line
		(start 123.850146 -82.84972)
		(end 123.908312 -82.791554)
		(stroke
			(width 0.0508)
			(type default)
		)
		(layer "B.Cu")
	)
	(gr_arc
		(start 123.851162 -93.848682)
		(mid 123.661169 -93.927406)
		(end 123.58243 -94.117414)
		(stroke
			(width 0.0508)
			(type default)
		)
		(layer "B.Cu")
	)
	(gr_arc
		(start 123.880372 -250.965208)
		(mid 123.84988 -250.831215)
		(end 123.760992 -250.726448)
		(stroke
			(width 0.0508)
			(type default)
		)
		(layer "B.Cu")
	)
	(gr_line
		(start 123.880372 -250.965208)
		(end 123.880372 -251.270008)
		(stroke
			(width 0.0508)
			(type default)
		)
		(layer "B.Cu")
	)
	(gr_arc
		(start 123.880372 -249.400568)
		(mid 123.84988 -249.266575)
		(end 123.760992 -249.161808)
		(stroke
			(width 0.0508)
			(type default)
		)
		(layer "B.Cu")
	)
	(gr_line
		(start 123.880372 -249.400568)
		(end 123.880372 -249.705368)
		(stroke
			(width 0.0508)
			(type default)
		)
		(layer "B.Cu")
	)
	(gr_arc
		(start 123.880372 -247.835928)
		(mid 123.84988 -247.701935)
		(end 123.760992 -247.597168)
		(stroke
			(width 0.0508)
			(type default)
		)
		(layer "B.Cu")
	)
	(gr_line
		(start 123.880372 -247.835928)
		(end 123.880372 -248.140728)
		(stroke
			(width 0.0508)
			(type default)
		)
		(layer "B.Cu")
	)
	(gr_arc
		(start 123.880372 -246.271288)
		(mid 123.84988 -246.137295)
		(end 123.760992 -246.032528)
		(stroke
			(width 0.0508)
			(type default)
		)
		(layer "B.Cu")
	)
	(gr_line
		(start 123.880372 -246.271288)
		(end 123.880372 -246.576088)
		(stroke
			(width 0.0508)
			(type default)
		)
		(layer "B.Cu")
	)
	(gr_arc
		(start 123.922028 -84.328)
		(mid 123.962561 -84.319937)
		(end 123.996958 -84.297012)
		(stroke
			(width 0.0508)
			(type default)
		)
		(layer "B.Cu")
	)
	(gr_arc
		(start 123.983242 -82.738976)
		(mid 123.943444 -82.761943)
		(end 123.908312 -82.791554)
		(stroke
			(width 0.0508)
			(type default)
		)
		(layer "B.Cu")
	)
	(gr_arc
		(start 123.999752 -254.704342)
		(mid 123.984065 -254.564096)
		(end 123.937776 -254.430784)
		(stroke
			(width 0.0508)
			(type default)
		)
		(layer "B.Cu")
	)
	(gr_line
		(start 123.999752 -254.704342)
		(end 123.999752 -256.50444)
		(stroke
			(width 0.0508)
			(type default)
		)
		(layer "B.Cu")
	)
	(gr_line
		(start 124.005594 -83.693762)
		(end 124.007118 -83.692492)
		(stroke
			(width 0.0508)
			(type default)
		)
		(layer "B.Cu")
	)
	(gr_arc
		(start 124.04217 -82.3722)
		(mid 124.157209 -82.349403)
		(end 124.254768 -82.284316)
		(stroke
			(width 0.0508)
			(type default)
		)
		(layer "B.Cu")
	)
	(gr_arc
		(start 124.06757 -83.6676)
		(mid 124.034866 -83.674032)
		(end 124.007118 -83.692492)
		(stroke
			(width 0.0508)
			(type default)
		)
		(layer "B.Cu")
	)
	(gr_arc
		(start 124.070872 -82.715862)
		(mid 124.026049 -82.723596)
		(end 123.983242 -82.738976)
		(stroke
			(width 0.0508)
			(type default)
		)
		(layer "B.Cu")
	)
	(gr_arc
		(start 124.070872 -82.715862)
		(mid 124.290115 -82.672342)
		(end 124.476002 -82.548222)
		(stroke
			(width 0.0508)
			(type default)
		)
		(layer "B.Cu")
	)
	(gr_line
		(start 124.198126 -89.957148)
		(end 124.305314 -90.064336)
		(stroke
			(width 0.0508)
			(type default)
		)
		(layer "B.Cu")
	)
	(gr_line
		(start 124.305314 -90.064336)
		(end 124.361448 -90.120724)
		(stroke
			(width 0.0508)
			(type default)
		)
		(layer "B.Cu")
	)
	(gr_arc
		(start 124.316236 -90.520266)
		(mid 124.127845 -90.403729)
		(end 123.91009 -90.36304)
		(stroke
			(width 0.0508)
			(type default)
		)
		(layer "B.Cu")
	)
	(gr_line
		(start 124.779278 -80.251808)
		(end 124.862844 -80.335374)
		(stroke
			(width 0.0508)
			(type default)
		)
		(layer "B.Cu")
	)
	(gr_arc
		(start 125.09627 -80.899)
		(mid 125.03562 -80.59397)
		(end 124.862844 -80.335374)
		(stroke
			(width 0.0508)
			(type default)
		)
		(layer "B.Cu")
	)
	(gr_line
		(start 125.135894 -82.472276)
		(end 125.1585 -82.46237)
		(stroke
			(width 0.0508)
			(type default)
		)
		(layer "B.Cu")
	)
	(gr_line
		(start 125.604778 -82.269584)
		(end 125.631448 -82.2579)
		(stroke
			(width 0.0508)
			(type default)
		)
		(layer "B.Cu")
	)
	(gr_arc
		(start 125.672596 -80.335374)
		(mid 125.499809 -80.593968)
		(end 125.43917 -80.899)
		(stroke
			(width 0.0508)
			(type default)
		)
		(layer "B.Cu")
	)
	(gr_line
		(start 125.672596 -80.335374)
		(end 125.756162 -80.251808)
		(stroke
			(width 0.0508)
			(type default)
		)
		(layer "B.Cu")
	)
	(gr_line
		(start 126.999492 -254.772414)
		(end 126.999492 -256.50444)
		(stroke
			(width 0.0508)
			(type default)
		)
		(layer "B.Cu")
	)
	(gr_arc
		(start 127.047752 -254.52959)
		(mid 127.011676 -254.648628)
		(end 126.999492 -254.772414)
		(stroke
			(width 0.0508)
			(type default)
		)
		(layer "B.Cu")
	)
	(gr_line
		(start 127.047752 -254.52959)
		(end 127.314452 -253.884684)
		(stroke
			(width 0.0508)
			(type default)
		)
		(layer "B.Cu")
	)
	(gr_line
		(start 127.154178 -79.8068)
		(end 127.32639 -79.979266)
		(stroke
			(width 0.0508)
			(type default)
		)
		(layer "B.Cu")
	)
	(gr_arc
		(start 127.314452 -253.884684)
		(mid 127.343486 -253.796794)
		(end 127.35941 -253.705614)
		(stroke
			(width 0.0508)
			(type default)
		)
		(layer "B.Cu")
	)
	(gr_arc
		(start 127.35941 -253.705614)
		(mid 127.361867 -253.673779)
		(end 127.362712 -253.64186)
		(stroke
			(width 0.0508)
			(type default)
		)
		(layer "B.Cu")
	)
	(gr_line
		(start 127.362712 -247.973342)
		(end 127.362712 -248.542302)
		(stroke
			(width 0.0508)
			(type default)
		)
		(layer "B.Cu")
	)
	(gr_line
		(start 127.362712 -246.408702)
		(end 127.362712 -246.977662)
		(stroke
			(width 0.0508)
			(type default)
		)
		(layer "B.Cu")
	)
	(gr_line
		(start 127.362712 -244.844062)
		(end 127.362712 -245.413022)
		(stroke
			(width 0.0508)
			(type default)
		)
		(layer "B.Cu")
	)
	(gr_arc
		(start 127.4445 -80.264)
		(mid 127.413767 -80.109883)
		(end 127.32639 -79.979266)
		(stroke
			(width 0.0508)
			(type default)
		)
		(layer "B.Cu")
	)
	(gr_arc
		(start 127.705612 -253.74092)
		(mid 127.743924 -253.933363)
		(end 127.852932 -254.09652)
		(stroke
			(width 0.0508)
			(type default)
		)
		(layer "B.Cu")
	)
	(gr_arc
		(start 127.705612 -247.627902)
		(mid 127.736182 -247.761844)
		(end 127.824992 -247.866662)
		(stroke
			(width 0.0508)
			(type default)
		)
		(layer "B.Cu")
	)
	(gr_arc
		(start 127.705612 -246.063262)
		(mid 127.736204 -246.197186)
		(end 127.824992 -246.302022)
		(stroke
			(width 0.0508)
			(type default)
		)
		(layer "B.Cu")
	)
	(gr_arc
		(start 127.705612 -244.498622)
		(mid 127.736189 -244.632558)
		(end 127.824992 -244.737382)
		(stroke
			(width 0.0508)
			(type default)
		)
		(layer "B.Cu")
	)
	(gr_arc
		(start 127.824992 -248.648982)
		(mid 127.736203 -248.753811)
		(end 127.705612 -248.887742)
		(stroke
			(width 0.0508)
			(type default)
		)
		(layer "B.Cu")
	)
	(gr_arc
		(start 127.824992 -248.648982)
		(mid 127.913786 -248.544168)
		(end 127.944372 -248.410222)
		(stroke
			(width 0.0508)
			(type default)
		)
		(layer "B.Cu")
	)
	(gr_arc
		(start 127.824992 -247.084342)
		(mid 127.736189 -247.189169)
		(end 127.705612 -247.323102)
		(stroke
			(width 0.0508)
			(type default)
		)
		(layer "B.Cu")
	)
	(gr_arc
		(start 127.824992 -247.084342)
		(mid 127.913786 -246.979528)
		(end 127.944372 -246.845582)
		(stroke
			(width 0.0508)
			(type default)
		)
		(layer "B.Cu")
	)
	(gr_arc
		(start 127.824992 -245.519702)
		(mid 127.736174 -245.624526)
		(end 127.705612 -245.758462)
		(stroke
			(width 0.0508)
			(type default)
		)
		(layer "B.Cu")
	)
	(gr_arc
		(start 127.824992 -245.519702)
		(mid 127.913786 -245.414888)
		(end 127.944372 -245.280942)
		(stroke
			(width 0.0508)
			(type default)
		)
		(layer "B.Cu")
	)
	(gr_arc
		(start 127.944372 -248.105422)
		(mid 127.913786 -247.971504)
		(end 127.824992 -247.866662)
		(stroke
			(width 0.0508)
			(type default)
		)
		(layer "B.Cu")
	)
	(gr_line
		(start 127.944372 -248.105422)
		(end 127.944372 -248.410222)
		(stroke
			(width 0.0508)
			(type default)
		)
		(layer "B.Cu")
	)
	(gr_arc
		(start 127.944372 -246.540782)
		(mid 127.913786 -246.406864)
		(end 127.824992 -246.302022)
		(stroke
			(width 0.0508)
			(type default)
		)
		(layer "B.Cu")
	)
	(gr_line
		(start 127.944372 -246.540782)
		(end 127.944372 -246.845582)
		(stroke
			(width 0.0508)
			(type default)
		)
		(layer "B.Cu")
	)
	(gr_arc
		(start 127.944372 -244.976142)
		(mid 127.913786 -244.842224)
		(end 127.824992 -244.737382)
		(stroke
			(width 0.0508)
			(type default)
		)
		(layer "B.Cu")
	)
	(gr_line
		(start 127.944372 -244.976142)
		(end 127.944372 -245.280942)
		(stroke
			(width 0.0508)
			(type default)
		)
		(layer "B.Cu")
	)
	(gr_line
		(start 127.991362 -92.809568)
		(end 127.991362 -92.809822)
		(stroke
			(width 0.0508)
			(type default)
		)
		(layer "B.Cu")
	)
	(gr_arc
		(start 128.000252 -254.45212)
		(mid 127.961969 -254.259661)
		(end 127.852932 -254.09652)
		(stroke
			(width 0.0508)
			(type default)
		)
		(layer "B.Cu")
	)
	(gr_line
		(start 128.000252 -254.45212)
		(end 128.000252 -256.50444)
		(stroke
			(width 0.0508)
			(type default)
		)
		(layer "B.Cu")
	)
	(gr_arc
		(start 128.131062 -79.8068)
		(mid 127.8848 -79.947061)
		(end 127.7874 -80.2132)
		(stroke
			(width 0.0508)
			(type default)
		)
		(layer "B.Cu")
	)
	(gr_line
		(start 128.905 -140.889482)
		(end 128.905 -141.458442)
		(stroke
			(width 0.0508)
			(type default)
		)
		(layer "B.Cu")
	)
	(gr_line
		(start 128.905 -123.5583)
		(end 128.905 -124.12726)
		(stroke
			(width 0.0508)
			(type default)
		)
		(layer "B.Cu")
	)
	(gr_line
		(start 128.905 -121.99366)
		(end 128.905 -122.56262)
		(stroke
			(width 0.0508)
			(type default)
		)
		(layer "B.Cu")
	)
	(gr_line
		(start 128.905 -120.42902)
		(end 128.905 -120.99798)
		(stroke
			(width 0.0508)
			(type default)
		)
		(layer "B.Cu")
	)
	(gr_line
		(start 129.159 -81.28)
		(end 129.359152 -81.480152)
		(stroke
			(width 0.0508)
			(type default)
		)
		(layer "B.Cu")
	)
	(gr_arc
		(start 129.2479 -140.544042)
		(mid 129.278484 -140.677973)
		(end 129.36728 -140.782802)
		(stroke
			(width 0.0508)
			(type default)
		)
		(layer "B.Cu")
	)
	(gr_arc
		(start 129.2479 -123.21286)
		(mid 129.278393 -123.34684)
		(end 129.36728 -123.45162)
		(stroke
			(width 0.0508)
			(type default)
		)
		(layer "B.Cu")
	)
	(gr_arc
		(start 129.2479 -121.64822)
		(mid 129.278415 -121.782182)
		(end 129.36728 -121.88698)
		(stroke
			(width 0.0508)
			(type default)
		)
		(layer "B.Cu")
	)
	(gr_arc
		(start 129.2479 -120.08358)
		(mid 129.2784 -120.217554)
		(end 129.36728 -120.32234)
		(stroke
			(width 0.0508)
			(type default)
		)
		(layer "B.Cu")
	)
	(gr_arc
		(start 129.36728 -141.565122)
		(mid 129.27839 -141.669901)
		(end 129.2479 -141.803882)
		(stroke
			(width 0.0508)
			(type default)
		)
		(layer "B.Cu")
	)
	(gr_arc
		(start 129.36728 -141.565122)
		(mid 129.456074 -141.460308)
		(end 129.48666 -141.326362)
		(stroke
			(width 0.0508)
			(type default)
		)
		(layer "B.Cu")
	)
	(gr_arc
		(start 129.36728 -124.23394)
		(mid 129.278397 -124.33872)
		(end 129.2479 -124.4727)
		(stroke
			(width 0.0508)
			(type default)
		)
		(layer "B.Cu")
	)
	(gr_arc
		(start 129.36728 -124.23394)
		(mid 129.456168 -124.129145)
		(end 129.48666 -123.99518)
		(stroke
			(width 0.0508)
			(type default)
		)
		(layer "B.Cu")
	)
	(gr_arc
		(start 129.36728 -122.6693)
		(mid 129.278382 -122.774078)
		(end 129.2479 -122.90806)
		(stroke
			(width 0.0508)
			(type default)
		)
		(layer "B.Cu")
	)
	(gr_arc
		(start 129.36728 -122.6693)
		(mid 129.456168 -122.564505)
		(end 129.48666 -122.43054)
		(stroke
			(width 0.0508)
			(type default)
		)
		(layer "B.Cu")
	)
	(gr_arc
		(start 129.36728 -121.10466)
		(mid 129.278404 -121.209442)
		(end 129.2479 -121.34342)
		(stroke
			(width 0.0508)
			(type default)
		)
		(layer "B.Cu")
	)
	(gr_arc
		(start 129.36728 -121.10466)
		(mid 129.456168 -120.999865)
		(end 129.48666 -120.8659)
		(stroke
			(width 0.0508)
			(type default)
		)
		(layer "B.Cu")
	)
	(gr_arc
		(start 129.48666 -141.021562)
		(mid 129.456168 -140.887569)
		(end 129.36728 -140.782802)
		(stroke
			(width 0.0508)
			(type default)
		)
		(layer "B.Cu")
	)
	(gr_line
		(start 129.48666 -141.021562)
		(end 129.48666 -141.326362)
		(stroke
			(width 0.0508)
			(type default)
		)
		(layer "B.Cu")
	)
	(gr_arc
		(start 129.48666 -123.69038)
		(mid 129.456168 -123.556387)
		(end 129.36728 -123.45162)
		(stroke
			(width 0.0508)
			(type default)
		)
		(layer "B.Cu")
	)
	(gr_line
		(start 129.48666 -123.69038)
		(end 129.48666 -123.99518)
		(stroke
			(width 0.0508)
			(type default)
		)
		(layer "B.Cu")
	)
	(gr_arc
		(start 129.48666 -122.12574)
		(mid 129.456168 -121.991747)
		(end 129.36728 -121.88698)
		(stroke
			(width 0.0508)
			(type default)
		)
		(layer "B.Cu")
	)
	(gr_line
		(start 129.48666 -122.12574)
		(end 129.48666 -122.43054)
		(stroke
			(width 0.0508)
			(type default)
		)
		(layer "B.Cu")
	)
	(gr_arc
		(start 129.48666 -120.5611)
		(mid 129.456168 -120.427107)
		(end 129.36728 -120.32234)
		(stroke
			(width 0.0508)
			(type default)
		)
		(layer "B.Cu")
	)
	(gr_line
		(start 129.48666 -120.5611)
		(end 129.48666 -120.8659)
		(stroke
			(width 0.0508)
			(type default)
		)
		(layer "B.Cu")
	)
	(gr_line
		(start 129.847848 -81.480152)
		(end 130.048 -81.28)
		(stroke
			(width 0.0508)
			(type default)
		)
		(layer "B.Cu")
	)
	(gr_line
		(start 130.631184 -215.73617)
		(end 130.631184 -216.30513)
		(stroke
			(width 0.0508)
			(type default)
		)
		(layer "B.Cu")
	)
	(gr_line
		(start 130.631184 -214.17153)
		(end 130.631184 -214.74049)
		(stroke
			(width 0.0508)
			(type default)
		)
		(layer "B.Cu")
	)
	(gr_line
		(start 130.631184 -212.60689)
		(end 130.631184 -213.17585)
		(stroke
			(width 0.0508)
			(type default)
		)
		(layer "B.Cu")
	)
	(gr_arc
		(start 130.974084 -215.39073)
		(mid 131.004662 -215.524666)
		(end 131.093464 -215.62949)
		(stroke
			(width 0.0508)
			(type default)
		)
		(layer "B.Cu")
	)
	(gr_arc
		(start 130.974084 -213.82609)
		(mid 131.004647 -213.960038)
		(end 131.093464 -214.06485)
		(stroke
			(width 0.0508)
			(type default)
		)
		(layer "B.Cu")
	)
	(gr_arc
		(start 130.974084 -212.26145)
		(mid 131.004669 -212.39538)
		(end 131.093464 -212.50021)
		(stroke
			(width 0.0508)
			(type default)
		)
		(layer "B.Cu")
	)
	(gr_line
		(start 130.999992 -254.51689)
		(end 130.999992 -256.50444)
		(stroke
			(width 0.0508)
			(type default)
		)
		(layer "B.Cu")
	)
	(gr_arc
		(start 131.093464 -216.41181)
		(mid 131.004574 -216.51659)
		(end 130.974084 -216.65057)
		(stroke
			(width 0.0508)
			(type default)
		)
		(layer "B.Cu")
	)
	(gr_arc
		(start 131.093464 -216.41181)
		(mid 131.182258 -216.306996)
		(end 131.212844 -216.17305)
		(stroke
			(width 0.0508)
			(type default)
		)
		(layer "B.Cu")
	)
	(gr_arc
		(start 131.093464 -214.84717)
		(mid 131.004559 -214.951947)
		(end 130.974084 -215.08593)
		(stroke
			(width 0.0508)
			(type default)
		)
		(layer "B.Cu")
	)
	(gr_arc
		(start 131.093464 -214.84717)
		(mid 131.182258 -214.742356)
		(end 131.212844 -214.60841)
		(stroke
			(width 0.0508)
			(type default)
		)
		(layer "B.Cu")
	)
	(gr_arc
		(start 131.093464 -213.28253)
		(mid 131.004582 -213.387311)
		(end 130.974084 -213.52129)
		(stroke
			(width 0.0508)
			(type default)
		)
		(layer "B.Cu")
	)
	(gr_arc
		(start 131.093464 -213.28253)
		(mid 131.182258 -213.177716)
		(end 131.212844 -213.04377)
		(stroke
			(width 0.0508)
			(type default)
		)
		(layer "B.Cu")
	)
	(gr_arc
		(start 131.162552 -254.12446)
		(mid 131.042227 -254.304503)
		(end 130.999992 -254.51689)
		(stroke
			(width 0.0508)
			(type default)
		)
		(layer "B.Cu")
	)
	(gr_arc
		(start 131.162552 -254.12446)
		(mid 131.282857 -253.944412)
		(end 131.325112 -253.73203)
		(stroke
			(width 0.0508)
			(type default)
		)
		(layer "B.Cu")
	)
	(gr_arc
		(start 131.212844 -215.86825)
		(mid 131.182352 -215.734257)
		(end 131.093464 -215.62949)
		(stroke
			(width 0.0508)
			(type default)
		)
		(layer "B.Cu")
	)
	(gr_line
		(start 131.212844 -215.86825)
		(end 131.212844 -216.17305)
		(stroke
			(width 0.0508)
			(type default)
		)
		(layer "B.Cu")
	)
	(gr_arc
		(start 131.212844 -214.30361)
		(mid 131.182352 -214.169617)
		(end 131.093464 -214.06485)
		(stroke
			(width 0.0508)
			(type default)
		)
		(layer "B.Cu")
	)
	(gr_line
		(start 131.212844 -214.30361)
		(end 131.212844 -214.60841)
		(stroke
			(width 0.0508)
			(type default)
		)
		(layer "B.Cu")
	)
	(gr_arc
		(start 131.212844 -212.73897)
		(mid 131.182352 -212.604977)
		(end 131.093464 -212.50021)
		(stroke
			(width 0.0508)
			(type default)
		)
		(layer "B.Cu")
	)
	(gr_line
		(start 131.212844 -212.73897)
		(end 131.212844 -213.04377)
		(stroke
			(width 0.0508)
			(type default)
		)
		(layer "B.Cu")
	)
	(gr_line
		(start 131.325112 -250.2154)
		(end 131.325112 -250.78436)
		(stroke
			(width 0.0508)
			(type default)
		)
		(layer "B.Cu")
	)
	(gr_line
		(start 131.325112 -248.65076)
		(end 131.325112 -249.21972)
		(stroke
			(width 0.0508)
			(type default)
		)
		(layer "B.Cu")
	)
	(gr_line
		(start 131.325112 -247.08612)
		(end 131.325112 -247.65508)
		(stroke
			(width 0.0508)
			(type default)
		)
		(layer "B.Cu")
	)
	(gr_arc
		(start 131.668012 -253.613412)
		(mid 131.710965 -253.82974)
		(end 131.833366 -254.013208)
		(stroke
			(width 0.0508)
			(type default)
		)
		(layer "B.Cu")
	)
	(gr_arc
		(start 131.668012 -249.86996)
		(mid 131.698506 -250.003939)
		(end 131.787392 -250.10872)
		(stroke
			(width 0.0508)
			(type default)
		)
		(layer "B.Cu")
	)
	(gr_arc
		(start 131.668012 -248.30532)
		(mid 131.698528 -248.439281)
		(end 131.787392 -248.54408)
		(stroke
			(width 0.0508)
			(type default)
		)
		(layer "B.Cu")
	)
	(gr_arc
		(start 131.668012 -246.74068)
		(mid 131.698513 -246.874653)
		(end 131.787392 -246.97944)
		(stroke
			(width 0.0508)
			(type default)
		)
		(layer "B.Cu")
	)
	(gr_arc
		(start 131.787392 -250.89104)
		(mid 131.698505 -250.995819)
		(end 131.668012 -251.1298)
		(stroke
			(width 0.0508)
			(type default)
		)
		(layer "B.Cu")
	)
	(gr_arc
		(start 131.787392 -250.89104)
		(mid 131.87628 -250.786245)
		(end 131.906772 -250.65228)
		(stroke
			(width 0.0508)
			(type default)
		)
		(layer "B.Cu")
	)
	(gr_arc
		(start 131.787392 -249.3264)
		(mid 131.69849 -249.431176)
		(end 131.668012 -249.56516)
		(stroke
			(width 0.0508)
			(type default)
		)
		(layer "B.Cu")
	)
	(gr_arc
		(start 131.787392 -249.3264)
		(mid 131.87628 -249.221605)
		(end 131.906772 -249.08764)
		(stroke
			(width 0.0508)
			(type default)
		)
		(layer "B.Cu")
	)
	(gr_arc
		(start 131.787392 -247.76176)
		(mid 131.698512 -247.866541)
		(end 131.668012 -248.00052)
		(stroke
			(width 0.0508)
			(type default)
		)
		(layer "B.Cu")
	)
	(gr_arc
		(start 131.787392 -247.76176)
		(mid 131.87628 -247.656965)
		(end 131.906772 -247.523)
		(stroke
			(width 0.0508)
			(type default)
		)
		(layer "B.Cu")
	)
	(gr_line
		(start 131.833366 -254.013208)
		(end 131.83362 -254.013462)
		(stroke
			(width 0.0508)
			(type default)
		)
		(layer "B.Cu")
	)
	(gr_arc
		(start 131.906772 -250.34748)
		(mid 131.87628 -250.213487)
		(end 131.787392 -250.10872)
		(stroke
			(width 0.0508)
			(type default)
		)
		(layer "B.Cu")
	)
	(gr_line
		(start 131.906772 -250.34748)
		(end 131.906772 -250.65228)
		(stroke
			(width 0.0508)
			(type default)
		)
		(layer "B.Cu")
	)
	(gr_arc
		(start 131.906772 -248.78284)
		(mid 131.87628 -248.648847)
		(end 131.787392 -248.54408)
		(stroke
			(width 0.0508)
			(type default)
		)
		(layer "B.Cu")
	)
	(gr_line
		(start 131.906772 -248.78284)
		(end 131.906772 -249.08764)
		(stroke
			(width 0.0508)
			(type default)
		)
		(layer "B.Cu")
	)
	(gr_arc
		(start 131.906772 -247.2182)
		(mid 131.87628 -247.084207)
		(end 131.787392 -246.97944)
		(stroke
			(width 0.0508)
			(type default)
		)
		(layer "B.Cu")
	)
	(gr_line
		(start 131.906772 -247.2182)
		(end 131.906772 -247.523)
		(stroke
			(width 0.0508)
			(type default)
		)
		(layer "B.Cu")
	)
	(gr_arc
		(start 131.999482 -254.413512)
		(mid 131.956322 -254.197001)
		(end 131.83362 -254.013462)
		(stroke
			(width 0.0508)
			(type default)
		)
		(layer "B.Cu")
	)
	(gr_line
		(start 131.999482 -254.413512)
		(end 131.999482 -256.50444)
		(stroke
			(width 0.0508)
			(type default)
		)
		(layer "B.Cu")
	)
	(gr_line
		(start 132.663184 -214.140542)
		(end 132.663184 -214.709502)
		(stroke
			(width 0.0508)
			(type default)
		)
		(layer "B.Cu")
	)
	(gr_line
		(start 132.663184 -212.575902)
		(end 132.663184 -213.144862)
		(stroke
			(width 0.0508)
			(type default)
		)
		(layer "B.Cu")
	)
	(gr_line
		(start 132.663184 -211.011262)
		(end 132.663184 -211.580222)
		(stroke
			(width 0.0508)
			(type default)
		)
		(layer "B.Cu")
	)
	(gr_line
		(start 132.663184 -209.446622)
		(end 132.663184 -210.015582)
		(stroke
			(width 0.0508)
			(type default)
		)
		(layer "B.Cu")
	)
	(gr_arc
		(start 133.006084 -213.795102)
		(mid 133.036652 -213.929047)
		(end 133.125464 -214.033862)
		(stroke
			(width 0.0508)
			(type default)
		)
		(layer "B.Cu")
	)
	(gr_arc
		(start 133.006084 -212.230462)
		(mid 133.036674 -212.364389)
		(end 133.125464 -212.469222)
		(stroke
			(width 0.0508)
			(type default)
		)
		(layer "B.Cu")
	)
	(gr_arc
		(start 133.006084 -210.665822)
		(mid 133.036659 -210.799761)
		(end 133.125464 -210.904582)
		(stroke
			(width 0.0508)
			(type default)
		)
		(layer "B.Cu")
	)
	(gr_arc
		(start 133.006084 -209.101182)
		(mid 133.036681 -209.235103)
		(end 133.125464 -209.339942)
		(stroke
			(width 0.0508)
			(type default)
		)
		(layer "B.Cu")
	)
	(gr_arc
		(start 133.125464 -214.816182)
		(mid 133.036564 -214.92096)
		(end 133.006084 -215.054942)
		(stroke
			(width 0.0508)
			(type default)
		)
		(layer "B.Cu")
	)
	(gr_arc
		(start 133.125464 -214.816182)
		(mid 133.214258 -214.711368)
		(end 133.244844 -214.577422)
		(stroke
			(width 0.0508)
			(type default)
		)
		(layer "B.Cu")
	)
	(gr_arc
		(start 133.125464 -213.251542)
		(mid 133.036586 -213.356324)
		(end 133.006084 -213.490302)
		(stroke
			(width 0.0508)
			(type default)
		)
		(layer "B.Cu")
	)
	(gr_arc
		(start 133.125464 -213.251542)
		(mid 133.214258 -213.146728)
		(end 133.244844 -213.012782)
		(stroke
			(width 0.0508)
			(type default)
		)
		(layer "B.Cu")
	)
	(gr_arc
		(start 133.125464 -211.686902)
		(mid 133.036571 -211.791681)
		(end 133.006084 -211.925662)
		(stroke
			(width 0.0508)
			(type default)
		)
		(layer "B.Cu")
	)
	(gr_arc
		(start 133.125464 -211.686902)
		(mid 133.214258 -211.582088)
		(end 133.244844 -211.448142)
		(stroke
			(width 0.0508)
			(type default)
		)
		(layer "B.Cu")
	)
	(gr_arc
		(start 133.125464 -210.122262)
		(mid 133.036593 -210.227045)
		(end 133.006084 -210.361022)
		(stroke
			(width 0.0508)
			(type default)
		)
		(layer "B.Cu")
	)
	(gr_arc
		(start 133.125464 -210.122262)
		(mid 133.214258 -210.017448)
		(end 133.244844 -209.883502)
		(stroke
			(width 0.0508)
			(type default)
		)
		(layer "B.Cu")
	)
	(gr_arc
		(start 133.244844 -214.272622)
		(mid 133.214352 -214.138629)
		(end 133.125464 -214.033862)
		(stroke
			(width 0.0508)
			(type default)
		)
		(layer "B.Cu")
	)
	(gr_line
		(start 133.244844 -214.272622)
		(end 133.244844 -214.577422)
		(stroke
			(width 0.0508)
			(type default)
		)
		(layer "B.Cu")
	)
	(gr_arc
		(start 133.244844 -212.707982)
		(mid 133.214352 -212.573989)
		(end 133.125464 -212.469222)
		(stroke
			(width 0.0508)
			(type default)
		)
		(layer "B.Cu")
	)
	(gr_line
		(start 133.244844 -212.707982)
		(end 133.244844 -213.012782)
		(stroke
			(width 0.0508)
			(type default)
		)
		(layer "B.Cu")
	)
	(gr_arc
		(start 133.244844 -211.143342)
		(mid 133.214352 -211.009349)
		(end 133.125464 -210.904582)
		(stroke
			(width 0.0508)
			(type default)
		)
		(layer "B.Cu")
	)
	(gr_line
		(start 133.244844 -211.143342)
		(end 133.244844 -211.448142)
		(stroke
			(width 0.0508)
			(type default)
		)
		(layer "B.Cu")
	)
	(gr_arc
		(start 133.244844 -209.578702)
		(mid 133.214352 -209.444709)
		(end 133.125464 -209.339942)
		(stroke
			(width 0.0508)
			(type default)
		)
		(layer "B.Cu")
	)
	(gr_line
		(start 133.244844 -209.578702)
		(end 133.244844 -209.883502)
		(stroke
			(width 0.0508)
			(type default)
		)
		(layer "B.Cu")
	)
	(gr_line
		(start 135.000492 -254.313182)
		(end 135.000492 -256.50444)
		(stroke
			(width 0.0508)
			(type default)
		)
		(layer "B.Cu")
	)
	(gr_arc
		(start 135.094472 -254.08636)
		(mid 135.024923 -254.190421)
		(end 135.000492 -254.313182)
		(stroke
			(width 0.0508)
			(type default)
		)
		(layer "B.Cu")
	)
	(gr_line
		(start 135.094472 -254.08636)
		(end 135.12165 -254.050546)
		(stroke
			(width 0.0508)
			(type default)
		)
		(layer "B.Cu")
	)
	(gr_arc
		(start 135.177784 -253.985776)
		(mid 135.148628 -254.017217)
		(end 135.12165 -254.050546)
		(stroke
			(width 0.0508)
			(type default)
		)
		(layer "B.Cu")
	)
	(gr_line
		(start 135.177784 -253.985776)
		(end 135.199628 -253.963932)
		(stroke
			(width 0.0508)
			(type default)
		)
		(layer "B.Cu")
	)
	(gr_arc
		(start 135.199628 -253.963932)
		(mid 135.238304 -253.906144)
		(end 135.251952 -253.837948)
		(stroke
			(width 0.0508)
			(type default)
		)
		(layer "B.Cu")
	)
	(gr_line
		(start 135.457184 -223.669352)
		(end 135.457184 -224.238312)
		(stroke
			(width 0.0508)
			(type default)
		)
		(layer "B.Cu")
	)
	(gr_line
		(start 135.457184 -222.104712)
		(end 135.457184 -222.673672)
		(stroke
			(width 0.0508)
			(type default)
		)
		(layer "B.Cu")
	)
	(gr_line
		(start 135.457184 -220.540072)
		(end 135.457184 -221.109032)
		(stroke
			(width 0.0508)
			(type default)
		)
		(layer "B.Cu")
	)
	(gr_line
		(start 135.457184 -218.975432)
		(end 135.457184 -219.544392)
		(stroke
			(width 0.0508)
			(type default)
		)
		(layer "B.Cu")
	)
	(gr_arc
		(start 135.594852 -253.524766)
		(mid 135.604473 -253.622151)
		(end 135.632952 -253.715774)
		(stroke
			(width 0.0508)
			(type default)
		)
		(layer "B.Cu")
	)
	(gr_line
		(start 135.632952 -253.715774)
		(end 135.736584 -253.965964)
		(stroke
			(width 0.0508)
			(type default)
		)
		(layer "B.Cu")
	)
	(gr_arc
		(start 135.736584 -253.965964)
		(mid 135.756607 -254.003462)
		(end 135.783574 -254.036322)
		(stroke
			(width 0.0508)
			(type default)
		)
		(layer "B.Cu")
	)
	(gr_line
		(start 135.783574 -254.036322)
		(end 135.814054 -254.066802)
		(stroke
			(width 0.0508)
			(type default)
		)
		(layer "B.Cu")
	)
	(gr_arc
		(start 135.800084 -223.323912)
		(mid 135.830655 -223.457854)
		(end 135.919464 -223.562672)
		(stroke
			(width 0.0508)
			(type default)
		)
		(layer "B.Cu")
	)
	(gr_arc
		(start 135.800084 -221.759272)
		(mid 135.830678 -221.893196)
		(end 135.919464 -221.998032)
		(stroke
			(width 0.0508)
			(type default)
		)
		(layer "B.Cu")
	)
	(gr_arc
		(start 135.800084 -220.194632)
		(mid 135.830663 -220.328568)
		(end 135.919464 -220.433392)
		(stroke
			(width 0.0508)
			(type default)
		)
		(layer "B.Cu")
	)
	(gr_arc
		(start 135.800084 -218.629992)
		(mid 135.830648 -218.76394)
		(end 135.919464 -218.868752)
		(stroke
			(width 0.0508)
			(type default)
		)
		(layer "B.Cu")
	)
	(gr_arc
		(start 135.919464 -224.344992)
		(mid 135.830568 -224.44977)
		(end 135.800084 -224.583752)
		(stroke
			(width 0.0508)
			(type default)
		)
		(layer "B.Cu")
	)
	(gr_arc
		(start 135.919464 -224.344992)
		(mid 136.008258 -224.240178)
		(end 136.038844 -224.106232)
		(stroke
			(width 0.0508)
			(type default)
		)
		(layer "B.Cu")
	)
	(gr_arc
		(start 135.919464 -222.780352)
		(mid 135.83059 -222.885135)
		(end 135.800084 -223.019112)
		(stroke
			(width 0.0508)
			(type default)
		)
		(layer "B.Cu")
	)
	(gr_arc
		(start 135.919464 -222.780352)
		(mid 136.008258 -222.675538)
		(end 136.038844 -222.541592)
		(stroke
			(width 0.0508)
			(type default)
		)
		(layer "B.Cu")
	)
	(gr_arc
		(start 135.919464 -221.215712)
		(mid 135.830575 -221.320492)
		(end 135.800084 -221.454472)
		(stroke
			(width 0.0508)
			(type default)
		)
		(layer "B.Cu")
	)
	(gr_arc
		(start 135.919464 -221.215712)
		(mid 136.008258 -221.110898)
		(end 136.038844 -220.976952)
		(stroke
			(width 0.0508)
			(type default)
		)
		(layer "B.Cu")
	)
	(gr_arc
		(start 135.919464 -219.651072)
		(mid 135.83056 -219.755849)
		(end 135.800084 -219.889832)
		(stroke
			(width 0.0508)
			(type default)
		)
		(layer "B.Cu")
	)
	(gr_arc
		(start 135.919464 -219.651072)
		(mid 136.008258 -219.546258)
		(end 136.038844 -219.412312)
		(stroke
			(width 0.0508)
			(type default)
		)
		(layer "B.Cu")
	)
	(gr_arc
		(start 135.999982 -254.515874)
		(mid 135.951661 -254.272856)
		(end 135.814054 -254.066802)
		(stroke
			(width 0.0508)
			(type default)
		)
		(layer "B.Cu")
	)
	(gr_line
		(start 135.999982 -254.515874)
		(end 135.999982 -256.50444)
		(stroke
			(width 0.0508)
			(type default)
		)
		(layer "B.Cu")
	)
	(gr_arc
		(start 136.038844 -223.801432)
		(mid 136.008352 -223.667439)
		(end 135.919464 -223.562672)
		(stroke
			(width 0.0508)
			(type default)
		)
		(layer "B.Cu")
	)
	(gr_line
		(start 136.038844 -223.801432)
		(end 136.038844 -224.106232)
		(stroke
			(width 0.0508)
			(type default)
		)
		(layer "B.Cu")
	)
	(gr_arc
		(start 136.038844 -222.236792)
		(mid 136.008352 -222.102799)
		(end 135.919464 -221.998032)
		(stroke
			(width 0.0508)
			(type default)
		)
		(layer "B.Cu")
	)
	(gr_line
		(start 136.038844 -222.236792)
		(end 136.038844 -222.541592)
		(stroke
			(width 0.0508)
			(type default)
		)
		(layer "B.Cu")
	)
	(gr_arc
		(start 136.038844 -220.672152)
		(mid 136.008352 -220.538159)
		(end 135.919464 -220.433392)
		(stroke
			(width 0.0508)
			(type default)
		)
		(layer "B.Cu")
	)
	(gr_line
		(start 136.038844 -220.672152)
		(end 136.038844 -220.976952)
		(stroke
			(width 0.0508)
			(type default)
		)
		(layer "B.Cu")
	)
	(gr_arc
		(start 136.038844 -219.107512)
		(mid 136.008352 -218.973519)
		(end 135.919464 -218.868752)
		(stroke
			(width 0.0508)
			(type default)
		)
		(layer "B.Cu")
	)
	(gr_line
		(start 136.038844 -219.107512)
		(end 136.038844 -219.412312)
		(stroke
			(width 0.0508)
			(type default)
		)
		(layer "B.Cu")
	)
	(gr_line
		(start 136.13257 -135.280654)
		(end 136.13257 -135.849614)
		(stroke
			(width 0.0508)
			(type default)
		)
		(layer "B.Cu")
	)
	(gr_line
		(start 136.13257 -120.877076)
		(end 136.13257 -121.446036)
		(stroke
			(width 0.0508)
			(type default)
		)
		(layer "B.Cu")
	)
	(gr_line
		(start 136.13257 -119.312436)
		(end 136.13257 -119.881396)
		(stroke
			(width 0.0508)
			(type default)
		)
		(layer "B.Cu")
	)
	(gr_line
		(start 136.13257 -117.747796)
		(end 136.13257 -118.316756)
		(stroke
			(width 0.0508)
			(type default)
		)
		(layer "B.Cu")
	)
	(gr_arc
		(start 136.47547 -134.935214)
		(mid 136.506041 -135.069156)
		(end 136.59485 -135.173974)
		(stroke
			(width 0.0508)
			(type default)
		)
		(layer "B.Cu")
	)
	(gr_arc
		(start 136.47547 -120.531636)
		(mid 136.506049 -120.665572)
		(end 136.59485 -120.770396)
		(stroke
			(width 0.0508)
			(type default)
		)
		(layer "B.Cu")
	)
	(gr_arc
		(start 136.47547 -118.966996)
		(mid 136.506035 -119.100944)
		(end 136.59485 -119.205756)
		(stroke
			(width 0.0508)
			(type default)
		)
		(layer "B.Cu")
	)
	(gr_arc
		(start 136.47547 -117.402356)
		(mid 136.506057 -117.536286)
		(end 136.59485 -117.641116)
		(stroke
			(width 0.0508)
			(type default)
		)
		(layer "B.Cu")
	)
	(gr_arc
		(start 136.59485 -135.956294)
		(mid 136.505958 -136.061074)
		(end 136.47547 -136.195054)
		(stroke
			(width 0.0508)
			(type default)
		)
		(layer "B.Cu")
	)
	(gr_arc
		(start 136.59485 -135.956294)
		(mid 136.683644 -135.85148)
		(end 136.71423 -135.717534)
		(stroke
			(width 0.0508)
			(type default)
		)
		(layer "B.Cu")
	)
	(gr_arc
		(start 136.59485 -121.552716)
		(mid 136.505967 -121.657497)
		(end 136.47547 -121.791476)
		(stroke
			(width 0.0508)
			(type default)
		)
		(layer "B.Cu")
	)
	(gr_arc
		(start 136.59485 -121.552716)
		(mid 136.683644 -121.447902)
		(end 136.71423 -121.313956)
		(stroke
			(width 0.0508)
			(type default)
		)
		(layer "B.Cu")
	)
	(gr_arc
		(start 136.59485 -119.988076)
		(mid 136.505952 -120.092855)
		(end 136.47547 -120.226836)
		(stroke
			(width 0.0508)
			(type default)
		)
		(layer "B.Cu")
	)
	(gr_arc
		(start 136.59485 -119.988076)
		(mid 136.683644 -119.883262)
		(end 136.71423 -119.749316)
		(stroke
			(width 0.0508)
			(type default)
		)
		(layer "B.Cu")
	)
	(gr_arc
		(start 136.59485 -118.423436)
		(mid 136.505974 -118.528219)
		(end 136.47547 -118.662196)
		(stroke
			(width 0.0508)
			(type default)
		)
		(layer "B.Cu")
	)
	(gr_arc
		(start 136.59485 -118.423436)
		(mid 136.683644 -118.318622)
		(end 136.71423 -118.184676)
		(stroke
			(width 0.0508)
			(type default)
		)
		(layer "B.Cu")
	)
	(gr_arc
		(start 136.71423 -135.412734)
		(mid 136.683738 -135.278741)
		(end 136.59485 -135.173974)
		(stroke
			(width 0.0508)
			(type default)
		)
		(layer "B.Cu")
	)
	(gr_line
		(start 136.71423 -135.412734)
		(end 136.71423 -135.717534)
		(stroke
			(width 0.0508)
			(type default)
		)
		(layer "B.Cu")
	)
	(gr_arc
		(start 136.71423 -121.009156)
		(mid 136.683738 -120.875163)
		(end 136.59485 -120.770396)
		(stroke
			(width 0.0508)
			(type default)
		)
		(layer "B.Cu")
	)
	(gr_line
		(start 136.71423 -121.009156)
		(end 136.71423 -121.313956)
		(stroke
			(width 0.0508)
			(type default)
		)
		(layer "B.Cu")
	)
	(gr_arc
		(start 136.71423 -119.444516)
		(mid 136.683738 -119.310523)
		(end 136.59485 -119.205756)
		(stroke
			(width 0.0508)
			(type default)
		)
		(layer "B.Cu")
	)
	(gr_line
		(start 136.71423 -119.444516)
		(end 136.71423 -119.749316)
		(stroke
			(width 0.0508)
			(type default)
		)
		(layer "B.Cu")
	)
	(gr_arc
		(start 136.71423 -117.879876)
		(mid 136.683738 -117.745883)
		(end 136.59485 -117.641116)
		(stroke
			(width 0.0508)
			(type default)
		)
		(layer "B.Cu")
	)
	(gr_line
		(start 136.71423 -117.879876)
		(end 136.71423 -118.184676)
		(stroke
			(width 0.0508)
			(type default)
		)
		(layer "B.Cu")
	)
	(gr_line
		(start 140.999972 -254.234188)
		(end 140.999972 -256.50444)
		(stroke
			(width 0.0508)
			(type default)
		)
		(layer "B.Cu")
	)
	(gr_arc
		(start 141.097 -254)
		(mid 141.025163 -254.107435)
		(end 140.999972 -254.234188)
		(stroke
			(width 0.0508)
			(type default)
		)
		(layer "B.Cu")
	)
	(gr_line
		(start 141.097 -254)
		(end 141.134084 -253.962662)
		(stroke
			(width 0.0508)
			(type default)
		)
		(layer "B.Cu")
	)
	(gr_arc
		(start 141.15034 -248.586498)
		(mid 141.180903 -248.720448)
		(end 141.26972 -248.825258)
		(stroke
			(width 0.0508)
			(type default)
		)
		(layer "B.Cu")
	)
	(gr_line
		(start 141.15034 -248.281698)
		(end 141.15034 -248.586498)
		(stroke
			(width 0.0508)
			(type default)
		)
		(layer "B.Cu")
	)
	(gr_arc
		(start 141.233652 -253.896368)
		(mid 141.180606 -253.924616)
		(end 141.134084 -253.962662)
		(stroke
			(width 0.0508)
			(type default)
		)
		(layer "B.Cu")
	)
	(gr_arc
		(start 141.233652 -253.896368)
		(mid 141.270632 -253.888919)
		(end 141.301978 -253.86792)
		(stroke
			(width 0.0508)
			(type default)
		)
		(layer "B.Cu")
	)
	(gr_arc
		(start 141.26972 -248.042938)
		(mid 141.180824 -248.147715)
		(end 141.15034 -248.281698)
		(stroke
			(width 0.0508)
			(type default)
		)
		(layer "B.Cu")
	)
	(gr_arc
		(start 141.26972 -248.042938)
		(mid 141.358514 -247.938124)
		(end 141.3891 -247.804178)
		(stroke
			(width 0.0508)
			(type default)
		)
		(layer "B.Cu")
	)
	(gr_arc
		(start 141.301978 -253.86792)
		(mid 141.366452 -253.771428)
		(end 141.3891 -253.657608)
		(stroke
			(width 0.0508)
			(type default)
		)
		(layer "B.Cu")
	)
	(gr_arc
		(start 141.3891 -249.064018)
		(mid 141.358608 -248.930025)
		(end 141.26972 -248.825258)
		(stroke
			(width 0.0508)
			(type default)
		)
		(layer "B.Cu")
	)
	(gr_arc
		(start 141.732 -253.820422)
		(mid 141.732277 -253.837961)
		(end 141.73327 -253.855474)
		(stroke
			(width 0.0508)
			(type default)
		)
		(layer "B.Cu")
	)
	(gr_line
		(start 141.732 -248.149618)
		(end 141.732 -248.718578)
		(stroke
			(width 0.0508)
			(type default)
		)
		(layer "B.Cu")
	)
	(gr_arc
		(start 141.73327 -253.855474)
		(mid 141.739006 -253.898415)
		(end 141.749018 -253.940564)
		(stroke
			(width 0.0508)
			(type default)
		)
		(layer "B.Cu")
	)
	(gr_arc
		(start 141.749018 -253.940818)
		(mid 141.753237 -253.954481)
		(end 141.757908 -253.967996)
		(stroke
			(width 0.0508)
			(type default)
		)
		(layer "B.Cu")
	)
	(gr_line
		(start 141.749018 -253.940564)
		(end 141.749018 -253.940818)
		(stroke
			(width 0.0508)
			(type default)
		)
		(layer "B.Cu")
	)
	(gr_arc
		(start 141.757908 -253.967996)
		(mid 141.799716 -254.053052)
		(end 141.859 -254.127)
		(stroke
			(width 0.0508)
			(type default)
		)
		(layer "B.Cu")
	)
	(gr_arc
		(start 141.999462 -254.46609)
		(mid 141.962958 -254.282573)
		(end 141.859 -254.127)
		(stroke
			(width 0.0508)
			(type default)
		)
		(layer "B.Cu")
	)
	(gr_line
		(start 141.999462 -254.46609)
		(end 141.999462 -256.50444)
		(stroke
			(width 0.0508)
			(type default)
		)
		(layer "B.Cu")
	)
	(gr_line
		(start 145.000472 -254.465836)
		(end 145.000472 -256.50444)
		(stroke
			(width 0.0508)
			(type default)
		)
		(layer "B.Cu")
	)
	(gr_arc
		(start 145.1483 -254.108458)
		(mid 145.038844 -254.272445)
		(end 145.000472 -254.465836)
		(stroke
			(width 0.0508)
			(type default)
		)
		(layer "B.Cu")
	)
	(gr_line
		(start 145.1483 -254.108458)
		(end 145.178018 -254.078994)
		(stroke
			(width 0.0508)
			(type default)
		)
		(layer "B.Cu")
	)
	(gr_arc
		(start 145.178018 -254.078994)
		(mid 145.265643 -253.947904)
		(end 145.296382 -253.793244)
		(stroke
			(width 0.0508)
			(type default)
		)
		(layer "B.Cu")
	)
	(gr_line
		(start 145.296382 -253.35484)
		(end 145.296382 -253.793244)
		(stroke
			(width 0.0508)
			(type default)
		)
		(layer "B.Cu")
	)
	(gr_arc
		(start 145.639282 -253.0094)
		(mid 145.704436 -253.697027)
		(end 145.8976 -254.360172)
		(stroke
			(width 0.0508)
			(type default)
		)
		(layer "B.Cu")
	)
	(gr_line
		(start 145.8976 -254.360172)
		(end 145.951702 -254.490982)
		(stroke
			(width 0.0508)
			(type default)
		)
		(layer "B.Cu")
	)
	(gr_arc
		(start 145.999962 -254.733806)
		(mid 145.98778 -254.61002)
		(end 145.951702 -254.490982)
		(stroke
			(width 0.0508)
			(type default)
		)
		(layer "B.Cu")
	)
	(gr_line
		(start 145.999962 -254.733806)
		(end 145.999962 -256.50444)
		(stroke
			(width 0.0508)
			(type default)
		)
		(layer "B.Cu")
	)
	(gr_line
		(start 148.999702 -254.533654)
		(end 148.999702 -256.50444)
		(stroke
			(width 0.0508)
			(type default)
		)
		(layer "B.Cu")
	)
	(gr_arc
		(start 149.18563 -254.084582)
		(mid 149.048009 -254.290632)
		(end 148.999702 -254.533654)
		(stroke
			(width 0.0508)
			(type default)
		)
		(layer "B.Cu")
	)
	(gr_line
		(start 149.18563 -254.084582)
		(end 149.216364 -254.053848)
		(stroke
			(width 0.0508)
			(type default)
		)
		(layer "B.Cu")
	)
	(gr_arc
		(start 149.216364 -254.053848)
		(mid 149.353979 -253.847798)
		(end 149.402292 -253.604776)
		(stroke
			(width 0.0508)
			(type default)
		)
		(layer "B.Cu")
	)
	(gr_arc
		(start 149.745192 -253.57963)
		(mid 149.75297 -253.658108)
		(end 149.775926 -253.733554)
		(stroke
			(width 0.0508)
			(type default)
		)
		(layer "B.Cu")
	)
	(gr_line
		(start 149.775926 -253.733554)
		(end 149.8727 -253.967488)
		(stroke
			(width 0.0508)
			(type default)
		)
		(layer "B.Cu")
	)
	(gr_line
		(start 149.8727 -253.967488)
		(end 149.952202 -254.159004)
		(stroke
			(width 0.0508)
			(type default)
		)
		(layer "B.Cu")
	)
	(gr_arc
		(start 150.000462 -254.402082)
		(mid 149.988305 -254.278166)
		(end 149.952202 -254.159004)
		(stroke
			(width 0.0508)
			(type default)
		)
		(layer "B.Cu")
	)
	(gr_line
		(start 150.000462 -254.402082)
		(end 150.000462 -256.50444)
		(stroke
			(width 0.0508)
			(type default)
		)
		(layer "B.Cu")
	)
	(gr_line
		(start 153.389838 -20.349972)
		(end 153.864564 -20.349972)
		(stroke
			(width 0.06985)
			(type default)
		)
		(layer "B.Cu")
	)
	(gr_line
		(start 153.864564 -20.349972)
		(end 154.198828 -20.553172)
		(stroke
			(width 0.06985)
			(type default)
		)
		(layer "B.Cu")
	)
	(gr_line
		(start 154.198828 -21.610828)
		(end 155.321 -22.733)
		(stroke
			(width 0.06985)
			(type default)
		)
		(layer "B.Cu")
	)
	(gr_line
		(start 154.198828 -20.553172)
		(end 154.198828 -21.610828)
		(stroke
			(width 0.06985)
			(type default)
		)
		(layer "B.Cu")
	)
	(gr_line
		(start 154.414982 -17.800066)
		(end 154.414982 -17.809972)
		(stroke
			(width 0.06985)
			(type default)
		)
		(layer "B.Cu")
	)
	(gr_line
		(start 154.414982 -17.800066)
		(end 155.12542 -17.089628)
		(stroke
			(width 0.06985)
			(type default)
		)
		(layer "B.Cu")
	)
	(gr_line
		(start 154.583892 -21.487892)
		(end 155.342082 -22.246082)
		(stroke
			(width 0.06985)
			(type default)
		)
		(layer "B.Cu")
	)
	(gr_line
		(start 154.583892 -20.743672)
		(end 154.583892 -21.487892)
		(stroke
			(width 0.06985)
			(type default)
		)
		(layer "B.Cu")
	)
	(gr_line
		(start 154.583892 -20.743672)
		(end 154.977592 -20.349972)
		(stroke
			(width 0.06985)
			(type default)
		)
		(layer "B.Cu")
	)
	(gr_line
		(start 154.977592 -20.349972)
		(end 155.419806 -20.349972)
		(stroke
			(width 0.06985)
			(type default)
		)
		(layer "B.Cu")
	)
	(gr_arc
		(start 155.12542 -17.089628)
		(mid 155.216602 -16.953164)
		(end 155.24861 -16.792194)
		(stroke
			(width 0.06985)
			(type default)
		)
		(layer "B.Cu")
	)
	(gr_line
		(start 155.321 -22.733)
		(end 155.340558 -22.733)
		(stroke
			(width 0.06985)
			(type default)
		)
		(layer "B.Cu")
	)
	(gr_arc
		(start 155.59151 -16.7894)
		(mid 155.624076 -16.952975)
		(end 155.716732 -17.09166)
		(stroke
			(width 0.06985)
			(type default)
		)
		(layer "B.Cu")
	)
	(gr_line
		(start 155.716732 -17.09166)
		(end 156.435044 -17.809972)
		(stroke
			(width 0.06985)
			(type default)
		)
		(layer "B.Cu")
	)
	(gr_line
		(start 155.946348 -77.0255)
		(end 156.188664 -77.267562)
		(stroke
			(width 0.06985)
			(type default)
		)
		(layer "B.Cu")
	)
	(gr_arc
		(start 156.2608 -77.44206)
		(mid 156.242109 -77.347624)
		(end 156.188664 -77.267562)
		(stroke
			(width 0.06985)
			(type default)
		)
		(layer "B.Cu")
	)
	(gr_line
		(start 156.435044 -17.809972)
		(end 156.44495 -17.809972)
		(stroke
			(width 0.06985)
			(type default)
		)
		(layer "B.Cu")
	)
	(gr_line
		(start 156.449776 -80.25003)
		(end 156.811218 -79.528416)
		(stroke
			(width 0.06985)
			(type default)
		)
		(layer "B.Cu")
	)
	(gr_line
		(start 156.57957 -79.256128)
		(end 156.747718 -79.340202)
		(stroke
			(width 0.06985)
			(type default)
		)
		(layer "B.Cu")
	)
	(gr_arc
		(start 156.668724 -77.285088)
		(mid 156.62059 -77.357105)
		(end 156.6037 -77.44206)
		(stroke
			(width 0.06985)
			(type default)
		)
		(layer "B.Cu")
	)
	(gr_line
		(start 156.668724 -77.285088)
		(end 156.928312 -77.0255)
		(stroke
			(width 0.06985)
			(type default)
		)
		(layer "B.Cu")
	)
	(gr_line
		(start 156.748226 -79.34071)
		(end 156.748226 -79.340964)
		(stroke
			(width 0.06985)
			(type default)
		)
		(layer "B.Cu")
	)
	(gr_line
		(start 156.748226 -79.34071)
		(end 156.748734 -79.340964)
		(stroke
			(width 0.06985)
			(type default)
		)
		(layer "B.Cu")
	)
	(gr_line
		(start 156.748734 -79.340964)
		(end 156.748988 -79.340964)
		(stroke
			(width 0.06985)
			(type default)
		)
		(layer "B.Cu")
	)
	(gr_arc
		(start 156.811218 -79.528416)
		(mid 156.818834 -79.421857)
		(end 156.748988 -79.340964)
		(stroke
			(width 0.06985)
			(type default)
		)
		(layer "B.Cu")
	)
	(gr_line
		(start 156.927042 -79.033624)
		(end 157.089348 -79.033624)
		(stroke
			(width 0.06985)
			(type default)
		)
		(layer "B.Cu")
	)
	(gr_arc
		(start 157.089348 -79.033624)
		(mid 157.344728 -78.92782)
		(end 157.450536 -78.672436)
		(stroke
			(width 0.06985)
			(type default)
		)
		(layer "B.Cu")
	)
	(gr_line
		(start 157.450536 -78.24978)
		(end 157.450536 -78.672436)
		(stroke
			(width 0.06985)
			(type default)
		)
		(layer "B.Cu")
	)
	(gr_arc
		(start 158.0134 -15.72133)
		(mid 157.924896 -15.647501)
		(end 157.81274 -15.621)
		(stroke
			(width 0.06985)
			(type default)
		)
		(layer "B.Cu")
	)
	(gr_arc
		(start 158.0134 -15.72133)
		(mid 158.101926 -15.79509)
		(end 158.21406 -15.82166)
		(stroke
			(width 0.06985)
			(type default)
		)
		(layer "B.Cu")
	)
	(gr_line
		(start 158.15818 -15.2781)
		(end 158.68904 -15.2781)
		(stroke
			(width 0.06985)
			(type default)
		)
		(layer "B.Cu")
	)
	(gr_line
		(start 158.21406 -15.82166)
		(end 158.63316 -15.82166)
		(stroke
			(width 0.06985)
			(type default)
		)
		(layer "B.Cu")
	)
	(gr_line
		(start 158.369 -74.422)
		(end 158.533338 -74.586084)
		(stroke
			(width 0.06985)
			(type default)
		)
		(layer "B.Cu")
	)
	(gr_arc
		(start 158.369 -73.831196)
		(mid 158.246638 -74.126599)
		(end 158.369 -74.422)
		(stroke
			(width 0.06985)
			(type default)
		)
		(layer "B.Cu")
	)
	(gr_line
		(start 158.369 -73.831196)
		(end 158.450026 -73.75017)
		(stroke
			(width 0.06985)
			(type default)
		)
		(layer "B.Cu")
	)
	(gr_arc
		(start 158.533338 -74.586084)
		(mid 158.632727 -74.652598)
		(end 158.75 -74.676)
		(stroke
			(width 0.06985)
			(type default)
		)
		(layer "B.Cu")
	)
	(gr_arc
		(start 158.63316 -15.82166)
		(mid 158.745317 -15.795136)
		(end 158.83382 -15.72133)
		(stroke
			(width 0.06985)
			(type default)
		)
		(layer "B.Cu")
	)
	(gr_line
		(start 158.75 -74.676)
		(end 158.836868 -74.676)
		(stroke
			(width 0.06985)
			(type default)
		)
		(layer "B.Cu")
	)
	(gr_arc
		(start 159.03448 -15.621)
		(mid 158.922349 -15.647566)
		(end 158.83382 -15.72133)
		(stroke
			(width 0.06985)
			(type default)
		)
		(layer "B.Cu")
	)
	(gr_line
		(start 159.355536 -75.65644)
		(end 159.449516 -75.75042)
		(stroke
			(width 0.06985)
			(type default)
		)
		(layer "B.Cu")
	)
	(gr_arc
		(start 159.36976 -74.808842)
		(mid 159.182813 -75.229656)
		(end 159.355536 -75.65644)
		(stroke
			(width 0.06985)
			(type default)
		)
		(layer "B.Cu")
	)
	(gr_arc
		(start 159.65424 -15.72133)
		(mid 159.565732 -15.647523)
		(end 159.45358 -15.621)
		(stroke
			(width 0.06985)
			(type default)
		)
		(layer "B.Cu")
	)
	(gr_arc
		(start 159.65424 -15.72133)
		(mid 159.742766 -15.79509)
		(end 159.8549 -15.82166)
		(stroke
			(width 0.06985)
			(type default)
		)
		(layer "B.Cu")
	)
	(gr_line
		(start 159.79902 -15.2781)
		(end 160.32988 -15.2781)
		(stroke
			(width 0.06985)
			(type default)
		)
		(layer "B.Cu")
	)
	(gr_line
		(start 159.8549 -15.82166)
		(end 160.274 -15.82166)
		(stroke
			(width 0.06985)
			(type default)
		)
		(layer "B.Cu")
	)
	(gr_line
		(start 159.946848 -77.0255)
		(end 160.115504 -77.194156)
		(stroke
			(width 0.06985)
			(type default)
		)
		(layer "B.Cu")
	)
	(gr_arc
		(start 160.26765 -77.56144)
		(mid 160.228111 -77.362663)
		(end 160.115504 -77.194156)
		(stroke
			(width 0.06985)
			(type default)
		)
		(layer "B.Cu")
	)
	(gr_arc
		(start 160.274 -15.82166)
		(mid 160.386157 -15.795136)
		(end 160.47466 -15.72133)
		(stroke
			(width 0.06985)
			(type default)
		)
		(layer "B.Cu")
	)
	(gr_line
		(start 160.450276 -80.25003)
		(end 160.810956 -79.52867)
		(stroke
			(width 0.06985)
			(type default)
		)
		(layer "B.Cu")
	)
	(gr_line
		(start 160.579308 -79.256382)
		(end 160.586166 -79.259938)
		(stroke
			(width 0.06985)
			(type default)
		)
		(layer "B.Cu")
	)
	(gr_arc
		(start 160.67532 -15.621)
		(mid 160.563177 -15.647552)
		(end 160.47466 -15.72133)
		(stroke
			(width 0.06985)
			(type default)
		)
		(layer "B.Cu")
	)
	(gr_arc
		(start 160.764474 -77.189838)
		(mid 160.650573 -77.360334)
		(end 160.61055 -77.56144)
		(stroke
			(width 0.06985)
			(type default)
		)
		(layer "B.Cu")
	)
	(gr_line
		(start 160.764474 -77.189838)
		(end 160.928812 -77.0255)
		(stroke
			(width 0.06985)
			(type default)
		)
		(layer "B.Cu")
	)
	(gr_arc
		(start 160.810956 -79.52867)
		(mid 160.818537 -79.422003)
		(end 160.748472 -79.341218)
		(stroke
			(width 0.06985)
			(type default)
		)
		(layer "B.Cu")
	)
	(gr_line
		(start 160.938718 -79.052928)
		(end 160.938972 -79.052928)
		(stroke
			(width 0.06985)
			(type default)
		)
		(layer "B.Cu")
	)
	(gr_arc
		(start 160.938972 -79.052928)
		(mid 161.130984 -79.082387)
		(end 161.30397 -78.994)
		(stroke
			(width 0.06985)
			(type default)
		)
		(layer "B.Cu")
	)
	(gr_arc
		(start 161.30397 -78.994)
		(mid 161.411885 -78.832477)
		(end 161.449766 -78.641956)
		(stroke
			(width 0.06985)
			(type default)
		)
		(layer "B.Cu")
	)
	(gr_line
		(start 161.449766 -78.24978)
		(end 161.449766 -78.641956)
		(stroke
			(width 0.06985)
			(type default)
		)
		(layer "B.Cu")
	)
	(gr_line
		(start 162.433 -74.422)
		(end 162.597338 -74.586084)
		(stroke
			(width 0.06985)
			(type default)
		)
		(layer "B.Cu")
	)
	(gr_arc
		(start 162.433 -73.767696)
		(mid 162.297537 -74.094834)
		(end 162.433 -74.422)
		(stroke
			(width 0.06985)
			(type default)
		)
		(layer "B.Cu")
	)
	(gr_line
		(start 162.433 -73.767696)
		(end 162.450526 -73.75017)
		(stroke
			(width 0.06985)
			(type default)
		)
		(layer "B.Cu")
	)
	(gr_arc
		(start 162.597338 -74.586084)
		(mid 162.696727 -74.652598)
		(end 162.814 -74.676)
		(stroke
			(width 0.06985)
			(type default)
		)
		(layer "B.Cu")
	)
	(gr_line
		(start 162.814 -74.676)
		(end 162.93084 -74.676)
		(stroke
			(width 0.06985)
			(type default)
		)
		(layer "B.Cu")
	)
	(gr_line
		(start 163.391342 -75.691746)
		(end 163.450016 -75.75042)
		(stroke
			(width 0.06985)
			(type default)
		)
		(layer "B.Cu")
	)
	(gr_arc
		(start 163.40455 -74.831448)
		(mid 163.215817 -75.258823)
		(end 163.391342 -75.691746)
		(stroke
			(width 0.06985)
			(type default)
		)
		(layer "B.Cu")
	)
	(gr_arc
		(start 163.80333 -16.666464)
		(mid 163.792955 -16.5517)
		(end 163.732464 -16.453612)
		(stroke
			(width 0.06985)
			(type default)
		)
		(layer "B.Cu")
	)
	(gr_arc
		(start 163.80333 -16.666464)
		(mid 163.813854 -16.781247)
		(end 163.87445 -16.879316)
		(stroke
			(width 0.06985)
			(type default)
		)
		(layer "B.Cu")
	)
	(gr_line
		(start 163.87445 -16.879316)
		(end 164.170614 -17.175734)
		(stroke
			(width 0.06985)
			(type default)
		)
		(layer "B.Cu")
	)
	(gr_line
		(start 163.946078 -77.0255)
		(end 164.188394 -77.267562)
		(stroke
			(width 0.06985)
			(type default)
		)
		(layer "B.Cu")
	)
	(gr_line
		(start 164.003228 -16.239236)
		(end 164.740844 -16.976598)
		(stroke
			(width 0.06985)
			(type default)
		)
		(layer "B.Cu")
	)
	(gr_arc
		(start 164.170614 -17.175734)
		(mid 164.268696 -17.236241)
		(end 164.383466 -17.2466)
		(stroke
			(width 0.06985)
			(type default)
		)
		(layer "B.Cu")
	)
	(gr_arc
		(start 164.26053 -77.44206)
		(mid 164.241839 -77.347624)
		(end 164.188394 -77.267562)
		(stroke
			(width 0.06985)
			(type default)
		)
		(layer "B.Cu")
	)
	(gr_line
		(start 164.383466 -17.2466)
		(end 164.465 -17.2466)
		(stroke
			(width 0.06985)
			(type default)
		)
		(layer "B.Cu")
	)
	(gr_line
		(start 164.449506 -80.25003)
		(end 164.810948 -79.528416)
		(stroke
			(width 0.06985)
			(type default)
		)
		(layer "B.Cu")
	)
	(gr_line
		(start 164.465 -17.2466)
		(end 164.551106 -17.275302)
		(stroke
			(width 0.06985)
			(type default)
		)
		(layer "B.Cu")
	)
	(gr_line
		(start 164.5793 -79.256128)
		(end 164.747448 -79.340202)
		(stroke
			(width 0.06985)
			(type default)
		)
		(layer "B.Cu")
	)
	(gr_arc
		(start 164.668454 -77.285088)
		(mid 164.620314 -77.357104)
		(end 164.60343 -77.44206)
		(stroke
			(width 0.06985)
			(type default)
		)
		(layer "B.Cu")
	)
	(gr_line
		(start 164.668454 -77.285088)
		(end 164.928042 -77.0255)
		(stroke
			(width 0.06985)
			(type default)
		)
		(layer "B.Cu")
	)
	(gr_line
		(start 164.747956 -79.34071)
		(end 164.747956 -79.340964)
		(stroke
			(width 0.06985)
			(type default)
		)
		(layer "B.Cu")
	)
	(gr_line
		(start 164.747956 -79.34071)
		(end 164.748464 -79.340964)
		(stroke
			(width 0.06985)
			(type default)
		)
		(layer "B.Cu")
	)
	(gr_line
		(start 164.748464 -79.340964)
		(end 164.748718 -79.340964)
		(stroke
			(width 0.06985)
			(type default)
		)
		(layer "B.Cu")
	)
	(gr_arc
		(start 164.810948 -79.528416)
		(mid 164.818564 -79.421857)
		(end 164.748718 -79.340964)
		(stroke
			(width 0.06985)
			(type default)
		)
		(layer "B.Cu")
	)
	(gr_line
		(start 164.926772 -79.033624)
		(end 165.089078 -79.033624)
		(stroke
			(width 0.06985)
			(type default)
		)
		(layer "B.Cu")
	)
	(gr_arc
		(start 164.963602 -17.826736)
		(mid 164.974126 -17.941519)
		(end 165.034722 -18.039588)
		(stroke
			(width 0.06985)
			(type default)
		)
		(layer "B.Cu")
	)
	(gr_line
		(start 165.034722 -18.039588)
		(end 165.330886 -18.335752)
		(stroke
			(width 0.06985)
			(type default)
		)
		(layer "B.Cu")
	)
	(gr_arc
		(start 165.089078 -79.033624)
		(mid 165.344503 -78.927844)
		(end 165.450266 -78.672436)
		(stroke
			(width 0.06985)
			(type default)
		)
		(layer "B.Cu")
	)
	(gr_line
		(start 165.162992 -17.398746)
		(end 165.971474 -18.207228)
		(stroke
			(width 0.06985)
			(type default)
		)
		(layer "B.Cu")
	)
	(gr_arc
		(start 165.330886 -18.335752)
		(mid 165.428933 -18.396416)
		(end 165.543738 -18.406872)
		(stroke
			(width 0.06985)
			(type default)
		)
		(layer "B.Cu")
	)
	(gr_line
		(start 165.450266 -78.24978)
		(end 165.450266 -78.672436)
		(stroke
			(width 0.06985)
			(type default)
		)
		(layer "B.Cu")
	)
	(gr_arc
		(start 165.75659 -18.477738)
		(mid 165.6585 -18.417263)
		(end 165.543738 -18.406872)
		(stroke
			(width 0.06985)
			(type default)
		)
		(layer "B.Cu")
	)
	(gr_arc
		(start 166.123874 -18.987008)
		(mid 166.113518 -18.872232)
		(end 166.053008 -18.774156)
		(stroke
			(width 0.06985)
			(type default)
		)
		(layer "B.Cu")
	)
	(gr_arc
		(start 166.123874 -18.987008)
		(mid 166.13426 -19.101777)
		(end 166.19474 -19.19986)
		(stroke
			(width 0.06985)
			(type default)
		)
		(layer "B.Cu")
	)
	(gr_line
		(start 166.19474 -19.19986)
		(end 166.491158 -19.496024)
		(stroke
			(width 0.06985)
			(type default)
		)
		(layer "B.Cu")
	)
	(gr_line
		(start 166.323518 -18.559272)
		(end 167.131746 -19.3675)
		(stroke
			(width 0.06985)
			(type default)
		)
		(layer "B.Cu")
	)
	(gr_line
		(start 166.37 -74.422)
		(end 166.497 -74.549)
		(stroke
			(width 0.06985)
			(type default)
		)
		(layer "B.Cu")
	)
	(gr_arc
		(start 166.37 -73.829926)
		(mid 166.247487 -74.125974)
		(end 166.37 -74.422)
		(stroke
			(width 0.06985)
			(type default)
		)
		(layer "B.Cu")
	)
	(gr_line
		(start 166.37 -73.829926)
		(end 166.449756 -73.75017)
		(stroke
			(width 0.06985)
			(type default)
		)
		(layer "B.Cu")
	)
	(gr_arc
		(start 166.491158 -19.496024)
		(mid 166.589205 -19.556688)
		(end 166.70401 -19.567144)
		(stroke
			(width 0.06985)
			(type default)
		)
		(layer "B.Cu")
	)
	(gr_arc
		(start 166.497 -74.549)
		(mid 166.8145 -74.680513)
		(end 167.132 -74.549)
		(stroke
			(width 0.06985)
			(type default)
		)
		(layer "B.Cu")
	)
	(gr_arc
		(start 166.916862 -19.63801)
		(mid 166.818774 -19.577529)
		(end 166.70401 -19.567144)
		(stroke
			(width 0.06985)
			(type default)
		)
		(layer "B.Cu")
	)
	(gr_arc
		(start 167.132 -74.549)
		(mid 167.2497 -74.372925)
		(end 167.291004 -74.165206)
		(stroke
			(width 0.06985)
			(type default)
		)
		(layer "B.Cu")
	)
	(gr_arc
		(start 167.284146 -20.14728)
		(mid 167.273778 -20.032512)
		(end 167.21328 -19.934428)
		(stroke
			(width 0.06985)
			(type default)
		)
		(layer "B.Cu")
	)
	(gr_arc
		(start 167.284146 -20.14728)
		(mid 167.294539 -20.262038)
		(end 167.355012 -20.360132)
		(stroke
			(width 0.06985)
			(type default)
		)
		(layer "B.Cu")
	)
	(gr_line
		(start 167.355012 -20.360132)
		(end 167.65143 -20.656296)
		(stroke
			(width 0.06985)
			(type default)
		)
		(layer "B.Cu")
	)
	(gr_arc
		(start 167.450516 -75.75042)
		(mid 167.586239 -75.547298)
		(end 167.633904 -75.307698)
		(stroke
			(width 0.06985)
			(type default)
		)
		(layer "B.Cu")
	)
	(gr_line
		(start 167.48379 -19.719798)
		(end 168.075356 -20.311364)
		(stroke
			(width 0.06985)
			(type default)
		)
		(layer "B.Cu")
	)
	(gr_line
		(start 167.633904 -74.510646)
		(end 167.633904 -75.307698)
		(stroke
			(width 0.06985)
			(type default)
		)
		(layer "B.Cu")
	)
	(gr_arc
		(start 167.65143 -20.656296)
		(mid 167.749477 -20.71696)
		(end 167.864282 -20.727416)
		(stroke
			(width 0.06985)
			(type default)
		)
		(layer "B.Cu")
	)
	(gr_line
		(start 167.946578 -77.0255)
		(end 168.188894 -77.267562)
		(stroke
			(width 0.06985)
			(type default)
		)
		(layer "B.Cu")
	)
	(gr_arc
		(start 168.077134 -20.798282)
		(mid 167.979044 -20.737819)
		(end 167.864282 -20.727416)
		(stroke
			(width 0.06985)
			(type default)
		)
		(layer "B.Cu")
	)
	(gr_arc
		(start 168.26103 -77.44206)
		(mid 168.242339 -77.347624)
		(end 168.188894 -77.267562)
		(stroke
			(width 0.06985)
			(type default)
		)
		(layer "B.Cu")
	)
	(gr_line
		(start 168.450006 -80.25003)
		(end 168.811448 -79.528416)
		(stroke
			(width 0.06985)
			(type default)
		)
		(layer "B.Cu")
	)
	(gr_line
		(start 168.5798 -79.256128)
		(end 168.747948 -79.340202)
		(stroke
			(width 0.06985)
			(type default)
		)
		(layer "B.Cu")
	)
	(gr_arc
		(start 168.668954 -77.285088)
		(mid 168.620814 -77.357104)
		(end 168.60393 -77.44206)
		(stroke
			(width 0.06985)
			(type default)
		)
		(layer "B.Cu")
	)
	(gr_line
		(start 168.668954 -77.285088)
		(end 168.928542 -77.0255)
		(stroke
			(width 0.06985)
			(type default)
		)
		(layer "B.Cu")
	)
	(gr_line
		(start 168.748456 -79.34071)
		(end 168.748456 -79.340964)
		(stroke
			(width 0.06985)
			(type default)
		)
		(layer "B.Cu")
	)
	(gr_line
		(start 168.748456 -79.34071)
		(end 168.748964 -79.340964)
		(stroke
			(width 0.06985)
			(type default)
		)
		(layer "B.Cu")
	)
	(gr_line
		(start 168.748964 -79.340964)
		(end 168.749218 -79.340964)
		(stroke
			(width 0.06985)
			(type default)
		)
		(layer "B.Cu")
	)
	(gr_arc
		(start 168.759632 -21.622766)
		(mid 168.749258 -21.508002)
		(end 168.688766 -21.409914)
		(stroke
			(width 0.06985)
			(type default)
		)
		(layer "B.Cu")
	)
	(gr_arc
		(start 168.759632 -21.622766)
		(mid 168.770156 -21.737549)
		(end 168.830752 -21.835618)
		(stroke
			(width 0.06985)
			(type default)
		)
		(layer "B.Cu")
	)
	(gr_arc
		(start 168.811448 -79.528416)
		(mid 168.819064 -79.421857)
		(end 168.749218 -79.340964)
		(stroke
			(width 0.06985)
			(type default)
		)
		(layer "B.Cu")
	)
	(gr_line
		(start 168.830752 -21.835618)
		(end 169.126916 -22.132036)
		(stroke
			(width 0.06985)
			(type default)
		)
		(layer "B.Cu")
	)
	(gr_line
		(start 168.927272 -79.033624)
		(end 169.089578 -79.033624)
		(stroke
			(width 0.06985)
			(type default)
		)
		(layer "B.Cu")
	)
	(gr_arc
		(start 169.089578 -79.033624)
		(mid 169.344095 -78.928215)
		(end 169.449496 -78.673706)
		(stroke
			(width 0.06985)
			(type default)
		)
		(layer "B.Cu")
	)
	(gr_arc
		(start 169.126916 -22.132036)
		(mid 169.224998 -22.192543)
		(end 169.339768 -22.202902)
		(stroke
			(width 0.06985)
			(type default)
		)
		(layer "B.Cu")
	)
	(gr_line
		(start 169.175684 -21.411692)
		(end 169.550842 -21.78685)
		(stroke
			(width 0.06985)
			(type default)
		)
		(layer "B.Cu")
	)
	(gr_line
		(start 169.449496 -78.24978)
		(end 169.449496 -78.673706)
		(stroke
			(width 0.06985)
			(type default)
		)
		(layer "B.Cu")
	)
	(gr_arc
		(start 169.526458 -27.3431)
		(mid 169.637268 -27.321059)
		(end 169.731182 -27.258264)
		(stroke
			(width 0.06985)
			(type default)
		)
		(layer "B.Cu")
	)
	(gr_arc
		(start 169.55262 -22.273768)
		(mid 169.454529 -22.213314)
		(end 169.339768 -22.202902)
		(stroke
			(width 0.06985)
			(type default)
		)
		(layer "B.Cu")
	)
	(gr_arc
		(start 169.731182 -27.258264)
		(mid 169.737689 -27.250646)
		(end 169.743882 -27.24277)
		(stroke
			(width 0.06985)
			(type default)
		)
		(layer "B.Cu")
	)
	(gr_line
		(start 169.871898 -27.686)
		(end 170.419522 -27.686)
		(stroke
			(width 0.06985)
			(type default)
		)
		(layer "B.Cu")
	)
	(gr_arc
		(start 169.944542 -27.14244)
		(mid 169.832425 -27.169023)
		(end 169.743882 -27.24277)
		(stroke
			(width 0.06985)
			(type default)
		)
		(layer "B.Cu")
	)
	(gr_line
		(start 169.944542 -27.14244)
		(end 170.363642 -27.14244)
		(stroke
			(width 0.06985)
			(type default)
		)
		(layer "B.Cu")
	)
	(gr_line
		(start 170.383708 -74.498708)
		(end 170.482514 -74.597514)
		(stroke
			(width 0.06985)
			(type default)
		)
		(layer "B.Cu")
	)
	(gr_arc
		(start 170.383708 -73.816718)
		(mid 170.242589 -74.157709)
		(end 170.383708 -74.498708)
		(stroke
			(width 0.06985)
			(type default)
		)
		(layer "B.Cu")
	)
	(gr_line
		(start 170.383708 -73.816718)
		(end 170.450256 -73.75017)
		(stroke
			(width 0.06985)
			(type default)
		)
		(layer "B.Cu")
	)
	(gr_arc
		(start 170.482514 -74.597514)
		(mid 170.7515 -74.708932)
		(end 171.020486 -74.597514)
		(stroke
			(width 0.06985)
			(type default)
		)
		(layer "B.Cu")
	)
	(gr_arc
		(start 170.564302 -27.24277)
		(mid 170.475793 -27.168957)
		(end 170.363642 -27.14244)
		(stroke
			(width 0.06985)
			(type default)
		)
		(layer "B.Cu")
	)
	(gr_arc
		(start 170.564302 -27.24277)
		(mid 170.570494 -27.250646)
		(end 170.577002 -27.258264)
		(stroke
			(width 0.06985)
			(type default)
		)
		(layer "B.Cu")
	)
	(gr_arc
		(start 170.577002 -27.258264)
		(mid 170.661893 -27.320796)
		(end 170.764962 -27.3431)
		(stroke
			(width 0.06985)
			(type default)
		)
		(layer "B.Cu")
	)
	(gr_line
		(start 171.020486 -74.597514)
		(end 171.119546 -74.498454)
		(stroke
			(width 0.06985)
			(type default)
		)
		(layer "B.Cu")
	)
	(gr_line
		(start 171.286932 -25.983946)
		(end 171.286932 -26.20518)
		(stroke
			(width 0.06985)
			(type default)
		)
		(layer "B.Cu")
	)
	(gr_arc
		(start 171.315126 -25.24252)
		(mid 171.590631 -25.426559)
		(end 171.915582 -25.491186)
		(stroke
			(width 0.06985)
			(type default)
		)
		(layer "B.Cu")
	)
	(gr_arc
		(start 171.382944 -74.719434)
		(mid 171.193858 -75.214385)
		(end 171.401232 -75.701906)
		(stroke
			(width 0.06985)
			(type default)
		)
		(layer "B.Cu")
	)
	(gr_line
		(start 171.401232 -75.701906)
		(end 171.449746 -75.75042)
		(stroke
			(width 0.06985)
			(type default)
		)
		(layer "B.Cu")
	)
	(gr_arc
		(start 171.436792 -25.834086)
		(mid 171.330825 -25.877979)
		(end 171.286932 -25.983946)
		(stroke
			(width 0.06985)
			(type default)
		)
		(layer "B.Cu")
	)
	(gr_line
		(start 171.436792 -25.834086)
		(end 171.570142 -25.834086)
		(stroke
			(width 0.06985)
			(type default)
		)
		(layer "B.Cu")
	)
	(gr_arc
		(start 171.977304 -27.3431)
		(mid 172.089461 -27.316576)
		(end 172.177964 -27.24277)
		(stroke
			(width 0.06985)
			(type default)
		)
		(layer "B.Cu")
	)
	(gr_arc
		(start 172.047662 -23.04923)
		(mid 171.959156 -22.975415)
		(end 171.847002 -22.9489)
		(stroke
			(width 0.06985)
			(type default)
		)
		(layer "B.Cu")
	)
	(gr_arc
		(start 172.047662 -23.04923)
		(mid 172.136188 -23.12299)
		(end 172.248322 -23.14956)
		(stroke
			(width 0.06985)
			(type default)
		)
		(layer "B.Cu")
	)
	(gr_line
		(start 172.192442 -22.606)
		(end 172.723302 -22.606)
		(stroke
			(width 0.06985)
			(type default)
		)
		(layer "B.Cu")
	)
	(gr_line
		(start 172.248322 -23.14956)
		(end 172.667422 -23.14956)
		(stroke
			(width 0.06985)
			(type default)
		)
		(layer "B.Cu")
	)
	(gr_line
		(start 172.322744 -27.686)
		(end 172.853604 -27.686)
		(stroke
			(width 0.06985)
			(type default)
		)
		(layer "B.Cu")
	)
	(gr_arc
		(start 172.378624 -27.14244)
		(mid 172.266484 -27.168993)
		(end 172.177964 -27.24277)
		(stroke
			(width 0.06985)
			(type default)
		)
		(layer "B.Cu")
	)
	(gr_line
		(start 172.378624 -27.14244)
		(end 172.797724 -27.14244)
		(stroke
			(width 0.06985)
			(type default)
		)
		(layer "B.Cu")
	)
	(gr_arc
		(start 172.667422 -23.14956)
		(mid 172.779579 -23.123036)
		(end 172.868082 -23.04923)
		(stroke
			(width 0.06985)
			(type default)
		)
		(layer "B.Cu")
	)
	(gr_arc
		(start 172.998384 -27.24277)
		(mid 172.909874 -27.168964)
		(end 172.797724 -27.14244)
		(stroke
			(width 0.06985)
			(type default)
		)
		(layer "B.Cu")
	)
	(gr_arc
		(start 172.998384 -27.24277)
		(mid 173.08691 -27.31653)
		(end 173.199044 -27.3431)
		(stroke
			(width 0.06985)
			(type default)
		)
		(layer "B.Cu")
	)
	(gr_arc
		(start 173.068742 -22.9489)
		(mid 172.956621 -22.97548)
		(end 172.868082 -23.04923)
		(stroke
			(width 0.06985)
			(type default)
		)
		(layer "B.Cu")
	)
	(gr_line
		(start 173.334172 -33.01492)
		(end 173.34738 -33.028128)
		(stroke
			(width 0.06985)
			(type default)
		)
		(layer "B.Cu")
	)
	(gr_arc
		(start 173.34738 -33.028128)
		(mid 173.644052 -33.151014)
		(end 173.940724 -33.028128)
		(stroke
			(width 0.06985)
			(type default)
		)
		(layer "B.Cu")
	)
	(gr_line
		(start 174.218092 -33.36163)
		(end 174.218092 -33.87852)
		(stroke
			(width 0.06985)
			(type default)
		)
		(layer "B.Cu")
	)
	(gr_arc
		(start 174.306992 -33.147)
		(mid 174.241194 -33.245473)
		(end 174.218092 -33.36163)
		(stroke
			(width 0.06985)
			(type default)
		)
		(layer "B.Cu")
	)
	(gr_arc
		(start 174.730156 -32.238696)
		(mid 174.790547 -32.140716)
		(end 174.801022 -32.026098)
		(stroke
			(width 0.06985)
			(type default)
		)
		(layer "B.Cu")
	)
	(gr_arc
		(start 174.871888 -31.813246)
		(mid 174.811381 -31.911328)
		(end 174.801022 -32.026098)
		(stroke
			(width 0.06985)
			(type default)
		)
		(layer "B.Cu")
	)
	(gr_line
		(start 174.871888 -31.813246)
		(end 175.168306 -31.516828)
		(stroke
			(width 0.06985)
			(type default)
		)
		(layer "B.Cu")
	)
	(gr_line
		(start 175.217074 -32.236918)
		(end 175.592232 -31.86176)
		(stroke
			(width 0.06985)
			(type default)
		)
		(layer "B.Cu")
	)
	(gr_arc
		(start 175.381158 -31.445962)
		(mid 175.2664 -31.456355)
		(end 175.168306 -31.516828)
		(stroke
			(width 0.06985)
			(type default)
		)
		(layer "B.Cu")
	)
	(gr_arc
		(start 175.381158 -31.445962)
		(mid 175.495949 -31.435441)
		(end 175.59401 -31.374842)
		(stroke
			(width 0.06985)
			(type default)
		)
		(layer "B.Cu")
	)
	(gr_arc
		(start 190.373 -74.422)
		(mid 190.6905 -74.553513)
		(end 191.008 -74.422)
		(stroke
			(width 0.06985)
			(type default)
		)
		(layer "B.Cu")
	)
	(gr_arc
		(start 190.373 -73.827386)
		(mid 190.249961 -74.124695)
		(end 190.373 -74.422)
		(stroke
			(width 0.06985)
			(type default)
		)
		(layer "B.Cu")
	)
	(gr_line
		(start 190.373 -73.827386)
		(end 190.450216 -73.75017)
		(stroke
			(width 0.06985)
			(type default)
		)
		(layer "B.Cu")
	)
	(gr_line
		(start 191.008 -74.422)
		(end 191.11468 -74.31532)
		(stroke
			(width 0.06985)
			(type default)
		)
		(layer "B.Cu")
	)
	(gr_arc
		(start 191.11468 -74.31532)
		(mid 191.258486 -74.100074)
		(end 191.30899 -73.846182)
		(stroke
			(width 0.06985)
			(type default)
		)
		(layer "B.Cu")
	)
	(gr_line
		(start 191.379602 -75.680316)
		(end 191.449706 -75.75042)
		(stroke
			(width 0.06985)
			(type default)
		)
		(layer "B.Cu")
	)
	(gr_arc
		(start 191.379602 -74.939398)
		(mid 191.2261 -75.309894)
		(end 191.379602 -75.680316)
		(stroke
			(width 0.06985)
			(type default)
		)
		(layer "B.Cu")
	)
	(gr_line
		(start 191.379602 -74.939398)
		(end 191.478662 -74.840592)
		(stroke
			(width 0.06985)
			(type default)
		)
		(layer "B.Cu")
	)
	(gr_arc
		(start 191.478662 -74.840592)
		(mid 191.606916 -74.64853)
		(end 191.65189 -74.422)
		(stroke
			(width 0.06985)
			(type default)
		)
		(layer "B.Cu")
	)
	(gr_line
		(start 191.65189 -74.191622)
		(end 191.65189 -74.422)
		(stroke
			(width 0.06985)
			(type default)
		)
		(layer "B.Cu")
	)
	(gr_line
		(start 191.947038 -77.0255)
		(end 192.189354 -77.267562)
		(stroke
			(width 0.06985)
			(type default)
		)
		(layer "B.Cu")
	)
	(gr_arc
		(start 192.26149 -77.44206)
		(mid 192.242799 -77.347624)
		(end 192.189354 -77.267562)
		(stroke
			(width 0.06985)
			(type default)
		)
		(layer "B.Cu")
	)
	(gr_line
		(start 192.450466 -80.25003)
		(end 192.811908 -79.528416)
		(stroke
			(width 0.06985)
			(type default)
		)
		(layer "B.Cu")
	)
	(gr_line
		(start 192.58026 -79.256128)
		(end 192.748408 -79.340202)
		(stroke
			(width 0.06985)
			(type default)
		)
		(layer "B.Cu")
	)
	(gr_arc
		(start 192.669414 -77.285088)
		(mid 192.621282 -77.357106)
		(end 192.60439 -77.44206)
		(stroke
			(width 0.06985)
			(type default)
		)
		(layer "B.Cu")
	)
	(gr_line
		(start 192.669414 -77.285088)
		(end 192.929002 -77.0255)
		(stroke
			(width 0.06985)
			(type default)
		)
		(layer "B.Cu")
	)
	(gr_line
		(start 192.748916 -79.34071)
		(end 192.748916 -79.340964)
		(stroke
			(width 0.06985)
			(type default)
		)
		(layer "B.Cu")
	)
	(gr_line
		(start 192.748916 -79.34071)
		(end 192.749424 -79.340964)
		(stroke
			(width 0.06985)
			(type default)
		)
		(layer "B.Cu")
	)
	(gr_line
		(start 192.749424 -79.340964)
		(end 192.749678 -79.340964)
		(stroke
			(width 0.06985)
			(type default)
		)
		(layer "B.Cu")
	)
	(gr_arc
		(start 192.811908 -79.528416)
		(mid 192.819524 -79.421857)
		(end 192.749678 -79.340964)
		(stroke
			(width 0.06985)
			(type default)
		)
		(layer "B.Cu")
	)
	(gr_line
		(start 192.927732 -79.033624)
		(end 193.090038 -79.033624)
		(stroke
			(width 0.06985)
			(type default)
		)
		(layer "B.Cu")
	)
	(gr_arc
		(start 193.090038 -79.033624)
		(mid 193.344516 -78.928193)
		(end 193.449956 -78.673706)
		(stroke
			(width 0.06985)
			(type default)
		)
		(layer "B.Cu")
	)
	(gr_line
		(start 193.449956 -78.24978)
		(end 193.449956 -78.673706)
		(stroke
			(width 0.06985)
			(type default)
		)
		(layer "B.Cu")
	)
	(gr_arc
		(start 194.31 -74.422)
		(mid 194.691 -74.579815)
		(end 195.072 -74.422)
		(stroke
			(width 0.06985)
			(type default)
		)
		(layer "B.Cu")
	)
	(gr_arc
		(start 194.31 -73.889616)
		(mid 194.199748 -74.155806)
		(end 194.31 -74.422)
		(stroke
			(width 0.06985)
			(type default)
		)
		(layer "B.Cu")
	)
	(gr_line
		(start 194.31 -73.889616)
		(end 194.449446 -73.75017)
		(stroke
			(width 0.06985)
			(type default)
		)
		(layer "B.Cu")
	)
	(gr_line
		(start 195.072 -74.422)
		(end 195.072254 -74.421746)
		(stroke
			(width 0.06985)
			(type default)
		)
		(layer "B.Cu")
	)
	(gr_arc
		(start 195.072254 -74.421746)
		(mid 195.221132 -74.19879)
		(end 195.273422 -73.935844)
		(stroke
			(width 0.06985)
			(type default)
		)
		(layer "B.Cu")
	)
	(gr_arc
		(start 195.450206 -74.805794)
		(mid 195.254515 -75.278144)
		(end 195.450206 -75.75042)
		(stroke
			(width 0.06985)
			(type default)
		)
		(layer "B.Cu")
	)
	(gr_line
		(start 195.450206 -74.805794)
		(end 195.453 -74.803)
		(stroke
			(width 0.06985)
			(type default)
		)
		(layer "B.Cu")
	)
	(gr_arc
		(start 195.453 -74.803)
		(mid 195.573891 -74.622147)
		(end 195.616322 -74.408792)
		(stroke
			(width 0.06985)
			(type default)
		)
		(layer "B.Cu")
	)
	(gr_line
		(start 195.616322 -74.281284)
		(end 195.616322 -74.408792)
		(stroke
			(width 0.06985)
			(type default)
		)
		(layer "B.Cu")
	)
	(gr_line
		(start 195.947538 -77.0255)
		(end 196.189854 -77.267562)
		(stroke
			(width 0.06985)
			(type default)
		)
		(layer "B.Cu")
	)
	(gr_arc
		(start 196.26199 -77.44206)
		(mid 196.243299 -77.347624)
		(end 196.189854 -77.267562)
		(stroke
			(width 0.06985)
			(type default)
		)
		(layer "B.Cu")
	)
	(gr_line
		(start 196.449696 -80.249776)
		(end 196.449696 -80.25003)
		(stroke
			(width 0.06985)
			(type default)
		)
		(layer "B.Cu")
	)
	(gr_line
		(start 196.449696 -80.249776)
		(end 196.717666 -79.981806)
		(stroke
			(width 0.06985)
			(type default)
		)
		(layer "B.Cu")
	)
	(gr_line
		(start 196.58076 -79.256128)
		(end 196.76999 -79.421736)
		(stroke
			(width 0.06985)
			(type default)
		)
		(layer "B.Cu")
	)
	(gr_arc
		(start 196.669914 -77.285088)
		(mid 196.621782 -77.357106)
		(end 196.60489 -77.44206)
		(stroke
			(width 0.06985)
			(type default)
		)
		(layer "B.Cu")
	)
	(gr_line
		(start 196.669914 -77.285088)
		(end 196.929502 -77.0255)
		(stroke
			(width 0.06985)
			(type default)
		)
		(layer "B.Cu")
	)
	(gr_arc
		(start 196.717666 -79.981806)
		(mid 196.825906 -79.819952)
		(end 196.86397 -79.629)
		(stroke
			(width 0.06985)
			(type default)
		)
		(layer "B.Cu")
	)
	(gr_arc
		(start 196.86397 -79.629)
		(mid 196.839364 -79.515227)
		(end 196.76999 -79.421736)
		(stroke
			(width 0.06985)
			(type default)
		)
		(layer "B.Cu")
	)
	(gr_line
		(start 196.928232 -79.033624)
		(end 197.090538 -79.033624)
		(stroke
			(width 0.06985)
			(type default)
		)
		(layer "B.Cu")
	)
	(gr_arc
		(start 197.090538 -79.033624)
		(mid 197.345016 -78.928193)
		(end 197.450456 -78.673706)
		(stroke
			(width 0.06985)
			(type default)
		)
		(layer "B.Cu")
	)
	(gr_line
		(start 197.450456 -78.24978)
		(end 197.450456 -78.673706)
		(stroke
			(width 0.06985)
			(type default)
		)
		(layer "B.Cu")
	)
	(gr_line
		(start 198.276464 -74.324464)
		(end 198.37527 -74.42327)
		(stroke
			(width 0.06985)
			(type default)
		)
		(layer "B.Cu")
	)
	(gr_arc
		(start 198.276464 -73.923652)
		(mid 198.193432 -74.12407)
		(end 198.276464 -74.324464)
		(stroke
			(width 0.06985)
			(type default)
		)
		(layer "B.Cu")
	)
	(gr_line
		(start 198.276464 -73.923652)
		(end 198.449946 -73.75017)
		(stroke
			(width 0.06985)
			(type default)
		)
		(layer "B.Cu")
	)
	(gr_arc
		(start 198.37527 -74.42327)
		(mid 198.755889 -74.580875)
		(end 199.136508 -74.42327)
		(stroke
			(width 0.06985)
			(type default)
		)
		(layer "B.Cu")
	)
	(gr_arc
		(start 199.136508 -74.42327)
		(mid 199.2401 -74.268286)
		(end 199.276462 -74.08545)
		(stroke
			(width 0.06985)
			(type default)
		)
		(layer "B.Cu")
	)
	(gr_arc
		(start 199.449436 -75.75042)
		(mid 199.57521 -75.562219)
		(end 199.619362 -75.34021)
		(stroke
			(width 0.06985)
			(type default)
		)
		(layer "B.Cu")
	)
	(gr_line
		(start 199.619362 -74.43089)
		(end 199.619362 -75.34021)
		(stroke
			(width 0.06985)
			(type default)
		)
		(layer "B.Cu")
	)
	(gr_line
		(start 199.946768 -77.0255)
		(end 200.189084 -77.267562)
		(stroke
			(width 0.06985)
			(type default)
		)
		(layer "B.Cu")
	)
	(gr_arc
		(start 200.26122 -77.44206)
		(mid 200.242529 -77.347624)
		(end 200.189084 -77.267562)
		(stroke
			(width 0.06985)
			(type default)
		)
		(layer "B.Cu")
	)
	(gr_line
		(start 200.450196 -80.25003)
		(end 200.811638 -79.528416)
		(stroke
			(width 0.06985)
			(type default)
		)
		(layer "B.Cu")
	)
	(gr_line
		(start 200.57999 -79.256128)
		(end 200.748138 -79.340202)
		(stroke
			(width 0.06985)
			(type default)
		)
		(layer "B.Cu")
	)
	(gr_arc
		(start 200.669144 -77.285088)
		(mid 200.621006 -77.357104)
		(end 200.60412 -77.44206)
		(stroke
			(width 0.06985)
			(type default)
		)
		(layer "B.Cu")
	)
	(gr_line
		(start 200.669144 -77.285088)
		(end 200.928732 -77.0255)
		(stroke
			(width 0.06985)
			(type default)
		)
		(layer "B.Cu")
	)
	(gr_line
		(start 200.748646 -79.34071)
		(end 200.748646 -79.340964)
		(stroke
			(width 0.06985)
			(type default)
		)
		(layer "B.Cu")
	)
	(gr_line
		(start 200.748646 -79.34071)
		(end 200.749154 -79.340964)
		(stroke
			(width 0.06985)
			(type default)
		)
		(layer "B.Cu")
	)
	(gr_line
		(start 200.749154 -79.340964)
		(end 200.749408 -79.340964)
		(stroke
			(width 0.06985)
			(type default)
		)
		(layer "B.Cu")
	)
	(gr_arc
		(start 200.811638 -79.528416)
		(mid 200.819254 -79.421857)
		(end 200.749408 -79.340964)
		(stroke
			(width 0.06985)
			(type default)
		)
		(layer "B.Cu")
	)
	(gr_line
		(start 200.927462 -79.033624)
		(end 201.089768 -79.033624)
		(stroke
			(width 0.06985)
			(type default)
		)
		(layer "B.Cu")
	)
	(gr_arc
		(start 201.089768 -79.033624)
		(mid 201.344291 -78.928218)
		(end 201.449686 -78.673706)
		(stroke
			(width 0.06985)
			(type default)
		)
		(layer "B.Cu")
	)
	(gr_line
		(start 201.449686 -78.24978)
		(end 201.449686 -78.673706)
		(stroke
			(width 0.06985)
			(type default)
		)
		(layer "B.Cu")
	)
	(gr_arc
		(start 202.145646 -74.625962)
		(mid 202.320323 -74.742726)
		(end 202.526392 -74.783696)
		(stroke
			(width 0.06985)
			(type default)
		)
		(layer "B.Cu")
	)
	(gr_arc
		(start 202.145646 -74.05497)
		(mid 202.027353 -74.340476)
		(end 202.145646 -74.625962)
		(stroke
			(width 0.06985)
			(type default)
		)
		(layer "B.Cu")
	)
	(gr_line
		(start 202.145646 -74.05497)
		(end 202.450446 -73.75017)
		(stroke
			(width 0.06985)
			(type default)
		)
		(layer "B.Cu")
	)
	(gr_line
		(start 202.526392 -74.783696)
		(end 202.813412 -74.783696)
		(stroke
			(width 0.06985)
			(type default)
		)
		(layer "B.Cu")
	)
	(gr_arc
		(start 202.813412 -74.783696)
		(mid 202.891696 -74.753297)
		(end 202.9587 -74.70267)
		(stroke
			(width 0.06985)
			(type default)
		)
		(layer "B.Cu")
	)
	(gr_arc
		(start 203.051918 -75.643232)
		(mid 203.170668 -75.722578)
		(end 203.310744 -75.75042)
		(stroke
			(width 0.06985)
			(type default)
		)
		(layer "B.Cu")
	)
	(gr_arc
		(start 203.051918 -75.094592)
		(mid 202.938291 -75.368912)
		(end 203.051918 -75.643232)
		(stroke
			(width 0.06985)
			(type default)
		)
		(layer "B.Cu")
	)
	(gr_line
		(start 203.310744 -75.75042)
		(end 203.449936 -75.75042)
		(stroke
			(width 0.06985)
			(type default)
		)
		(layer "B.Cu")
	)
	(gr_line
		(start 203.947268 -77.0255)
		(end 204.189584 -77.267562)
		(stroke
			(width 0.06985)
			(type default)
		)
		(layer "B.Cu")
	)
	(gr_arc
		(start 204.26172 -77.44206)
		(mid 204.243029 -77.347624)
		(end 204.189584 -77.267562)
		(stroke
			(width 0.06985)
			(type default)
		)
		(layer "B.Cu")
	)
	(gr_line
		(start 204.449426 -80.25003)
		(end 204.45984 -80.25003)
		(stroke
			(width 0.06985)
			(type default)
		)
		(layer "B.Cu")
	)
	(gr_arc
		(start 204.45984 -80.25003)
		(mid 204.719369 -80.142529)
		(end 204.82687 -79.883)
		(stroke
			(width 0.06985)
			(type default)
		)
		(layer "B.Cu")
	)
	(gr_line
		(start 204.58049 -79.256128)
		(end 204.785214 -79.435198)
		(stroke
			(width 0.06985)
			(type default)
		)
		(layer "B.Cu")
	)
	(gr_arc
		(start 204.669644 -77.285088)
		(mid 204.621506 -77.357104)
		(end 204.60462 -77.44206)
		(stroke
			(width 0.06985)
			(type default)
		)
		(layer "B.Cu")
	)
	(gr_line
		(start 204.669644 -77.285088)
		(end 204.929232 -77.0255)
		(stroke
			(width 0.06985)
			(type default)
		)
		(layer "B.Cu")
	)
	(gr_arc
		(start 204.82687 -79.5274)
		(mid 204.816031 -79.476781)
		(end 204.785214 -79.435198)
		(stroke
			(width 0.06985)
			(type default)
		)
		(layer "B.Cu")
	)
	(gr_line
		(start 204.82687 -79.5274)
		(end 204.82687 -79.883)
		(stroke
			(width 0.06985)
			(type default)
		)
		(layer "B.Cu")
	)
	(gr_line
		(start 204.927962 -79.033624)
		(end 205.097634 -79.033624)
		(stroke
			(width 0.06985)
			(type default)
		)
		(layer "B.Cu")
	)
	(gr_arc
		(start 205.097634 -79.033624)
		(mid 205.315372 -78.990328)
		(end 205.49997 -78.867)
		(stroke
			(width 0.06985)
			(type default)
		)
		(layer "B.Cu")
	)
	(gr_line
		(start 205.450186 -78.24978)
		(end 205.49997 -78.299564)
		(stroke
			(width 0.06985)
			(type default)
		)
		(layer "B.Cu")
	)
	(gr_arc
		(start 205.49997 -78.867)
		(mid 205.617491 -78.583287)
		(end 205.49997 -78.299564)
		(stroke
			(width 0.06985)
			(type default)
		)
		(layer "B.Cu")
	)
	(gr_arc
		(start 206.017114 -74.547222)
		(mid 206.327874 -74.849896)
		(end 206.761334 -74.867516)
		(stroke
			(width 0.06985)
			(type default)
		)
		(layer "B.Cu")
	)
	(gr_arc
		(start 206.274924 -73.925176)
		(mid 206.084145 -74.210558)
		(end 206.017114 -74.547222)
		(stroke
			(width 0.06985)
			(type default)
		)
		(layer "B.Cu")
	)
	(gr_line
		(start 206.274924 -73.925176)
		(end 206.449676 -73.75017)
		(stroke
			(width 0.06985)
			(type default)
		)
		(layer "B.Cu")
	)
	(gr_arc
		(start 206.761334 -74.867516)
		(mid 207.119907 -74.619525)
		(end 207.292194 -74.219054)
		(stroke
			(width 0.06985)
			(type default)
		)
		(layer "B.Cu")
	)
	(gr_arc
		(start 207.450436 -75.75042)
		(mid 207.593527 -74.940398)
		(end 207.641444 -74.119232)
		(stroke
			(width 0.06985)
			(type default)
		)
		(layer "B.Cu")
	)
	(gr_line
		(start 207.637634 -74.115422)
		(end 207.641444 -74.119232)
		(stroke
			(width 0.06985)
			(type default)
		)
		(layer "B.Cu")
	)
	(gr_line
		(start 212.450426 -80.25003)
		(end 212.705442 -80.25003)
		(stroke
			(width 0.06985)
			(type default)
		)
		(layer "B.Cu")
	)
	(gr_arc
		(start 212.95614 -87.198962)
		(mid 212.982724 -87.311078)
		(end 213.05647 -87.399622)
		(stroke
			(width 0.06985)
			(type default)
		)
		(layer "B.Cu")
	)
	(gr_line
		(start 212.95614 -86.779862)
		(end 212.95614 -87.198962)
		(stroke
			(width 0.06985)
			(type default)
		)
		(layer "B.Cu")
	)
	(gr_arc
		(start 212.95614 -85.558122)
		(mid 212.98271 -85.670249)
		(end 213.05647 -85.758782)
		(stroke
			(width 0.06985)
			(type default)
		)
		(layer "B.Cu")
	)
	(gr_line
		(start 212.95614 -85.139022)
		(end 212.95614 -85.558122)
		(stroke
			(width 0.06985)
			(type default)
		)
		(layer "B.Cu")
	)
	(gr_arc
		(start 212.95614 -83.917282)
		(mid 212.982695 -84.02942)
		(end 213.05647 -84.117942)
		(stroke
			(width 0.06985)
			(type default)
		)
		(layer "B.Cu")
	)
	(gr_line
		(start 212.95614 -83.498182)
		(end 212.95614 -83.917282)
		(stroke
			(width 0.06985)
			(type default)
		)
		(layer "B.Cu")
	)
	(gr_arc
		(start 212.95614 -82.276442)
		(mid 212.982717 -82.388563)
		(end 213.05647 -82.477102)
		(stroke
			(width 0.06985)
			(type default)
		)
		(layer "B.Cu")
	)
	(gr_line
		(start 212.95614 -81.857342)
		(end 212.95614 -82.276442)
		(stroke
			(width 0.06985)
			(type default)
		)
		(layer "B.Cu")
	)
	(gr_arc
		(start 213.05647 -86.579202)
		(mid 212.982659 -86.667711)
		(end 212.95614 -86.779862)
		(stroke
			(width 0.06985)
			(type default)
		)
		(layer "B.Cu")
	)
	(gr_arc
		(start 213.05647 -86.579202)
		(mid 213.13023 -86.490676)
		(end 213.1568 -86.378542)
		(stroke
			(width 0.06985)
			(type default)
		)
		(layer "B.Cu")
	)
	(gr_arc
		(start 213.05647 -84.938362)
		(mid 212.98268 -85.026875)
		(end 212.95614 -85.139022)
		(stroke
			(width 0.06985)
			(type default)
		)
		(layer "B.Cu")
	)
	(gr_arc
		(start 213.05647 -84.938362)
		(mid 213.13023 -84.849836)
		(end 213.1568 -84.737702)
		(stroke
			(width 0.06985)
			(type default)
		)
		(layer "B.Cu")
	)
	(gr_arc
		(start 213.05647 -83.297522)
		(mid 212.982666 -83.386033)
		(end 212.95614 -83.498182)
		(stroke
			(width 0.06985)
			(type default)
		)
		(layer "B.Cu")
	)
	(gr_arc
		(start 213.05647 -83.297522)
		(mid 213.13023 -83.208996)
		(end 213.1568 -83.096862)
		(stroke
			(width 0.06985)
			(type default)
		)
		(layer "B.Cu")
	)
	(gr_arc
		(start 213.05647 -81.656682)
		(mid 212.982687 -81.745197)
		(end 212.95614 -81.857342)
		(stroke
			(width 0.06985)
			(type default)
		)
		(layer "B.Cu")
	)
	(gr_arc
		(start 213.05647 -81.656682)
		(mid 213.130287 -81.568043)
		(end 213.1568 -81.455768)
		(stroke
			(width 0.06985)
			(type default)
		)
		(layer "B.Cu")
	)
	(gr_arc
		(start 213.141814 -80.58658)
		(mid 212.980997 -80.343905)
		(end 212.705442 -80.25003)
		(stroke
			(width 0.06985)
			(type default)
		)
		(layer "B.Cu")
	)
	(gr_arc
		(start 213.1568 -87.600282)
		(mid 213.130276 -87.488125)
		(end 213.05647 -87.399622)
		(stroke
			(width 0.06985)
			(type default)
		)
		(layer "B.Cu")
	)
	(gr_arc
		(start 213.1568 -85.959442)
		(mid 213.130276 -85.847285)
		(end 213.05647 -85.758782)
		(stroke
			(width 0.06985)
			(type default)
		)
		(layer "B.Cu")
	)
	(gr_arc
		(start 213.1568 -84.318602)
		(mid 213.130276 -84.206445)
		(end 213.05647 -84.117942)
		(stroke
			(width 0.06985)
			(type default)
		)
		(layer "B.Cu")
	)
	(gr_arc
		(start 213.1568 -82.677762)
		(mid 213.130276 -82.565605)
		(end 213.05647 -82.477102)
		(stroke
			(width 0.06985)
			(type default)
		)
		(layer "B.Cu")
	)
	(gr_arc
		(start 213.1568 -80.701388)
		(mid 213.153007 -80.643501)
		(end 213.141814 -80.58658)
		(stroke
			(width 0.06985)
			(type default)
		)
		(layer "B.Cu")
	)
	(gr_line
		(start 213.4997 -86.723982)
		(end 213.4997 -87.254842)
		(stroke
			(width 0.06985)
			(type default)
		)
		(layer "B.Cu")
	)
	(gr_line
		(start 213.4997 -85.083142)
		(end 213.4997 -85.614002)
		(stroke
			(width 0.06985)
			(type default)
		)
		(layer "B.Cu")
	)
	(gr_line
		(start 213.4997 -83.442302)
		(end 213.4997 -83.973162)
		(stroke
			(width 0.06985)
			(type default)
		)
		(layer "B.Cu")
	)
	(gr_line
		(start 213.4997 -81.801208)
		(end 213.4997 -82.332322)
		(stroke
			(width 0.06985)
			(type default)
		)
		(layer "B.Cu")
	)
	(gr_arc
		(start 213.4997 -78.369922)
		(mid 213.486765 -78.304894)
		(end 213.449916 -78.24978)
		(stroke
			(width 0.06985)
			(type default)
		)
		(layer "B.Cu")
	)
	(gr_line
		(start 213.4997 -78.369922)
		(end 213.4997 -80.355948)
		(stroke
			(width 0.06985)
			(type default)
		)
		(layer "B.Cu")
	)
	(gr_arc
		(start 219.5195 -103.220774)
		(mid 219.54605 -103.332918)
		(end 219.61983 -103.421434)
		(stroke
			(width 0.06985)
			(type default)
		)
		(layer "B.Cu")
	)
	(gr_line
		(start 219.5195 -102.801674)
		(end 219.5195 -103.220774)
		(stroke
			(width 0.06985)
			(type default)
		)
		(layer "B.Cu")
	)
	(gr_arc
		(start 219.5195 -101.579934)
		(mid 219.546071 -101.692061)
		(end 219.61983 -101.780594)
		(stroke
			(width 0.06985)
			(type default)
		)
		(layer "B.Cu")
	)
	(gr_line
		(start 219.5195 -101.160834)
		(end 219.5195 -101.579934)
		(stroke
			(width 0.06985)
			(type default)
		)
		(layer "B.Cu")
	)
	(gr_arc
		(start 219.5195 -99.939094)
		(mid 219.546057 -100.051233)
		(end 219.61983 -100.139754)
		(stroke
			(width 0.06985)
			(type default)
		)
		(layer "B.Cu")
	)
	(gr_line
		(start 219.5195 -99.519994)
		(end 219.5195 -99.939094)
		(stroke
			(width 0.06985)
			(type default)
		)
		(layer "B.Cu")
	)
	(gr_arc
		(start 219.61983 -102.601014)
		(mid 219.546006 -102.689519)
		(end 219.5195 -102.801674)
		(stroke
			(width 0.06985)
			(type default)
		)
		(layer "B.Cu")
	)
	(gr_arc
		(start 219.61983 -102.601014)
		(mid 219.69359 -102.512488)
		(end 219.72016 -102.400354)
		(stroke
			(width 0.06985)
			(type default)
		)
		(layer "B.Cu")
	)
	(gr_arc
		(start 219.61983 -100.960174)
		(mid 219.546028 -101.048683)
		(end 219.5195 -101.160834)
		(stroke
			(width 0.06985)
			(type default)
		)
		(layer "B.Cu")
	)
	(gr_arc
		(start 219.61983 -100.960174)
		(mid 219.69359 -100.871648)
		(end 219.72016 -100.759514)
		(stroke
			(width 0.06985)
			(type default)
		)
		(layer "B.Cu")
	)
	(gr_arc
		(start 219.61983 -99.319334)
		(mid 219.546013 -99.40784)
		(end 219.5195 -99.519994)
		(stroke
			(width 0.06985)
			(type default)
		)
		(layer "B.Cu")
	)
	(gr_arc
		(start 219.61983 -99.319334)
		(mid 219.69359 -99.230808)
		(end 219.72016 -99.118674)
		(stroke
			(width 0.06985)
			(type default)
		)
		(layer "B.Cu")
	)
	(gr_arc
		(start 219.72016 -103.622094)
		(mid 219.693636 -103.509937)
		(end 219.61983 -103.421434)
		(stroke
			(width 0.06985)
			(type default)
		)
		(layer "B.Cu")
	)
	(gr_arc
		(start 219.72016 -101.981254)
		(mid 219.693636 -101.869097)
		(end 219.61983 -101.780594)
		(stroke
			(width 0.06985)
			(type default)
		)
		(layer "B.Cu")
	)
	(gr_arc
		(start 219.72016 -100.340414)
		(mid 219.693636 -100.228257)
		(end 219.61983 -100.139754)
		(stroke
			(width 0.06985)
			(type default)
		)
		(layer "B.Cu")
	)
	(gr_line
		(start 220.06306 -102.745794)
		(end 220.06306 -103.276654)
		(stroke
			(width 0.06985)
			(type default)
		)
		(layer "B.Cu")
	)
	(gr_line
		(start 220.06306 -101.104954)
		(end 220.06306 -101.635814)
		(stroke
			(width 0.06985)
			(type default)
		)
		(layer "B.Cu")
	)
	(gr_line
		(start 220.06306 -99.464114)
		(end 220.06306 -99.994974)
		(stroke
			(width 0.06985)
			(type default)
		)
		(layer "B.Cu")
	)
	(gr_line
		(start 290.150042 -198.1835)
		(end 290.378134 -198.1835)
		(stroke
			(width 0.0508)
			(type default)
		)
		(layer "B.Cu")
	)
	(gr_line
		(start 290.44138 -198.608696)
		(end 290.44138 -198.83247)
		(stroke
			(width 0.0508)
			(type default)
		)
		(layer "B.Cu")
	)
	(gr_line
		(start 292.670992 -185.522616)
		(end 292.918642 -185.522616)
		(stroke
			(width 0.0508)
			(type default)
		)
		(layer "B.Cu")
	)
	(gr_line
		(start 292.7096 -184.863232)
		(end 293.000938 -185.15457)
		(stroke
			(width 0.0508)
			(type default)
		)
		(layer "B.Cu")
	)
	(gr_line
		(start 292.7096 -184.8104)
		(end 292.7096 -184.863232)
		(stroke
			(width 0.0508)
			(type default)
		)
		(layer "B.Cu")
	)
	(gr_line
		(start 293.000938 -185.15457)
		(end 293.039038 -185.15457)
		(stroke
			(width 0.0508)
			(type default)
		)
		(layer "B.Cu")
	)
	(gr_line
		(start 293.497 -114.492532)
		(end 293.665148 -114.32413)
		(stroke
			(width 0.06985)
			(type default)
		)
		(layer "B.Cu")
	)
	(gr_line
		(start 293.497 -113.510568)
		(end 293.665148 -113.67897)
		(stroke
			(width 0.06985)
			(type default)
		)
		(layer "B.Cu")
	)
	(gr_arc
		(start 293.665148 -113.67897)
		(mid 293.832742 -113.79086)
		(end 294.0304 -113.8301)
		(stroke
			(width 0.06985)
			(type default)
		)
		(layer "B.Cu")
	)
	(gr_arc
		(start 294.0304 -114.173)
		(mid 293.83274 -114.212235)
		(end 293.665148 -114.32413)
		(stroke
			(width 0.06985)
			(type default)
		)
		(layer "B.Cu")
	)
	(gr_line
		(start 295.91 -78.27645)
		(end 296.007282 -78.179168)
		(stroke
			(width 0.06985)
			(type default)
		)
		(layer "B.Cu")
	)
	(gr_arc
		(start 295.91 -77.35951)
		(mid 296.191313 -77.547493)
		(end 296.523156 -77.61351)
		(stroke
			(width 0.06985)
			(type default)
		)
		(layer "B.Cu")
	)
	(gr_arc
		(start 296.545 -77.95641)
		(mid 296.253993 -78.014324)
		(end 296.007282 -78.179168)
		(stroke
			(width 0.06985)
			(type default)
		)
		(layer "B.Cu")
	)
	(gr_arc
		(start 298.425362 -77.61351)
		(mid 298.537473 -77.586922)
		(end 298.626022 -77.51318)
		(stroke
			(width 0.06985)
			(type default)
		)
		(layer "B.Cu")
	)
	(gr_line
		(start 298.770802 -77.95641)
		(end 299.301662 -77.95641)
		(stroke
			(width 0.06985)
			(type default)
		)
		(layer "B.Cu")
	)
	(gr_arc
		(start 298.826682 -77.41285)
		(mid 298.714525 -77.439374)
		(end 298.626022 -77.51318)
		(stroke
			(width 0.06985)
			(type default)
		)
		(layer "B.Cu")
	)
	(gr_line
		(start 298.826682 -77.41285)
		(end 299.245782 -77.41285)
		(stroke
			(width 0.06985)
			(type default)
		)
		(layer "B.Cu")
	)
	(gr_arc
		(start 299.446442 -77.51318)
		(mid 299.357916 -77.43942)
		(end 299.245782 -77.41285)
		(stroke
			(width 0.06985)
			(type default)
		)
		(layer "B.Cu")
	)
	(gr_arc
		(start 299.446442 -77.51318)
		(mid 299.53495 -77.586991)
		(end 299.647102 -77.61351)
		(stroke
			(width 0.06985)
			(type default)
		)
		(layer "B.Cu")
	)
	(gr_arc
		(start 300.066202 -77.61351)
		(mid 300.17833 -77.586944)
		(end 300.266862 -77.51318)
		(stroke
			(width 0.06985)
			(type default)
		)
		(layer "B.Cu")
	)
	(gr_line
		(start 300.411642 -77.95641)
		(end 300.942502 -77.95641)
		(stroke
			(width 0.06985)
			(type default)
		)
		(layer "B.Cu")
	)
	(gr_arc
		(start 300.467522 -77.41285)
		(mid 300.355365 -77.439374)
		(end 300.266862 -77.51318)
		(stroke
			(width 0.06985)
			(type default)
		)
		(layer "B.Cu")
	)
	(gr_line
		(start 300.467522 -77.41285)
		(end 300.886622 -77.41285)
		(stroke
			(width 0.06985)
			(type default)
		)
		(layer "B.Cu")
	)
	(gr_arc
		(start 301.087282 -77.51318)
		(mid 300.998756 -77.43942)
		(end 300.886622 -77.41285)
		(stroke
			(width 0.06985)
			(type default)
		)
		(layer "B.Cu")
	)
	(gr_arc
		(start 301.087282 -77.51318)
		(mid 301.175792 -77.586977)
		(end 301.287942 -77.61351)
		(stroke
			(width 0.06985)
			(type default)
		)
		(layer "B.Cu")
	)
	(gr_arc
		(start 301.707042 -77.61351)
		(mid 301.819159 -77.586929)
		(end 301.907702 -77.51318)
		(stroke
			(width 0.06985)
			(type default)
		)
		(layer "B.Cu")
	)
	(gr_line
		(start 302.052482 -77.95641)
		(end 302.583342 -77.95641)
		(stroke
			(width 0.06985)
			(type default)
		)
		(layer "B.Cu")
	)
	(gr_arc
		(start 302.108362 -77.41285)
		(mid 301.996205 -77.439374)
		(end 301.907702 -77.51318)
		(stroke
			(width 0.06985)
			(type default)
		)
		(layer "B.Cu")
	)
	(gr_line
		(start 302.108362 -77.41285)
		(end 302.527462 -77.41285)
		(stroke
			(width 0.06985)
			(type default)
		)
		(layer "B.Cu")
	)
	(gr_arc
		(start 302.728122 -77.51318)
		(mid 302.639596 -77.43942)
		(end 302.527462 -77.41285)
		(stroke
			(width 0.06985)
			(type default)
		)
		(layer "B.Cu")
	)
	(gr_arc
		(start 302.728122 -77.51318)
		(mid 302.816628 -77.586998)
		(end 302.928782 -77.61351)
		(stroke
			(width 0.06985)
			(type default)
		)
		(layer "B.Cu")
	)
	(gr_arc
		(start 304.007774 -77.61351)
		(mid 304.11991 -77.586954)
		(end 304.208434 -77.51318)
		(stroke
			(width 0.06985)
			(type default)
		)
		(layer "B.Cu")
	)
	(gr_line
		(start 304.353214 -77.95641)
		(end 304.884074 -77.95641)
		(stroke
			(width 0.06985)
			(type default)
		)
		(layer "B.Cu")
	)
	(gr_arc
		(start 304.409094 -77.41285)
		(mid 304.296937 -77.439374)
		(end 304.208434 -77.51318)
		(stroke
			(width 0.06985)
			(type default)
		)
		(layer "B.Cu")
	)
	(gr_line
		(start 304.409094 -77.41285)
		(end 304.828194 -77.41285)
		(stroke
			(width 0.06985)
			(type default)
		)
		(layer "B.Cu")
	)
	(gr_arc
		(start 305.028854 -77.51318)
		(mid 304.940328 -77.43942)
		(end 304.828194 -77.41285)
		(stroke
			(width 0.06985)
			(type default)
		)
		(layer "B.Cu")
	)
	(gr_arc
		(start 305.028854 -77.51318)
		(mid 305.117362 -77.586987)
		(end 305.229514 -77.61351)
		(stroke
			(width 0.06985)
			(type default)
		)
		(layer "B.Cu")
	)
	(gr_arc
		(start 305.648614 -77.61351)
		(mid 305.760739 -77.586939)
		(end 305.849274 -77.51318)
		(stroke
			(width 0.06985)
			(type default)
		)
		(layer "B.Cu")
	)
	(gr_line
		(start 305.994054 -77.95641)
		(end 306.524914 -77.95641)
		(stroke
			(width 0.06985)
			(type default)
		)
		(layer "B.Cu")
	)
	(gr_arc
		(start 306.049934 -77.41285)
		(mid 305.937777 -77.439374)
		(end 305.849274 -77.51318)
		(stroke
			(width 0.06985)
			(type default)
		)
		(layer "B.Cu")
	)
	(gr_line
		(start 306.049934 -77.41285)
		(end 306.469034 -77.41285)
		(stroke
			(width 0.06985)
			(type default)
		)
		(layer "B.Cu")
	)
	(gr_arc
		(start 306.669694 -77.51318)
		(mid 306.581168 -77.43942)
		(end 306.469034 -77.41285)
		(stroke
			(width 0.06985)
			(type default)
		)
		(layer "B.Cu")
	)
	(gr_arc
		(start 306.669694 -77.51318)
		(mid 306.758205 -77.586973)
		(end 306.870354 -77.61351)
		(stroke
			(width 0.06985)
			(type default)
		)
		(layer "B.Cu")
	)
	(gr_arc
		(start 311.227724 -75.764136)
		(mid 311.288186 -75.666046)
		(end 311.29859 -75.551284)
		(stroke
			(width 0.06985)
			(type default)
		)
		(layer "B.Cu")
	)
	(gr_arc
		(start 311.36971 -75.338432)
		(mid 311.309046 -75.436479)
		(end 311.29859 -75.551284)
		(stroke
			(width 0.06985)
			(type default)
		)
		(layer "B.Cu")
	)
	(gr_line
		(start 311.36971 -75.338432)
		(end 311.665874 -75.042014)
		(stroke
			(width 0.06985)
			(type default)
		)
		(layer "B.Cu")
	)
	(gr_line
		(start 311.714642 -75.762358)
		(end 312.0898 -75.3872)
		(stroke
			(width 0.06985)
			(type default)
		)
		(layer "B.Cu")
	)
	(gr_arc
		(start 311.878726 -74.971148)
		(mid 311.763957 -74.981534)
		(end 311.665874 -75.042014)
		(stroke
			(width 0.06985)
			(type default)
		)
		(layer "B.Cu")
	)
	(gr_arc
		(start 311.878726 -74.971148)
		(mid 311.993493 -74.960777)
		(end 312.091578 -74.900282)
		(stroke
			(width 0.06985)
			(type default)
		)
		(layer "B.Cu")
	)
	(gr_arc
		(start 312.387996 -74.603864)
		(mid 312.448476 -74.505776)
		(end 312.458862 -74.391012)
		(stroke
			(width 0.06985)
			(type default)
		)
		(layer "B.Cu")
	)
	(gr_arc
		(start 312.529982 -74.17816)
		(mid 312.469318 -74.276207)
		(end 312.458862 -74.391012)
		(stroke
			(width 0.06985)
			(type default)
		)
		(layer "B.Cu")
	)
	(gr_line
		(start 312.529982 -74.17816)
		(end 312.826146 -73.881996)
		(stroke
			(width 0.06985)
			(type default)
		)
		(layer "B.Cu")
	)
	(gr_line
		(start 312.874914 -74.602086)
		(end 313.250072 -74.226928)
		(stroke
			(width 0.06985)
			(type default)
		)
		(layer "B.Cu")
	)
	(gr_arc
		(start 313.038998 -73.810876)
		(mid 312.924215 -73.8214)
		(end 312.826146 -73.881996)
		(stroke
			(width 0.06985)
			(type default)
		)
		(layer "B.Cu")
	)
	(gr_arc
		(start 313.038998 -73.810876)
		(mid 313.153773 -73.800517)
		(end 313.25185 -73.74001)
		(stroke
			(width 0.06985)
			(type default)
		)
		(layer "B.Cu")
	)
	(gr_arc
		(start 313.548268 -73.443592)
		(mid 313.608742 -73.345501)
		(end 313.619134 -73.23074)
		(stroke
			(width 0.06985)
			(type default)
		)
		(layer "B.Cu")
	)
	(gr_arc
		(start 313.69 -73.017888)
		(mid 313.629554 -73.115982)
		(end 313.619134 -73.23074)
		(stroke
			(width 0.06985)
			(type default)
		)
		(layer "B.Cu")
	)
	(gr_line
		(start 313.69 -73.017888)
		(end 313.986418 -72.721724)
		(stroke
			(width 0.06985)
			(type default)
		)
		(layer "B.Cu")
	)
	(gr_line
		(start 314.035186 -73.441814)
		(end 314.410344 -73.066656)
		(stroke
			(width 0.06985)
			(type default)
		)
		(layer "B.Cu")
	)
	(gr_arc
		(start 314.19927 -72.650604)
		(mid 314.084487 -72.661128)
		(end 313.986418 -72.721724)
		(stroke
			(width 0.06985)
			(type default)
		)
		(layer "B.Cu")
	)
	(gr_arc
		(start 314.19927 -72.650604)
		(mid 314.314053 -72.640257)
		(end 314.412122 -72.579738)
		(stroke
			(width 0.06985)
			(type default)
		)
		(layer "B.Cu")
	)
	(gr_line
		(start 318.755776 -69.197982)
		(end 319.034414 -68.919344)
		(stroke
			(width 0.06985)
			(type default)
		)
		(layer "B.Cu")
	)
	(gr_line
		(start 318.755776 -68.216018)
		(end 319.034414 -68.494656)
		(stroke
			(width 0.06985)
			(type default)
		)
		(layer "B.Cu")
	)
	(gr_arc
		(start 319.034414 -68.494656)
		(mid 319.079756 -68.52492)
		(end 319.13322 -68.53555)
		(stroke
			(width 0.06985)
			(type default)
		)
		(layer "B.Cu")
	)
	(gr_arc
		(start 319.13322 -68.87845)
		(mid 319.079742 -68.889054)
		(end 319.034414 -68.919344)
		(stroke
			(width 0.06985)
			(type default)
		)
		(layer "B.Cu")
	)
	(gr_line
		(start 335.8896 -135.4074)
		(end 335.911952 -135.385048)
		(stroke
			(width 0.06985)
			(type default)
		)
		(layer "B.Cu")
	)
	(gr_line
		(start 335.911952 -135.385048)
		(end 337.951318 -135.385048)
		(stroke
			(width 0.06985)
			(type default)
		)
		(layer "B.Cu")
	)
	(gr_line
		(start 336.0166 -133.2484)
		(end 336.121248 -133.353048)
		(stroke
			(width 0.06985)
			(type default)
		)
		(layer "B.Cu")
	)
	(gr_line
		(start 336.121248 -133.353048)
		(end 337.951318 -133.353048)
		(stroke
			(width 0.06985)
			(type default)
		)
		(layer "B.Cu")
	)
	(gr_arc
		(start 338.4296 -134.1755)
		(mid 338.609205 -134.101105)
		(end 338.6836 -133.9215)
		(stroke
			(width 0.06985)
			(type default)
		)
		(layer "B.Cu")
	)
	(gr_arc
		(start 338.6582 -135.1534)
		(mid 338.726051 -135.317183)
		(end 338.889848 -135.385048)
		(stroke
			(width 0.06985)
			(type default)
		)
		(layer "B.Cu")
	)
	(gr_arc
		(start 338.6582 -134.789672)
		(mid 338.578746 -134.597854)
		(end 338.386928 -134.5184)
		(stroke
			(width 0.06985)
			(type default)
		)
		(layer "B.Cu")
	)
	(gr_line
		(start 338.6582 -134.789672)
		(end 338.6582 -135.1534)
		(stroke
			(width 0.06985)
			(type default)
		)
		(layer "B.Cu")
	)
	(gr_line
		(start 338.6836 -133.6294)
		(end 338.6836 -133.9215)
		(stroke
			(width 0.06985)
			(type default)
		)
		(layer "B.Cu")
	)
	(gr_line
		(start 338.889848 -135.385048)
		(end 339.348318 -135.385048)
		(stroke
			(width 0.06985)
			(type default)
		)
		(layer "B.Cu")
	)
	(gr_arc
		(start 338.959952 -133.353048)
		(mid 338.764542 -133.43399)
		(end 338.6836 -133.6294)
		(stroke
			(width 0.06985)
			(type default)
		)
		(layer "B.Cu")
	)
	(gr_line
		(start 338.959952 -133.353048)
		(end 339.348318 -133.353048)
		(stroke
			(width 0.06985)
			(type default)
		)
		(layer "B.Cu")
	)
	(gr_line
		(start 340.872318 -135.385048)
		(end 341.296752 -135.385048)
		(stroke
			(width 0.06985)
			(type default)
		)
		(layer "B.Cu")
	)
	(gr_line
		(start 340.872318 -133.353048)
		(end 341.404448 -133.353048)
		(stroke
			(width 0.06985)
			(type default)
		)
		(layer "B.Cu")
	)
	(gr_arc
		(start 341.296752 -135.385048)
		(mid 341.460583 -135.317217)
		(end 341.5284 -135.1534)
		(stroke
			(width 0.06985)
			(type default)
		)
		(layer "B.Cu")
	)
	(gr_line
		(start 341.5284 -134.845298)
		(end 341.5284 -135.1534)
		(stroke
			(width 0.06985)
			(type default)
		)
		(layer "B.Cu")
	)
	(gr_arc
		(start 341.5538 -133.918198)
		(mid 341.635634 -134.115765)
		(end 341.8332 -134.197598)
		(stroke
			(width 0.06985)
			(type default)
		)
		(layer "B.Cu")
	)
	(gr_arc
		(start 341.5538 -133.5024)
		(mid 341.510056 -133.396792)
		(end 341.404448 -133.353048)
		(stroke
			(width 0.06985)
			(type default)
		)
		(layer "B.Cu")
	)
	(gr_line
		(start 341.5538 -133.5024)
		(end 341.5538 -133.918198)
		(stroke
			(width 0.06985)
			(type default)
		)
		(layer "B.Cu")
	)
	(gr_arc
		(start 341.8332 -134.540498)
		(mid 341.617674 -134.629772)
		(end 341.5284 -134.845298)
		(stroke
			(width 0.06985)
			(type default)
		)
		(layer "B.Cu")
	)
	(gr_line
		(start 342.269318 -135.385048)
		(end 343.360248 -135.385048)
		(stroke
			(width 0.06985)
			(type default)
		)
		(layer "B.Cu")
	)
	(gr_line
		(start 342.269318 -133.353048)
		(end 343.277952 -133.353048)
		(stroke
			(width 0.06985)
			(type default)
		)
		(layer "B.Cu")
	)
	(gr_line
		(start 343.277952 -133.353048)
		(end 343.3826 -133.2484)
		(stroke
			(width 0.06985)
			(type default)
		)
		(layer "B.Cu")
	)
	(gr_line
		(start 343.360248 -135.385048)
		(end 343.5096 -135.5344)
		(stroke
			(width 0.06985)
			(type default)
		)
		(layer "B.Cu")
	)
	(gr_line
		(start 0 -246.000016)
		(end 0 -81.009998)
		(stroke
			(width 1.524)
			(type default)
		)
		(layer "In1.Cu")
	)
	(gr_arc
		(start 0 -246.000016)
		(mid 1.464462 -249.535545)
		(end 4.99999 -251.000006)
		(stroke
			(width 1.524)
			(type default)
		)
		(layer "In1.Cu")
	)
	(gr_arc
		(start 2.999994 -78.010004)
		(mid 0.878678 -78.888682)
		(end 0 -81.009998)
		(stroke
			(width 1.524)
			(type default)
		)
		(layer "In1.Cu")
	)
	(gr_line
		(start 2.999994 -78.010004)
		(end 25.500076 -78.010004)
		(stroke
			(width 1.524)
			(type default)
		)
		(layer "In1.Cu")
	)
	(gr_arc
		(start 10.51814 -103.213662)
		(mid 10.80008 -103.495602)
		(end 11.08202 -103.213662)
		(stroke
			(width 0.2)
			(type default)
		)
		(layer "In1.Cu")
	)
	(gr_line
		(start 10.51814 -101.765862)
		(end 10.51814 -103.213662)
		(stroke
			(width 0.2)
			(type default)
		)
		(layer "In1.Cu")
	)
	(gr_arc
		(start 10.91819 -100.704142)
		(mid 11.20013 -100.986082)
		(end 11.48207 -100.704142)
		(stroke
			(width 0.2)
			(type default)
		)
		(layer "In1.Cu")
	)
	(gr_line
		(start 10.91819 -99.256342)
		(end 10.91819 -100.704142)
		(stroke
			(width 0.2)
			(type default)
		)
		(layer "In1.Cu")
	)
	(gr_line
		(start 11.08202 -103.213662)
		(end 11.08202 -101.765862)
		(stroke
			(width 0.2)
			(type default)
		)
		(layer "In1.Cu")
	)
	(gr_arc
		(start 11.08202 -101.765862)
		(mid 10.80008 -101.483922)
		(end 10.51814 -101.765862)
		(stroke
			(width 0.2)
			(type default)
		)
		(layer "In1.Cu")
	)
	(gr_line
		(start 11.14552 -98.876866)
		(end 12.059666 -98.878644)
		(stroke
			(width 0.2)
			(type default)
		)
		(layer "In1.Cu")
	)
	(gr_arc
		(start 11.147044 -98.109786)
		(mid 10.762742 -98.492564)
		(end 11.14552 -98.876866)
		(stroke
			(width 0.2)
			(type default)
		)
		(layer "In1.Cu")
	)
	(gr_arc
		(start 11.31824 -103.213662)
		(mid 11.60018 -103.495602)
		(end 11.88212 -103.213662)
		(stroke
			(width 0.2)
			(type default)
		)
		(layer "In1.Cu")
	)
	(gr_line
		(start 11.31824 -101.765862)
		(end 11.31824 -103.213662)
		(stroke
			(width 0.2)
			(type default)
		)
		(layer "In1.Cu")
	)
	(gr_line
		(start 11.48207 -100.704142)
		(end 11.48207 -99.256342)
		(stroke
			(width 0.2)
			(type default)
		)
		(layer "In1.Cu")
	)
	(gr_arc
		(start 11.48207 -99.256342)
		(mid 11.20013 -98.974402)
		(end 10.91819 -99.256342)
		(stroke
			(width 0.2)
			(type default)
		)
		(layer "In1.Cu")
	)
	(gr_arc
		(start 11.71829 -100.704142)
		(mid 12.00023 -100.986082)
		(end 12.28217 -100.704142)
		(stroke
			(width 0.2)
			(type default)
		)
		(layer "In1.Cu")
	)
	(gr_line
		(start 11.71829 -99.256342)
		(end 11.71829 -100.704142)
		(stroke
			(width 0.2)
			(type default)
		)
		(layer "In1.Cu")
	)
	(gr_line
		(start 11.88212 -103.213662)
		(end 11.88212 -101.765862)
		(stroke
			(width 0.2)
			(type default)
		)
		(layer "In1.Cu")
	)
	(gr_arc
		(start 11.88212 -101.765862)
		(mid 11.60018 -101.483922)
		(end 11.31824 -101.765862)
		(stroke
			(width 0.2)
			(type default)
		)
		(layer "In1.Cu")
	)
	(gr_arc
		(start 12.059666 -98.878644)
		(mid 12.444222 -98.495993)
		(end 12.061444 -98.111564)
		(stroke
			(width 0.2)
			(type default)
		)
		(layer "In1.Cu")
	)
	(gr_line
		(start 12.061444 -98.111564)
		(end 11.147044 -98.109786)
		(stroke
			(width 0.2)
			(type default)
		)
		(layer "In1.Cu")
	)
	(gr_line
		(start 12.28217 -100.704142)
		(end 12.28217 -99.256342)
		(stroke
			(width 0.2)
			(type default)
		)
		(layer "In1.Cu")
	)
	(gr_arc
		(start 12.28217 -99.256342)
		(mid 12.00023 -98.974402)
		(end 11.71829 -99.256342)
		(stroke
			(width 0.2)
			(type default)
		)
		(layer "In1.Cu")
	)
	(gr_arc
		(start 12.91844 -103.213662)
		(mid 13.20038 -103.495602)
		(end 13.48232 -103.213662)
		(stroke
			(width 0.2)
			(type default)
		)
		(layer "In1.Cu")
	)
	(gr_line
		(start 12.91844 -101.765862)
		(end 12.91844 -103.213662)
		(stroke
			(width 0.2)
			(type default)
		)
		(layer "In1.Cu")
	)
	(gr_arc
		(start 13.31849 -100.704142)
		(mid 13.60043 -100.986082)
		(end 13.88237 -100.704142)
		(stroke
			(width 0.2)
			(type default)
		)
		(layer "In1.Cu")
	)
	(gr_line
		(start 13.31849 -99.256342)
		(end 13.31849 -100.704142)
		(stroke
			(width 0.2)
			(type default)
		)
		(layer "In1.Cu")
	)
	(gr_line
		(start 13.48232 -103.213662)
		(end 13.48232 -101.765862)
		(stroke
			(width 0.2)
			(type default)
		)
		(layer "In1.Cu")
	)
	(gr_arc
		(start 13.48232 -101.765862)
		(mid 13.20038 -101.483922)
		(end 12.91844 -101.765862)
		(stroke
			(width 0.2)
			(type default)
		)
		(layer "In1.Cu")
	)
	(gr_line
		(start 13.487654 -98.852736)
		(end 14.4272 -98.903536)
		(stroke
			(width 0.2)
			(type default)
		)
		(layer "In1.Cu")
	)
	(gr_arc
		(start 13.52931 -98.086672)
		(mid 13.12545 -98.448876)
		(end 13.487654 -98.852736)
		(stroke
			(width 0.2)
			(type default)
		)
		(layer "In1.Cu")
	)
	(gr_arc
		(start 13.71854 -103.213662)
		(mid 14.00048 -103.495602)
		(end 14.28242 -103.213662)
		(stroke
			(width 0.2)
			(type default)
		)
		(layer "In1.Cu")
	)
	(gr_line
		(start 13.71854 -101.765862)
		(end 13.71854 -103.213662)
		(stroke
			(width 0.2)
			(type default)
		)
		(layer "In1.Cu")
	)
	(gr_line
		(start 13.88237 -100.704142)
		(end 13.88237 -99.256342)
		(stroke
			(width 0.2)
			(type default)
		)
		(layer "In1.Cu")
	)
	(gr_arc
		(start 13.88237 -99.256342)
		(mid 13.60043 -98.974402)
		(end 13.31849 -99.256342)
		(stroke
			(width 0.2)
			(type default)
		)
		(layer "In1.Cu")
	)
	(gr_arc
		(start 14.11859 -100.704142)
		(mid 14.40053 -100.986082)
		(end 14.68247 -100.704142)
		(stroke
			(width 0.2)
			(type default)
		)
		(layer "In1.Cu")
	)
	(gr_line
		(start 14.11859 -99.256342)
		(end 14.11859 -100.704142)
		(stroke
			(width 0.2)
			(type default)
		)
		(layer "In1.Cu")
	)
	(gr_line
		(start 14.28242 -103.213662)
		(end 14.28242 -101.765862)
		(stroke
			(width 0.2)
			(type default)
		)
		(layer "In1.Cu")
	)
	(gr_arc
		(start 14.28242 -101.765862)
		(mid 14.00048 -101.483922)
		(end 13.71854 -101.765862)
		(stroke
			(width 0.2)
			(type default)
		)
		(layer "In1.Cu")
	)
	(gr_line
		(start 14.4272 -98.903536)
		(end 14.427454 -98.903536)
		(stroke
			(width 0.2)
			(type default)
		)
		(layer "In1.Cu")
	)
	(gr_arc
		(start 14.427454 -98.903536)
		(mid 14.831314 -98.541332)
		(end 14.46911 -98.137472)
		(stroke
			(width 0.2)
			(type default)
		)
		(layer "In1.Cu")
	)
	(gr_line
		(start 14.46911 -98.137472)
		(end 13.52931 -98.086672)
		(stroke
			(width 0.2)
			(type default)
		)
		(layer "In1.Cu")
	)
	(gr_line
		(start 14.68247 -100.704142)
		(end 14.68247 -99.256342)
		(stroke
			(width 0.2)
			(type default)
		)
		(layer "In1.Cu")
	)
	(gr_arc
		(start 14.68247 -99.256342)
		(mid 14.40053 -98.974402)
		(end 14.11859 -99.256342)
		(stroke
			(width 0.2)
			(type default)
		)
		(layer "In1.Cu")
	)
	(gr_arc
		(start 15.31747 -103.213662)
		(mid 15.59941 -103.495602)
		(end 15.88135 -103.213662)
		(stroke
			(width 0.2)
			(type default)
		)
		(layer "In1.Cu")
	)
	(gr_line
		(start 15.31747 -101.765862)
		(end 15.31747 -103.213662)
		(stroke
			(width 0.2)
			(type default)
		)
		(layer "In1.Cu")
	)
	(gr_arc
		(start 15.71752 -100.704142)
		(mid 15.99946 -100.986082)
		(end 16.2814 -100.704142)
		(stroke
			(width 0.2)
			(type default)
		)
		(layer "In1.Cu")
	)
	(gr_line
		(start 15.71752 -99.256342)
		(end 15.71752 -100.704142)
		(stroke
			(width 0.2)
			(type default)
		)
		(layer "In1.Cu")
	)
	(gr_line
		(start 15.88135 -103.213662)
		(end 15.88135 -101.765862)
		(stroke
			(width 0.2)
			(type default)
		)
		(layer "In1.Cu")
	)
	(gr_arc
		(start 15.88135 -101.765862)
		(mid 15.59941 -101.483922)
		(end 15.31747 -101.765862)
		(stroke
			(width 0.2)
			(type default)
		)
		(layer "In1.Cu")
	)
	(gr_line
		(start 15.936468 -98.88093)
		(end 16.876268 -98.90633)
		(stroke
			(width 0.2)
			(type default)
		)
		(layer "In1.Cu")
	)
	(gr_line
		(start 15.936468 -98.87839)
		(end 15.936468 -98.88093)
		(stroke
			(width 0.2)
			(type default)
		)
		(layer "In1.Cu")
	)
	(gr_arc
		(start 15.957296 -98.111818)
		(mid 15.563596 -98.48469)
		(end 15.936468 -98.87839)
		(stroke
			(width 0.2)
			(type default)
		)
		(layer "In1.Cu")
	)
	(gr_line
		(start 15.957296 -98.109532)
		(end 15.957296 -98.111818)
		(stroke
			(width 0.2)
			(type default)
		)
		(layer "In1.Cu")
	)
	(gr_line
		(start 15.95755 -98.109278)
		(end 15.957296 -98.109532)
		(stroke
			(width 0.2)
			(type default)
		)
		(layer "In1.Cu")
	)
	(gr_arc
		(start 16.11757 -103.213662)
		(mid 16.39951 -103.495602)
		(end 16.68145 -103.213662)
		(stroke
			(width 0.2)
			(type default)
		)
		(layer "In1.Cu")
	)
	(gr_line
		(start 16.11757 -101.765862)
		(end 16.11757 -103.213662)
		(stroke
			(width 0.2)
			(type default)
		)
		(layer "In1.Cu")
	)
	(gr_line
		(start 16.2814 -100.704142)
		(end 16.2814 -99.256342)
		(stroke
			(width 0.2)
			(type default)
		)
		(layer "In1.Cu")
	)
	(gr_arc
		(start 16.2814 -99.256342)
		(mid 15.99946 -98.974402)
		(end 15.71752 -99.256342)
		(stroke
			(width 0.2)
			(type default)
		)
		(layer "In1.Cu")
	)
	(gr_arc
		(start 16.51762 -100.704142)
		(mid 16.79956 -100.986082)
		(end 17.0815 -100.704142)
		(stroke
			(width 0.2)
			(type default)
		)
		(layer "In1.Cu")
	)
	(gr_line
		(start 16.51762 -99.256342)
		(end 16.51762 -100.704142)
		(stroke
			(width 0.2)
			(type default)
		)
		(layer "In1.Cu")
	)
	(gr_line
		(start 16.68145 -103.213662)
		(end 16.68145 -101.765862)
		(stroke
			(width 0.2)
			(type default)
		)
		(layer "In1.Cu")
	)
	(gr_arc
		(start 16.68145 -101.765862)
		(mid 16.39951 -101.483922)
		(end 16.11757 -101.765862)
		(stroke
			(width 0.2)
			(type default)
		)
		(layer "In1.Cu")
	)
	(gr_line
		(start 16.876268 -98.90633)
		(end 16.876268 -98.90379)
		(stroke
			(width 0.2)
			(type default)
		)
		(layer "In1.Cu")
	)
	(gr_arc
		(start 16.876268 -98.90379)
		(mid 17.269968 -98.530918)
		(end 16.897096 -98.137218)
		(stroke
			(width 0.2)
			(type default)
		)
		(layer "In1.Cu")
	)
	(gr_line
		(start 16.897096 -98.137218)
		(end 16.897096 -98.134678)
		(stroke
			(width 0.2)
			(type default)
		)
		(layer "In1.Cu")
	)
	(gr_line
		(start 16.897096 -98.134678)
		(end 15.95755 -98.109278)
		(stroke
			(width 0.2)
			(type default)
		)
		(layer "In1.Cu")
	)
	(gr_line
		(start 17.0815 -100.704142)
		(end 17.0815 -99.256342)
		(stroke
			(width 0.2)
			(type default)
		)
		(layer "In1.Cu")
	)
	(gr_arc
		(start 17.0815 -99.256342)
		(mid 16.79956 -98.974402)
		(end 16.51762 -99.256342)
		(stroke
			(width 0.2)
			(type default)
		)
		(layer "In1.Cu")
	)
	(gr_arc
		(start 17.71777 -103.213662)
		(mid 17.99971 -103.495602)
		(end 18.28165 -103.213662)
		(stroke
			(width 0.2)
			(type default)
		)
		(layer "In1.Cu")
	)
	(gr_line
		(start 17.71777 -101.765862)
		(end 17.71777 -103.213662)
		(stroke
			(width 0.2)
			(type default)
		)
		(layer "In1.Cu")
	)
	(gr_arc
		(start 18.11782 -100.704142)
		(mid 18.39976 -100.986082)
		(end 18.6817 -100.704142)
		(stroke
			(width 0.2)
			(type default)
		)
		(layer "In1.Cu")
	)
	(gr_line
		(start 18.11782 -99.256342)
		(end 18.11782 -100.704142)
		(stroke
			(width 0.2)
			(type default)
		)
		(layer "In1.Cu")
	)
	(gr_line
		(start 18.258282 -98.929444)
		(end 19.325082 -98.929444)
		(stroke
			(width 0.2)
			(type default)
		)
		(layer "In1.Cu")
	)
	(gr_arc
		(start 18.258536 -98.162364)
		(mid 17.874742 -98.545777)
		(end 18.258282 -98.929444)
		(stroke
			(width 0.2)
			(type default)
		)
		(layer "In1.Cu")
	)
	(gr_line
		(start 18.28165 -103.213662)
		(end 18.28165 -101.765862)
		(stroke
			(width 0.2)
			(type default)
		)
		(layer "In1.Cu")
	)
	(gr_arc
		(start 18.28165 -101.765862)
		(mid 17.99971 -101.483922)
		(end 17.71777 -101.765862)
		(stroke
			(width 0.2)
			(type default)
		)
		(layer "In1.Cu")
	)
	(gr_arc
		(start 18.51787 -103.213662)
		(mid 18.79981 -103.495602)
		(end 19.08175 -103.213662)
		(stroke
			(width 0.2)
			(type default)
		)
		(layer "In1.Cu")
	)
	(gr_line
		(start 18.51787 -101.765862)
		(end 18.51787 -103.213662)
		(stroke
			(width 0.2)
			(type default)
		)
		(layer "In1.Cu")
	)
	(gr_line
		(start 18.6817 -100.704142)
		(end 18.6817 -99.256342)
		(stroke
			(width 0.2)
			(type default)
		)
		(layer "In1.Cu")
	)
	(gr_arc
		(start 18.6817 -99.256342)
		(mid 18.39976 -98.974402)
		(end 18.11782 -99.256342)
		(stroke
			(width 0.2)
			(type default)
		)
		(layer "In1.Cu")
	)
	(gr_arc
		(start 18.91792 -100.704142)
		(mid 19.19986 -100.986082)
		(end 19.4818 -100.704142)
		(stroke
			(width 0.2)
			(type default)
		)
		(layer "In1.Cu")
	)
	(gr_line
		(start 18.91792 -99.256342)
		(end 18.91792 -100.704142)
		(stroke
			(width 0.2)
			(type default)
		)
		(layer "In1.Cu")
	)
	(gr_line
		(start 19.08175 -103.213662)
		(end 19.08175 -101.765862)
		(stroke
			(width 0.2)
			(type default)
		)
		(layer "In1.Cu")
	)
	(gr_arc
		(start 19.08175 -101.765862)
		(mid 18.79981 -101.483922)
		(end 18.51787 -101.765862)
		(stroke
			(width 0.2)
			(type default)
		)
		(layer "In1.Cu")
	)
	(gr_arc
		(start 19.325082 -98.929444)
		(mid 19.708622 -98.545904)
		(end 19.325082 -98.162364)
		(stroke
			(width 0.2)
			(type default)
		)
		(layer "In1.Cu")
	)
	(gr_line
		(start 19.325082 -98.162364)
		(end 18.258536 -98.162364)
		(stroke
			(width 0.2)
			(type default)
		)
		(layer "In1.Cu")
	)
	(gr_line
		(start 19.4818 -100.704142)
		(end 19.4818 -99.256342)
		(stroke
			(width 0.2)
			(type default)
		)
		(layer "In1.Cu")
	)
	(gr_arc
		(start 19.4818 -99.256342)
		(mid 19.19986 -98.974402)
		(end 18.91792 -99.256342)
		(stroke
			(width 0.2)
			(type default)
		)
		(layer "In1.Cu")
	)
	(gr_arc
		(start 25.500076 -78.010004)
		(mid 26.914287 -77.424219)
		(end 27.500072 -76.010008)
		(stroke
			(width 1.524)
			(type default)
		)
		(layer "In1.Cu")
	)
	(gr_line
		(start 26.34996 -251.000006)
		(end 4.99999 -251.000006)
		(stroke
			(width 1.524)
			(type default)
		)
		(layer "In1.Cu")
	)
	(gr_line
		(start 27.349958 -258.59994)
		(end 27.349958 -252.000004)
		(stroke
			(width 1.524)
			(type default)
		)
		(layer "In1.Cu")
	)
	(gr_arc
		(start 27.349958 -252.000004)
		(mid 27.057065 -251.292899)
		(end 26.34996 -251.000006)
		(stroke
			(width 1.524)
			(type default)
		)
		(layer "In1.Cu")
	)
	(gr_line
		(start 27.500072 -76.010008)
		(end 27.500072 -60.01004)
		(stroke
			(width 1.524)
			(type default)
		)
		(layer "In1.Cu")
	)
	(gr_arc
		(start 29.500068 -58.010044)
		(mid 28.085859 -58.59583)
		(end 27.500072 -60.01004)
		(stroke
			(width 1.524)
			(type default)
		)
		(layer "In1.Cu")
	)
	(gr_line
		(start 29.500068 -58.010044)
		(end 60.950094 -58.010044)
		(stroke
			(width 1.524)
			(type default)
		)
		(layer "In1.Cu")
	)
	(gr_line
		(start 32.334454 -90.479626)
		(end 33.311338 -90.479626)
		(stroke
			(width 0.2)
			(type default)
		)
		(layer "In1.Cu")
	)
	(gr_arc
		(start 32.334708 -89.712546)
		(mid 31.950914 -90.095959)
		(end 32.334454 -90.479626)
		(stroke
			(width 0.2)
			(type default)
		)
		(layer "In1.Cu")
	)
	(gr_arc
		(start 33.311338 -90.479626)
		(mid 33.694878 -90.096086)
		(end 33.311338 -89.712546)
		(stroke
			(width 0.2)
			(type default)
		)
		(layer "In1.Cu")
	)
	(gr_line
		(start 33.311338 -89.712546)
		(end 32.334708 -89.712546)
		(stroke
			(width 0.2)
			(type default)
		)
		(layer "In1.Cu")
	)
	(gr_line
		(start 34.550096 -258.59994)
		(end 27.349958 -258.59994)
		(stroke
			(width 5.08)
			(type default)
		)
		(layer "In1.Cu")
	)
	(gr_line
		(start 34.550096 -252.549914)
		(end 34.550096 -258.59994)
		(stroke
			(width 1.524)
			(type default)
		)
		(layer "In1.Cu")
	)
	(gr_line
		(start 35.382454 -90.479626)
		(end 36.359084 -90.479626)
		(stroke
			(width 0.2)
			(type default)
		)
		(layer "In1.Cu")
	)
	(gr_arc
		(start 35.382454 -89.712546)
		(mid 34.998914 -90.096086)
		(end 35.382454 -90.479626)
		(stroke
			(width 0.2)
			(type default)
		)
		(layer "In1.Cu")
	)
	(gr_arc
		(start 36.359084 -90.479626)
		(mid 36.742878 -90.096213)
		(end 36.359338 -89.712546)
		(stroke
			(width 0.2)
			(type default)
		)
		(layer "In1.Cu")
	)
	(gr_line
		(start 36.359338 -89.712546)
		(end 35.382454 -89.712546)
		(stroke
			(width 0.2)
			(type default)
		)
		(layer "In1.Cu")
	)
	(gr_line
		(start 36.450016 -258.59994)
		(end 36.450016 -252.549914)
		(stroke
			(width 1.524)
			(type default)
		)
		(layer "In1.Cu")
	)
	(gr_arc
		(start 36.450016 -252.549914)
		(mid 35.500056 -251.599954)
		(end 34.550096 -252.549914)
		(stroke
			(width 1.524)
			(type default)
		)
		(layer "In1.Cu")
	)
	(gr_line
		(start 38.430454 -90.479626)
		(end 39.407084 -90.479626)
		(stroke
			(width 0.2)
			(type default)
		)
		(layer "In1.Cu")
	)
	(gr_arc
		(start 38.430454 -89.712546)
		(mid 38.046914 -90.096086)
		(end 38.430454 -90.479626)
		(stroke
			(width 0.2)
			(type default)
		)
		(layer "In1.Cu")
	)
	(gr_arc
		(start 39.208456 -83.046824)
		(mid 39.591869 -83.430618)
		(end 39.975536 -83.047078)
		(stroke
			(width 0.2)
			(type default)
		)
		(layer "In1.Cu")
	)
	(gr_line
		(start 39.208456 -82.070194)
		(end 39.208456 -83.046824)
		(stroke
			(width 0.2)
			(type default)
		)
		(layer "In1.Cu")
	)
	(gr_arc
		(start 39.208456 -80.722978)
		(mid 39.591996 -81.106518)
		(end 39.975536 -80.722978)
		(stroke
			(width 0.2)
			(type default)
		)
		(layer "In1.Cu")
	)
	(gr_line
		(start 39.208456 -79.746094)
		(end 39.208456 -80.722978)
		(stroke
			(width 0.2)
			(type default)
		)
		(layer "In1.Cu")
	)
	(gr_arc
		(start 39.407084 -90.479626)
		(mid 39.790878 -90.096213)
		(end 39.407338 -89.712546)
		(stroke
			(width 0.2)
			(type default)
		)
		(layer "In1.Cu")
	)
	(gr_line
		(start 39.407338 -89.712546)
		(end 38.430454 -89.712546)
		(stroke
			(width 0.2)
			(type default)
		)
		(layer "In1.Cu")
	)
	(gr_line
		(start 39.975536 -83.047078)
		(end 39.975536 -82.070194)
		(stroke
			(width 0.2)
			(type default)
		)
		(layer "In1.Cu")
	)
	(gr_arc
		(start 39.975536 -82.070194)
		(mid 39.591996 -81.686654)
		(end 39.208456 -82.070194)
		(stroke
			(width 0.2)
			(type default)
		)
		(layer "In1.Cu")
	)
	(gr_line
		(start 39.975536 -80.722978)
		(end 39.975536 -79.746348)
		(stroke
			(width 0.2)
			(type default)
		)
		(layer "In1.Cu")
	)
	(gr_arc
		(start 39.975536 -79.746348)
		(mid 39.592123 -79.362554)
		(end 39.208456 -79.746094)
		(stroke
			(width 0.2)
			(type default)
		)
		(layer "In1.Cu")
	)
	(gr_line
		(start 41.351454 -90.479626)
		(end 42.328338 -90.479626)
		(stroke
			(width 0.2)
			(type default)
		)
		(layer "In1.Cu")
	)
	(gr_arc
		(start 41.351708 -89.712546)
		(mid 40.967914 -90.095959)
		(end 41.351454 -90.479626)
		(stroke
			(width 0.2)
			(type default)
		)
		(layer "In1.Cu")
	)
	(gr_arc
		(start 41.518078 -80.314038)
		(mid 41.800018 -80.595978)
		(end 42.081958 -80.314038)
		(stroke
			(width 0.2)
			(type default)
		)
		(layer "In1.Cu")
	)
	(gr_line
		(start 41.518078 -78.866238)
		(end 41.518078 -80.314038)
		(stroke
			(width 0.2)
			(type default)
		)
		(layer "In1.Cu")
	)
	(gr_line
		(start 41.693338 -83.873086)
		(end 42.670222 -83.873086)
		(stroke
			(width 0.2)
			(type default)
		)
		(layer "In1.Cu")
	)
	(gr_arc
		(start 41.693592 -83.106006)
		(mid 41.309798 -83.489419)
		(end 41.693338 -83.873086)
		(stroke
			(width 0.2)
			(type default)
		)
		(layer "In1.Cu")
	)
	(gr_arc
		(start 41.917874 -77.80401)
		(mid 42.199814 -78.08595)
		(end 42.481754 -77.80401)
		(stroke
			(width 0.2)
			(type default)
		)
		(layer "In1.Cu")
	)
	(gr_line
		(start 41.917874 -76.35621)
		(end 41.917874 -77.80401)
		(stroke
			(width 0.2)
			(type default)
		)
		(layer "In1.Cu")
	)
	(gr_line
		(start 42.081958 -80.314038)
		(end 42.081958 -78.866238)
		(stroke
			(width 0.2)
			(type default)
		)
		(layer "In1.Cu")
	)
	(gr_arc
		(start 42.081958 -78.866238)
		(mid 41.800018 -78.584298)
		(end 41.518078 -78.866238)
		(stroke
			(width 0.2)
			(type default)
		)
		(layer "In1.Cu")
	)
	(gr_line
		(start 42.111422 -75.138026)
		(end 43.088306 -75.138026)
		(stroke
			(width 0.2)
			(type default)
		)
		(layer "In1.Cu")
	)
	(gr_arc
		(start 42.111676 -74.370946)
		(mid 41.727882 -74.754359)
		(end 42.111422 -75.138026)
		(stroke
			(width 0.2)
			(type default)
		)
		(layer "In1.Cu")
	)
	(gr_arc
		(start 42.317924 -80.314038)
		(mid 42.599864 -80.595978)
		(end 42.881804 -80.314038)
		(stroke
			(width 0.2)
			(type default)
		)
		(layer "In1.Cu")
	)
	(gr_line
		(start 42.317924 -78.866238)
		(end 42.317924 -80.314038)
		(stroke
			(width 0.2)
			(type default)
		)
		(layer "In1.Cu")
	)
	(gr_arc
		(start 42.328338 -90.479626)
		(mid 42.711878 -90.096086)
		(end 42.328338 -89.712546)
		(stroke
			(width 0.2)
			(type default)
		)
		(layer "In1.Cu")
	)
	(gr_line
		(start 42.328338 -89.712546)
		(end 41.351708 -89.712546)
		(stroke
			(width 0.2)
			(type default)
		)
		(layer "In1.Cu")
	)
	(gr_line
		(start 42.481754 -77.80401)
		(end 42.481754 -76.35621)
		(stroke
			(width 0.2)
			(type default)
		)
		(layer "In1.Cu")
	)
	(gr_arc
		(start 42.481754 -76.35621)
		(mid 42.199814 -76.07427)
		(end 41.917874 -76.35621)
		(stroke
			(width 0.2)
			(type default)
		)
		(layer "In1.Cu")
	)
	(gr_arc
		(start 42.670222 -83.873086)
		(mid 43.053762 -83.489546)
		(end 42.670222 -83.106006)
		(stroke
			(width 0.2)
			(type default)
		)
		(layer "In1.Cu")
	)
	(gr_line
		(start 42.670222 -83.106006)
		(end 41.693592 -83.106006)
		(stroke
			(width 0.2)
			(type default)
		)
		(layer "In1.Cu")
	)
	(gr_arc
		(start 42.717974 -77.80401)
		(mid 42.999914 -78.08595)
		(end 43.281854 -77.80401)
		(stroke
			(width 0.2)
			(type default)
		)
		(layer "In1.Cu")
	)
	(gr_line
		(start 42.717974 -76.35621)
		(end 42.717974 -77.80401)
		(stroke
			(width 0.2)
			(type default)
		)
		(layer "In1.Cu")
	)
	(gr_line
		(start 42.881804 -80.314038)
		(end 42.881804 -78.866238)
		(stroke
			(width 0.2)
			(type default)
		)
		(layer "In1.Cu")
	)
	(gr_arc
		(start 42.881804 -78.866238)
		(mid 42.599864 -78.584298)
		(end 42.317924 -78.866238)
		(stroke
			(width 0.2)
			(type default)
		)
		(layer "In1.Cu")
	)
	(gr_arc
		(start 43.088306 -75.138026)
		(mid 43.471846 -74.754486)
		(end 43.088306 -74.370946)
		(stroke
			(width 0.2)
			(type default)
		)
		(layer "In1.Cu")
	)
	(gr_line
		(start 43.088306 -74.370946)
		(end 42.111676 -74.370946)
		(stroke
			(width 0.2)
			(type default)
		)
		(layer "In1.Cu")
	)
	(gr_line
		(start 43.281854 -77.80401)
		(end 43.281854 -76.35621)
		(stroke
			(width 0.2)
			(type default)
		)
		(layer "In1.Cu")
	)
	(gr_arc
		(start 43.281854 -76.35621)
		(mid 42.999914 -76.07427)
		(end 42.717974 -76.35621)
		(stroke
			(width 0.2)
			(type default)
		)
		(layer "In1.Cu")
	)
	(gr_arc
		(start 43.91787 -80.314038)
		(mid 44.19981 -80.595978)
		(end 44.48175 -80.314038)
		(stroke
			(width 0.2)
			(type default)
		)
		(layer "In1.Cu")
	)
	(gr_line
		(start 43.91787 -78.866238)
		(end 43.91787 -80.314038)
		(stroke
			(width 0.2)
			(type default)
		)
		(layer "In1.Cu")
	)
	(gr_arc
		(start 44.31792 -77.80401)
		(mid 44.59986 -78.08595)
		(end 44.8818 -77.80401)
		(stroke
			(width 0.2)
			(type default)
		)
		(layer "In1.Cu")
	)
	(gr_line
		(start 44.31792 -76.35621)
		(end 44.31792 -77.80401)
		(stroke
			(width 0.2)
			(type default)
		)
		(layer "In1.Cu")
	)
	(gr_line
		(start 44.48175 -80.314038)
		(end 44.48175 -78.866238)
		(stroke
			(width 0.2)
			(type default)
		)
		(layer "In1.Cu")
	)
	(gr_arc
		(start 44.48175 -78.866238)
		(mid 44.19981 -78.584298)
		(end 43.91787 -78.866238)
		(stroke
			(width 0.2)
			(type default)
		)
		(layer "In1.Cu")
	)
	(gr_line
		(start 44.511468 -75.290426)
		(end 45.488098 -75.290426)
		(stroke
			(width 0.2)
			(type default)
		)
		(layer "In1.Cu")
	)
	(gr_arc
		(start 44.511468 -74.523346)
		(mid 44.127928 -74.906886)
		(end 44.511468 -75.290426)
		(stroke
			(width 0.2)
			(type default)
		)
		(layer "In1.Cu")
	)
	(gr_line
		(start 44.647104 -83.885786)
		(end 45.623734 -83.885786)
		(stroke
			(width 0.2)
			(type default)
		)
		(layer "In1.Cu")
	)
	(gr_arc
		(start 44.647104 -83.118706)
		(mid 44.263564 -83.502246)
		(end 44.647104 -83.885786)
		(stroke
			(width 0.2)
			(type default)
		)
		(layer "In1.Cu")
	)
	(gr_arc
		(start 44.71797 -80.314038)
		(mid 44.99991 -80.595978)
		(end 45.28185 -80.314038)
		(stroke
			(width 0.2)
			(type default)
		)
		(layer "In1.Cu")
	)
	(gr_line
		(start 44.71797 -78.866238)
		(end 44.71797 -80.314038)
		(stroke
			(width 0.2)
			(type default)
		)
		(layer "In1.Cu")
	)
	(gr_line
		(start 44.8818 -77.80401)
		(end 44.8818 -76.35621)
		(stroke
			(width 0.2)
			(type default)
		)
		(layer "In1.Cu")
	)
	(gr_arc
		(start 44.8818 -76.35621)
		(mid 44.59986 -76.07427)
		(end 44.31792 -76.35621)
		(stroke
			(width 0.2)
			(type default)
		)
		(layer "In1.Cu")
	)
	(gr_arc
		(start 45.11802 -77.80401)
		(mid 45.39996 -78.08595)
		(end 45.6819 -77.80401)
		(stroke
			(width 0.2)
			(type default)
		)
		(layer "In1.Cu")
	)
	(gr_line
		(start 45.11802 -76.35621)
		(end 45.11802 -77.80401)
		(stroke
			(width 0.2)
			(type default)
		)
		(layer "In1.Cu")
	)
	(gr_line
		(start 45.28185 -80.314038)
		(end 45.28185 -78.866238)
		(stroke
			(width 0.2)
			(type default)
		)
		(layer "In1.Cu")
	)
	(gr_arc
		(start 45.28185 -78.866238)
		(mid 44.99991 -78.584298)
		(end 44.71797 -78.866238)
		(stroke
			(width 0.2)
			(type default)
		)
		(layer "In1.Cu")
	)
	(gr_arc
		(start 45.488098 -75.290426)
		(mid 45.871892 -74.907013)
		(end 45.488352 -74.523346)
		(stroke
			(width 0.2)
			(type default)
		)
		(layer "In1.Cu")
	)
	(gr_line
		(start 45.488352 -74.523346)
		(end 44.511468 -74.523346)
		(stroke
			(width 0.2)
			(type default)
		)
		(layer "In1.Cu")
	)
	(gr_arc
		(start 45.623734 -83.885786)
		(mid 46.007528 -83.502373)
		(end 45.623988 -83.118706)
		(stroke
			(width 0.2)
			(type default)
		)
		(layer "In1.Cu")
	)
	(gr_line
		(start 45.623988 -83.118706)
		(end 44.647104 -83.118706)
		(stroke
			(width 0.2)
			(type default)
		)
		(layer "In1.Cu")
	)
	(gr_line
		(start 45.6819 -77.80401)
		(end 45.6819 -76.35621)
		(stroke
			(width 0.2)
			(type default)
		)
		(layer "In1.Cu")
	)
	(gr_arc
		(start 45.6819 -76.35621)
		(mid 45.39996 -76.07427)
		(end 45.11802 -76.35621)
		(stroke
			(width 0.2)
			(type default)
		)
		(layer "In1.Cu")
	)
	(gr_line
		(start 47.649892 -258.59994)
		(end 36.450016 -258.59994)
		(stroke
			(width 5.08)
			(type default)
		)
		(layer "In1.Cu")
	)
	(gr_line
		(start 47.649892 -252.000004)
		(end 47.649892 -258.59994)
		(stroke
			(width 1.524)
			(type default)
		)
		(layer "In1.Cu")
	)
	(gr_arc
		(start 48.606456 -87.746078)
		(mid 48.989996 -88.129618)
		(end 49.373536 -87.746078)
		(stroke
			(width 0.2)
			(type default)
		)
		(layer "In1.Cu")
	)
	(gr_line
		(start 48.606456 -86.769194)
		(end 48.606456 -87.746078)
		(stroke
			(width 0.2)
			(type default)
		)
		(layer "In1.Cu")
	)
	(gr_arc
		(start 48.606456 -84.913724)
		(mid 48.989869 -85.297518)
		(end 49.373536 -84.913978)
		(stroke
			(width 0.2)
			(type default)
		)
		(layer "In1.Cu")
	)
	(gr_line
		(start 48.606456 -83.937094)
		(end 48.606456 -84.913724)
		(stroke
			(width 0.2)
			(type default)
		)
		(layer "In1.Cu")
	)
	(gr_arc
		(start 48.64989 -251.000006)
		(mid 47.942785 -251.292899)
		(end 47.649892 -252.000004)
		(stroke
			(width 1.524)
			(type default)
		)
		(layer "In1.Cu")
	)
	(gr_line
		(start 49.373536 -87.746078)
		(end 49.373536 -86.769448)
		(stroke
			(width 0.2)
			(type default)
		)
		(layer "In1.Cu")
	)
	(gr_arc
		(start 49.373536 -86.769448)
		(mid 48.990123 -86.385654)
		(end 48.606456 -86.769194)
		(stroke
			(width 0.2)
			(type default)
		)
		(layer "In1.Cu")
	)
	(gr_line
		(start 49.373536 -84.913978)
		(end 49.373536 -83.937094)
		(stroke
			(width 0.2)
			(type default)
		)
		(layer "In1.Cu")
	)
	(gr_arc
		(start 49.373536 -83.937094)
		(mid 48.989996 -83.553554)
		(end 48.606456 -83.937094)
		(stroke
			(width 0.2)
			(type default)
		)
		(layer "In1.Cu")
	)
	(gr_arc
		(start 50.317908 -80.314038)
		(mid 50.599848 -80.595978)
		(end 50.881788 -80.314038)
		(stroke
			(width 0.2)
			(type default)
		)
		(layer "In1.Cu")
	)
	(gr_line
		(start 50.317908 -78.866238)
		(end 50.317908 -80.314038)
		(stroke
			(width 0.2)
			(type default)
		)
		(layer "In1.Cu")
	)
	(gr_arc
		(start 50.717958 -77.80401)
		(mid 50.999898 -78.08595)
		(end 51.281838 -77.80401)
		(stroke
			(width 0.2)
			(type default)
		)
		(layer "In1.Cu")
	)
	(gr_line
		(start 50.717958 -76.35621)
		(end 50.717958 -77.80401)
		(stroke
			(width 0.2)
			(type default)
		)
		(layer "In1.Cu")
	)
	(gr_line
		(start 50.881788 -80.314038)
		(end 50.881788 -78.866238)
		(stroke
			(width 0.2)
			(type default)
		)
		(layer "In1.Cu")
	)
	(gr_arc
		(start 50.881788 -78.866238)
		(mid 50.599848 -78.584298)
		(end 50.317908 -78.866238)
		(stroke
			(width 0.2)
			(type default)
		)
		(layer "In1.Cu")
	)
	(gr_line
		(start 50.911506 -75.290426)
		(end 51.888136 -75.290426)
		(stroke
			(width 0.2)
			(type default)
		)
		(layer "In1.Cu")
	)
	(gr_arc
		(start 50.911506 -74.523346)
		(mid 50.527966 -74.906886)
		(end 50.911506 -75.290426)
		(stroke
			(width 0.2)
			(type default)
		)
		(layer "In1.Cu")
	)
	(gr_arc
		(start 51.118008 -80.314038)
		(mid 51.399948 -80.595978)
		(end 51.681888 -80.314038)
		(stroke
			(width 0.2)
			(type default)
		)
		(layer "In1.Cu")
	)
	(gr_line
		(start 51.118008 -78.866238)
		(end 51.118008 -80.314038)
		(stroke
			(width 0.2)
			(type default)
		)
		(layer "In1.Cu")
	)
	(gr_line
		(start 51.281838 -77.80401)
		(end 51.281838 -76.35621)
		(stroke
			(width 0.2)
			(type default)
		)
		(layer "In1.Cu")
	)
	(gr_arc
		(start 51.281838 -76.35621)
		(mid 50.999898 -76.07427)
		(end 50.717958 -76.35621)
		(stroke
			(width 0.2)
			(type default)
		)
		(layer "In1.Cu")
	)
	(gr_arc
		(start 51.518058 -77.80401)
		(mid 51.799998 -78.08595)
		(end 52.081938 -77.80401)
		(stroke
			(width 0.2)
			(type default)
		)
		(layer "In1.Cu")
	)
	(gr_line
		(start 51.518058 -76.35621)
		(end 51.518058 -77.80401)
		(stroke
			(width 0.2)
			(type default)
		)
		(layer "In1.Cu")
	)
	(gr_line
		(start 51.681888 -80.314038)
		(end 51.681888 -78.866238)
		(stroke
			(width 0.2)
			(type default)
		)
		(layer "In1.Cu")
	)
	(gr_arc
		(start 51.681888 -78.866238)
		(mid 51.399948 -78.584298)
		(end 51.118008 -78.866238)
		(stroke
			(width 0.2)
			(type default)
		)
		(layer "In1.Cu")
	)
	(gr_arc
		(start 51.888136 -75.290426)
		(mid 52.27193 -74.907013)
		(end 51.88839 -74.523346)
		(stroke
			(width 0.2)
			(type default)
		)
		(layer "In1.Cu")
	)
	(gr_line
		(start 51.88839 -74.523346)
		(end 50.911506 -74.523346)
		(stroke
			(width 0.2)
			(type default)
		)
		(layer "In1.Cu")
	)
	(gr_line
		(start 52.081938 -77.80401)
		(end 52.081938 -76.35621)
		(stroke
			(width 0.2)
			(type default)
		)
		(layer "In1.Cu")
	)
	(gr_arc
		(start 52.081938 -76.35621)
		(mid 51.799998 -76.07427)
		(end 51.518058 -76.35621)
		(stroke
			(width 0.2)
			(type default)
		)
		(layer "In1.Cu")
	)
	(gr_arc
		(start 52.717954 -80.314038)
		(mid 52.999894 -80.595978)
		(end 53.281834 -80.314038)
		(stroke
			(width 0.2)
			(type default)
		)
		(layer "In1.Cu")
	)
	(gr_line
		(start 52.717954 -78.866238)
		(end 52.717954 -80.314038)
		(stroke
			(width 0.2)
			(type default)
		)
		(layer "In1.Cu")
	)
	(gr_arc
		(start 53.118004 -77.80401)
		(mid 53.399944 -78.08595)
		(end 53.681884 -77.80401)
		(stroke
			(width 0.2)
			(type default)
		)
		(layer "In1.Cu")
	)
	(gr_line
		(start 53.118004 -76.35621)
		(end 53.118004 -77.80401)
		(stroke
			(width 0.2)
			(type default)
		)
		(layer "In1.Cu")
	)
	(gr_line
		(start 53.281834 -80.314038)
		(end 53.281834 -78.866238)
		(stroke
			(width 0.2)
			(type default)
		)
		(layer "In1.Cu")
	)
	(gr_arc
		(start 53.281834 -78.866238)
		(mid 52.999894 -78.584298)
		(end 52.717954 -78.866238)
		(stroke
			(width 0.2)
			(type default)
		)
		(layer "In1.Cu")
	)
	(gr_line
		(start 53.311298 -75.290426)
		(end 54.287928 -75.290426)
		(stroke
			(width 0.2)
			(type default)
		)
		(layer "In1.Cu")
	)
	(gr_arc
		(start 53.311298 -74.523346)
		(mid 52.927758 -74.906886)
		(end 53.311298 -75.290426)
		(stroke
			(width 0.2)
			(type default)
		)
		(layer "In1.Cu")
	)
	(gr_arc
		(start 53.518054 -80.314038)
		(mid 53.799994 -80.595978)
		(end 54.081934 -80.314038)
		(stroke
			(width 0.2)
			(type default)
		)
		(layer "In1.Cu")
	)
	(gr_line
		(start 53.518054 -78.866238)
		(end 53.518054 -80.314038)
		(stroke
			(width 0.2)
			(type default)
		)
		(layer "In1.Cu")
	)
	(gr_line
		(start 53.681884 -77.80401)
		(end 53.681884 -76.35621)
		(stroke
			(width 0.2)
			(type default)
		)
		(layer "In1.Cu")
	)
	(gr_arc
		(start 53.681884 -76.35621)
		(mid 53.399944 -76.07427)
		(end 53.118004 -76.35621)
		(stroke
			(width 0.2)
			(type default)
		)
		(layer "In1.Cu")
	)
	(gr_arc
		(start 53.91785 -77.80401)
		(mid 54.19979 -78.08595)
		(end 54.48173 -77.80401)
		(stroke
			(width 0.2)
			(type default)
		)
		(layer "In1.Cu")
	)
	(gr_line
		(start 53.91785 -76.35621)
		(end 53.91785 -77.80401)
		(stroke
			(width 0.2)
			(type default)
		)
		(layer "In1.Cu")
	)
	(gr_line
		(start 54.081934 -80.314038)
		(end 54.081934 -78.866238)
		(stroke
			(width 0.2)
			(type default)
		)
		(layer "In1.Cu")
	)
	(gr_arc
		(start 54.081934 -78.866238)
		(mid 53.799994 -78.584298)
		(end 53.518054 -78.866238)
		(stroke
			(width 0.2)
			(type default)
		)
		(layer "In1.Cu")
	)
	(gr_arc
		(start 54.287928 -75.290426)
		(mid 54.671722 -74.907013)
		(end 54.288182 -74.523346)
		(stroke
			(width 0.2)
			(type default)
		)
		(layer "In1.Cu")
	)
	(gr_line
		(start 54.288182 -74.523346)
		(end 53.311298 -74.523346)
		(stroke
			(width 0.2)
			(type default)
		)
		(layer "In1.Cu")
	)
	(gr_line
		(start 54.48173 -77.80401)
		(end 54.48173 -76.35621)
		(stroke
			(width 0.2)
			(type default)
		)
		(layer "In1.Cu")
	)
	(gr_arc
		(start 54.48173 -76.35621)
		(mid 54.19979 -76.07427)
		(end 53.91785 -76.35621)
		(stroke
			(width 0.2)
			(type default)
		)
		(layer "In1.Cu")
	)
	(gr_arc
		(start 60.950094 -58.010044)
		(mid 61.657199 -57.717151)
		(end 61.950092 -57.010046)
		(stroke
			(width 1.524)
			(type default)
		)
		(layer "In1.Cu")
	)
	(gr_line
		(start 61.950092 -57.010046)
		(end 61.950092 -17.999964)
		(stroke
			(width 1.524)
			(type default)
		)
		(layer "In1.Cu")
	)
	(gr_arc
		(start 62.95009 -16.999966)
		(mid 62.242978 -17.29286)
		(end 61.950092 -17.999964)
		(stroke
			(width 1.524)
			(type default)
		)
		(layer "In1.Cu")
	)
	(gr_line
		(start 62.95009 -16.999966)
		(end 73.449942 -16.999966)
		(stroke
			(width 1.524)
			(type default)
		)
		(layer "In1.Cu")
	)
	(gr_line
		(start 66.34988 -251.000006)
		(end 48.64989 -251.000006)
		(stroke
			(width 1.524)
			(type default)
		)
		(layer "In1.Cu")
	)
	(gr_rect
		(start 67.1322 -254.4064)
		(end 151.4602 -258.5974)
		(stroke
			(width 0)
			(type default)
		)
		(fill no)
		(layer "In1.Cu")
	)
	(gr_line
		(start 67.349878 -258.59994)
		(end 67.349878 -252.000004)
		(stroke
			(width 1.524)
			(type default)
		)
		(layer "In1.Cu")
	)
	(gr_arc
		(start 67.349878 -252.000004)
		(mid 67.056985 -251.292899)
		(end 66.34988 -251.000006)
		(stroke
			(width 1.524)
			(type default)
		)
		(layer "In1.Cu")
	)
	(gr_arc
		(start 73.449942 -16.999966)
		(mid 74.157047 -16.707073)
		(end 74.44994 -15.999968)
		(stroke
			(width 1.524)
			(type default)
		)
		(layer "In1.Cu")
	)
	(gr_line
		(start 74.44994 -15.999968)
		(end 74.44994 -0.999998)
		(stroke
			(width 1.524)
			(type default)
		)
		(layer "In1.Cu")
	)
	(gr_arc
		(start 75.449938 0)
		(mid 74.742807 -0.292879)
		(end 74.44994 -0.999998)
		(stroke
			(width 1.524)
			(type default)
		)
		(layer "In1.Cu")
	)
	(gr_line
		(start 75.449938 0)
		(end 281.485086 0)
		(stroke
			(width 1.524)
			(type default)
		)
		(layer "In1.Cu")
	)
	(gr_line
		(start 76.157074 -37.042852)
		(end 77.133958 -37.042852)
		(stroke
			(width 0.2)
			(type default)
		)
		(layer "In1.Cu")
	)
	(gr_arc
		(start 76.157328 -36.275772)
		(mid 75.773534 -36.659185)
		(end 76.157074 -37.042852)
		(stroke
			(width 0.2)
			(type default)
		)
		(layer "In1.Cu")
	)
	(gr_arc
		(start 77.133958 -37.042852)
		(mid 77.517498 -36.659312)
		(end 77.133958 -36.275772)
		(stroke
			(width 0.2)
			(type default)
		)
		(layer "In1.Cu")
	)
	(gr_line
		(start 77.133958 -36.275772)
		(end 76.157328 -36.275772)
		(stroke
			(width 0.2)
			(type default)
		)
		(layer "In1.Cu")
	)
	(gr_line
		(start 77.686408 -41.98874)
		(end 78.663038 -41.98874)
		(stroke
			(width 0.2)
			(type default)
		)
		(layer "In1.Cu")
	)
	(gr_arc
		(start 77.686408 -41.22166)
		(mid 77.302868 -41.6052)
		(end 77.686408 -41.98874)
		(stroke
			(width 0.2)
			(type default)
		)
		(layer "In1.Cu")
	)
	(gr_arc
		(start 78.663038 -41.98874)
		(mid 79.046832 -41.605327)
		(end 78.663292 -41.22166)
		(stroke
			(width 0.2)
			(type default)
		)
		(layer "In1.Cu")
	)
	(gr_line
		(start 78.663292 -41.22166)
		(end 77.686408 -41.22166)
		(stroke
			(width 0.2)
			(type default)
		)
		(layer "In1.Cu")
	)
	(gr_line
		(start 79.604108 -40.00754)
		(end 80.580738 -40.00754)
		(stroke
			(width 0.2)
			(type default)
		)
		(layer "In1.Cu")
	)
	(gr_arc
		(start 79.604108 -39.24046)
		(mid 79.220568 -39.624)
		(end 79.604108 -40.00754)
		(stroke
			(width 0.2)
			(type default)
		)
		(layer "In1.Cu")
	)
	(gr_arc
		(start 80.580738 -40.00754)
		(mid 80.964532 -39.624127)
		(end 80.580992 -39.24046)
		(stroke
			(width 0.2)
			(type default)
		)
		(layer "In1.Cu")
	)
	(gr_line
		(start 80.580992 -39.24046)
		(end 79.604108 -39.24046)
		(stroke
			(width 0.2)
			(type default)
		)
		(layer "In1.Cu")
	)
	(gr_arc
		(start 80.84566 -37.312092)
		(mid 81.2292 -37.695632)
		(end 81.61274 -37.312092)
		(stroke
			(width 0.2)
			(type default)
		)
		(layer "In1.Cu")
	)
	(gr_line
		(start 80.84566 -36.335208)
		(end 80.84566 -37.312092)
		(stroke
			(width 0.2)
			(type default)
		)
		(layer "In1.Cu")
	)
	(gr_line
		(start 81.61274 -37.312092)
		(end 81.61274 -36.335462)
		(stroke
			(width 0.2)
			(type default)
		)
		(layer "In1.Cu")
	)
	(gr_arc
		(start 81.61274 -36.335462)
		(mid 81.229327 -35.951668)
		(end 80.84566 -36.335208)
		(stroke
			(width 0.2)
			(type default)
		)
		(layer "In1.Cu")
	)
	(gr_arc
		(start 82.527648 -38.736524)
		(mid 82.911061 -39.120318)
		(end 83.294728 -38.736778)
		(stroke
			(width 0.2)
			(type default)
		)
		(layer "In1.Cu")
	)
	(gr_line
		(start 82.527648 -37.831776)
		(end 82.527648 -38.736524)
		(stroke
			(width 0.2)
			(type default)
		)
		(layer "In1.Cu")
	)
	(gr_arc
		(start 82.69986 -35.523678)
		(mid 83.0834 -35.907218)
		(end 83.46694 -35.523678)
		(stroke
			(width 0.2)
			(type default)
		)
		(layer "In1.Cu")
	)
	(gr_line
		(start 82.69986 -34.618676)
		(end 82.69986 -35.523678)
		(stroke
			(width 0.2)
			(type default)
		)
		(layer "In1.Cu")
	)
	(gr_line
		(start 83.294728 -38.736778)
		(end 83.294728 -37.831776)
		(stroke
			(width 0.2)
			(type default)
		)
		(layer "In1.Cu")
	)
	(gr_arc
		(start 83.294728 -37.831776)
		(mid 82.911188 -37.448236)
		(end 82.527648 -37.831776)
		(stroke
			(width 0.2)
			(type default)
		)
		(layer "In1.Cu")
	)
	(gr_line
		(start 83.46694 -35.523678)
		(end 83.46694 -34.61893)
		(stroke
			(width 0.2)
			(type default)
		)
		(layer "In1.Cu")
	)
	(gr_arc
		(start 83.46694 -34.61893)
		(mid 83.083527 -34.235136)
		(end 82.69986 -34.618676)
		(stroke
			(width 0.2)
			(type default)
		)
		(layer "In1.Cu")
	)
	(gr_line
		(start 83.69554 -37.754306)
		(end 83.723734 -38.770306)
		(stroke
			(width 0.2)
			(type default)
		)
		(layer "In1.Cu")
	)
	(gr_line
		(start 83.69808 -37.754306)
		(end 83.69554 -37.754306)
		(stroke
			(width 0.2)
			(type default)
		)
		(layer "In1.Cu")
	)
	(gr_line
		(start 83.723734 -38.770306)
		(end 83.723988 -38.77056)
		(stroke
			(width 0.2)
			(type default)
		)
		(layer "In1.Cu")
	)
	(gr_line
		(start 83.723988 -38.77056)
		(end 83.726274 -38.77056)
		(stroke
			(width 0.2)
			(type default)
		)
		(layer "In1.Cu")
	)
	(gr_arc
		(start 83.726274 -38.77056)
		(mid 84.094066 -39.11854)
		(end 84.442046 -38.750748)
		(stroke
			(width 0.2)
			(type default)
		)
		(layer "In1.Cu")
	)
	(gr_arc
		(start 84.413852 -37.734494)
		(mid 84.04606 -37.386514)
		(end 83.69808 -37.754306)
		(stroke
			(width 0.2)
			(type default)
		)
		(layer "In1.Cu")
	)
	(gr_line
		(start 84.416392 -37.734494)
		(end 84.413852 -37.734494)
		(stroke
			(width 0.2)
			(type default)
		)
		(layer "In1.Cu")
	)
	(gr_line
		(start 84.442046 -38.750748)
		(end 84.444586 -38.750748)
		(stroke
			(width 0.2)
			(type default)
		)
		(layer "In1.Cu")
	)
	(gr_line
		(start 84.444586 -38.750748)
		(end 84.416392 -37.734494)
		(stroke
			(width 0.2)
			(type default)
		)
		(layer "In1.Cu")
	)
	(gr_arc
		(start 84.60486 -33.789874)
		(mid 84.9884 -34.173414)
		(end 85.37194 -33.789874)
		(stroke
			(width 0.2)
			(type default)
		)
		(layer "In1.Cu")
	)
	(gr_line
		(start 84.60486 -32.884872)
		(end 84.60486 -33.789874)
		(stroke
			(width 0.2)
			(type default)
		)
		(layer "In1.Cu")
	)
	(gr_line
		(start 85.37194 -33.789874)
		(end 85.37194 -32.885126)
		(stroke
			(width 0.2)
			(type default)
		)
		(layer "In1.Cu")
	)
	(gr_arc
		(start 85.37194 -32.885126)
		(mid 84.988527 -32.501332)
		(end 84.60486 -32.884872)
		(stroke
			(width 0.2)
			(type default)
		)
		(layer "In1.Cu")
	)
	(gr_arc
		(start 85.93582 -45.3136)
		(mid 85.981201 -45.423159)
		(end 86.09076 -45.46854)
		(stroke
			(width 0.2)
			(type default)
		)
		(layer "In1.Cu")
	)
	(gr_line
		(start 85.93582 -45.1104)
		(end 85.93582 -45.3136)
		(stroke
			(width 0.2)
			(type default)
		)
		(layer "In1.Cu")
	)
	(gr_arc
		(start 85.93582 -44.6786)
		(mid 85.981201 -44.788159)
		(end 86.09076 -44.83354)
		(stroke
			(width 0.2)
			(type default)
		)
		(layer "In1.Cu")
	)
	(gr_line
		(start 85.93582 -44.4754)
		(end 85.93582 -44.6786)
		(stroke
			(width 0.2)
			(type default)
		)
		(layer "In1.Cu")
	)
	(gr_arc
		(start 85.93582 -43.6626)
		(mid 85.981201 -43.772159)
		(end 86.09076 -43.81754)
		(stroke
			(width 0.2)
			(type default)
		)
		(layer "In1.Cu")
	)
	(gr_line
		(start 85.93582 -43.4594)
		(end 85.93582 -43.6626)
		(stroke
			(width 0.2)
			(type default)
		)
		(layer "In1.Cu")
	)
	(gr_arc
		(start 85.93582 -43.0276)
		(mid 85.981201 -43.137159)
		(end 86.09076 -43.18254)
		(stroke
			(width 0.2)
			(type default)
		)
		(layer "In1.Cu")
	)
	(gr_line
		(start 85.93582 -42.8244)
		(end 85.93582 -43.0276)
		(stroke
			(width 0.2)
			(type default)
		)
		(layer "In1.Cu")
	)
	(gr_arc
		(start 85.93582 -42.0116)
		(mid 85.981201 -42.121159)
		(end 86.09076 -42.16654)
		(stroke
			(width 0.2)
			(type default)
		)
		(layer "In1.Cu")
	)
	(gr_line
		(start 85.93582 -41.8084)
		(end 85.93582 -42.0116)
		(stroke
			(width 0.2)
			(type default)
		)
		(layer "In1.Cu")
	)
	(gr_arc
		(start 85.93582 -41.3766)
		(mid 85.981201 -41.486159)
		(end 86.09076 -41.53154)
		(stroke
			(width 0.2)
			(type default)
		)
		(layer "In1.Cu")
	)
	(gr_line
		(start 85.93582 -41.1734)
		(end 85.93582 -41.3766)
		(stroke
			(width 0.2)
			(type default)
		)
		(layer "In1.Cu")
	)
	(gr_arc
		(start 85.93582 -40.3606)
		(mid 85.981201 -40.470159)
		(end 86.09076 -40.51554)
		(stroke
			(width 0.2)
			(type default)
		)
		(layer "In1.Cu")
	)
	(gr_line
		(start 85.93582 -40.1574)
		(end 85.93582 -40.3606)
		(stroke
			(width 0.2)
			(type default)
		)
		(layer "In1.Cu")
	)
	(gr_arc
		(start 85.93582 -39.7256)
		(mid 85.981201 -39.835159)
		(end 86.09076 -39.88054)
		(stroke
			(width 0.2)
			(type default)
		)
		(layer "In1.Cu")
	)
	(gr_line
		(start 85.93582 -39.5224)
		(end 85.93582 -39.7256)
		(stroke
			(width 0.2)
			(type default)
		)
		(layer "In1.Cu")
	)
	(gr_arc
		(start 85.93582 -38.7096)
		(mid 85.981201 -38.819159)
		(end 86.09076 -38.86454)
		(stroke
			(width 0.2)
			(type default)
		)
		(layer "In1.Cu")
	)
	(gr_line
		(start 85.93582 -38.5064)
		(end 85.93582 -38.7096)
		(stroke
			(width 0.2)
			(type default)
		)
		(layer "In1.Cu")
	)
	(gr_arc
		(start 85.93582 -38.0746)
		(mid 85.981201 -38.184159)
		(end 86.09076 -38.22954)
		(stroke
			(width 0.2)
			(type default)
		)
		(layer "In1.Cu")
	)
	(gr_line
		(start 85.93582 -37.8714)
		(end 85.93582 -38.0746)
		(stroke
			(width 0.2)
			(type default)
		)
		(layer "In1.Cu")
	)
	(gr_arc
		(start 85.93582 -37.0586)
		(mid 85.981201 -37.168159)
		(end 86.09076 -37.21354)
		(stroke
			(width 0.2)
			(type default)
		)
		(layer "In1.Cu")
	)
	(gr_line
		(start 85.93582 -36.8554)
		(end 85.93582 -37.0586)
		(stroke
			(width 0.2)
			(type default)
		)
		(layer "In1.Cu")
	)
	(gr_arc
		(start 85.93582 -36.4236)
		(mid 85.981201 -36.533159)
		(end 86.09076 -36.57854)
		(stroke
			(width 0.2)
			(type default)
		)
		(layer "In1.Cu")
	)
	(gr_line
		(start 85.93582 -36.2204)
		(end 85.93582 -36.4236)
		(stroke
			(width 0.2)
			(type default)
		)
		(layer "In1.Cu")
	)
	(gr_arc
		(start 85.93582 -35.4076)
		(mid 85.981201 -35.517159)
		(end 86.09076 -35.56254)
		(stroke
			(width 0.2)
			(type default)
		)
		(layer "In1.Cu")
	)
	(gr_line
		(start 85.93582 -35.2044)
		(end 85.93582 -35.4076)
		(stroke
			(width 0.2)
			(type default)
		)
		(layer "In1.Cu")
	)
	(gr_arc
		(start 85.93582 -34.7726)
		(mid 85.981201 -34.882159)
		(end 86.09076 -34.92754)
		(stroke
			(width 0.2)
			(type default)
		)
		(layer "In1.Cu")
	)
	(gr_line
		(start 85.93582 -34.5694)
		(end 85.93582 -34.7726)
		(stroke
			(width 0.2)
			(type default)
		)
		(layer "In1.Cu")
	)
	(gr_arc
		(start 85.93582 -33.7566)
		(mid 85.981201 -33.866159)
		(end 86.09076 -33.91154)
		(stroke
			(width 0.2)
			(type default)
		)
		(layer "In1.Cu")
	)
	(gr_line
		(start 85.93582 -33.5534)
		(end 85.93582 -33.7566)
		(stroke
			(width 0.2)
			(type default)
		)
		(layer "In1.Cu")
	)
	(gr_arc
		(start 85.93582 -33.1216)
		(mid 85.981201 -33.231159)
		(end 86.09076 -33.27654)
		(stroke
			(width 0.2)
			(type default)
		)
		(layer "In1.Cu")
	)
	(gr_line
		(start 85.93582 -32.9184)
		(end 85.93582 -33.1216)
		(stroke
			(width 0.2)
			(type default)
		)
		(layer "In1.Cu")
	)
	(gr_line
		(start 86.09076 -45.46854)
		(end 86.34476 -45.46854)
		(stroke
			(width 0.2)
			(type default)
		)
		(layer "In1.Cu")
	)
	(gr_arc
		(start 86.09076 -44.95546)
		(mid 85.981201 -45.000841)
		(end 85.93582 -45.1104)
		(stroke
			(width 0.2)
			(type default)
		)
		(layer "In1.Cu")
	)
	(gr_line
		(start 86.09076 -44.83354)
		(end 86.34476 -44.83354)
		(stroke
			(width 0.2)
			(type default)
		)
		(layer "In1.Cu")
	)
	(gr_arc
		(start 86.09076 -44.32046)
		(mid 85.981201 -44.365841)
		(end 85.93582 -44.4754)
		(stroke
			(width 0.2)
			(type default)
		)
		(layer "In1.Cu")
	)
	(gr_line
		(start 86.09076 -43.81754)
		(end 86.34476 -43.81754)
		(stroke
			(width 0.2)
			(type default)
		)
		(layer "In1.Cu")
	)
	(gr_arc
		(start 86.09076 -43.30446)
		(mid 85.981201 -43.349841)
		(end 85.93582 -43.4594)
		(stroke
			(width 0.2)
			(type default)
		)
		(layer "In1.Cu")
	)
	(gr_line
		(start 86.09076 -43.18254)
		(end 86.34476 -43.18254)
		(stroke
			(width 0.2)
			(type default)
		)
		(layer "In1.Cu")
	)
	(gr_arc
		(start 86.09076 -42.66946)
		(mid 85.981201 -42.714841)
		(end 85.93582 -42.8244)
		(stroke
			(width 0.2)
			(type default)
		)
		(layer "In1.Cu")
	)
	(gr_line
		(start 86.09076 -42.16654)
		(end 86.34476 -42.16654)
		(stroke
			(width 0.2)
			(type default)
		)
		(layer "In1.Cu")
	)
	(gr_arc
		(start 86.09076 -41.65346)
		(mid 85.981201 -41.698841)
		(end 85.93582 -41.8084)
		(stroke
			(width 0.2)
			(type default)
		)
		(layer "In1.Cu")
	)
	(gr_line
		(start 86.09076 -41.53154)
		(end 86.34476 -41.53154)
		(stroke
			(width 0.2)
			(type default)
		)
		(layer "In1.Cu")
	)
	(gr_arc
		(start 86.09076 -41.01846)
		(mid 85.981201 -41.063841)
		(end 85.93582 -41.1734)
		(stroke
			(width 0.2)
			(type default)
		)
		(layer "In1.Cu")
	)
	(gr_line
		(start 86.09076 -40.51554)
		(end 86.34476 -40.51554)
		(stroke
			(width 0.2)
			(type default)
		)
		(layer "In1.Cu")
	)
	(gr_arc
		(start 86.09076 -40.00246)
		(mid 85.981201 -40.047841)
		(end 85.93582 -40.1574)
		(stroke
			(width 0.2)
			(type default)
		)
		(layer "In1.Cu")
	)
	(gr_line
		(start 86.09076 -39.88054)
		(end 86.34476 -39.88054)
		(stroke
			(width 0.2)
			(type default)
		)
		(layer "In1.Cu")
	)
	(gr_arc
		(start 86.09076 -39.36746)
		(mid 85.981201 -39.412841)
		(end 85.93582 -39.5224)
		(stroke
			(width 0.2)
			(type default)
		)
		(layer "In1.Cu")
	)
	(gr_line
		(start 86.09076 -38.86454)
		(end 86.34476 -38.86454)
		(stroke
			(width 0.2)
			(type default)
		)
		(layer "In1.Cu")
	)
	(gr_arc
		(start 86.09076 -38.35146)
		(mid 85.981201 -38.396841)
		(end 85.93582 -38.5064)
		(stroke
			(width 0.2)
			(type default)
		)
		(layer "In1.Cu")
	)
	(gr_line
		(start 86.09076 -38.22954)
		(end 86.34476 -38.22954)
		(stroke
			(width 0.2)
			(type default)
		)
		(layer "In1.Cu")
	)
	(gr_arc
		(start 86.09076 -37.71646)
		(mid 85.981201 -37.761841)
		(end 85.93582 -37.8714)
		(stroke
			(width 0.2)
			(type default)
		)
		(layer "In1.Cu")
	)
	(gr_line
		(start 86.09076 -37.21354)
		(end 86.34476 -37.21354)
		(stroke
			(width 0.2)
			(type default)
		)
		(layer "In1.Cu")
	)
	(gr_arc
		(start 86.09076 -36.70046)
		(mid 85.981201 -36.745841)
		(end 85.93582 -36.8554)
		(stroke
			(width 0.2)
			(type default)
		)
		(layer "In1.Cu")
	)
	(gr_line
		(start 86.09076 -36.57854)
		(end 86.34476 -36.57854)
		(stroke
			(width 0.2)
			(type default)
		)
		(layer "In1.Cu")
	)
	(gr_arc
		(start 86.09076 -36.06546)
		(mid 85.981201 -36.110841)
		(end 85.93582 -36.2204)
		(stroke
			(width 0.2)
			(type default)
		)
		(layer "In1.Cu")
	)
	(gr_line
		(start 86.09076 -35.56254)
		(end 86.34476 -35.56254)
		(stroke
			(width 0.2)
			(type default)
		)
		(layer "In1.Cu")
	)
	(gr_arc
		(start 86.09076 -35.04946)
		(mid 85.981201 -35.094841)
		(end 85.93582 -35.2044)
		(stroke
			(width 0.2)
			(type default)
		)
		(layer "In1.Cu")
	)
	(gr_line
		(start 86.09076 -34.92754)
		(end 86.34476 -34.92754)
		(stroke
			(width 0.2)
			(type default)
		)
		(layer "In1.Cu")
	)
	(gr_arc
		(start 86.09076 -34.41446)
		(mid 85.981201 -34.459841)
		(end 85.93582 -34.5694)
		(stroke
			(width 0.2)
			(type default)
		)
		(layer "In1.Cu")
	)
	(gr_line
		(start 86.09076 -33.91154)
		(end 86.34476 -33.91154)
		(stroke
			(width 0.2)
			(type default)
		)
		(layer "In1.Cu")
	)
	(gr_arc
		(start 86.09076 -33.39846)
		(mid 85.981201 -33.443841)
		(end 85.93582 -33.5534)
		(stroke
			(width 0.2)
			(type default)
		)
		(layer "In1.Cu")
	)
	(gr_line
		(start 86.09076 -33.27654)
		(end 86.34476 -33.27654)
		(stroke
			(width 0.2)
			(type default)
		)
		(layer "In1.Cu")
	)
	(gr_arc
		(start 86.09076 -32.76346)
		(mid 85.981201 -32.808841)
		(end 85.93582 -32.9184)
		(stroke
			(width 0.2)
			(type default)
		)
		(layer "In1.Cu")
	)
	(gr_arc
		(start 86.34476 -45.46854)
		(mid 86.454319 -45.423159)
		(end 86.4997 -45.3136)
		(stroke
			(width 0.2)
			(type default)
		)
		(layer "In1.Cu")
	)
	(gr_line
		(start 86.34476 -44.95546)
		(end 86.09076 -44.95546)
		(stroke
			(width 0.2)
			(type default)
		)
		(layer "In1.Cu")
	)
	(gr_arc
		(start 86.34476 -44.83354)
		(mid 86.454319 -44.788159)
		(end 86.4997 -44.6786)
		(stroke
			(width 0.2)
			(type default)
		)
		(layer "In1.Cu")
	)
	(gr_line
		(start 86.34476 -44.32046)
		(end 86.09076 -44.32046)
		(stroke
			(width 0.2)
			(type default)
		)
		(layer "In1.Cu")
	)
	(gr_arc
		(start 86.34476 -43.81754)
		(mid 86.454319 -43.772159)
		(end 86.4997 -43.6626)
		(stroke
			(width 0.2)
			(type default)
		)
		(layer "In1.Cu")
	)
	(gr_line
		(start 86.34476 -43.30446)
		(end 86.09076 -43.30446)
		(stroke
			(width 0.2)
			(type default)
		)
		(layer "In1.Cu")
	)
	(gr_arc
		(start 86.34476 -43.18254)
		(mid 86.454319 -43.137159)
		(end 86.4997 -43.0276)
		(stroke
			(width 0.2)
			(type default)
		)
		(layer "In1.Cu")
	)
	(gr_line
		(start 86.34476 -42.66946)
		(end 86.09076 -42.66946)
		(stroke
			(width 0.2)
			(type default)
		)
		(layer "In1.Cu")
	)
	(gr_arc
		(start 86.34476 -42.16654)
		(mid 86.454319 -42.121159)
		(end 86.4997 -42.0116)
		(stroke
			(width 0.2)
			(type default)
		)
		(layer "In1.Cu")
	)
	(gr_line
		(start 86.34476 -41.65346)
		(end 86.09076 -41.65346)
		(stroke
			(width 0.2)
			(type default)
		)
		(layer "In1.Cu")
	)
	(gr_arc
		(start 86.34476 -41.53154)
		(mid 86.454319 -41.486159)
		(end 86.4997 -41.3766)
		(stroke
			(width 0.2)
			(type default)
		)
		(layer "In1.Cu")
	)
	(gr_line
		(start 86.34476 -41.01846)
		(end 86.09076 -41.01846)
		(stroke
			(width 0.2)
			(type default)
		)
		(layer "In1.Cu")
	)
	(gr_arc
		(start 86.34476 -40.51554)
		(mid 86.454319 -40.470159)
		(end 86.4997 -40.3606)
		(stroke
			(width 0.2)
			(type default)
		)
		(layer "In1.Cu")
	)
	(gr_line
		(start 86.34476 -40.00246)
		(end 86.09076 -40.00246)
		(stroke
			(width 0.2)
			(type default)
		)
		(layer "In1.Cu")
	)
	(gr_arc
		(start 86.34476 -39.88054)
		(mid 86.454319 -39.835159)
		(end 86.4997 -39.7256)
		(stroke
			(width 0.2)
			(type default)
		)
		(layer "In1.Cu")
	)
	(gr_line
		(start 86.34476 -39.36746)
		(end 86.09076 -39.36746)
		(stroke
			(width 0.2)
			(type default)
		)
		(layer "In1.Cu")
	)
	(gr_arc
		(start 86.34476 -38.86454)
		(mid 86.454319 -38.819159)
		(end 86.4997 -38.7096)
		(stroke
			(width 0.2)
			(type default)
		)
		(layer "In1.Cu")
	)
	(gr_line
		(start 86.34476 -38.35146)
		(end 86.09076 -38.35146)
		(stroke
			(width 0.2)
			(type default)
		)
		(layer "In1.Cu")
	)
	(gr_arc
		(start 86.34476 -38.22954)
		(mid 86.454319 -38.184159)
		(end 86.4997 -38.0746)
		(stroke
			(width 0.2)
			(type default)
		)
		(layer "In1.Cu")
	)
	(gr_line
		(start 86.34476 -37.71646)
		(end 86.09076 -37.71646)
		(stroke
			(width 0.2)
			(type default)
		)
		(layer "In1.Cu")
	)
	(gr_arc
		(start 86.34476 -37.21354)
		(mid 86.454319 -37.168159)
		(end 86.4997 -37.0586)
		(stroke
			(width 0.2)
			(type default)
		)
		(layer "In1.Cu")
	)
	(gr_line
		(start 86.34476 -36.70046)
		(end 86.09076 -36.70046)
		(stroke
			(width 0.2)
			(type default)
		)
		(layer "In1.Cu")
	)
	(gr_arc
		(start 86.34476 -36.57854)
		(mid 86.454319 -36.533159)
		(end 86.4997 -36.4236)
		(stroke
			(width 0.2)
			(type default)
		)
		(layer "In1.Cu")
	)
	(gr_line
		(start 86.34476 -36.06546)
		(end 86.09076 -36.06546)
		(stroke
			(width 0.2)
			(type default)
		)
		(layer "In1.Cu")
	)
	(gr_arc
		(start 86.34476 -35.56254)
		(mid 86.454319 -35.517159)
		(end 86.4997 -35.4076)
		(stroke
			(width 0.2)
			(type default)
		)
		(layer "In1.Cu")
	)
	(gr_line
		(start 86.34476 -35.04946)
		(end 86.09076 -35.04946)
		(stroke
			(width 0.2)
			(type default)
		)
		(layer "In1.Cu")
	)
	(gr_arc
		(start 86.34476 -34.92754)
		(mid 86.454319 -34.882159)
		(end 86.4997 -34.7726)
		(stroke
			(width 0.2)
			(type default)
		)
		(layer "In1.Cu")
	)
	(gr_line
		(start 86.34476 -34.41446)
		(end 86.09076 -34.41446)
		(stroke
			(width 0.2)
			(type default)
		)
		(layer "In1.Cu")
	)
	(gr_arc
		(start 86.34476 -33.91154)
		(mid 86.454319 -33.866159)
		(end 86.4997 -33.7566)
		(stroke
			(width 0.2)
			(type default)
		)
		(layer "In1.Cu")
	)
	(gr_line
		(start 86.34476 -33.39846)
		(end 86.09076 -33.39846)
		(stroke
			(width 0.2)
			(type default)
		)
		(layer "In1.Cu")
	)
	(gr_arc
		(start 86.34476 -33.27654)
		(mid 86.454319 -33.231159)
		(end 86.4997 -33.1216)
		(stroke
			(width 0.2)
			(type default)
		)
		(layer "In1.Cu")
	)
	(gr_line
		(start 86.34476 -32.76346)
		(end 86.09076 -32.76346)
		(stroke
			(width 0.2)
			(type default)
		)
		(layer "In1.Cu")
	)
	(gr_arc
		(start 86.49462 -45.3136)
		(mid 86.540001 -45.423159)
		(end 86.64956 -45.46854)
		(stroke
			(width 0.2)
			(type default)
		)
		(layer "In1.Cu")
	)
	(gr_line
		(start 86.49462 -45.1104)
		(end 86.49462 -45.3136)
		(stroke
			(width 0.2)
			(type default)
		)
		(layer "In1.Cu")
	)
	(gr_arc
		(start 86.49462 -44.6786)
		(mid 86.540001 -44.788159)
		(end 86.64956 -44.83354)
		(stroke
			(width 0.2)
			(type default)
		)
		(layer "In1.Cu")
	)
	(gr_line
		(start 86.49462 -44.4754)
		(end 86.49462 -44.6786)
		(stroke
			(width 0.2)
			(type default)
		)
		(layer "In1.Cu")
	)
	(gr_arc
		(start 86.49462 -43.6626)
		(mid 86.540001 -43.772159)
		(end 86.64956 -43.81754)
		(stroke
			(width 0.2)
			(type default)
		)
		(layer "In1.Cu")
	)
	(gr_line
		(start 86.49462 -43.4594)
		(end 86.49462 -43.6626)
		(stroke
			(width 0.2)
			(type default)
		)
		(layer "In1.Cu")
	)
	(gr_arc
		(start 86.49462 -43.0276)
		(mid 86.540001 -43.137159)
		(end 86.64956 -43.18254)
		(stroke
			(width 0.2)
			(type default)
		)
		(layer "In1.Cu")
	)
	(gr_line
		(start 86.49462 -42.8244)
		(end 86.49462 -43.0276)
		(stroke
			(width 0.2)
			(type default)
		)
		(layer "In1.Cu")
	)
	(gr_arc
		(start 86.49462 -42.0116)
		(mid 86.540001 -42.121159)
		(end 86.64956 -42.16654)
		(stroke
			(width 0.2)
			(type default)
		)
		(layer "In1.Cu")
	)
	(gr_line
		(start 86.49462 -41.8084)
		(end 86.49462 -42.0116)
		(stroke
			(width 0.2)
			(type default)
		)
		(layer "In1.Cu")
	)
	(gr_arc
		(start 86.49462 -41.3766)
		(mid 86.540001 -41.486159)
		(end 86.64956 -41.53154)
		(stroke
			(width 0.2)
			(type default)
		)
		(layer "In1.Cu")
	)
	(gr_line
		(start 86.49462 -41.1734)
		(end 86.49462 -41.3766)
		(stroke
			(width 0.2)
			(type default)
		)
		(layer "In1.Cu")
	)
	(gr_arc
		(start 86.49462 -40.3606)
		(mid 86.540001 -40.470159)
		(end 86.64956 -40.51554)
		(stroke
			(width 0.2)
			(type default)
		)
		(layer "In1.Cu")
	)
	(gr_line
		(start 86.49462 -40.1574)
		(end 86.49462 -40.3606)
		(stroke
			(width 0.2)
			(type default)
		)
		(layer "In1.Cu")
	)
	(gr_arc
		(start 86.49462 -39.7256)
		(mid 86.540001 -39.835159)
		(end 86.64956 -39.88054)
		(stroke
			(width 0.2)
			(type default)
		)
		(layer "In1.Cu")
	)
	(gr_line
		(start 86.49462 -39.5224)
		(end 86.49462 -39.7256)
		(stroke
			(width 0.2)
			(type default)
		)
		(layer "In1.Cu")
	)
	(gr_arc
		(start 86.49462 -38.7096)
		(mid 86.540001 -38.819159)
		(end 86.64956 -38.86454)
		(stroke
			(width 0.2)
			(type default)
		)
		(layer "In1.Cu")
	)
	(gr_line
		(start 86.49462 -38.5064)
		(end 86.49462 -38.7096)
		(stroke
			(width 0.2)
			(type default)
		)
		(layer "In1.Cu")
	)
	(gr_arc
		(start 86.49462 -38.0746)
		(mid 86.540001 -38.184159)
		(end 86.64956 -38.22954)
		(stroke
			(width 0.2)
			(type default)
		)
		(layer "In1.Cu")
	)
	(gr_line
		(start 86.49462 -37.8714)
		(end 86.49462 -38.0746)
		(stroke
			(width 0.2)
			(type default)
		)
		(layer "In1.Cu")
	)
	(gr_arc
		(start 86.49462 -37.0586)
		(mid 86.540001 -37.168159)
		(end 86.64956 -37.21354)
		(stroke
			(width 0.2)
			(type default)
		)
		(layer "In1.Cu")
	)
	(gr_line
		(start 86.49462 -36.8554)
		(end 86.49462 -37.0586)
		(stroke
			(width 0.2)
			(type default)
		)
		(layer "In1.Cu")
	)
	(gr_arc
		(start 86.49462 -36.4236)
		(mid 86.540001 -36.533159)
		(end 86.64956 -36.57854)
		(stroke
			(width 0.2)
			(type default)
		)
		(layer "In1.Cu")
	)
	(gr_line
		(start 86.49462 -36.2204)
		(end 86.49462 -36.4236)
		(stroke
			(width 0.2)
			(type default)
		)
		(layer "In1.Cu")
	)
	(gr_arc
		(start 86.49462 -35.4076)
		(mid 86.540001 -35.517159)
		(end 86.64956 -35.56254)
		(stroke
			(width 0.2)
			(type default)
		)
		(layer "In1.Cu")
	)
	(gr_line
		(start 86.49462 -35.2044)
		(end 86.49462 -35.4076)
		(stroke
			(width 0.2)
			(type default)
		)
		(layer "In1.Cu")
	)
	(gr_arc
		(start 86.49462 -34.7726)
		(mid 86.540001 -34.882159)
		(end 86.64956 -34.92754)
		(stroke
			(width 0.2)
			(type default)
		)
		(layer "In1.Cu")
	)
	(gr_line
		(start 86.49462 -34.5694)
		(end 86.49462 -34.7726)
		(stroke
			(width 0.2)
			(type default)
		)
		(layer "In1.Cu")
	)
	(gr_arc
		(start 86.49462 -33.7566)
		(mid 86.540001 -33.866159)
		(end 86.64956 -33.91154)
		(stroke
			(width 0.2)
			(type default)
		)
		(layer "In1.Cu")
	)
	(gr_line
		(start 86.49462 -33.5534)
		(end 86.49462 -33.7566)
		(stroke
			(width 0.2)
			(type default)
		)
		(layer "In1.Cu")
	)
	(gr_arc
		(start 86.49462 -33.1216)
		(mid 86.540001 -33.231159)
		(end 86.64956 -33.27654)
		(stroke
			(width 0.2)
			(type default)
		)
		(layer "In1.Cu")
	)
	(gr_line
		(start 86.49462 -32.9184)
		(end 86.49462 -33.1216)
		(stroke
			(width 0.2)
			(type default)
		)
		(layer "In1.Cu")
	)
	(gr_line
		(start 86.4997 -45.3136)
		(end 86.4997 -45.1104)
		(stroke
			(width 0.2)
			(type default)
		)
		(layer "In1.Cu")
	)
	(gr_arc
		(start 86.4997 -45.1104)
		(mid 86.454319 -45.000841)
		(end 86.34476 -44.95546)
		(stroke
			(width 0.2)
			(type default)
		)
		(layer "In1.Cu")
	)
	(gr_line
		(start 86.4997 -44.6786)
		(end 86.4997 -44.4754)
		(stroke
			(width 0.2)
			(type default)
		)
		(layer "In1.Cu")
	)
	(gr_arc
		(start 86.4997 -44.4754)
		(mid 86.454319 -44.365841)
		(end 86.34476 -44.32046)
		(stroke
			(width 0.2)
			(type default)
		)
		(layer "In1.Cu")
	)
	(gr_line
		(start 86.4997 -43.6626)
		(end 86.4997 -43.4594)
		(stroke
			(width 0.2)
			(type default)
		)
		(layer "In1.Cu")
	)
	(gr_arc
		(start 86.4997 -43.4594)
		(mid 86.454319 -43.349841)
		(end 86.34476 -43.30446)
		(stroke
			(width 0.2)
			(type default)
		)
		(layer "In1.Cu")
	)
	(gr_line
		(start 86.4997 -43.0276)
		(end 86.4997 -42.8244)
		(stroke
			(width 0.2)
			(type default)
		)
		(layer "In1.Cu")
	)
	(gr_arc
		(start 86.4997 -42.8244)
		(mid 86.454319 -42.714841)
		(end 86.34476 -42.66946)
		(stroke
			(width 0.2)
			(type default)
		)
		(layer "In1.Cu")
	)
	(gr_line
		(start 86.4997 -42.0116)
		(end 86.4997 -41.8084)
		(stroke
			(width 0.2)
			(type default)
		)
		(layer "In1.Cu")
	)
	(gr_arc
		(start 86.4997 -41.8084)
		(mid 86.454319 -41.698841)
		(end 86.34476 -41.65346)
		(stroke
			(width 0.2)
			(type default)
		)
		(layer "In1.Cu")
	)
	(gr_line
		(start 86.4997 -41.3766)
		(end 86.4997 -41.1734)
		(stroke
			(width 0.2)
			(type default)
		)
		(layer "In1.Cu")
	)
	(gr_arc
		(start 86.4997 -41.1734)
		(mid 86.454319 -41.063841)
		(end 86.34476 -41.01846)
		(stroke
			(width 0.2)
			(type default)
		)
		(layer "In1.Cu")
	)
	(gr_line
		(start 86.4997 -40.3606)
		(end 86.4997 -40.1574)
		(stroke
			(width 0.2)
			(type default)
		)
		(layer "In1.Cu")
	)
	(gr_arc
		(start 86.4997 -40.1574)
		(mid 86.454319 -40.047841)
		(end 86.34476 -40.00246)
		(stroke
			(width 0.2)
			(type default)
		)
		(layer "In1.Cu")
	)
	(gr_line
		(start 86.4997 -39.7256)
		(end 86.4997 -39.5224)
		(stroke
			(width 0.2)
			(type default)
		)
		(layer "In1.Cu")
	)
	(gr_arc
		(start 86.4997 -39.5224)
		(mid 86.454319 -39.412841)
		(end 86.34476 -39.36746)
		(stroke
			(width 0.2)
			(type default)
		)
		(layer "In1.Cu")
	)
	(gr_line
		(start 86.4997 -38.7096)
		(end 86.4997 -38.5064)
		(stroke
			(width 0.2)
			(type default)
		)
		(layer "In1.Cu")
	)
	(gr_arc
		(start 86.4997 -38.5064)
		(mid 86.454319 -38.396841)
		(end 86.34476 -38.35146)
		(stroke
			(width 0.2)
			(type default)
		)
		(layer "In1.Cu")
	)
	(gr_line
		(start 86.4997 -38.0746)
		(end 86.4997 -37.8714)
		(stroke
			(width 0.2)
			(type default)
		)
		(layer "In1.Cu")
	)
	(gr_arc
		(start 86.4997 -37.8714)
		(mid 86.454319 -37.761841)
		(end 86.34476 -37.71646)
		(stroke
			(width 0.2)
			(type default)
		)
		(layer "In1.Cu")
	)
	(gr_line
		(start 86.4997 -37.0586)
		(end 86.4997 -36.8554)
		(stroke
			(width 0.2)
			(type default)
		)
		(layer "In1.Cu")
	)
	(gr_arc
		(start 86.4997 -36.8554)
		(mid 86.454319 -36.745841)
		(end 86.34476 -36.70046)
		(stroke
			(width 0.2)
			(type default)
		)
		(layer "In1.Cu")
	)
	(gr_line
		(start 86.4997 -36.4236)
		(end 86.4997 -36.2204)
		(stroke
			(width 0.2)
			(type default)
		)
		(layer "In1.Cu")
	)
	(gr_arc
		(start 86.4997 -36.2204)
		(mid 86.454319 -36.110841)
		(end 86.34476 -36.06546)
		(stroke
			(width 0.2)
			(type default)
		)
		(layer "In1.Cu")
	)
	(gr_line
		(start 86.4997 -35.4076)
		(end 86.4997 -35.2044)
		(stroke
			(width 0.2)
			(type default)
		)
		(layer "In1.Cu")
	)
	(gr_arc
		(start 86.4997 -35.2044)
		(mid 86.454319 -35.094841)
		(end 86.34476 -35.04946)
		(stroke
			(width 0.2)
			(type default)
		)
		(layer "In1.Cu")
	)
	(gr_line
		(start 86.4997 -34.7726)
		(end 86.4997 -34.5694)
		(stroke
			(width 0.2)
			(type default)
		)
		(layer "In1.Cu")
	)
	(gr_arc
		(start 86.4997 -34.5694)
		(mid 86.454319 -34.459841)
		(end 86.34476 -34.41446)
		(stroke
			(width 0.2)
			(type default)
		)
		(layer "In1.Cu")
	)
	(gr_line
		(start 86.4997 -33.7566)
		(end 86.4997 -33.5534)
		(stroke
			(width 0.2)
			(type default)
		)
		(layer "In1.Cu")
	)
	(gr_arc
		(start 86.4997 -33.5534)
		(mid 86.454319 -33.443841)
		(end 86.34476 -33.39846)
		(stroke
			(width 0.2)
			(type default)
		)
		(layer "In1.Cu")
	)
	(gr_line
		(start 86.4997 -33.1216)
		(end 86.4997 -32.9184)
		(stroke
			(width 0.2)
			(type default)
		)
		(layer "In1.Cu")
	)
	(gr_arc
		(start 86.4997 -32.9184)
		(mid 86.454319 -32.808841)
		(end 86.34476 -32.76346)
		(stroke
			(width 0.2)
			(type default)
		)
		(layer "In1.Cu")
	)
	(gr_line
		(start 86.64956 -45.46854)
		(end 86.90356 -45.46854)
		(stroke
			(width 0.2)
			(type default)
		)
		(layer "In1.Cu")
	)
	(gr_arc
		(start 86.64956 -44.95546)
		(mid 86.540001 -45.000841)
		(end 86.49462 -45.1104)
		(stroke
			(width 0.2)
			(type default)
		)
		(layer "In1.Cu")
	)
	(gr_line
		(start 86.64956 -44.83354)
		(end 86.90356 -44.83354)
		(stroke
			(width 0.2)
			(type default)
		)
		(layer "In1.Cu")
	)
	(gr_arc
		(start 86.64956 -44.32046)
		(mid 86.540001 -44.365841)
		(end 86.49462 -44.4754)
		(stroke
			(width 0.2)
			(type default)
		)
		(layer "In1.Cu")
	)
	(gr_line
		(start 86.64956 -43.81754)
		(end 86.90356 -43.81754)
		(stroke
			(width 0.2)
			(type default)
		)
		(layer "In1.Cu")
	)
	(gr_arc
		(start 86.64956 -43.30446)
		(mid 86.540001 -43.349841)
		(end 86.49462 -43.4594)
		(stroke
			(width 0.2)
			(type default)
		)
		(layer "In1.Cu")
	)
	(gr_line
		(start 86.64956 -43.18254)
		(end 86.90356 -43.18254)
		(stroke
			(width 0.2)
			(type default)
		)
		(layer "In1.Cu")
	)
	(gr_arc
		(start 86.64956 -42.66946)
		(mid 86.540001 -42.714841)
		(end 86.49462 -42.8244)
		(stroke
			(width 0.2)
			(type default)
		)
		(layer "In1.Cu")
	)
	(gr_line
		(start 86.64956 -42.16654)
		(end 86.90356 -42.16654)
		(stroke
			(width 0.2)
			(type default)
		)
		(layer "In1.Cu")
	)
	(gr_arc
		(start 86.64956 -41.65346)
		(mid 86.540001 -41.698841)
		(end 86.49462 -41.8084)
		(stroke
			(width 0.2)
			(type default)
		)
		(layer "In1.Cu")
	)
	(gr_line
		(start 86.64956 -41.53154)
		(end 86.90356 -41.53154)
		(stroke
			(width 0.2)
			(type default)
		)
		(layer "In1.Cu")
	)
	(gr_arc
		(start 86.64956 -41.01846)
		(mid 86.540001 -41.063841)
		(end 86.49462 -41.1734)
		(stroke
			(width 0.2)
			(type default)
		)
		(layer "In1.Cu")
	)
	(gr_line
		(start 86.64956 -40.51554)
		(end 86.90356 -40.51554)
		(stroke
			(width 0.2)
			(type default)
		)
		(layer "In1.Cu")
	)
	(gr_arc
		(start 86.64956 -40.00246)
		(mid 86.540001 -40.047841)
		(end 86.49462 -40.1574)
		(stroke
			(width 0.2)
			(type default)
		)
		(layer "In1.Cu")
	)
	(gr_line
		(start 86.64956 -39.88054)
		(end 86.90356 -39.88054)
		(stroke
			(width 0.2)
			(type default)
		)
		(layer "In1.Cu")
	)
	(gr_arc
		(start 86.64956 -39.36746)
		(mid 86.540001 -39.412841)
		(end 86.49462 -39.5224)
		(stroke
			(width 0.2)
			(type default)
		)
		(layer "In1.Cu")
	)
	(gr_line
		(start 86.64956 -38.86454)
		(end 86.90356 -38.86454)
		(stroke
			(width 0.2)
			(type default)
		)
		(layer "In1.Cu")
	)
	(gr_arc
		(start 86.64956 -38.35146)
		(mid 86.540001 -38.396841)
		(end 86.49462 -38.5064)
		(stroke
			(width 0.2)
			(type default)
		)
		(layer "In1.Cu")
	)
	(gr_line
		(start 86.64956 -38.22954)
		(end 86.90356 -38.22954)
		(stroke
			(width 0.2)
			(type default)
		)
		(layer "In1.Cu")
	)
	(gr_arc
		(start 86.64956 -37.71646)
		(mid 86.540001 -37.761841)
		(end 86.49462 -37.8714)
		(stroke
			(width 0.2)
			(type default)
		)
		(layer "In1.Cu")
	)
	(gr_line
		(start 86.64956 -37.21354)
		(end 86.90356 -37.21354)
		(stroke
			(width 0.2)
			(type default)
		)
		(layer "In1.Cu")
	)
	(gr_arc
		(start 86.64956 -36.70046)
		(mid 86.540001 -36.745841)
		(end 86.49462 -36.8554)
		(stroke
			(width 0.2)
			(type default)
		)
		(layer "In1.Cu")
	)
	(gr_line
		(start 86.64956 -36.57854)
		(end 86.90356 -36.57854)
		(stroke
			(width 0.2)
			(type default)
		)
		(layer "In1.Cu")
	)
	(gr_arc
		(start 86.64956 -36.06546)
		(mid 86.540001 -36.110841)
		(end 86.49462 -36.2204)
		(stroke
			(width 0.2)
			(type default)
		)
		(layer "In1.Cu")
	)
	(gr_line
		(start 86.64956 -35.56254)
		(end 86.90356 -35.56254)
		(stroke
			(width 0.2)
			(type default)
		)
		(layer "In1.Cu")
	)
	(gr_arc
		(start 86.64956 -35.04946)
		(mid 86.540001 -35.094841)
		(end 86.49462 -35.2044)
		(stroke
			(width 0.2)
			(type default)
		)
		(layer "In1.Cu")
	)
	(gr_line
		(start 86.64956 -34.92754)
		(end 86.90356 -34.92754)
		(stroke
			(width 0.2)
			(type default)
		)
		(layer "In1.Cu")
	)
	(gr_arc
		(start 86.64956 -34.41446)
		(mid 86.540001 -34.459841)
		(end 86.49462 -34.5694)
		(stroke
			(width 0.2)
			(type default)
		)
		(layer "In1.Cu")
	)
	(gr_line
		(start 86.64956 -33.91154)
		(end 86.90356 -33.91154)
		(stroke
			(width 0.2)
			(type default)
		)
		(layer "In1.Cu")
	)
	(gr_arc
		(start 86.64956 -33.39846)
		(mid 86.540001 -33.443841)
		(end 86.49462 -33.5534)
		(stroke
			(width 0.2)
			(type default)
		)
		(layer "In1.Cu")
	)
	(gr_line
		(start 86.64956 -33.27654)
		(end 86.90356 -33.27654)
		(stroke
			(width 0.2)
			(type default)
		)
		(layer "In1.Cu")
	)
	(gr_arc
		(start 86.64956 -32.76346)
		(mid 86.540001 -32.808841)
		(end 86.49462 -32.9184)
		(stroke
			(width 0.2)
			(type default)
		)
		(layer "In1.Cu")
	)
	(gr_arc
		(start 86.90356 -45.46854)
		(mid 87.013119 -45.423159)
		(end 87.0585 -45.3136)
		(stroke
			(width 0.2)
			(type default)
		)
		(layer "In1.Cu")
	)
	(gr_line
		(start 86.90356 -44.95546)
		(end 86.64956 -44.95546)
		(stroke
			(width 0.2)
			(type default)
		)
		(layer "In1.Cu")
	)
	(gr_arc
		(start 86.90356 -44.83354)
		(mid 87.013119 -44.788159)
		(end 87.0585 -44.6786)
		(stroke
			(width 0.2)
			(type default)
		)
		(layer "In1.Cu")
	)
	(gr_line
		(start 86.90356 -44.32046)
		(end 86.64956 -44.32046)
		(stroke
			(width 0.2)
			(type default)
		)
		(layer "In1.Cu")
	)
	(gr_arc
		(start 86.90356 -43.81754)
		(mid 87.013119 -43.772159)
		(end 87.0585 -43.6626)
		(stroke
			(width 0.2)
			(type default)
		)
		(layer "In1.Cu")
	)
	(gr_line
		(start 86.90356 -43.30446)
		(end 86.64956 -43.30446)
		(stroke
			(width 0.2)
			(type default)
		)
		(layer "In1.Cu")
	)
	(gr_arc
		(start 86.90356 -43.18254)
		(mid 87.013119 -43.137159)
		(end 87.0585 -43.0276)
		(stroke
			(width 0.2)
			(type default)
		)
		(layer "In1.Cu")
	)
	(gr_line
		(start 86.90356 -42.66946)
		(end 86.64956 -42.66946)
		(stroke
			(width 0.2)
			(type default)
		)
		(layer "In1.Cu")
	)
	(gr_arc
		(start 86.90356 -42.16654)
		(mid 87.013119 -42.121159)
		(end 87.0585 -42.0116)
		(stroke
			(width 0.2)
			(type default)
		)
		(layer "In1.Cu")
	)
	(gr_line
		(start 86.90356 -41.65346)
		(end 86.64956 -41.65346)
		(stroke
			(width 0.2)
			(type default)
		)
		(layer "In1.Cu")
	)
	(gr_arc
		(start 86.90356 -41.53154)
		(mid 87.013119 -41.486159)
		(end 87.0585 -41.3766)
		(stroke
			(width 0.2)
			(type default)
		)
		(layer "In1.Cu")
	)
	(gr_line
		(start 86.90356 -41.01846)
		(end 86.64956 -41.01846)
		(stroke
			(width 0.2)
			(type default)
		)
		(layer "In1.Cu")
	)
	(gr_arc
		(start 86.90356 -40.51554)
		(mid 87.013119 -40.470159)
		(end 87.0585 -40.3606)
		(stroke
			(width 0.2)
			(type default)
		)
		(layer "In1.Cu")
	)
	(gr_line
		(start 86.90356 -40.00246)
		(end 86.64956 -40.00246)
		(stroke
			(width 0.2)
			(type default)
		)
		(layer "In1.Cu")
	)
	(gr_arc
		(start 86.90356 -39.88054)
		(mid 87.013119 -39.835159)
		(end 87.0585 -39.7256)
		(stroke
			(width 0.2)
			(type default)
		)
		(layer "In1.Cu")
	)
	(gr_line
		(start 86.90356 -39.36746)
		(end 86.64956 -39.36746)
		(stroke
			(width 0.2)
			(type default)
		)
		(layer "In1.Cu")
	)
	(gr_arc
		(start 86.90356 -38.86454)
		(mid 87.013119 -38.819159)
		(end 87.0585 -38.7096)
		(stroke
			(width 0.2)
			(type default)
		)
		(layer "In1.Cu")
	)
	(gr_line
		(start 86.90356 -38.35146)
		(end 86.64956 -38.35146)
		(stroke
			(width 0.2)
			(type default)
		)
		(layer "In1.Cu")
	)
	(gr_arc
		(start 86.90356 -38.22954)
		(mid 87.013119 -38.184159)
		(end 87.0585 -38.0746)
		(stroke
			(width 0.2)
			(type default)
		)
		(layer "In1.Cu")
	)
	(gr_line
		(start 86.90356 -37.71646)
		(end 86.64956 -37.71646)
		(stroke
			(width 0.2)
			(type default)
		)
		(layer "In1.Cu")
	)
	(gr_arc
		(start 86.90356 -37.21354)
		(mid 87.013119 -37.168159)
		(end 87.0585 -37.0586)
		(stroke
			(width 0.2)
			(type default)
		)
		(layer "In1.Cu")
	)
	(gr_line
		(start 86.90356 -36.70046)
		(end 86.64956 -36.70046)
		(stroke
			(width 0.2)
			(type default)
		)
		(layer "In1.Cu")
	)
	(gr_arc
		(start 86.90356 -36.57854)
		(mid 87.013119 -36.533159)
		(end 87.0585 -36.4236)
		(stroke
			(width 0.2)
			(type default)
		)
		(layer "In1.Cu")
	)
	(gr_line
		(start 86.90356 -36.06546)
		(end 86.64956 -36.06546)
		(stroke
			(width 0.2)
			(type default)
		)
		(layer "In1.Cu")
	)
	(gr_arc
		(start 86.90356 -35.56254)
		(mid 87.013119 -35.517159)
		(end 87.0585 -35.4076)
		(stroke
			(width 0.2)
			(type default)
		)
		(layer "In1.Cu")
	)
	(gr_line
		(start 86.90356 -35.04946)
		(end 86.64956 -35.04946)
		(stroke
			(width 0.2)
			(type default)
		)
		(layer "In1.Cu")
	)
	(gr_arc
		(start 86.90356 -34.92754)
		(mid 87.013119 -34.882159)
		(end 87.0585 -34.7726)
		(stroke
			(width 0.2)
			(type default)
		)
		(layer "In1.Cu")
	)
	(gr_line
		(start 86.90356 -34.41446)
		(end 86.64956 -34.41446)
		(stroke
			(width 0.2)
			(type default)
		)
		(layer "In1.Cu")
	)
	(gr_arc
		(start 86.90356 -33.91154)
		(mid 87.013119 -33.866159)
		(end 87.0585 -33.7566)
		(stroke
			(width 0.2)
			(type default)
		)
		(layer "In1.Cu")
	)
	(gr_line
		(start 86.90356 -33.39846)
		(end 86.64956 -33.39846)
		(stroke
			(width 0.2)
			(type default)
		)
		(layer "In1.Cu")
	)
	(gr_arc
		(start 86.90356 -33.27654)
		(mid 87.013119 -33.231159)
		(end 87.0585 -33.1216)
		(stroke
			(width 0.2)
			(type default)
		)
		(layer "In1.Cu")
	)
	(gr_line
		(start 86.90356 -32.76346)
		(end 86.64956 -32.76346)
		(stroke
			(width 0.2)
			(type default)
		)
		(layer "In1.Cu")
	)
	(gr_line
		(start 87.0585 -45.3136)
		(end 87.0585 -45.1104)
		(stroke
			(width 0.2)
			(type default)
		)
		(layer "In1.Cu")
	)
	(gr_arc
		(start 87.0585 -45.1104)
		(mid 87.013119 -45.000841)
		(end 86.90356 -44.95546)
		(stroke
			(width 0.2)
			(type default)
		)
		(layer "In1.Cu")
	)
	(gr_line
		(start 87.0585 -44.6786)
		(end 87.0585 -44.4754)
		(stroke
			(width 0.2)
			(type default)
		)
		(layer "In1.Cu")
	)
	(gr_arc
		(start 87.0585 -44.4754)
		(mid 87.013119 -44.365841)
		(end 86.90356 -44.32046)
		(stroke
			(width 0.2)
			(type default)
		)
		(layer "In1.Cu")
	)
	(gr_line
		(start 87.0585 -43.6626)
		(end 87.0585 -43.4594)
		(stroke
			(width 0.2)
			(type default)
		)
		(layer "In1.Cu")
	)
	(gr_arc
		(start 87.0585 -43.4594)
		(mid 87.013119 -43.349841)
		(end 86.90356 -43.30446)
		(stroke
			(width 0.2)
			(type default)
		)
		(layer "In1.Cu")
	)
	(gr_line
		(start 87.0585 -43.0276)
		(end 87.0585 -42.8244)
		(stroke
			(width 0.2)
			(type default)
		)
		(layer "In1.Cu")
	)
	(gr_arc
		(start 87.0585 -42.8244)
		(mid 87.013119 -42.714841)
		(end 86.90356 -42.66946)
		(stroke
			(width 0.2)
			(type default)
		)
		(layer "In1.Cu")
	)
	(gr_line
		(start 87.0585 -42.0116)
		(end 87.0585 -41.8084)
		(stroke
			(width 0.2)
			(type default)
		)
		(layer "In1.Cu")
	)
	(gr_arc
		(start 87.0585 -41.8084)
		(mid 87.013119 -41.698841)
		(end 86.90356 -41.65346)
		(stroke
			(width 0.2)
			(type default)
		)
		(layer "In1.Cu")
	)
	(gr_line
		(start 87.0585 -41.3766)
		(end 87.0585 -41.1734)
		(stroke
			(width 0.2)
			(type default)
		)
		(layer "In1.Cu")
	)
	(gr_arc
		(start 87.0585 -41.1734)
		(mid 87.013119 -41.063841)
		(end 86.90356 -41.01846)
		(stroke
			(width 0.2)
			(type default)
		)
		(layer "In1.Cu")
	)
	(gr_line
		(start 87.0585 -40.3606)
		(end 87.0585 -40.1574)
		(stroke
			(width 0.2)
			(type default)
		)
		(layer "In1.Cu")
	)
	(gr_arc
		(start 87.0585 -40.1574)
		(mid 87.013119 -40.047841)
		(end 86.90356 -40.00246)
		(stroke
			(width 0.2)
			(type default)
		)
		(layer "In1.Cu")
	)
	(gr_line
		(start 87.0585 -39.7256)
		(end 87.0585 -39.5224)
		(stroke
			(width 0.2)
			(type default)
		)
		(layer "In1.Cu")
	)
	(gr_arc
		(start 87.0585 -39.5224)
		(mid 87.013119 -39.412841)
		(end 86.90356 -39.36746)
		(stroke
			(width 0.2)
			(type default)
		)
		(layer "In1.Cu")
	)
	(gr_line
		(start 87.0585 -38.7096)
		(end 87.0585 -38.5064)
		(stroke
			(width 0.2)
			(type default)
		)
		(layer "In1.Cu")
	)
	(gr_arc
		(start 87.0585 -38.5064)
		(mid 87.013119 -38.396841)
		(end 86.90356 -38.35146)
		(stroke
			(width 0.2)
			(type default)
		)
		(layer "In1.Cu")
	)
	(gr_line
		(start 87.0585 -38.0746)
		(end 87.0585 -37.8714)
		(stroke
			(width 0.2)
			(type default)
		)
		(layer "In1.Cu")
	)
	(gr_arc
		(start 87.0585 -37.8714)
		(mid 87.013119 -37.761841)
		(end 86.90356 -37.71646)
		(stroke
			(width 0.2)
			(type default)
		)
		(layer "In1.Cu")
	)
	(gr_line
		(start 87.0585 -37.0586)
		(end 87.0585 -36.8554)
		(stroke
			(width 0.2)
			(type default)
		)
		(layer "In1.Cu")
	)
	(gr_arc
		(start 87.0585 -36.8554)
		(mid 87.013119 -36.745841)
		(end 86.90356 -36.70046)
		(stroke
			(width 0.2)
			(type default)
		)
		(layer "In1.Cu")
	)
	(gr_line
		(start 87.0585 -36.4236)
		(end 87.0585 -36.2204)
		(stroke
			(width 0.2)
			(type default)
		)
		(layer "In1.Cu")
	)
	(gr_arc
		(start 87.0585 -36.2204)
		(mid 87.013119 -36.110841)
		(end 86.90356 -36.06546)
		(stroke
			(width 0.2)
			(type default)
		)
		(layer "In1.Cu")
	)
	(gr_line
		(start 87.0585 -35.4076)
		(end 87.0585 -35.2044)
		(stroke
			(width 0.2)
			(type default)
		)
		(layer "In1.Cu")
	)
	(gr_arc
		(start 87.0585 -35.2044)
		(mid 87.013119 -35.094841)
		(end 86.90356 -35.04946)
		(stroke
			(width 0.2)
			(type default)
		)
		(layer "In1.Cu")
	)
	(gr_line
		(start 87.0585 -34.7726)
		(end 87.0585 -34.5694)
		(stroke
			(width 0.2)
			(type default)
		)
		(layer "In1.Cu")
	)
	(gr_arc
		(start 87.0585 -34.5694)
		(mid 87.013119 -34.459841)
		(end 86.90356 -34.41446)
		(stroke
			(width 0.2)
			(type default)
		)
		(layer "In1.Cu")
	)
	(gr_line
		(start 87.0585 -33.7566)
		(end 87.0585 -33.5534)
		(stroke
			(width 0.2)
			(type default)
		)
		(layer "In1.Cu")
	)
	(gr_arc
		(start 87.0585 -33.5534)
		(mid 87.013119 -33.443841)
		(end 86.90356 -33.39846)
		(stroke
			(width 0.2)
			(type default)
		)
		(layer "In1.Cu")
	)
	(gr_line
		(start 87.0585 -33.1216)
		(end 87.0585 -32.9184)
		(stroke
			(width 0.2)
			(type default)
		)
		(layer "In1.Cu")
	)
	(gr_arc
		(start 87.0585 -32.9184)
		(mid 87.013119 -32.808841)
		(end 86.90356 -32.76346)
		(stroke
			(width 0.2)
			(type default)
		)
		(layer "In1.Cu")
	)
	(gr_line
		(start 92.744798 -39.75354)
		(end 93.55582 -39.755318)
		(stroke
			(width 0.2)
			(type default)
		)
		(layer "In1.Cu")
	)
	(gr_line
		(start 92.746576 -42.154856)
		(end 93.550994 -42.16273)
		(stroke
			(width 0.2)
			(type default)
		)
		(layer "In1.Cu")
	)
	(gr_arc
		(start 92.746576 -39.03726)
		(mid 92.387674 -39.394511)
		(end 92.744798 -39.75354)
		(stroke
			(width 0.2)
			(type default)
		)
		(layer "In1.Cu")
	)
	(gr_arc
		(start 92.753942 -41.438576)
		(mid 92.392247 -41.793033)
		(end 92.746576 -42.154856)
		(stroke
			(width 0.2)
			(type default)
		)
		(layer "In1.Cu")
	)
	(gr_line
		(start 93.182694 -40.206422)
		(end 93.196664 -41.001696)
		(stroke
			(width 0.2)
			(type default)
		)
		(layer "In1.Cu")
	)
	(gr_line
		(start 93.19133 -35.40887)
		(end 93.193616 -36.197032)
		(stroke
			(width 0.2)
			(type default)
		)
		(layer "In1.Cu")
	)
	(gr_arc
		(start 93.192346 -43.387772)
		(mid 93.547565 -43.748961)
		(end 93.908626 -43.393614)
		(stroke
			(width 0.2)
			(type default)
		)
		(layer "In1.Cu")
	)
	(gr_arc
		(start 93.193616 -36.197032)
		(mid 93.552645 -36.55441)
		(end 93.909896 -36.195254)
		(stroke
			(width 0.2)
			(type default)
		)
		(layer "In1.Cu")
	)
	(gr_arc
		(start 93.196664 -41.001696)
		(mid 93.561027 -41.353738)
		(end 93.912944 -40.98925)
		(stroke
			(width 0.2)
			(type default)
		)
		(layer "In1.Cu")
	)
	(gr_arc
		(start 93.197426 -38.596316)
		(mid 93.555058 -38.954964)
		(end 93.913706 -38.597332)
		(stroke
			(width 0.2)
			(type default)
		)
		(layer "In1.Cu")
	)
	(gr_line
		(start 93.198442 -37.80155)
		(end 93.197426 -38.596316)
		(stroke
			(width 0.2)
			(type default)
		)
		(layer "In1.Cu")
	)
	(gr_line
		(start 93.198696 -42.59453)
		(end 93.192346 -43.387772)
		(stroke
			(width 0.2)
			(type default)
		)
		(layer "In1.Cu")
	)
	(gr_arc
		(start 93.544644 -34.248344)
		(mid 93.189297 -34.609151)
		(end 93.549978 -34.964624)
		(stroke
			(width 0.2)
			(type default)
		)
		(layer "In1.Cu")
	)
	(gr_line
		(start 93.549978 -34.964624)
		(end 94.352618 -34.958274)
		(stroke
			(width 0.2)
			(type default)
		)
		(layer "In1.Cu")
	)
	(gr_arc
		(start 93.550232 -36.64458)
		(mid 93.193616 -37.004244)
		(end 93.55328 -37.36086)
		(stroke
			(width 0.2)
			(type default)
		)
		(layer "In1.Cu")
	)
	(gr_arc
		(start 93.550994 -42.16273)
		(mid 93.91269 -41.808146)
		(end 93.558106 -41.44645)
		(stroke
			(width 0.2)
			(type default)
		)
		(layer "In1.Cu")
	)
	(gr_line
		(start 93.55328 -37.36086)
		(end 94.360492 -37.357558)
		(stroke
			(width 0.2)
			(type default)
		)
		(layer "In1.Cu")
	)
	(gr_arc
		(start 93.55582 -39.755318)
		(mid 93.914722 -39.39794)
		(end 93.557344 -39.039038)
		(stroke
			(width 0.2)
			(type default)
		)
		(layer "In1.Cu")
	)
	(gr_line
		(start 93.557344 -39.039038)
		(end 92.746576 -39.03726)
		(stroke
			(width 0.2)
			(type default)
		)
		(layer "In1.Cu")
	)
	(gr_line
		(start 93.558106 -41.44645)
		(end 92.753942 -41.438576)
		(stroke
			(width 0.2)
			(type default)
		)
		(layer "In1.Cu")
	)
	(gr_arc
		(start 93.898974 -40.193722)
		(mid 93.534484 -39.841932)
		(end 93.182694 -40.206422)
		(stroke
			(width 0.2)
			(type default)
		)
		(layer "In1.Cu")
	)
	(gr_line
		(start 93.90761 -35.407854)
		(end 93.90761 -35.406838)
		(stroke
			(width 0.2)
			(type default)
		)
		(layer "In1.Cu")
	)
	(gr_arc
		(start 93.90761 -35.406838)
		(mid 93.548454 -35.049714)
		(end 93.19133 -35.40887)
		(stroke
			(width 0.2)
			(type default)
		)
		(layer "In1.Cu")
	)
	(gr_line
		(start 93.908626 -43.393614)
		(end 93.914976 -42.600118)
		(stroke
			(width 0.2)
			(type default)
		)
		(layer "In1.Cu")
	)
	(gr_line
		(start 93.909896 -36.195254)
		(end 93.90761 -35.407854)
		(stroke
			(width 0.2)
			(type default)
		)
		(layer "In1.Cu")
	)
	(gr_line
		(start 93.912944 -40.98925)
		(end 93.898974 -40.193722)
		(stroke
			(width 0.2)
			(type default)
		)
		(layer "In1.Cu")
	)
	(gr_line
		(start 93.913706 -38.597332)
		(end 93.913706 -38.596824)
		(stroke
			(width 0.2)
			(type default)
		)
		(layer "In1.Cu")
	)
	(gr_line
		(start 93.913706 -38.596824)
		(end 93.914722 -37.80282)
		(stroke
			(width 0.2)
			(type default)
		)
		(layer "In1.Cu")
	)
	(gr_arc
		(start 93.914722 -37.80282)
		(mid 93.557217 -37.444172)
		(end 93.198442 -37.80155)
		(stroke
			(width 0.2)
			(type default)
		)
		(layer "In1.Cu")
	)
	(gr_arc
		(start 93.914976 -42.600118)
		(mid 93.55963 -42.239184)
		(end 93.198696 -42.59453)
		(stroke
			(width 0.2)
			(type default)
		)
		(layer "In1.Cu")
	)
	(gr_rect
		(start 94.293436 -1.354328)
		(end 95.644716 -2.705608)
		(stroke
			(width 0)
			(type default)
		)
		(fill no)
		(layer "In1.Cu")
	)
	(gr_line
		(start 94.34703 -34.241994)
		(end 93.544644 -34.248344)
		(stroke
			(width 0.2)
			(type default)
		)
		(layer "In1.Cu")
	)
	(gr_arc
		(start 94.352618 -34.958274)
		(mid 94.707964 -34.59734)
		(end 94.34703 -34.241994)
		(stroke
			(width 0.2)
			(type default)
		)
		(layer "In1.Cu")
	)
	(gr_line
		(start 94.357698 -36.641278)
		(end 93.550232 -36.64458)
		(stroke
			(width 0.2)
			(type default)
		)
		(layer "In1.Cu")
	)
	(gr_arc
		(start 94.360492 -37.357558)
		(mid 94.717362 -36.998021)
		(end 94.357698 -36.641278)
		(stroke
			(width 0.2)
			(type default)
		)
		(layer "In1.Cu")
	)
	(gr_line
		(start 94.79026 -35.405822)
		(end 94.792038 -36.200588)
		(stroke
			(width 0.2)
			(type default)
		)
		(layer "In1.Cu")
	)
	(gr_arc
		(start 94.792038 -36.200588)
		(mid 95.150813 -36.55822)
		(end 95.508318 -36.199318)
		(stroke
			(width 0.2)
			(type default)
		)
		(layer "In1.Cu")
	)
	(gr_line
		(start 95.50654 -35.40506)
		(end 95.50654 -35.404298)
		(stroke
			(width 0.2)
			(type default)
		)
		(layer "In1.Cu")
	)
	(gr_arc
		(start 95.50654 -35.404298)
		(mid 95.147638 -35.04692)
		(end 94.79026 -35.405822)
		(stroke
			(width 0.2)
			(type default)
		)
		(layer "In1.Cu")
	)
	(gr_line
		(start 95.508318 -36.199318)
		(end 95.50654 -35.40506)
		(stroke
			(width 0.2)
			(type default)
		)
		(layer "In1.Cu")
	)
	(gr_line
		(start 95.59036 -35.408362)
		(end 95.592138 -36.200588)
		(stroke
			(width 0.2)
			(type default)
		)
		(layer "In1.Cu")
	)
	(gr_arc
		(start 95.592138 -36.200588)
		(mid 95.950913 -36.55822)
		(end 96.308418 -36.199318)
		(stroke
			(width 0.2)
			(type default)
		)
		(layer "In1.Cu")
	)
	(gr_line
		(start 96.30664 -35.4076)
		(end 96.30664 -35.406838)
		(stroke
			(width 0.2)
			(type default)
		)
		(layer "In1.Cu")
	)
	(gr_arc
		(start 96.30664 -35.406838)
		(mid 95.947738 -35.04946)
		(end 95.59036 -35.408362)
		(stroke
			(width 0.2)
			(type default)
		)
		(layer "In1.Cu")
	)
	(gr_line
		(start 96.308418 -36.199318)
		(end 96.30664 -35.4076)
		(stroke
			(width 0.2)
			(type default)
		)
		(layer "In1.Cu")
	)
	(gr_line
		(start 97.182686 -35.404552)
		(end 97.192084 -36.204144)
		(stroke
			(width 0.2)
			(type default)
		)
		(layer "In1.Cu")
	)
	(gr_arc
		(start 97.192084 -36.204144)
		(mid 97.554415 -36.558219)
		(end 97.908364 -36.195762)
		(stroke
			(width 0.2)
			(type default)
		)
		(layer "In1.Cu")
	)
	(gr_rect
		(start 97.435416 -1.354328)
		(end 98.786696 -2.705608)
		(stroke
			(width 0)
			(type default)
		)
		(fill no)
		(layer "In1.Cu")
	)
	(gr_arc
		(start 97.898966 -35.395916)
		(mid 97.536508 -35.042094)
		(end 97.182686 -35.404552)
		(stroke
			(width 0.2)
			(type default)
		)
		(layer "In1.Cu")
	)
	(gr_line
		(start 97.908364 -36.195762)
		(end 97.898966 -35.395916)
		(stroke
			(width 0.2)
			(type default)
		)
		(layer "In1.Cu")
	)
	(gr_line
		(start 97.983802 -35.405314)
		(end 97.992184 -36.203636)
		(stroke
			(width 0.2)
			(type default)
		)
		(layer "In1.Cu")
	)
	(gr_arc
		(start 97.992184 -36.203636)
		(mid 98.354007 -36.558219)
		(end 98.708464 -36.19627)
		(stroke
			(width 0.2)
			(type default)
		)
		(layer "In1.Cu")
	)
	(gr_arc
		(start 98.700082 -35.397694)
		(mid 98.338132 -35.043364)
		(end 97.983802 -35.405314)
		(stroke
			(width 0.2)
			(type default)
		)
		(layer "In1.Cu")
	)
	(gr_line
		(start 98.708464 -36.19627)
		(end 98.700082 -35.397694)
		(stroke
			(width 0.2)
			(type default)
		)
		(layer "In1.Cu")
	)
	(gr_arc
		(start 99.59213 -36.199318)
		(mid 99.949635 -36.55822)
		(end 100.30841 -36.200588)
		(stroke
			(width 0.2)
			(type default)
		)
		(layer "In1.Cu")
	)
	(gr_line
		(start 99.5934 -35.391852)
		(end 99.59213 -36.199318)
		(stroke
			(width 0.2)
			(type default)
		)
		(layer "In1.Cu")
	)
	(gr_line
		(start 100.30841 -36.200588)
		(end 100.30841 -36.20008)
		(stroke
			(width 0.2)
			(type default)
		)
		(layer "In1.Cu")
	)
	(gr_line
		(start 100.30841 -36.20008)
		(end 100.30968 -35.392868)
		(stroke
			(width 0.2)
			(type default)
		)
		(layer "In1.Cu")
	)
	(gr_arc
		(start 100.30968 -35.392868)
		(mid 99.952048 -35.03422)
		(end 99.5934 -35.391852)
		(stroke
			(width 0.2)
			(type default)
		)
		(layer "In1.Cu")
	)
	(gr_arc
		(start 100.39223 -36.196524)
		(mid 100.746941 -36.558221)
		(end 101.10851 -36.203382)
		(stroke
			(width 0.2)
			(type default)
		)
		(layer "In1.Cu")
	)
	(gr_line
		(start 100.399342 -35.394646)
		(end 100.39223 -36.196524)
		(stroke
			(width 0.2)
			(type default)
		)
		(layer "In1.Cu")
	)
	(gr_line
		(start 101.10851 -36.203382)
		(end 101.115622 -35.40125)
		(stroke
			(width 0.2)
			(type default)
		)
		(layer "In1.Cu")
	)
	(gr_arc
		(start 101.115622 -35.40125)
		(mid 100.760784 -35.039808)
		(end 100.399342 -35.394646)
		(stroke
			(width 0.2)
			(type default)
		)
		(layer "In1.Cu")
	)
	(gr_arc
		(start 101.48443 -114.7064)
		(mid 101.529811 -114.815959)
		(end 101.63937 -114.86134)
		(stroke
			(width 0.2)
			(type default)
		)
		(layer "In1.Cu")
	)
	(gr_line
		(start 101.48443 -114.4524)
		(end 101.48443 -114.7064)
		(stroke
			(width 0.2)
			(type default)
		)
		(layer "In1.Cu")
	)
	(gr_arc
		(start 101.48443 -114.1476)
		(mid 101.529811 -114.257159)
		(end 101.63937 -114.30254)
		(stroke
			(width 0.2)
			(type default)
		)
		(layer "In1.Cu")
	)
	(gr_line
		(start 101.48443 -113.8936)
		(end 101.48443 -114.1476)
		(stroke
			(width 0.2)
			(type default)
		)
		(layer "In1.Cu")
	)
	(gr_line
		(start 101.63937 -114.86134)
		(end 101.84257 -114.86134)
		(stroke
			(width 0.2)
			(type default)
		)
		(layer "In1.Cu")
	)
	(gr_line
		(start 101.63937 -114.30254)
		(end 101.84257 -114.30254)
		(stroke
			(width 0.2)
			(type default)
		)
		(layer "In1.Cu")
	)
	(gr_arc
		(start 101.63937 -114.29746)
		(mid 101.529811 -114.342841)
		(end 101.48443 -114.4524)
		(stroke
			(width 0.2)
			(type default)
		)
		(layer "In1.Cu")
	)
	(gr_arc
		(start 101.63937 -113.73866)
		(mid 101.529811 -113.784041)
		(end 101.48443 -113.8936)
		(stroke
			(width 0.2)
			(type default)
		)
		(layer "In1.Cu")
	)
	(gr_arc
		(start 101.84257 -114.86134)
		(mid 101.952129 -114.815959)
		(end 101.99751 -114.7064)
		(stroke
			(width 0.2)
			(type default)
		)
		(layer "In1.Cu")
	)
	(gr_arc
		(start 101.84257 -114.30254)
		(mid 101.952129 -114.257159)
		(end 101.99751 -114.1476)
		(stroke
			(width 0.2)
			(type default)
		)
		(layer "In1.Cu")
	)
	(gr_line
		(start 101.84257 -114.29746)
		(end 101.63937 -114.29746)
		(stroke
			(width 0.2)
			(type default)
		)
		(layer "In1.Cu")
	)
	(gr_line
		(start 101.84257 -113.73866)
		(end 101.63937 -113.73866)
		(stroke
			(width 0.2)
			(type default)
		)
		(layer "In1.Cu")
	)
	(gr_line
		(start 101.991922 -35.400234)
		(end 101.992176 -36.199826)
		(stroke
			(width 0.2)
			(type default)
		)
		(layer "In1.Cu")
	)
	(gr_arc
		(start 101.992176 -36.199826)
		(mid 102.350316 -36.55822)
		(end 102.708456 -36.199826)
		(stroke
			(width 0.2)
			(type default)
		)
		(layer "In1.Cu")
	)
	(gr_line
		(start 101.99751 -114.7064)
		(end 101.99751 -114.4524)
		(stroke
			(width 0.2)
			(type default)
		)
		(layer "In1.Cu")
	)
	(gr_arc
		(start 101.99751 -114.4524)
		(mid 101.952129 -114.342841)
		(end 101.84257 -114.29746)
		(stroke
			(width 0.2)
			(type default)
		)
		(layer "In1.Cu")
	)
	(gr_line
		(start 101.99751 -114.1476)
		(end 101.99751 -113.8936)
		(stroke
			(width 0.2)
			(type default)
		)
		(layer "In1.Cu")
	)
	(gr_arc
		(start 101.99751 -113.8936)
		(mid 101.952129 -113.784041)
		(end 101.84257 -113.73866)
		(stroke
			(width 0.2)
			(type default)
		)
		(layer "In1.Cu")
	)
	(gr_arc
		(start 102.11943 -114.7064)
		(mid 102.164811 -114.815959)
		(end 102.27437 -114.86134)
		(stroke
			(width 0.2)
			(type default)
		)
		(layer "In1.Cu")
	)
	(gr_line
		(start 102.11943 -114.4524)
		(end 102.11943 -114.7064)
		(stroke
			(width 0.2)
			(type default)
		)
		(layer "In1.Cu")
	)
	(gr_arc
		(start 102.11943 -114.1476)
		(mid 102.164811 -114.257159)
		(end 102.27437 -114.30254)
		(stroke
			(width 0.2)
			(type default)
		)
		(layer "In1.Cu")
	)
	(gr_line
		(start 102.11943 -113.8936)
		(end 102.11943 -114.1476)
		(stroke
			(width 0.2)
			(type default)
		)
		(layer "In1.Cu")
	)
	(gr_line
		(start 102.27437 -114.86134)
		(end 102.47757 -114.86134)
		(stroke
			(width 0.2)
			(type default)
		)
		(layer "In1.Cu")
	)
	(gr_line
		(start 102.27437 -114.30254)
		(end 102.47757 -114.30254)
		(stroke
			(width 0.2)
			(type default)
		)
		(layer "In1.Cu")
	)
	(gr_arc
		(start 102.27437 -114.29746)
		(mid 102.164811 -114.342841)
		(end 102.11943 -114.4524)
		(stroke
			(width 0.2)
			(type default)
		)
		(layer "In1.Cu")
	)
	(gr_arc
		(start 102.27437 -113.73866)
		(mid 102.164811 -113.784041)
		(end 102.11943 -113.8936)
		(stroke
			(width 0.2)
			(type default)
		)
		(layer "In1.Cu")
	)
	(gr_circle
		(center 102.350062 -5.999988)
		(end 103.025702 -5.999988)
		(stroke
			(width 0.2)
			(type default)
		)
		(fill no)
		(layer "In1.Cu")
	)
	(gr_arc
		(start 102.47757 -114.86134)
		(mid 102.587129 -114.815959)
		(end 102.63251 -114.7064)
		(stroke
			(width 0.2)
			(type default)
		)
		(layer "In1.Cu")
	)
	(gr_arc
		(start 102.47757 -114.30254)
		(mid 102.587129 -114.257159)
		(end 102.63251 -114.1476)
		(stroke
			(width 0.2)
			(type default)
		)
		(layer "In1.Cu")
	)
	(gr_line
		(start 102.47757 -114.29746)
		(end 102.27437 -114.29746)
		(stroke
			(width 0.2)
			(type default)
		)
		(layer "In1.Cu")
	)
	(gr_line
		(start 102.47757 -113.73866)
		(end 102.27437 -113.73866)
		(stroke
			(width 0.2)
			(type default)
		)
		(layer "In1.Cu")
	)
	(gr_line
		(start 102.63251 -114.7064)
		(end 102.63251 -114.4524)
		(stroke
			(width 0.2)
			(type default)
		)
		(layer "In1.Cu")
	)
	(gr_arc
		(start 102.63251 -114.4524)
		(mid 102.587129 -114.342841)
		(end 102.47757 -114.29746)
		(stroke
			(width 0.2)
			(type default)
		)
		(layer "In1.Cu")
	)
	(gr_line
		(start 102.63251 -114.1476)
		(end 102.63251 -113.8936)
		(stroke
			(width 0.2)
			(type default)
		)
		(layer "In1.Cu")
	)
	(gr_arc
		(start 102.63251 -113.8936)
		(mid 102.587129 -113.784041)
		(end 102.47757 -113.73866)
		(stroke
			(width 0.2)
			(type default)
		)
		(layer "In1.Cu")
	)
	(gr_line
		(start 102.708202 -35.75812)
		(end 102.708202 -35.39998)
		(stroke
			(width 0.2)
			(type default)
		)
		(layer "In1.Cu")
	)
	(gr_arc
		(start 102.708202 -35.39998)
		(mid 102.349935 -35.04184)
		(end 101.991922 -35.400234)
		(stroke
			(width 0.2)
			(type default)
		)
		(layer "In1.Cu")
	)
	(gr_line
		(start 102.708456 -36.199826)
		(end 102.708202 -35.75812)
		(stroke
			(width 0.2)
			(type default)
		)
		(layer "In1.Cu")
	)
	(gr_arc
		(start 102.792022 -36.199826)
		(mid 103.150035 -36.55822)
		(end 103.508302 -36.20008)
		(stroke
			(width 0.2)
			(type default)
		)
		(layer "In1.Cu")
	)
	(gr_line
		(start 102.792022 -35.400234)
		(end 102.792022 -36.199826)
		(stroke
			(width 0.2)
			(type default)
		)
		(layer "In1.Cu")
	)
	(gr_arc
		(start 103.26243 -114.7064)
		(mid 103.307811 -114.815959)
		(end 103.41737 -114.86134)
		(stroke
			(width 0.2)
			(type default)
		)
		(layer "In1.Cu")
	)
	(gr_line
		(start 103.26243 -114.4524)
		(end 103.26243 -114.7064)
		(stroke
			(width 0.2)
			(type default)
		)
		(layer "In1.Cu")
	)
	(gr_arc
		(start 103.26243 -114.1476)
		(mid 103.307811 -114.257159)
		(end 103.41737 -114.30254)
		(stroke
			(width 0.2)
			(type default)
		)
		(layer "In1.Cu")
	)
	(gr_line
		(start 103.26243 -113.8936)
		(end 103.26243 -114.1476)
		(stroke
			(width 0.2)
			(type default)
		)
		(layer "In1.Cu")
	)
	(gr_line
		(start 103.41737 -114.86134)
		(end 103.62057 -114.86134)
		(stroke
			(width 0.2)
			(type default)
		)
		(layer "In1.Cu")
	)
	(gr_line
		(start 103.41737 -114.30254)
		(end 103.62057 -114.30254)
		(stroke
			(width 0.2)
			(type default)
		)
		(layer "In1.Cu")
	)
	(gr_arc
		(start 103.41737 -114.29746)
		(mid 103.307811 -114.342841)
		(end 103.26243 -114.4524)
		(stroke
			(width 0.2)
			(type default)
		)
		(layer "In1.Cu")
	)
	(gr_arc
		(start 103.41737 -113.73866)
		(mid 103.307811 -113.784041)
		(end 103.26243 -113.8936)
		(stroke
			(width 0.2)
			(type default)
		)
		(layer "In1.Cu")
	)
	(gr_line
		(start 103.508302 -36.20008)
		(end 103.508302 -35.400234)
		(stroke
			(width 0.2)
			(type default)
		)
		(layer "In1.Cu")
	)
	(gr_arc
		(start 103.508302 -35.400234)
		(mid 103.150162 -35.042094)
		(end 102.792022 -35.400234)
		(stroke
			(width 0.2)
			(type default)
		)
		(layer "In1.Cu")
	)
	(gr_arc
		(start 103.62057 -114.86134)
		(mid 103.730129 -114.815959)
		(end 103.77551 -114.7064)
		(stroke
			(width 0.2)
			(type default)
		)
		(layer "In1.Cu")
	)
	(gr_arc
		(start 103.62057 -114.30254)
		(mid 103.730129 -114.257159)
		(end 103.77551 -114.1476)
		(stroke
			(width 0.2)
			(type default)
		)
		(layer "In1.Cu")
	)
	(gr_line
		(start 103.62057 -114.29746)
		(end 103.41737 -114.29746)
		(stroke
			(width 0.2)
			(type default)
		)
		(layer "In1.Cu")
	)
	(gr_line
		(start 103.62057 -113.73866)
		(end 103.41737 -113.73866)
		(stroke
			(width 0.2)
			(type default)
		)
		(layer "In1.Cu")
	)
	(gr_line
		(start 103.77551 -114.7064)
		(end 103.77551 -114.4524)
		(stroke
			(width 0.2)
			(type default)
		)
		(layer "In1.Cu")
	)
	(gr_arc
		(start 103.77551 -114.4524)
		(mid 103.730129 -114.342841)
		(end 103.62057 -114.29746)
		(stroke
			(width 0.2)
			(type default)
		)
		(layer "In1.Cu")
	)
	(gr_line
		(start 103.77551 -114.1476)
		(end 103.77551 -113.8936)
		(stroke
			(width 0.2)
			(type default)
		)
		(layer "In1.Cu")
	)
	(gr_arc
		(start 103.77551 -113.8936)
		(mid 103.730129 -113.784041)
		(end 103.62057 -113.73866)
		(stroke
			(width 0.2)
			(type default)
		)
		(layer "In1.Cu")
	)
	(gr_arc
		(start 103.89743 -114.7064)
		(mid 103.942811 -114.815959)
		(end 104.05237 -114.86134)
		(stroke
			(width 0.2)
			(type default)
		)
		(layer "In1.Cu")
	)
	(gr_line
		(start 103.89743 -114.4524)
		(end 103.89743 -114.7064)
		(stroke
			(width 0.2)
			(type default)
		)
		(layer "In1.Cu")
	)
	(gr_arc
		(start 103.89743 -114.1476)
		(mid 103.942811 -114.257159)
		(end 104.05237 -114.30254)
		(stroke
			(width 0.2)
			(type default)
		)
		(layer "In1.Cu")
	)
	(gr_line
		(start 103.89743 -113.8936)
		(end 103.89743 -114.1476)
		(stroke
			(width 0.2)
			(type default)
		)
		(layer "In1.Cu")
	)
	(gr_line
		(start 104.05237 -114.86134)
		(end 104.25557 -114.86134)
		(stroke
			(width 0.2)
			(type default)
		)
		(layer "In1.Cu")
	)
	(gr_line
		(start 104.05237 -114.30254)
		(end 104.25557 -114.30254)
		(stroke
			(width 0.2)
			(type default)
		)
		(layer "In1.Cu")
	)
	(gr_arc
		(start 104.05237 -114.29746)
		(mid 103.942811 -114.342841)
		(end 103.89743 -114.4524)
		(stroke
			(width 0.2)
			(type default)
		)
		(layer "In1.Cu")
	)
	(gr_arc
		(start 104.05237 -113.73866)
		(mid 103.942811 -113.784041)
		(end 103.89743 -113.8936)
		(stroke
			(width 0.2)
			(type default)
		)
		(layer "In1.Cu")
	)
	(gr_arc
		(start 104.25557 -114.86134)
		(mid 104.365129 -114.815959)
		(end 104.41051 -114.7064)
		(stroke
			(width 0.2)
			(type default)
		)
		(layer "In1.Cu")
	)
	(gr_arc
		(start 104.25557 -114.30254)
		(mid 104.365129 -114.257159)
		(end 104.41051 -114.1476)
		(stroke
			(width 0.2)
			(type default)
		)
		(layer "In1.Cu")
	)
	(gr_line
		(start 104.25557 -114.29746)
		(end 104.05237 -114.29746)
		(stroke
			(width 0.2)
			(type default)
		)
		(layer "In1.Cu")
	)
	(gr_line
		(start 104.25557 -113.73866)
		(end 104.05237 -113.73866)
		(stroke
			(width 0.2)
			(type default)
		)
		(layer "In1.Cu")
	)
	(gr_line
		(start 104.41051 -114.7064)
		(end 104.41051 -114.4524)
		(stroke
			(width 0.2)
			(type default)
		)
		(layer "In1.Cu")
	)
	(gr_arc
		(start 104.41051 -114.4524)
		(mid 104.365129 -114.342841)
		(end 104.25557 -114.29746)
		(stroke
			(width 0.2)
			(type default)
		)
		(layer "In1.Cu")
	)
	(gr_line
		(start 104.41051 -114.1476)
		(end 104.41051 -113.8936)
		(stroke
			(width 0.2)
			(type default)
		)
		(layer "In1.Cu")
	)
	(gr_arc
		(start 104.41051 -113.8936)
		(mid 104.365129 -113.784041)
		(end 104.25557 -113.73866)
		(stroke
			(width 0.2)
			(type default)
		)
		(layer "In1.Cu")
	)
	(gr_circle
		(center 104.950006 -5.999988)
		(end 105.625646 -5.999988)
		(stroke
			(width 0.2)
			(type default)
		)
		(fill no)
		(layer "In1.Cu")
	)
	(gr_arc
		(start 105.04043 -114.7064)
		(mid 105.085811 -114.815959)
		(end 105.19537 -114.86134)
		(stroke
			(width 0.2)
			(type default)
		)
		(layer "In1.Cu")
	)
	(gr_line
		(start 105.04043 -114.4524)
		(end 105.04043 -114.7064)
		(stroke
			(width 0.2)
			(type default)
		)
		(layer "In1.Cu")
	)
	(gr_arc
		(start 105.04043 -114.1476)
		(mid 105.085811 -114.257159)
		(end 105.19537 -114.30254)
		(stroke
			(width 0.2)
			(type default)
		)
		(layer "In1.Cu")
	)
	(gr_line
		(start 105.04043 -113.8936)
		(end 105.04043 -114.1476)
		(stroke
			(width 0.2)
			(type default)
		)
		(layer "In1.Cu")
	)
	(gr_line
		(start 105.19537 -114.86134)
		(end 105.39857 -114.86134)
		(stroke
			(width 0.2)
			(type default)
		)
		(layer "In1.Cu")
	)
	(gr_line
		(start 105.19537 -114.30254)
		(end 105.39857 -114.30254)
		(stroke
			(width 0.2)
			(type default)
		)
		(layer "In1.Cu")
	)
	(gr_arc
		(start 105.19537 -114.29746)
		(mid 105.085811 -114.342841)
		(end 105.04043 -114.4524)
		(stroke
			(width 0.2)
			(type default)
		)
		(layer "In1.Cu")
	)
	(gr_arc
		(start 105.19537 -113.73866)
		(mid 105.085811 -113.784041)
		(end 105.04043 -113.8936)
		(stroke
			(width 0.2)
			(type default)
		)
		(layer "In1.Cu")
	)
	(gr_arc
		(start 105.39857 -114.86134)
		(mid 105.508129 -114.815959)
		(end 105.55351 -114.7064)
		(stroke
			(width 0.2)
			(type default)
		)
		(layer "In1.Cu")
	)
	(gr_arc
		(start 105.39857 -114.30254)
		(mid 105.508129 -114.257159)
		(end 105.55351 -114.1476)
		(stroke
			(width 0.2)
			(type default)
		)
		(layer "In1.Cu")
	)
	(gr_line
		(start 105.39857 -114.29746)
		(end 105.19537 -114.29746)
		(stroke
			(width 0.2)
			(type default)
		)
		(layer "In1.Cu")
	)
	(gr_line
		(start 105.39857 -113.73866)
		(end 105.19537 -113.73866)
		(stroke
			(width 0.2)
			(type default)
		)
		(layer "In1.Cu")
	)
	(gr_line
		(start 105.55351 -114.7064)
		(end 105.55351 -114.4524)
		(stroke
			(width 0.2)
			(type default)
		)
		(layer "In1.Cu")
	)
	(gr_arc
		(start 105.55351 -114.4524)
		(mid 105.508129 -114.342841)
		(end 105.39857 -114.29746)
		(stroke
			(width 0.2)
			(type default)
		)
		(layer "In1.Cu")
	)
	(gr_line
		(start 105.55351 -114.1476)
		(end 105.55351 -113.8936)
		(stroke
			(width 0.2)
			(type default)
		)
		(layer "In1.Cu")
	)
	(gr_arc
		(start 105.55351 -113.8936)
		(mid 105.508129 -113.784041)
		(end 105.39857 -113.73866)
		(stroke
			(width 0.2)
			(type default)
		)
		(layer "In1.Cu")
	)
	(gr_arc
		(start 105.67543 -114.7064)
		(mid 105.720811 -114.815959)
		(end 105.83037 -114.86134)
		(stroke
			(width 0.2)
			(type default)
		)
		(layer "In1.Cu")
	)
	(gr_line
		(start 105.67543 -114.4524)
		(end 105.67543 -114.7064)
		(stroke
			(width 0.2)
			(type default)
		)
		(layer "In1.Cu")
	)
	(gr_arc
		(start 105.67543 -114.1476)
		(mid 105.720811 -114.257159)
		(end 105.83037 -114.30254)
		(stroke
			(width 0.2)
			(type default)
		)
		(layer "In1.Cu")
	)
	(gr_line
		(start 105.67543 -113.8936)
		(end 105.67543 -114.1476)
		(stroke
			(width 0.2)
			(type default)
		)
		(layer "In1.Cu")
	)
	(gr_line
		(start 105.83037 -114.86134)
		(end 106.03357 -114.86134)
		(stroke
			(width 0.2)
			(type default)
		)
		(layer "In1.Cu")
	)
	(gr_line
		(start 105.83037 -114.30254)
		(end 106.03357 -114.30254)
		(stroke
			(width 0.2)
			(type default)
		)
		(layer "In1.Cu")
	)
	(gr_arc
		(start 105.83037 -114.29746)
		(mid 105.720811 -114.342841)
		(end 105.67543 -114.4524)
		(stroke
			(width 0.2)
			(type default)
		)
		(layer "In1.Cu")
	)
	(gr_arc
		(start 105.83037 -113.73866)
		(mid 105.720811 -113.784041)
		(end 105.67543 -113.8936)
		(stroke
			(width 0.2)
			(type default)
		)
		(layer "In1.Cu")
	)
	(gr_arc
		(start 106.03357 -114.86134)
		(mid 106.143129 -114.815959)
		(end 106.18851 -114.7064)
		(stroke
			(width 0.2)
			(type default)
		)
		(layer "In1.Cu")
	)
	(gr_arc
		(start 106.03357 -114.30254)
		(mid 106.143129 -114.257159)
		(end 106.18851 -114.1476)
		(stroke
			(width 0.2)
			(type default)
		)
		(layer "In1.Cu")
	)
	(gr_line
		(start 106.03357 -114.29746)
		(end 105.83037 -114.29746)
		(stroke
			(width 0.2)
			(type default)
		)
		(layer "In1.Cu")
	)
	(gr_line
		(start 106.03357 -113.73866)
		(end 105.83037 -113.73866)
		(stroke
			(width 0.2)
			(type default)
		)
		(layer "In1.Cu")
	)
	(gr_line
		(start 106.18851 -114.7064)
		(end 106.18851 -114.4524)
		(stroke
			(width 0.2)
			(type default)
		)
		(layer "In1.Cu")
	)
	(gr_arc
		(start 106.18851 -114.4524)
		(mid 106.143129 -114.342841)
		(end 106.03357 -114.29746)
		(stroke
			(width 0.2)
			(type default)
		)
		(layer "In1.Cu")
	)
	(gr_line
		(start 106.18851 -114.1476)
		(end 106.18851 -113.8936)
		(stroke
			(width 0.2)
			(type default)
		)
		(layer "In1.Cu")
	)
	(gr_arc
		(start 106.18851 -113.8936)
		(mid 106.143129 -113.784041)
		(end 106.03357 -113.73866)
		(stroke
			(width 0.2)
			(type default)
		)
		(layer "In1.Cu")
	)
	(gr_arc
		(start 106.491532 -103.850186)
		(mid 106.849672 -104.208326)
		(end 107.207812 -103.850186)
		(stroke
			(width 0.2)
			(type default)
		)
		(layer "In1.Cu")
	)
	(gr_line
		(start 106.491532 -102.850188)
		(end 106.491532 -103.850186)
		(stroke
			(width 0.2)
			(type default)
		)
		(layer "In1.Cu")
	)
	(gr_rect
		(start 106.548428 -1.303528)
		(end 107.798108 -2.756408)
		(stroke
			(width 0)
			(type default)
		)
		(fill no)
		(layer "In1.Cu")
	)
	(gr_arc
		(start 106.81843 -114.7064)
		(mid 106.863811 -114.815959)
		(end 106.97337 -114.86134)
		(stroke
			(width 0.2)
			(type default)
		)
		(layer "In1.Cu")
	)
	(gr_line
		(start 106.81843 -114.4524)
		(end 106.81843 -114.7064)
		(stroke
			(width 0.2)
			(type default)
		)
		(layer "In1.Cu")
	)
	(gr_arc
		(start 106.81843 -114.1476)
		(mid 106.863811 -114.257159)
		(end 106.97337 -114.30254)
		(stroke
			(width 0.2)
			(type default)
		)
		(layer "In1.Cu")
	)
	(gr_line
		(start 106.81843 -113.8936)
		(end 106.81843 -114.1476)
		(stroke
			(width 0.2)
			(type default)
		)
		(layer "In1.Cu")
	)
	(gr_line
		(start 106.97337 -114.86134)
		(end 107.17657 -114.86134)
		(stroke
			(width 0.2)
			(type default)
		)
		(layer "In1.Cu")
	)
	(gr_line
		(start 106.97337 -114.30254)
		(end 107.17657 -114.30254)
		(stroke
			(width 0.2)
			(type default)
		)
		(layer "In1.Cu")
	)
	(gr_arc
		(start 106.97337 -114.29746)
		(mid 106.863811 -114.342841)
		(end 106.81843 -114.4524)
		(stroke
			(width 0.2)
			(type default)
		)
		(layer "In1.Cu")
	)
	(gr_arc
		(start 106.97337 -113.73866)
		(mid 106.863811 -113.784041)
		(end 106.81843 -113.8936)
		(stroke
			(width 0.2)
			(type default)
		)
		(layer "In1.Cu")
	)
	(gr_arc
		(start 107.17657 -114.86134)
		(mid 107.286129 -114.815959)
		(end 107.33151 -114.7064)
		(stroke
			(width 0.2)
			(type default)
		)
		(layer "In1.Cu")
	)
	(gr_arc
		(start 107.17657 -114.30254)
		(mid 107.286129 -114.257159)
		(end 107.33151 -114.1476)
		(stroke
			(width 0.2)
			(type default)
		)
		(layer "In1.Cu")
	)
	(gr_line
		(start 107.17657 -114.29746)
		(end 106.97337 -114.29746)
		(stroke
			(width 0.2)
			(type default)
		)
		(layer "In1.Cu")
	)
	(gr_line
		(start 107.17657 -113.73866)
		(end 106.97337 -113.73866)
		(stroke
			(width 0.2)
			(type default)
		)
		(layer "In1.Cu")
	)
	(gr_line
		(start 107.207812 -103.850186)
		(end 107.207812 -102.850442)
		(stroke
			(width 0.2)
			(type default)
		)
		(layer "In1.Cu")
	)
	(gr_arc
		(start 107.207812 -102.850442)
		(mid 106.849799 -102.492048)
		(end 106.491532 -102.850188)
		(stroke
			(width 0.2)
			(type default)
		)
		(layer "In1.Cu")
	)
	(gr_line
		(start 107.33151 -114.7064)
		(end 107.33151 -114.4524)
		(stroke
			(width 0.2)
			(type default)
		)
		(layer "In1.Cu")
	)
	(gr_arc
		(start 107.33151 -114.4524)
		(mid 107.286129 -114.342841)
		(end 107.17657 -114.29746)
		(stroke
			(width 0.2)
			(type default)
		)
		(layer "In1.Cu")
	)
	(gr_line
		(start 107.33151 -114.1476)
		(end 107.33151 -113.8936)
		(stroke
			(width 0.2)
			(type default)
		)
		(layer "In1.Cu")
	)
	(gr_arc
		(start 107.33151 -113.8936)
		(mid 107.286129 -113.784041)
		(end 107.17657 -113.73866)
		(stroke
			(width 0.2)
			(type default)
		)
		(layer "In1.Cu")
	)
	(gr_arc
		(start 107.45343 -114.7064)
		(mid 107.498811 -114.815959)
		(end 107.60837 -114.86134)
		(stroke
			(width 0.2)
			(type default)
		)
		(layer "In1.Cu")
	)
	(gr_line
		(start 107.45343 -114.4524)
		(end 107.45343 -114.7064)
		(stroke
			(width 0.2)
			(type default)
		)
		(layer "In1.Cu")
	)
	(gr_arc
		(start 107.45343 -114.1476)
		(mid 107.498811 -114.257159)
		(end 107.60837 -114.30254)
		(stroke
			(width 0.2)
			(type default)
		)
		(layer "In1.Cu")
	)
	(gr_line
		(start 107.45343 -113.8936)
		(end 107.45343 -114.1476)
		(stroke
			(width 0.2)
			(type default)
		)
		(layer "In1.Cu")
	)
	(gr_arc
		(start 107.49153 -103.850186)
		(mid 107.84967 -104.208326)
		(end 108.20781 -103.850186)
		(stroke
			(width 0.2)
			(type default)
		)
		(layer "In1.Cu")
	)
	(gr_line
		(start 107.49153 -102.850188)
		(end 107.49153 -103.850186)
		(stroke
			(width 0.2)
			(type default)
		)
		(layer "In1.Cu")
	)
	(gr_circle
		(center 107.54995 -5.999988)
		(end 108.22559 -5.999988)
		(stroke
			(width 0.2)
			(type default)
		)
		(fill no)
		(layer "In1.Cu")
	)
	(gr_line
		(start 107.60837 -114.86134)
		(end 107.81157 -114.86134)
		(stroke
			(width 0.2)
			(type default)
		)
		(layer "In1.Cu")
	)
	(gr_line
		(start 107.60837 -114.30254)
		(end 107.81157 -114.30254)
		(stroke
			(width 0.2)
			(type default)
		)
		(layer "In1.Cu")
	)
	(gr_arc
		(start 107.60837 -114.29746)
		(mid 107.498811 -114.342841)
		(end 107.45343 -114.4524)
		(stroke
			(width 0.2)
			(type default)
		)
		(layer "In1.Cu")
	)
	(gr_arc
		(start 107.60837 -113.73866)
		(mid 107.498811 -113.784041)
		(end 107.45343 -113.8936)
		(stroke
			(width 0.2)
			(type default)
		)
		(layer "In1.Cu")
	)
	(gr_arc
		(start 107.81157 -114.86134)
		(mid 107.921129 -114.815959)
		(end 107.96651 -114.7064)
		(stroke
			(width 0.2)
			(type default)
		)
		(layer "In1.Cu")
	)
	(gr_arc
		(start 107.81157 -114.30254)
		(mid 107.921129 -114.257159)
		(end 107.96651 -114.1476)
		(stroke
			(width 0.2)
			(type default)
		)
		(layer "In1.Cu")
	)
	(gr_line
		(start 107.81157 -114.29746)
		(end 107.60837 -114.29746)
		(stroke
			(width 0.2)
			(type default)
		)
		(layer "In1.Cu")
	)
	(gr_line
		(start 107.81157 -113.73866)
		(end 107.60837 -113.73866)
		(stroke
			(width 0.2)
			(type default)
		)
		(layer "In1.Cu")
	)
	(gr_line
		(start 107.96651 -114.7064)
		(end 107.96651 -114.4524)
		(stroke
			(width 0.2)
			(type default)
		)
		(layer "In1.Cu")
	)
	(gr_arc
		(start 107.96651 -114.4524)
		(mid 107.921129 -114.342841)
		(end 107.81157 -114.29746)
		(stroke
			(width 0.2)
			(type default)
		)
		(layer "In1.Cu")
	)
	(gr_line
		(start 107.96651 -114.1476)
		(end 107.96651 -113.8936)
		(stroke
			(width 0.2)
			(type default)
		)
		(layer "In1.Cu")
	)
	(gr_arc
		(start 107.96651 -113.8936)
		(mid 107.921129 -113.784041)
		(end 107.81157 -113.73866)
		(stroke
			(width 0.2)
			(type default)
		)
		(layer "In1.Cu")
	)
	(gr_line
		(start 108.20781 -103.850186)
		(end 108.20781 -102.850442)
		(stroke
			(width 0.2)
			(type default)
		)
		(layer "In1.Cu")
	)
	(gr_arc
		(start 108.20781 -102.850442)
		(mid 107.849797 -102.492048)
		(end 107.49153 -102.850188)
		(stroke
			(width 0.2)
			(type default)
		)
		(layer "In1.Cu")
	)
	(gr_arc
		(start 108.491528 -103.849932)
		(mid 108.849541 -104.208326)
		(end 109.207808 -103.850186)
		(stroke
			(width 0.2)
			(type default)
		)
		(layer "In1.Cu")
	)
	(gr_line
		(start 108.491528 -102.850188)
		(end 108.491528 -103.849932)
		(stroke
			(width 0.2)
			(type default)
		)
		(layer "In1.Cu")
	)
	(gr_arc
		(start 108.59643 -114.7064)
		(mid 108.641811 -114.815959)
		(end 108.75137 -114.86134)
		(stroke
			(width 0.2)
			(type default)
		)
		(layer "In1.Cu")
	)
	(gr_line
		(start 108.59643 -114.4524)
		(end 108.59643 -114.7064)
		(stroke
			(width 0.2)
			(type default)
		)
		(layer "In1.Cu")
	)
	(gr_arc
		(start 108.59643 -114.1476)
		(mid 108.641811 -114.257159)
		(end 108.75137 -114.30254)
		(stroke
			(width 0.2)
			(type default)
		)
		(layer "In1.Cu")
	)
	(gr_line
		(start 108.59643 -113.8936)
		(end 108.59643 -114.1476)
		(stroke
			(width 0.2)
			(type default)
		)
		(layer "In1.Cu")
	)
	(gr_line
		(start 108.75137 -114.86134)
		(end 108.95457 -114.86134)
		(stroke
			(width 0.2)
			(type default)
		)
		(layer "In1.Cu")
	)
	(gr_line
		(start 108.75137 -114.30254)
		(end 108.95457 -114.30254)
		(stroke
			(width 0.2)
			(type default)
		)
		(layer "In1.Cu")
	)
	(gr_arc
		(start 108.75137 -114.29746)
		(mid 108.641811 -114.342841)
		(end 108.59643 -114.4524)
		(stroke
			(width 0.2)
			(type default)
		)
		(layer "In1.Cu")
	)
	(gr_arc
		(start 108.75137 -113.73866)
		(mid 108.641811 -113.784041)
		(end 108.59643 -113.8936)
		(stroke
			(width 0.2)
			(type default)
		)
		(layer "In1.Cu")
	)
	(gr_arc
		(start 108.95457 -114.86134)
		(mid 109.064129 -114.815959)
		(end 109.10951 -114.7064)
		(stroke
			(width 0.2)
			(type default)
		)
		(layer "In1.Cu")
	)
	(gr_arc
		(start 108.95457 -114.30254)
		(mid 109.064129 -114.257159)
		(end 109.10951 -114.1476)
		(stroke
			(width 0.2)
			(type default)
		)
		(layer "In1.Cu")
	)
	(gr_line
		(start 108.95457 -114.29746)
		(end 108.75137 -114.29746)
		(stroke
			(width 0.2)
			(type default)
		)
		(layer "In1.Cu")
	)
	(gr_line
		(start 108.95457 -113.73866)
		(end 108.75137 -113.73866)
		(stroke
			(width 0.2)
			(type default)
		)
		(layer "In1.Cu")
	)
	(gr_line
		(start 109.10951 -114.7064)
		(end 109.10951 -114.4524)
		(stroke
			(width 0.2)
			(type default)
		)
		(layer "In1.Cu")
	)
	(gr_arc
		(start 109.10951 -114.4524)
		(mid 109.064129 -114.342841)
		(end 108.95457 -114.29746)
		(stroke
			(width 0.2)
			(type default)
		)
		(layer "In1.Cu")
	)
	(gr_line
		(start 109.10951 -114.1476)
		(end 109.10951 -113.8936)
		(stroke
			(width 0.2)
			(type default)
		)
		(layer "In1.Cu")
	)
	(gr_arc
		(start 109.10951 -113.8936)
		(mid 109.064129 -113.784041)
		(end 108.95457 -113.73866)
		(stroke
			(width 0.2)
			(type default)
		)
		(layer "In1.Cu")
	)
	(gr_line
		(start 109.207808 -103.850186)
		(end 109.207808 -102.850188)
		(stroke
			(width 0.2)
			(type default)
		)
		(layer "In1.Cu")
	)
	(gr_arc
		(start 109.207808 -102.850188)
		(mid 108.849668 -102.492048)
		(end 108.491528 -102.850188)
		(stroke
			(width 0.2)
			(type default)
		)
		(layer "In1.Cu")
	)
	(gr_arc
		(start 109.23143 -114.7064)
		(mid 109.276811 -114.815959)
		(end 109.38637 -114.86134)
		(stroke
			(width 0.2)
			(type default)
		)
		(layer "In1.Cu")
	)
	(gr_line
		(start 109.23143 -114.4524)
		(end 109.23143 -114.7064)
		(stroke
			(width 0.2)
			(type default)
		)
		(layer "In1.Cu")
	)
	(gr_arc
		(start 109.23143 -114.1476)
		(mid 109.276811 -114.257159)
		(end 109.38637 -114.30254)
		(stroke
			(width 0.2)
			(type default)
		)
		(layer "In1.Cu")
	)
	(gr_line
		(start 109.23143 -113.8936)
		(end 109.23143 -114.1476)
		(stroke
			(width 0.2)
			(type default)
		)
		(layer "In1.Cu")
	)
	(gr_rect
		(start 109.281976 -1.303528)
		(end 110.531656 -2.756408)
		(stroke
			(width 0)
			(type default)
		)
		(fill no)
		(layer "In1.Cu")
	)
	(gr_line
		(start 109.38637 -114.86134)
		(end 109.58957 -114.86134)
		(stroke
			(width 0.2)
			(type default)
		)
		(layer "In1.Cu")
	)
	(gr_line
		(start 109.38637 -114.30254)
		(end 109.58957 -114.30254)
		(stroke
			(width 0.2)
			(type default)
		)
		(layer "In1.Cu")
	)
	(gr_arc
		(start 109.38637 -114.29746)
		(mid 109.276811 -114.342841)
		(end 109.23143 -114.4524)
		(stroke
			(width 0.2)
			(type default)
		)
		(layer "In1.Cu")
	)
	(gr_arc
		(start 109.38637 -113.73866)
		(mid 109.276811 -113.784041)
		(end 109.23143 -113.8936)
		(stroke
			(width 0.2)
			(type default)
		)
		(layer "In1.Cu")
	)
	(gr_arc
		(start 109.491526 -103.849932)
		(mid 109.849539 -104.208326)
		(end 110.207806 -103.850186)
		(stroke
			(width 0.2)
			(type default)
		)
		(layer "In1.Cu")
	)
	(gr_line
		(start 109.491526 -102.850188)
		(end 109.491526 -103.849932)
		(stroke
			(width 0.2)
			(type default)
		)
		(layer "In1.Cu")
	)
	(gr_arc
		(start 109.58957 -114.86134)
		(mid 109.699129 -114.815959)
		(end 109.74451 -114.7064)
		(stroke
			(width 0.2)
			(type default)
		)
		(layer "In1.Cu")
	)
	(gr_arc
		(start 109.58957 -114.30254)
		(mid 109.699129 -114.257159)
		(end 109.74451 -114.1476)
		(stroke
			(width 0.2)
			(type default)
		)
		(layer "In1.Cu")
	)
	(gr_line
		(start 109.58957 -114.29746)
		(end 109.38637 -114.29746)
		(stroke
			(width 0.2)
			(type default)
		)
		(layer "In1.Cu")
	)
	(gr_line
		(start 109.58957 -113.73866)
		(end 109.38637 -113.73866)
		(stroke
			(width 0.2)
			(type default)
		)
		(layer "In1.Cu")
	)
	(gr_line
		(start 109.74451 -114.7064)
		(end 109.74451 -114.4524)
		(stroke
			(width 0.2)
			(type default)
		)
		(layer "In1.Cu")
	)
	(gr_arc
		(start 109.74451 -114.4524)
		(mid 109.699129 -114.342841)
		(end 109.58957 -114.29746)
		(stroke
			(width 0.2)
			(type default)
		)
		(layer "In1.Cu")
	)
	(gr_line
		(start 109.74451 -114.1476)
		(end 109.74451 -113.8936)
		(stroke
			(width 0.2)
			(type default)
		)
		(layer "In1.Cu")
	)
	(gr_arc
		(start 109.74451 -113.8936)
		(mid 109.699129 -113.784041)
		(end 109.58957 -113.73866)
		(stroke
			(width 0.2)
			(type default)
		)
		(layer "In1.Cu")
	)
	(gr_line
		(start 110.207806 -103.850186)
		(end 110.207806 -102.850188)
		(stroke
			(width 0.2)
			(type default)
		)
		(layer "In1.Cu")
	)
	(gr_arc
		(start 110.207806 -102.850188)
		(mid 109.849666 -102.492048)
		(end 109.491526 -102.850188)
		(stroke
			(width 0.2)
			(type default)
		)
		(layer "In1.Cu")
	)
	(gr_arc
		(start 110.37443 -114.7064)
		(mid 110.419811 -114.815959)
		(end 110.52937 -114.86134)
		(stroke
			(width 0.2)
			(type default)
		)
		(layer "In1.Cu")
	)
	(gr_line
		(start 110.37443 -114.4524)
		(end 110.37443 -114.7064)
		(stroke
			(width 0.2)
			(type default)
		)
		(layer "In1.Cu")
	)
	(gr_arc
		(start 110.37443 -114.1476)
		(mid 110.419811 -114.257159)
		(end 110.52937 -114.30254)
		(stroke
			(width 0.2)
			(type default)
		)
		(layer "In1.Cu")
	)
	(gr_line
		(start 110.37443 -113.8936)
		(end 110.37443 -114.1476)
		(stroke
			(width 0.2)
			(type default)
		)
		(layer "In1.Cu")
	)
	(gr_arc
		(start 110.491524 -103.850186)
		(mid 110.849664 -104.208326)
		(end 111.207804 -103.850186)
		(stroke
			(width 0.2)
			(type default)
		)
		(layer "In1.Cu")
	)
	(gr_line
		(start 110.491524 -102.850188)
		(end 110.491524 -103.850186)
		(stroke
			(width 0.2)
			(type default)
		)
		(layer "In1.Cu")
	)
	(gr_line
		(start 110.52937 -114.86134)
		(end 110.73257 -114.86134)
		(stroke
			(width 0.2)
			(type default)
		)
		(layer "In1.Cu")
	)
	(gr_line
		(start 110.52937 -114.30254)
		(end 110.73257 -114.30254)
		(stroke
			(width 0.2)
			(type default)
		)
		(layer "In1.Cu")
	)
	(gr_arc
		(start 110.52937 -114.29746)
		(mid 110.419811 -114.342841)
		(end 110.37443 -114.4524)
		(stroke
			(width 0.2)
			(type default)
		)
		(layer "In1.Cu")
	)
	(gr_arc
		(start 110.52937 -113.73866)
		(mid 110.419811 -113.784041)
		(end 110.37443 -113.8936)
		(stroke
			(width 0.2)
			(type default)
		)
		(layer "In1.Cu")
	)
	(gr_arc
		(start 110.73257 -114.86134)
		(mid 110.842129 -114.815959)
		(end 110.88751 -114.7064)
		(stroke
			(width 0.2)
			(type default)
		)
		(layer "In1.Cu")
	)
	(gr_arc
		(start 110.73257 -114.30254)
		(mid 110.842129 -114.257159)
		(end 110.88751 -114.1476)
		(stroke
			(width 0.2)
			(type default)
		)
		(layer "In1.Cu")
	)
	(gr_line
		(start 110.73257 -114.29746)
		(end 110.52937 -114.29746)
		(stroke
			(width 0.2)
			(type default)
		)
		(layer "In1.Cu")
	)
	(gr_line
		(start 110.73257 -113.73866)
		(end 110.52937 -113.73866)
		(stroke
			(width 0.2)
			(type default)
		)
		(layer "In1.Cu")
	)
	(gr_line
		(start 110.88751 -114.7064)
		(end 110.88751 -114.4524)
		(stroke
			(width 0.2)
			(type default)
		)
		(layer "In1.Cu")
	)
	(gr_arc
		(start 110.88751 -114.4524)
		(mid 110.842129 -114.342841)
		(end 110.73257 -114.29746)
		(stroke
			(width 0.2)
			(type default)
		)
		(layer "In1.Cu")
	)
	(gr_line
		(start 110.88751 -114.1476)
		(end 110.88751 -113.8936)
		(stroke
			(width 0.2)
			(type default)
		)
		(layer "In1.Cu")
	)
	(gr_arc
		(start 110.88751 -113.8936)
		(mid 110.842129 -113.784041)
		(end 110.73257 -113.73866)
		(stroke
			(width 0.2)
			(type default)
		)
		(layer "In1.Cu")
	)
	(gr_arc
		(start 110.939072 -206.4766)
		(mid 110.999332 -206.62208)
		(end 111.144812 -206.68234)
		(stroke
			(width 0.2)
			(type default)
		)
		(layer "In1.Cu")
	)
	(gr_line
		(start 110.939072 -206.121)
		(end 110.939072 -206.4766)
		(stroke
			(width 0.2)
			(type default)
		)
		(layer "In1.Cu")
	)
	(gr_arc
		(start 110.939072 -205.5876)
		(mid 110.999332 -205.73308)
		(end 111.144812 -205.79334)
		(stroke
			(width 0.2)
			(type default)
		)
		(layer "In1.Cu")
	)
	(gr_line
		(start 110.939072 -205.232)
		(end 110.939072 -205.5876)
		(stroke
			(width 0.2)
			(type default)
		)
		(layer "In1.Cu")
	)
	(gr_arc
		(start 110.939072 -204.724)
		(mid 110.999332 -204.86948)
		(end 111.144812 -204.92974)
		(stroke
			(width 0.2)
			(type default)
		)
		(layer "In1.Cu")
	)
	(gr_line
		(start 110.939072 -204.3684)
		(end 110.939072 -204.724)
		(stroke
			(width 0.2)
			(type default)
		)
		(layer "In1.Cu")
	)
	(gr_arc
		(start 111.00943 -114.7064)
		(mid 111.054811 -114.815959)
		(end 111.16437 -114.86134)
		(stroke
			(width 0.2)
			(type default)
		)
		(layer "In1.Cu")
	)
	(gr_line
		(start 111.00943 -114.4524)
		(end 111.00943 -114.7064)
		(stroke
			(width 0.2)
			(type default)
		)
		(layer "In1.Cu")
	)
	(gr_arc
		(start 111.00943 -114.1476)
		(mid 111.054811 -114.257159)
		(end 111.16437 -114.30254)
		(stroke
			(width 0.2)
			(type default)
		)
		(layer "In1.Cu")
	)
	(gr_line
		(start 111.00943 -113.8936)
		(end 111.00943 -114.1476)
		(stroke
			(width 0.2)
			(type default)
		)
		(layer "In1.Cu")
	)
	(gr_line
		(start 111.144812 -206.68234)
		(end 111.500412 -206.68234)
		(stroke
			(width 0.2)
			(type default)
		)
		(layer "In1.Cu")
	)
	(gr_arc
		(start 111.144812 -205.91526)
		(mid 110.999332 -205.97552)
		(end 110.939072 -206.121)
		(stroke
			(width 0.2)
			(type default)
		)
		(layer "In1.Cu")
	)
	(gr_line
		(start 111.144812 -205.79334)
		(end 111.500412 -205.79334)
		(stroke
			(width 0.2)
			(type default)
		)
		(layer "In1.Cu")
	)
	(gr_arc
		(start 111.144812 -205.02626)
		(mid 110.999332 -205.08652)
		(end 110.939072 -205.232)
		(stroke
			(width 0.2)
			(type default)
		)
		(layer "In1.Cu")
	)
	(gr_line
		(start 111.144812 -204.92974)
		(end 111.500412 -204.92974)
		(stroke
			(width 0.2)
			(type default)
		)
		(layer "In1.Cu")
	)
	(gr_arc
		(start 111.144812 -204.16266)
		(mid 110.999332 -204.22292)
		(end 110.939072 -204.3684)
		(stroke
			(width 0.2)
			(type default)
		)
		(layer "In1.Cu")
	)
	(gr_line
		(start 111.16437 -114.86134)
		(end 111.36757 -114.86134)
		(stroke
			(width 0.2)
			(type default)
		)
		(layer "In1.Cu")
	)
	(gr_line
		(start 111.16437 -114.30254)
		(end 111.36757 -114.30254)
		(stroke
			(width 0.2)
			(type default)
		)
		(layer "In1.Cu")
	)
	(gr_arc
		(start 111.16437 -114.29746)
		(mid 111.054811 -114.342841)
		(end 111.00943 -114.4524)
		(stroke
			(width 0.2)
			(type default)
		)
		(layer "In1.Cu")
	)
	(gr_arc
		(start 111.16437 -113.73866)
		(mid 111.054811 -113.784041)
		(end 111.00943 -113.8936)
		(stroke
			(width 0.2)
			(type default)
		)
		(layer "In1.Cu")
	)
	(gr_line
		(start 111.207804 -103.850186)
		(end 111.207804 -102.850442)
		(stroke
			(width 0.2)
			(type default)
		)
		(layer "In1.Cu")
	)
	(gr_arc
		(start 111.207804 -102.850442)
		(mid 110.849791 -102.492048)
		(end 110.491524 -102.850188)
		(stroke
			(width 0.2)
			(type default)
		)
		(layer "In1.Cu")
	)
	(gr_arc
		(start 111.36757 -114.86134)
		(mid 111.477129 -114.815959)
		(end 111.52251 -114.7064)
		(stroke
			(width 0.2)
			(type default)
		)
		(layer "In1.Cu")
	)
	(gr_arc
		(start 111.36757 -114.30254)
		(mid 111.477129 -114.257159)
		(end 111.52251 -114.1476)
		(stroke
			(width 0.2)
			(type default)
		)
		(layer "In1.Cu")
	)
	(gr_line
		(start 111.36757 -114.29746)
		(end 111.16437 -114.29746)
		(stroke
			(width 0.2)
			(type default)
		)
		(layer "In1.Cu")
	)
	(gr_line
		(start 111.36757 -113.73866)
		(end 111.16437 -113.73866)
		(stroke
			(width 0.2)
			(type default)
		)
		(layer "In1.Cu")
	)
	(gr_arc
		(start 111.491522 -103.849932)
		(mid 111.849535 -104.208326)
		(end 112.207802 -103.850186)
		(stroke
			(width 0.2)
			(type default)
		)
		(layer "In1.Cu")
	)
	(gr_line
		(start 111.491522 -102.850188)
		(end 111.491522 -103.849932)
		(stroke
			(width 0.2)
			(type default)
		)
		(layer "In1.Cu")
	)
	(gr_arc
		(start 111.500412 -206.68234)
		(mid 111.645892 -206.62208)
		(end 111.706152 -206.4766)
		(stroke
			(width 0.2)
			(type default)
		)
		(layer "In1.Cu")
	)
	(gr_line
		(start 111.500412 -205.91526)
		(end 111.144812 -205.91526)
		(stroke
			(width 0.2)
			(type default)
		)
		(layer "In1.Cu")
	)
	(gr_arc
		(start 111.500412 -205.79334)
		(mid 111.645892 -205.73308)
		(end 111.706152 -205.5876)
		(stroke
			(width 0.2)
			(type default)
		)
		(layer "In1.Cu")
	)
	(gr_line
		(start 111.500412 -205.02626)
		(end 111.144812 -205.02626)
		(stroke
			(width 0.2)
			(type default)
		)
		(layer "In1.Cu")
	)
	(gr_arc
		(start 111.500412 -204.92974)
		(mid 111.645892 -204.86948)
		(end 111.706152 -204.724)
		(stroke
			(width 0.2)
			(type default)
		)
		(layer "In1.Cu")
	)
	(gr_line
		(start 111.500412 -204.16266)
		(end 111.144812 -204.16266)
		(stroke
			(width 0.2)
			(type default)
		)
		(layer "In1.Cu")
	)
	(gr_line
		(start 111.52251 -114.7064)
		(end 111.52251 -114.4524)
		(stroke
			(width 0.2)
			(type default)
		)
		(layer "In1.Cu")
	)
	(gr_arc
		(start 111.52251 -114.4524)
		(mid 111.477129 -114.342841)
		(end 111.36757 -114.29746)
		(stroke
			(width 0.2)
			(type default)
		)
		(layer "In1.Cu")
	)
	(gr_line
		(start 111.52251 -114.1476)
		(end 111.52251 -113.8936)
		(stroke
			(width 0.2)
			(type default)
		)
		(layer "In1.Cu")
	)
	(gr_arc
		(start 111.52251 -113.8936)
		(mid 111.477129 -113.784041)
		(end 111.36757 -113.73866)
		(stroke
			(width 0.2)
			(type default)
		)
		(layer "In1.Cu")
	)
	(gr_line
		(start 111.706152 -206.4766)
		(end 111.706152 -206.121)
		(stroke
			(width 0.2)
			(type default)
		)
		(layer "In1.Cu")
	)
	(gr_arc
		(start 111.706152 -206.121)
		(mid 111.645892 -205.97552)
		(end 111.500412 -205.91526)
		(stroke
			(width 0.2)
			(type default)
		)
		(layer "In1.Cu")
	)
	(gr_line
		(start 111.706152 -205.5876)
		(end 111.706152 -205.232)
		(stroke
			(width 0.2)
			(type default)
		)
		(layer "In1.Cu")
	)
	(gr_arc
		(start 111.706152 -205.232)
		(mid 111.645892 -205.08652)
		(end 111.500412 -205.02626)
		(stroke
			(width 0.2)
			(type default)
		)
		(layer "In1.Cu")
	)
	(gr_line
		(start 111.706152 -204.724)
		(end 111.706152 -204.3684)
		(stroke
			(width 0.2)
			(type default)
		)
		(layer "In1.Cu")
	)
	(gr_arc
		(start 111.706152 -204.3684)
		(mid 111.645892 -204.22292)
		(end 111.500412 -204.16266)
		(stroke
			(width 0.2)
			(type default)
		)
		(layer "In1.Cu")
	)
	(gr_arc
		(start 112.15243 -114.7064)
		(mid 112.197811 -114.815959)
		(end 112.30737 -114.86134)
		(stroke
			(width 0.2)
			(type default)
		)
		(layer "In1.Cu")
	)
	(gr_line
		(start 112.15243 -114.4524)
		(end 112.15243 -114.7064)
		(stroke
			(width 0.2)
			(type default)
		)
		(layer "In1.Cu")
	)
	(gr_arc
		(start 112.15243 -114.1476)
		(mid 112.197811 -114.257159)
		(end 112.30737 -114.30254)
		(stroke
			(width 0.2)
			(type default)
		)
		(layer "In1.Cu")
	)
	(gr_line
		(start 112.15243 -113.8936)
		(end 112.15243 -114.1476)
		(stroke
			(width 0.2)
			(type default)
		)
		(layer "In1.Cu")
	)
	(gr_line
		(start 112.207802 -103.850186)
		(end 112.207802 -102.850188)
		(stroke
			(width 0.2)
			(type default)
		)
		(layer "In1.Cu")
	)
	(gr_arc
		(start 112.207802 -102.850188)
		(mid 111.849662 -102.492048)
		(end 111.491522 -102.850188)
		(stroke
			(width 0.2)
			(type default)
		)
		(layer "In1.Cu")
	)
	(gr_line
		(start 112.30737 -114.86134)
		(end 112.51057 -114.86134)
		(stroke
			(width 0.2)
			(type default)
		)
		(layer "In1.Cu")
	)
	(gr_line
		(start 112.30737 -114.30254)
		(end 112.51057 -114.30254)
		(stroke
			(width 0.2)
			(type default)
		)
		(layer "In1.Cu")
	)
	(gr_arc
		(start 112.30737 -114.29746)
		(mid 112.197811 -114.342841)
		(end 112.15243 -114.4524)
		(stroke
			(width 0.2)
			(type default)
		)
		(layer "In1.Cu")
	)
	(gr_arc
		(start 112.30737 -113.73866)
		(mid 112.197811 -113.784041)
		(end 112.15243 -113.8936)
		(stroke
			(width 0.2)
			(type default)
		)
		(layer "In1.Cu")
	)
	(gr_arc
		(start 112.463072 -223.4946)
		(mid 112.523332 -223.64008)
		(end 112.668812 -223.70034)
		(stroke
			(width 0.2)
			(type default)
		)
		(layer "In1.Cu")
	)
	(gr_line
		(start 112.463072 -223.139)
		(end 112.463072 -223.4946)
		(stroke
			(width 0.2)
			(type default)
		)
		(layer "In1.Cu")
	)
	(gr_arc
		(start 112.463072 -222.631)
		(mid 112.523332 -222.77648)
		(end 112.668812 -222.83674)
		(stroke
			(width 0.2)
			(type default)
		)
		(layer "In1.Cu")
	)
	(gr_line
		(start 112.463072 -222.2754)
		(end 112.463072 -222.631)
		(stroke
			(width 0.2)
			(type default)
		)
		(layer "In1.Cu")
	)
	(gr_arc
		(start 112.463072 -221.742)
		(mid 112.523332 -221.88748)
		(end 112.668812 -221.94774)
		(stroke
			(width 0.2)
			(type default)
		)
		(layer "In1.Cu")
	)
	(gr_line
		(start 112.463072 -221.3864)
		(end 112.463072 -221.742)
		(stroke
			(width 0.2)
			(type default)
		)
		(layer "In1.Cu")
	)
	(gr_arc
		(start 112.49152 -103.850186)
		(mid 112.84966 -104.208326)
		(end 113.2078 -103.850186)
		(stroke
			(width 0.2)
			(type default)
		)
		(layer "In1.Cu")
	)
	(gr_line
		(start 112.49152 -102.850188)
		(end 112.49152 -103.850186)
		(stroke
			(width 0.2)
			(type default)
		)
		(layer "In1.Cu")
	)
	(gr_arc
		(start 112.51057 -114.86134)
		(mid 112.620129 -114.815959)
		(end 112.66551 -114.7064)
		(stroke
			(width 0.2)
			(type default)
		)
		(layer "In1.Cu")
	)
	(gr_arc
		(start 112.51057 -114.30254)
		(mid 112.620129 -114.257159)
		(end 112.66551 -114.1476)
		(stroke
			(width 0.2)
			(type default)
		)
		(layer "In1.Cu")
	)
	(gr_line
		(start 112.51057 -114.29746)
		(end 112.30737 -114.29746)
		(stroke
			(width 0.2)
			(type default)
		)
		(layer "In1.Cu")
	)
	(gr_line
		(start 112.51057 -113.73866)
		(end 112.30737 -113.73866)
		(stroke
			(width 0.2)
			(type default)
		)
		(layer "In1.Cu")
	)
	(gr_arc
		(start 112.590072 -206.4766)
		(mid 112.650332 -206.62208)
		(end 112.795812 -206.68234)
		(stroke
			(width 0.2)
			(type default)
		)
		(layer "In1.Cu")
	)
	(gr_line
		(start 112.590072 -206.121)
		(end 112.590072 -206.4766)
		(stroke
			(width 0.2)
			(type default)
		)
		(layer "In1.Cu")
	)
	(gr_arc
		(start 112.590072 -205.5876)
		(mid 112.650332 -205.73308)
		(end 112.795812 -205.79334)
		(stroke
			(width 0.2)
			(type default)
		)
		(layer "In1.Cu")
	)
	(gr_line
		(start 112.590072 -205.232)
		(end 112.590072 -205.5876)
		(stroke
			(width 0.2)
			(type default)
		)
		(layer "In1.Cu")
	)
	(gr_arc
		(start 112.590072 -204.724)
		(mid 112.650332 -204.86948)
		(end 112.795812 -204.92974)
		(stroke
			(width 0.2)
			(type default)
		)
		(layer "In1.Cu")
	)
	(gr_line
		(start 112.590072 -204.3684)
		(end 112.590072 -204.724)
		(stroke
			(width 0.2)
			(type default)
		)
		(layer "In1.Cu")
	)
	(gr_line
		(start 112.66551 -114.7064)
		(end 112.66551 -114.4524)
		(stroke
			(width 0.2)
			(type default)
		)
		(layer "In1.Cu")
	)
	(gr_arc
		(start 112.66551 -114.4524)
		(mid 112.620129 -114.342841)
		(end 112.51057 -114.29746)
		(stroke
			(width 0.2)
			(type default)
		)
		(layer "In1.Cu")
	)
	(gr_line
		(start 112.66551 -114.1476)
		(end 112.66551 -113.8936)
		(stroke
			(width 0.2)
			(type default)
		)
		(layer "In1.Cu")
	)
	(gr_arc
		(start 112.66551 -113.8936)
		(mid 112.620129 -113.784041)
		(end 112.51057 -113.73866)
		(stroke
			(width 0.2)
			(type default)
		)
		(layer "In1.Cu")
	)
	(gr_line
		(start 112.668812 -223.70034)
		(end 113.024412 -223.70034)
		(stroke
			(width 0.2)
			(type default)
		)
		(layer "In1.Cu")
	)
	(gr_arc
		(start 112.668812 -222.93326)
		(mid 112.523332 -222.99352)
		(end 112.463072 -223.139)
		(stroke
			(width 0.2)
			(type default)
		)
		(layer "In1.Cu")
	)
	(gr_line
		(start 112.668812 -222.83674)
		(end 113.024412 -222.83674)
		(stroke
			(width 0.2)
			(type default)
		)
		(layer "In1.Cu")
	)
	(gr_arc
		(start 112.668812 -222.06966)
		(mid 112.523332 -222.12992)
		(end 112.463072 -222.2754)
		(stroke
			(width 0.2)
			(type default)
		)
		(layer "In1.Cu")
	)
	(gr_line
		(start 112.668812 -221.94774)
		(end 113.024412 -221.94774)
		(stroke
			(width 0.2)
			(type default)
		)
		(layer "In1.Cu")
	)
	(gr_arc
		(start 112.668812 -221.18066)
		(mid 112.523332 -221.24092)
		(end 112.463072 -221.3864)
		(stroke
			(width 0.2)
			(type default)
		)
		(layer "In1.Cu")
	)
	(gr_arc
		(start 112.78743 -114.7064)
		(mid 112.832811 -114.815959)
		(end 112.94237 -114.86134)
		(stroke
			(width 0.2)
			(type default)
		)
		(layer "In1.Cu")
	)
	(gr_line
		(start 112.78743 -114.4524)
		(end 112.78743 -114.7064)
		(stroke
			(width 0.2)
			(type default)
		)
		(layer "In1.Cu")
	)
	(gr_arc
		(start 112.78743 -114.1476)
		(mid 112.832811 -114.257159)
		(end 112.94237 -114.30254)
		(stroke
			(width 0.2)
			(type default)
		)
		(layer "In1.Cu")
	)
	(gr_line
		(start 112.78743 -113.8936)
		(end 112.78743 -114.1476)
		(stroke
			(width 0.2)
			(type default)
		)
		(layer "In1.Cu")
	)
	(gr_line
		(start 112.795812 -206.68234)
		(end 113.151412 -206.68234)
		(stroke
			(width 0.2)
			(type default)
		)
		(layer "In1.Cu")
	)
	(gr_arc
		(start 112.795812 -205.91526)
		(mid 112.650332 -205.97552)
		(end 112.590072 -206.121)
		(stroke
			(width 0.2)
			(type default)
		)
		(layer "In1.Cu")
	)
	(gr_line
		(start 112.795812 -205.79334)
		(end 113.151412 -205.79334)
		(stroke
			(width 0.2)
			(type default)
		)
		(layer "In1.Cu")
	)
	(gr_arc
		(start 112.795812 -205.02626)
		(mid 112.650332 -205.08652)
		(end 112.590072 -205.232)
		(stroke
			(width 0.2)
			(type default)
		)
		(layer "In1.Cu")
	)
	(gr_line
		(start 112.795812 -204.92974)
		(end 113.151412 -204.92974)
		(stroke
			(width 0.2)
			(type default)
		)
		(layer "In1.Cu")
	)
	(gr_arc
		(start 112.795812 -204.16266)
		(mid 112.650332 -204.22292)
		(end 112.590072 -204.3684)
		(stroke
			(width 0.2)
			(type default)
		)
		(layer "In1.Cu")
	)
	(gr_line
		(start 112.94237 -114.86134)
		(end 113.14557 -114.86134)
		(stroke
			(width 0.2)
			(type default)
		)
		(layer "In1.Cu")
	)
	(gr_line
		(start 112.94237 -114.30254)
		(end 113.14557 -114.30254)
		(stroke
			(width 0.2)
			(type default)
		)
		(layer "In1.Cu")
	)
	(gr_arc
		(start 112.94237 -114.29746)
		(mid 112.832811 -114.342841)
		(end 112.78743 -114.4524)
		(stroke
			(width 0.2)
			(type default)
		)
		(layer "In1.Cu")
	)
	(gr_arc
		(start 112.94237 -113.73866)
		(mid 112.832811 -113.784041)
		(end 112.78743 -113.8936)
		(stroke
			(width 0.2)
			(type default)
		)
		(layer "In1.Cu")
	)
	(gr_arc
		(start 113.024412 -223.70034)
		(mid 113.169892 -223.64008)
		(end 113.230152 -223.4946)
		(stroke
			(width 0.2)
			(type default)
		)
		(layer "In1.Cu")
	)
	(gr_line
		(start 113.024412 -222.93326)
		(end 112.668812 -222.93326)
		(stroke
			(width 0.2)
			(type default)
		)
		(layer "In1.Cu")
	)
	(gr_arc
		(start 113.024412 -222.83674)
		(mid 113.169892 -222.77648)
		(end 113.230152 -222.631)
		(stroke
			(width 0.2)
			(type default)
		)
		(layer "In1.Cu")
	)
	(gr_line
		(start 113.024412 -222.06966)
		(end 112.668812 -222.06966)
		(stroke
			(width 0.2)
			(type default)
		)
		(layer "In1.Cu")
	)
	(gr_arc
		(start 113.024412 -221.94774)
		(mid 113.169892 -221.88748)
		(end 113.230152 -221.742)
		(stroke
			(width 0.2)
			(type default)
		)
		(layer "In1.Cu")
	)
	(gr_line
		(start 113.024412 -221.18066)
		(end 112.668812 -221.18066)
		(stroke
			(width 0.2)
			(type default)
		)
		(layer "In1.Cu")
	)
	(gr_arc
		(start 113.14557 -114.86134)
		(mid 113.255129 -114.815959)
		(end 113.30051 -114.7064)
		(stroke
			(width 0.2)
			(type default)
		)
		(layer "In1.Cu")
	)
	(gr_arc
		(start 113.14557 -114.30254)
		(mid 113.255129 -114.257159)
		(end 113.30051 -114.1476)
		(stroke
			(width 0.2)
			(type default)
		)
		(layer "In1.Cu")
	)
	(gr_line
		(start 113.14557 -114.29746)
		(end 112.94237 -114.29746)
		(stroke
			(width 0.2)
			(type default)
		)
		(layer "In1.Cu")
	)
	(gr_line
		(start 113.14557 -113.73866)
		(end 112.94237 -113.73866)
		(stroke
			(width 0.2)
			(type default)
		)
		(layer "In1.Cu")
	)
	(gr_arc
		(start 113.151412 -206.68234)
		(mid 113.296892 -206.62208)
		(end 113.357152 -206.4766)
		(stroke
			(width 0.2)
			(type default)
		)
		(layer "In1.Cu")
	)
	(gr_line
		(start 113.151412 -205.91526)
		(end 112.795812 -205.91526)
		(stroke
			(width 0.2)
			(type default)
		)
		(layer "In1.Cu")
	)
	(gr_arc
		(start 113.151412 -205.79334)
		(mid 113.296892 -205.73308)
		(end 113.357152 -205.5876)
		(stroke
			(width 0.2)
			(type default)
		)
		(layer "In1.Cu")
	)
	(gr_line
		(start 113.151412 -205.02626)
		(end 112.795812 -205.02626)
		(stroke
			(width 0.2)
			(type default)
		)
		(layer "In1.Cu")
	)
	(gr_arc
		(start 113.151412 -204.92974)
		(mid 113.296892 -204.86948)
		(end 113.357152 -204.724)
		(stroke
			(width 0.2)
			(type default)
		)
		(layer "In1.Cu")
	)
	(gr_line
		(start 113.151412 -204.16266)
		(end 112.795812 -204.16266)
		(stroke
			(width 0.2)
			(type default)
		)
		(layer "In1.Cu")
	)
	(gr_line
		(start 113.2078 -103.850186)
		(end 113.2078 -102.850442)
		(stroke
			(width 0.2)
			(type default)
		)
		(layer "In1.Cu")
	)
	(gr_arc
		(start 113.2078 -102.850442)
		(mid 112.849787 -102.492048)
		(end 112.49152 -102.850188)
		(stroke
			(width 0.2)
			(type default)
		)
		(layer "In1.Cu")
	)
	(gr_line
		(start 113.230152 -223.4946)
		(end 113.230152 -223.139)
		(stroke
			(width 0.2)
			(type default)
		)
		(layer "In1.Cu")
	)
	(gr_arc
		(start 113.230152 -223.139)
		(mid 113.169892 -222.99352)
		(end 113.024412 -222.93326)
		(stroke
			(width 0.2)
			(type default)
		)
		(layer "In1.Cu")
	)
	(gr_line
		(start 113.230152 -222.631)
		(end 113.230152 -222.2754)
		(stroke
			(width 0.2)
			(type default)
		)
		(layer "In1.Cu")
	)
	(gr_arc
		(start 113.230152 -222.2754)
		(mid 113.169892 -222.12992)
		(end 113.024412 -222.06966)
		(stroke
			(width 0.2)
			(type default)
		)
		(layer "In1.Cu")
	)
	(gr_line
		(start 113.230152 -221.742)
		(end 113.230152 -221.3864)
		(stroke
			(width 0.2)
			(type default)
		)
		(layer "In1.Cu")
	)
	(gr_arc
		(start 113.230152 -221.3864)
		(mid 113.169892 -221.24092)
		(end 113.024412 -221.18066)
		(stroke
			(width 0.2)
			(type default)
		)
		(layer "In1.Cu")
	)
	(gr_line
		(start 113.30051 -114.7064)
		(end 113.30051 -114.4524)
		(stroke
			(width 0.2)
			(type default)
		)
		(layer "In1.Cu")
	)
	(gr_arc
		(start 113.30051 -114.4524)
		(mid 113.255129 -114.342841)
		(end 113.14557 -114.29746)
		(stroke
			(width 0.2)
			(type default)
		)
		(layer "In1.Cu")
	)
	(gr_line
		(start 113.30051 -114.1476)
		(end 113.30051 -113.8936)
		(stroke
			(width 0.2)
			(type default)
		)
		(layer "In1.Cu")
	)
	(gr_arc
		(start 113.30051 -113.8936)
		(mid 113.255129 -113.784041)
		(end 113.14557 -113.73866)
		(stroke
			(width 0.2)
			(type default)
		)
		(layer "In1.Cu")
	)
	(gr_line
		(start 113.357152 -206.4766)
		(end 113.357152 -206.121)
		(stroke
			(width 0.2)
			(type default)
		)
		(layer "In1.Cu")
	)
	(gr_arc
		(start 113.357152 -206.121)
		(mid 113.296892 -205.97552)
		(end 113.151412 -205.91526)
		(stroke
			(width 0.2)
			(type default)
		)
		(layer "In1.Cu")
	)
	(gr_line
		(start 113.357152 -205.5876)
		(end 113.357152 -205.232)
		(stroke
			(width 0.2)
			(type default)
		)
		(layer "In1.Cu")
	)
	(gr_arc
		(start 113.357152 -205.232)
		(mid 113.296892 -205.08652)
		(end 113.151412 -205.02626)
		(stroke
			(width 0.2)
			(type default)
		)
		(layer "In1.Cu")
	)
	(gr_line
		(start 113.357152 -204.724)
		(end 113.357152 -204.3684)
		(stroke
			(width 0.2)
			(type default)
		)
		(layer "In1.Cu")
	)
	(gr_arc
		(start 113.357152 -204.3684)
		(mid 113.296892 -204.22292)
		(end 113.151412 -204.16266)
		(stroke
			(width 0.2)
			(type default)
		)
		(layer "In1.Cu")
	)
	(gr_arc
		(start 113.491518 -103.849932)
		(mid 113.849531 -104.208326)
		(end 114.207798 -103.850186)
		(stroke
			(width 0.2)
			(type default)
		)
		(layer "In1.Cu")
	)
	(gr_line
		(start 113.491518 -102.850188)
		(end 113.491518 -103.849932)
		(stroke
			(width 0.2)
			(type default)
		)
		(layer "In1.Cu")
	)
	(gr_arc
		(start 113.93043 -114.7064)
		(mid 113.975811 -114.815959)
		(end 114.08537 -114.86134)
		(stroke
			(width 0.2)
			(type default)
		)
		(layer "In1.Cu")
	)
	(gr_line
		(start 113.93043 -114.4524)
		(end 113.93043 -114.7064)
		(stroke
			(width 0.2)
			(type default)
		)
		(layer "In1.Cu")
	)
	(gr_arc
		(start 113.93043 -114.1476)
		(mid 113.975811 -114.257159)
		(end 114.08537 -114.30254)
		(stroke
			(width 0.2)
			(type default)
		)
		(layer "In1.Cu")
	)
	(gr_line
		(start 113.93043 -113.8936)
		(end 113.93043 -114.1476)
		(stroke
			(width 0.2)
			(type default)
		)
		(layer "In1.Cu")
	)
	(gr_line
		(start 114.08537 -114.86134)
		(end 114.28857 -114.86134)
		(stroke
			(width 0.2)
			(type default)
		)
		(layer "In1.Cu")
	)
	(gr_line
		(start 114.08537 -114.30254)
		(end 114.28857 -114.30254)
		(stroke
			(width 0.2)
			(type default)
		)
		(layer "In1.Cu")
	)
	(gr_arc
		(start 114.08537 -114.29746)
		(mid 113.975811 -114.342841)
		(end 113.93043 -114.4524)
		(stroke
			(width 0.2)
			(type default)
		)
		(layer "In1.Cu")
	)
	(gr_arc
		(start 114.08537 -113.73866)
		(mid 113.975811 -113.784041)
		(end 113.93043 -113.8936)
		(stroke
			(width 0.2)
			(type default)
		)
		(layer "In1.Cu")
	)
	(gr_arc
		(start 114.114072 -223.4946)
		(mid 114.174332 -223.64008)
		(end 114.319812 -223.70034)
		(stroke
			(width 0.2)
			(type default)
		)
		(layer "In1.Cu")
	)
	(gr_line
		(start 114.114072 -223.139)
		(end 114.114072 -223.4946)
		(stroke
			(width 0.2)
			(type default)
		)
		(layer "In1.Cu")
	)
	(gr_arc
		(start 114.114072 -222.631)
		(mid 114.174332 -222.77648)
		(end 114.319812 -222.83674)
		(stroke
			(width 0.2)
			(type default)
		)
		(layer "In1.Cu")
	)
	(gr_line
		(start 114.114072 -222.2754)
		(end 114.114072 -222.631)
		(stroke
			(width 0.2)
			(type default)
		)
		(layer "In1.Cu")
	)
	(gr_arc
		(start 114.114072 -221.742)
		(mid 114.174332 -221.88748)
		(end 114.319812 -221.94774)
		(stroke
			(width 0.2)
			(type default)
		)
		(layer "In1.Cu")
	)
	(gr_line
		(start 114.114072 -221.3864)
		(end 114.114072 -221.742)
		(stroke
			(width 0.2)
			(type default)
		)
		(layer "In1.Cu")
	)
	(gr_line
		(start 114.207798 -103.850186)
		(end 114.207798 -102.850188)
		(stroke
			(width 0.2)
			(type default)
		)
		(layer "In1.Cu")
	)
	(gr_arc
		(start 114.207798 -102.850188)
		(mid 113.849658 -102.492048)
		(end 113.491518 -102.850188)
		(stroke
			(width 0.2)
			(type default)
		)
		(layer "In1.Cu")
	)
	(gr_arc
		(start 114.28857 -114.86134)
		(mid 114.398129 -114.815959)
		(end 114.44351 -114.7064)
		(stroke
			(width 0.2)
			(type default)
		)
		(layer "In1.Cu")
	)
	(gr_arc
		(start 114.28857 -114.30254)
		(mid 114.398129 -114.257159)
		(end 114.44351 -114.1476)
		(stroke
			(width 0.2)
			(type default)
		)
		(layer "In1.Cu")
	)
	(gr_line
		(start 114.28857 -114.29746)
		(end 114.08537 -114.29746)
		(stroke
			(width 0.2)
			(type default)
		)
		(layer "In1.Cu")
	)
	(gr_line
		(start 114.28857 -113.73866)
		(end 114.08537 -113.73866)
		(stroke
			(width 0.2)
			(type default)
		)
		(layer "In1.Cu")
	)
	(gr_line
		(start 114.319812 -223.70034)
		(end 114.675412 -223.70034)
		(stroke
			(width 0.2)
			(type default)
		)
		(layer "In1.Cu")
	)
	(gr_arc
		(start 114.319812 -222.93326)
		(mid 114.174332 -222.99352)
		(end 114.114072 -223.139)
		(stroke
			(width 0.2)
			(type default)
		)
		(layer "In1.Cu")
	)
	(gr_line
		(start 114.319812 -222.83674)
		(end 114.675412 -222.83674)
		(stroke
			(width 0.2)
			(type default)
		)
		(layer "In1.Cu")
	)
	(gr_arc
		(start 114.319812 -222.06966)
		(mid 114.174332 -222.12992)
		(end 114.114072 -222.2754)
		(stroke
			(width 0.2)
			(type default)
		)
		(layer "In1.Cu")
	)
	(gr_line
		(start 114.319812 -221.94774)
		(end 114.675412 -221.94774)
		(stroke
			(width 0.2)
			(type default)
		)
		(layer "In1.Cu")
	)
	(gr_arc
		(start 114.319812 -221.18066)
		(mid 114.174332 -221.24092)
		(end 114.114072 -221.3864)
		(stroke
			(width 0.2)
			(type default)
		)
		(layer "In1.Cu")
	)
	(gr_line
		(start 114.44351 -114.7064)
		(end 114.44351 -114.4524)
		(stroke
			(width 0.2)
			(type default)
		)
		(layer "In1.Cu")
	)
	(gr_arc
		(start 114.44351 -114.4524)
		(mid 114.398129 -114.342841)
		(end 114.28857 -114.29746)
		(stroke
			(width 0.2)
			(type default)
		)
		(layer "In1.Cu")
	)
	(gr_line
		(start 114.44351 -114.1476)
		(end 114.44351 -113.8936)
		(stroke
			(width 0.2)
			(type default)
		)
		(layer "In1.Cu")
	)
	(gr_arc
		(start 114.44351 -113.8936)
		(mid 114.398129 -113.784041)
		(end 114.28857 -113.73866)
		(stroke
			(width 0.2)
			(type default)
		)
		(layer "In1.Cu")
	)
	(gr_arc
		(start 114.506502 -103.830882)
		(mid 114.864642 -104.189022)
		(end 115.222782 -103.830882)
		(stroke
			(width 0.2)
			(type default)
		)
		(layer "In1.Cu")
	)
	(gr_line
		(start 114.506502 -102.840282)
		(end 114.506502 -103.830882)
		(stroke
			(width 0.2)
			(type default)
		)
		(layer "In1.Cu")
	)
	(gr_arc
		(start 114.56543 -114.7064)
		(mid 114.610811 -114.815959)
		(end 114.72037 -114.86134)
		(stroke
			(width 0.2)
			(type default)
		)
		(layer "In1.Cu")
	)
	(gr_line
		(start 114.56543 -114.4524)
		(end 114.56543 -114.7064)
		(stroke
			(width 0.2)
			(type default)
		)
		(layer "In1.Cu")
	)
	(gr_arc
		(start 114.56543 -114.1476)
		(mid 114.610811 -114.257159)
		(end 114.72037 -114.30254)
		(stroke
			(width 0.2)
			(type default)
		)
		(layer "In1.Cu")
	)
	(gr_line
		(start 114.56543 -113.8936)
		(end 114.56543 -114.1476)
		(stroke
			(width 0.2)
			(type default)
		)
		(layer "In1.Cu")
	)
	(gr_arc
		(start 114.675412 -223.70034)
		(mid 114.820892 -223.64008)
		(end 114.881152 -223.4946)
		(stroke
			(width 0.2)
			(type default)
		)
		(layer "In1.Cu")
	)
	(gr_line
		(start 114.675412 -222.93326)
		(end 114.319812 -222.93326)
		(stroke
			(width 0.2)
			(type default)
		)
		(layer "In1.Cu")
	)
	(gr_arc
		(start 114.675412 -222.83674)
		(mid 114.820892 -222.77648)
		(end 114.881152 -222.631)
		(stroke
			(width 0.2)
			(type default)
		)
		(layer "In1.Cu")
	)
	(gr_line
		(start 114.675412 -222.06966)
		(end 114.319812 -222.06966)
		(stroke
			(width 0.2)
			(type default)
		)
		(layer "In1.Cu")
	)
	(gr_arc
		(start 114.675412 -221.94774)
		(mid 114.820892 -221.88748)
		(end 114.881152 -221.742)
		(stroke
			(width 0.2)
			(type default)
		)
		(layer "In1.Cu")
	)
	(gr_line
		(start 114.675412 -221.18066)
		(end 114.319812 -221.18066)
		(stroke
			(width 0.2)
			(type default)
		)
		(layer "In1.Cu")
	)
	(gr_line
		(start 114.72037 -114.86134)
		(end 114.92357 -114.86134)
		(stroke
			(width 0.2)
			(type default)
		)
		(layer "In1.Cu")
	)
	(gr_line
		(start 114.72037 -114.30254)
		(end 114.92357 -114.30254)
		(stroke
			(width 0.2)
			(type default)
		)
		(layer "In1.Cu")
	)
	(gr_arc
		(start 114.72037 -114.29746)
		(mid 114.610811 -114.342841)
		(end 114.56543 -114.4524)
		(stroke
			(width 0.2)
			(type default)
		)
		(layer "In1.Cu")
	)
	(gr_arc
		(start 114.72037 -113.73866)
		(mid 114.610811 -113.784041)
		(end 114.56543 -113.8936)
		(stroke
			(width 0.2)
			(type default)
		)
		(layer "In1.Cu")
	)
	(gr_line
		(start 114.881152 -223.4946)
		(end 114.881152 -223.139)
		(stroke
			(width 0.2)
			(type default)
		)
		(layer "In1.Cu")
	)
	(gr_arc
		(start 114.881152 -223.139)
		(mid 114.820892 -222.99352)
		(end 114.675412 -222.93326)
		(stroke
			(width 0.2)
			(type default)
		)
		(layer "In1.Cu")
	)
	(gr_line
		(start 114.881152 -222.631)
		(end 114.881152 -222.2754)
		(stroke
			(width 0.2)
			(type default)
		)
		(layer "In1.Cu")
	)
	(gr_arc
		(start 114.881152 -222.2754)
		(mid 114.820892 -222.12992)
		(end 114.675412 -222.06966)
		(stroke
			(width 0.2)
			(type default)
		)
		(layer "In1.Cu")
	)
	(gr_line
		(start 114.881152 -221.742)
		(end 114.881152 -221.3864)
		(stroke
			(width 0.2)
			(type default)
		)
		(layer "In1.Cu")
	)
	(gr_arc
		(start 114.881152 -221.3864)
		(mid 114.820892 -221.24092)
		(end 114.675412 -221.18066)
		(stroke
			(width 0.2)
			(type default)
		)
		(layer "In1.Cu")
	)
	(gr_arc
		(start 114.92357 -114.86134)
		(mid 115.033129 -114.815959)
		(end 115.07851 -114.7064)
		(stroke
			(width 0.2)
			(type default)
		)
		(layer "In1.Cu")
	)
	(gr_arc
		(start 114.92357 -114.30254)
		(mid 115.033129 -114.257159)
		(end 115.07851 -114.1476)
		(stroke
			(width 0.2)
			(type default)
		)
		(layer "In1.Cu")
	)
	(gr_line
		(start 114.92357 -114.29746)
		(end 114.72037 -114.29746)
		(stroke
			(width 0.2)
			(type default)
		)
		(layer "In1.Cu")
	)
	(gr_line
		(start 114.92357 -113.73866)
		(end 114.72037 -113.73866)
		(stroke
			(width 0.2)
			(type default)
		)
		(layer "In1.Cu")
	)
	(gr_line
		(start 115.07851 -114.7064)
		(end 115.07851 -114.4524)
		(stroke
			(width 0.2)
			(type default)
		)
		(layer "In1.Cu")
	)
	(gr_arc
		(start 115.07851 -114.4524)
		(mid 115.033129 -114.342841)
		(end 114.92357 -114.29746)
		(stroke
			(width 0.2)
			(type default)
		)
		(layer "In1.Cu")
	)
	(gr_line
		(start 115.07851 -114.1476)
		(end 115.07851 -113.8936)
		(stroke
			(width 0.2)
			(type default)
		)
		(layer "In1.Cu")
	)
	(gr_arc
		(start 115.07851 -113.8936)
		(mid 115.033129 -113.784041)
		(end 114.92357 -113.73866)
		(stroke
			(width 0.2)
			(type default)
		)
		(layer "In1.Cu")
	)
	(gr_line
		(start 115.222782 -103.830882)
		(end 115.222782 -102.840536)
		(stroke
			(width 0.2)
			(type default)
		)
		(layer "In1.Cu")
	)
	(gr_arc
		(start 115.222782 -102.840536)
		(mid 114.864769 -102.482142)
		(end 114.506502 -102.840282)
		(stroke
			(width 0.2)
			(type default)
		)
		(layer "In1.Cu")
	)
	(gr_arc
		(start 115.522502 -103.830882)
		(mid 115.880642 -104.189022)
		(end 116.238782 -103.830882)
		(stroke
			(width 0.2)
			(type default)
		)
		(layer "In1.Cu")
	)
	(gr_line
		(start 115.522502 -102.840282)
		(end 115.522502 -103.830882)
		(stroke
			(width 0.2)
			(type default)
		)
		(layer "In1.Cu")
	)
	(gr_arc
		(start 115.70843 -114.7064)
		(mid 115.753811 -114.815959)
		(end 115.86337 -114.86134)
		(stroke
			(width 0.2)
			(type default)
		)
		(layer "In1.Cu")
	)
	(gr_line
		(start 115.70843 -114.4524)
		(end 115.70843 -114.7064)
		(stroke
			(width 0.2)
			(type default)
		)
		(layer "In1.Cu")
	)
	(gr_arc
		(start 115.70843 -114.1476)
		(mid 115.753811 -114.257159)
		(end 115.86337 -114.30254)
		(stroke
			(width 0.2)
			(type default)
		)
		(layer "In1.Cu")
	)
	(gr_line
		(start 115.70843 -113.8936)
		(end 115.70843 -114.1476)
		(stroke
			(width 0.2)
			(type default)
		)
		(layer "In1.Cu")
	)
	(gr_line
		(start 115.86337 -114.86134)
		(end 116.06657 -114.86134)
		(stroke
			(width 0.2)
			(type default)
		)
		(layer "In1.Cu")
	)
	(gr_line
		(start 115.86337 -114.30254)
		(end 116.06657 -114.30254)
		(stroke
			(width 0.2)
			(type default)
		)
		(layer "In1.Cu")
	)
	(gr_arc
		(start 115.86337 -114.29746)
		(mid 115.753811 -114.342841)
		(end 115.70843 -114.4524)
		(stroke
			(width 0.2)
			(type default)
		)
		(layer "In1.Cu")
	)
	(gr_arc
		(start 115.86337 -113.73866)
		(mid 115.753811 -113.784041)
		(end 115.70843 -113.8936)
		(stroke
			(width 0.2)
			(type default)
		)
		(layer "In1.Cu")
	)
	(gr_arc
		(start 116.06657 -114.86134)
		(mid 116.176129 -114.815959)
		(end 116.22151 -114.7064)
		(stroke
			(width 0.2)
			(type default)
		)
		(layer "In1.Cu")
	)
	(gr_arc
		(start 116.06657 -114.30254)
		(mid 116.176129 -114.257159)
		(end 116.22151 -114.1476)
		(stroke
			(width 0.2)
			(type default)
		)
		(layer "In1.Cu")
	)
	(gr_line
		(start 116.06657 -114.29746)
		(end 115.86337 -114.29746)
		(stroke
			(width 0.2)
			(type default)
		)
		(layer "In1.Cu")
	)
	(gr_line
		(start 116.06657 -113.73866)
		(end 115.86337 -113.73866)
		(stroke
			(width 0.2)
			(type default)
		)
		(layer "In1.Cu")
	)
	(gr_line
		(start 116.22151 -114.7064)
		(end 116.22151 -114.4524)
		(stroke
			(width 0.2)
			(type default)
		)
		(layer "In1.Cu")
	)
	(gr_arc
		(start 116.22151 -114.4524)
		(mid 116.176129 -114.342841)
		(end 116.06657 -114.29746)
		(stroke
			(width 0.2)
			(type default)
		)
		(layer "In1.Cu")
	)
	(gr_line
		(start 116.22151 -114.1476)
		(end 116.22151 -113.8936)
		(stroke
			(width 0.2)
			(type default)
		)
		(layer "In1.Cu")
	)
	(gr_arc
		(start 116.22151 -113.8936)
		(mid 116.176129 -113.784041)
		(end 116.06657 -113.73866)
		(stroke
			(width 0.2)
			(type default)
		)
		(layer "In1.Cu")
	)
	(gr_line
		(start 116.238782 -103.830882)
		(end 116.238782 -102.840536)
		(stroke
			(width 0.2)
			(type default)
		)
		(layer "In1.Cu")
	)
	(gr_arc
		(start 116.238782 -102.840536)
		(mid 115.880769 -102.482142)
		(end 115.522502 -102.840282)
		(stroke
			(width 0.2)
			(type default)
		)
		(layer "In1.Cu")
	)
	(gr_arc
		(start 116.34343 -114.7064)
		(mid 116.388811 -114.815959)
		(end 116.49837 -114.86134)
		(stroke
			(width 0.2)
			(type default)
		)
		(layer "In1.Cu")
	)
	(gr_line
		(start 116.34343 -114.4524)
		(end 116.34343 -114.7064)
		(stroke
			(width 0.2)
			(type default)
		)
		(layer "In1.Cu")
	)
	(gr_arc
		(start 116.34343 -114.1476)
		(mid 116.388811 -114.257159)
		(end 116.49837 -114.30254)
		(stroke
			(width 0.2)
			(type default)
		)
		(layer "In1.Cu")
	)
	(gr_line
		(start 116.34343 -113.8936)
		(end 116.34343 -114.1476)
		(stroke
			(width 0.2)
			(type default)
		)
		(layer "In1.Cu")
	)
	(gr_line
		(start 116.49837 -114.86134)
		(end 116.70157 -114.86134)
		(stroke
			(width 0.2)
			(type default)
		)
		(layer "In1.Cu")
	)
	(gr_line
		(start 116.49837 -114.30254)
		(end 116.70157 -114.30254)
		(stroke
			(width 0.2)
			(type default)
		)
		(layer "In1.Cu")
	)
	(gr_arc
		(start 116.49837 -114.29746)
		(mid 116.388811 -114.342841)
		(end 116.34343 -114.4524)
		(stroke
			(width 0.2)
			(type default)
		)
		(layer "In1.Cu")
	)
	(gr_arc
		(start 116.49837 -113.73866)
		(mid 116.388811 -113.784041)
		(end 116.34343 -113.8936)
		(stroke
			(width 0.2)
			(type default)
		)
		(layer "In1.Cu")
	)
	(gr_arc
		(start 116.70157 -114.86134)
		(mid 116.811129 -114.815959)
		(end 116.85651 -114.7064)
		(stroke
			(width 0.2)
			(type default)
		)
		(layer "In1.Cu")
	)
	(gr_arc
		(start 116.70157 -114.30254)
		(mid 116.811129 -114.257159)
		(end 116.85651 -114.1476)
		(stroke
			(width 0.2)
			(type default)
		)
		(layer "In1.Cu")
	)
	(gr_line
		(start 116.70157 -114.29746)
		(end 116.49837 -114.29746)
		(stroke
			(width 0.2)
			(type default)
		)
		(layer "In1.Cu")
	)
	(gr_line
		(start 116.70157 -113.73866)
		(end 116.49837 -113.73866)
		(stroke
			(width 0.2)
			(type default)
		)
		(layer "In1.Cu")
	)
	(gr_line
		(start 116.85651 -114.7064)
		(end 116.85651 -114.4524)
		(stroke
			(width 0.2)
			(type default)
		)
		(layer "In1.Cu")
	)
	(gr_arc
		(start 116.85651 -114.4524)
		(mid 116.811129 -114.342841)
		(end 116.70157 -114.29746)
		(stroke
			(width 0.2)
			(type default)
		)
		(layer "In1.Cu")
	)
	(gr_line
		(start 116.85651 -114.1476)
		(end 116.85651 -113.8936)
		(stroke
			(width 0.2)
			(type default)
		)
		(layer "In1.Cu")
	)
	(gr_arc
		(start 116.85651 -113.8936)
		(mid 116.811129 -113.784041)
		(end 116.70157 -113.73866)
		(stroke
			(width 0.2)
			(type default)
		)
		(layer "In1.Cu")
	)
	(gr_arc
		(start 117.48643 -114.7064)
		(mid 117.531811 -114.815959)
		(end 117.64137 -114.86134)
		(stroke
			(width 0.2)
			(type default)
		)
		(layer "In1.Cu")
	)
	(gr_line
		(start 117.48643 -114.4524)
		(end 117.48643 -114.7064)
		(stroke
			(width 0.2)
			(type default)
		)
		(layer "In1.Cu")
	)
	(gr_arc
		(start 117.48643 -114.1476)
		(mid 117.531811 -114.257159)
		(end 117.64137 -114.30254)
		(stroke
			(width 0.2)
			(type default)
		)
		(layer "In1.Cu")
	)
	(gr_line
		(start 117.48643 -113.8936)
		(end 117.48643 -114.1476)
		(stroke
			(width 0.2)
			(type default)
		)
		(layer "In1.Cu")
	)
	(gr_arc
		(start 117.492018 -103.849932)
		(mid 117.850031 -104.208326)
		(end 118.208298 -103.850186)
		(stroke
			(width 0.2)
			(type default)
		)
		(layer "In1.Cu")
	)
	(gr_line
		(start 117.492018 -102.850188)
		(end 117.492018 -103.849932)
		(stroke
			(width 0.2)
			(type default)
		)
		(layer "In1.Cu")
	)
	(gr_line
		(start 117.64137 -114.86134)
		(end 117.84457 -114.86134)
		(stroke
			(width 0.2)
			(type default)
		)
		(layer "In1.Cu")
	)
	(gr_line
		(start 117.64137 -114.30254)
		(end 117.84457 -114.30254)
		(stroke
			(width 0.2)
			(type default)
		)
		(layer "In1.Cu")
	)
	(gr_arc
		(start 117.64137 -114.29746)
		(mid 117.531811 -114.342841)
		(end 117.48643 -114.4524)
		(stroke
			(width 0.2)
			(type default)
		)
		(layer "In1.Cu")
	)
	(gr_arc
		(start 117.64137 -113.73866)
		(mid 117.531811 -113.784041)
		(end 117.48643 -113.8936)
		(stroke
			(width 0.2)
			(type default)
		)
		(layer "In1.Cu")
	)
	(gr_arc
		(start 117.84457 -114.86134)
		(mid 117.954129 -114.815959)
		(end 117.99951 -114.7064)
		(stroke
			(width 0.2)
			(type default)
		)
		(layer "In1.Cu")
	)
	(gr_arc
		(start 117.84457 -114.30254)
		(mid 117.954129 -114.257159)
		(end 117.99951 -114.1476)
		(stroke
			(width 0.2)
			(type default)
		)
		(layer "In1.Cu")
	)
	(gr_line
		(start 117.84457 -114.29746)
		(end 117.64137 -114.29746)
		(stroke
			(width 0.2)
			(type default)
		)
		(layer "In1.Cu")
	)
	(gr_line
		(start 117.84457 -113.73866)
		(end 117.64137 -113.73866)
		(stroke
			(width 0.2)
			(type default)
		)
		(layer "In1.Cu")
	)
	(gr_line
		(start 117.99951 -114.7064)
		(end 117.99951 -114.4524)
		(stroke
			(width 0.2)
			(type default)
		)
		(layer "In1.Cu")
	)
	(gr_arc
		(start 117.99951 -114.4524)
		(mid 117.954129 -114.342841)
		(end 117.84457 -114.29746)
		(stroke
			(width 0.2)
			(type default)
		)
		(layer "In1.Cu")
	)
	(gr_line
		(start 117.99951 -114.1476)
		(end 117.99951 -113.8936)
		(stroke
			(width 0.2)
			(type default)
		)
		(layer "In1.Cu")
	)
	(gr_arc
		(start 117.99951 -113.8936)
		(mid 117.954129 -113.784041)
		(end 117.84457 -113.73866)
		(stroke
			(width 0.2)
			(type default)
		)
		(layer "In1.Cu")
	)
	(gr_arc
		(start 118.12143 -114.7064)
		(mid 118.166811 -114.815959)
		(end 118.27637 -114.86134)
		(stroke
			(width 0.2)
			(type default)
		)
		(layer "In1.Cu")
	)
	(gr_line
		(start 118.12143 -114.4524)
		(end 118.12143 -114.7064)
		(stroke
			(width 0.2)
			(type default)
		)
		(layer "In1.Cu")
	)
	(gr_arc
		(start 118.12143 -114.1476)
		(mid 118.166811 -114.257159)
		(end 118.27637 -114.30254)
		(stroke
			(width 0.2)
			(type default)
		)
		(layer "In1.Cu")
	)
	(gr_line
		(start 118.12143 -113.8936)
		(end 118.12143 -114.1476)
		(stroke
			(width 0.2)
			(type default)
		)
		(layer "In1.Cu")
	)
	(gr_line
		(start 118.208298 -103.850186)
		(end 118.208298 -102.850188)
		(stroke
			(width 0.2)
			(type default)
		)
		(layer "In1.Cu")
	)
	(gr_arc
		(start 118.208298 -102.850188)
		(mid 117.850158 -102.492048)
		(end 117.492018 -102.850188)
		(stroke
			(width 0.2)
			(type default)
		)
		(layer "In1.Cu")
	)
	(gr_line
		(start 118.27637 -114.86134)
		(end 118.47957 -114.86134)
		(stroke
			(width 0.2)
			(type default)
		)
		(layer "In1.Cu")
	)
	(gr_line
		(start 118.27637 -114.30254)
		(end 118.47957 -114.30254)
		(stroke
			(width 0.2)
			(type default)
		)
		(layer "In1.Cu")
	)
	(gr_arc
		(start 118.27637 -114.29746)
		(mid 118.166811 -114.342841)
		(end 118.12143 -114.4524)
		(stroke
			(width 0.2)
			(type default)
		)
		(layer "In1.Cu")
	)
	(gr_arc
		(start 118.27637 -113.73866)
		(mid 118.166811 -113.784041)
		(end 118.12143 -113.8936)
		(stroke
			(width 0.2)
			(type default)
		)
		(layer "In1.Cu")
	)
	(gr_arc
		(start 118.47957 -114.86134)
		(mid 118.589129 -114.815959)
		(end 118.63451 -114.7064)
		(stroke
			(width 0.2)
			(type default)
		)
		(layer "In1.Cu")
	)
	(gr_arc
		(start 118.47957 -114.30254)
		(mid 118.589129 -114.257159)
		(end 118.63451 -114.1476)
		(stroke
			(width 0.2)
			(type default)
		)
		(layer "In1.Cu")
	)
	(gr_line
		(start 118.47957 -114.29746)
		(end 118.27637 -114.29746)
		(stroke
			(width 0.2)
			(type default)
		)
		(layer "In1.Cu")
	)
	(gr_line
		(start 118.47957 -113.73866)
		(end 118.27637 -113.73866)
		(stroke
			(width 0.2)
			(type default)
		)
		(layer "In1.Cu")
	)
	(gr_arc
		(start 118.492016 -103.849932)
		(mid 118.850029 -104.208326)
		(end 119.208296 -103.850186)
		(stroke
			(width 0.2)
			(type default)
		)
		(layer "In1.Cu")
	)
	(gr_line
		(start 118.492016 -102.850188)
		(end 118.492016 -103.849932)
		(stroke
			(width 0.2)
			(type default)
		)
		(layer "In1.Cu")
	)
	(gr_line
		(start 118.63451 -114.7064)
		(end 118.63451 -114.4524)
		(stroke
			(width 0.2)
			(type default)
		)
		(layer "In1.Cu")
	)
	(gr_arc
		(start 118.63451 -114.4524)
		(mid 118.589129 -114.342841)
		(end 118.47957 -114.29746)
		(stroke
			(width 0.2)
			(type default)
		)
		(layer "In1.Cu")
	)
	(gr_line
		(start 118.63451 -114.1476)
		(end 118.63451 -113.8936)
		(stroke
			(width 0.2)
			(type default)
		)
		(layer "In1.Cu")
	)
	(gr_arc
		(start 118.63451 -113.8936)
		(mid 118.589129 -113.784041)
		(end 118.47957 -113.73866)
		(stroke
			(width 0.2)
			(type default)
		)
		(layer "In1.Cu")
	)
	(gr_arc
		(start 118.813072 -206.4766)
		(mid 118.873332 -206.62208)
		(end 119.018812 -206.68234)
		(stroke
			(width 0.2)
			(type default)
		)
		(layer "In1.Cu")
	)
	(gr_line
		(start 118.813072 -206.121)
		(end 118.813072 -206.4766)
		(stroke
			(width 0.2)
			(type default)
		)
		(layer "In1.Cu")
	)
	(gr_arc
		(start 118.813072 -205.5876)
		(mid 118.873332 -205.73308)
		(end 119.018812 -205.79334)
		(stroke
			(width 0.2)
			(type default)
		)
		(layer "In1.Cu")
	)
	(gr_line
		(start 118.813072 -205.232)
		(end 118.813072 -205.5876)
		(stroke
			(width 0.2)
			(type default)
		)
		(layer "In1.Cu")
	)
	(gr_arc
		(start 118.813072 -204.724)
		(mid 118.873332 -204.86948)
		(end 119.018812 -204.92974)
		(stroke
			(width 0.2)
			(type default)
		)
		(layer "In1.Cu")
	)
	(gr_line
		(start 118.813072 -204.3684)
		(end 118.813072 -204.724)
		(stroke
			(width 0.2)
			(type default)
		)
		(layer "In1.Cu")
	)
	(gr_line
		(start 119.018812 -206.68234)
		(end 119.374412 -206.68234)
		(stroke
			(width 0.2)
			(type default)
		)
		(layer "In1.Cu")
	)
	(gr_arc
		(start 119.018812 -205.91526)
		(mid 118.873332 -205.97552)
		(end 118.813072 -206.121)
		(stroke
			(width 0.2)
			(type default)
		)
		(layer "In1.Cu")
	)
	(gr_line
		(start 119.018812 -205.79334)
		(end 119.374412 -205.79334)
		(stroke
			(width 0.2)
			(type default)
		)
		(layer "In1.Cu")
	)
	(gr_arc
		(start 119.018812 -205.02626)
		(mid 118.873332 -205.08652)
		(end 118.813072 -205.232)
		(stroke
			(width 0.2)
			(type default)
		)
		(layer "In1.Cu")
	)
	(gr_line
		(start 119.018812 -204.92974)
		(end 119.374412 -204.92974)
		(stroke
			(width 0.2)
			(type default)
		)
		(layer "In1.Cu")
	)
	(gr_arc
		(start 119.018812 -204.16266)
		(mid 118.873332 -204.22292)
		(end 118.813072 -204.3684)
		(stroke
			(width 0.2)
			(type default)
		)
		(layer "In1.Cu")
	)
	(gr_line
		(start 119.208296 -103.850186)
		(end 119.208296 -102.850188)
		(stroke
			(width 0.2)
			(type default)
		)
		(layer "In1.Cu")
	)
	(gr_arc
		(start 119.208296 -102.850188)
		(mid 118.850156 -102.492048)
		(end 118.492016 -102.850188)
		(stroke
			(width 0.2)
			(type default)
		)
		(layer "In1.Cu")
	)
	(gr_arc
		(start 119.26443 -114.7064)
		(mid 119.309811 -114.815959)
		(end 119.41937 -114.86134)
		(stroke
			(width 0.2)
			(type default)
		)
		(layer "In1.Cu")
	)
	(gr_line
		(start 119.26443 -114.4524)
		(end 119.26443 -114.7064)
		(stroke
			(width 0.2)
			(type default)
		)
		(layer "In1.Cu")
	)
	(gr_arc
		(start 119.26443 -114.1476)
		(mid 119.309811 -114.257159)
		(end 119.41937 -114.30254)
		(stroke
			(width 0.2)
			(type default)
		)
		(layer "In1.Cu")
	)
	(gr_line
		(start 119.26443 -113.8936)
		(end 119.26443 -114.1476)
		(stroke
			(width 0.2)
			(type default)
		)
		(layer "In1.Cu")
	)
	(gr_arc
		(start 119.374412 -206.68234)
		(mid 119.519892 -206.62208)
		(end 119.580152 -206.4766)
		(stroke
			(width 0.2)
			(type default)
		)
		(layer "In1.Cu")
	)
	(gr_line
		(start 119.374412 -205.91526)
		(end 119.018812 -205.91526)
		(stroke
			(width 0.2)
			(type default)
		)
		(layer "In1.Cu")
	)
	(gr_arc
		(start 119.374412 -205.79334)
		(mid 119.519892 -205.73308)
		(end 119.580152 -205.5876)
		(stroke
			(width 0.2)
			(type default)
		)
		(layer "In1.Cu")
	)
	(gr_line
		(start 119.374412 -205.02626)
		(end 119.018812 -205.02626)
		(stroke
			(width 0.2)
			(type default)
		)
		(layer "In1.Cu")
	)
	(gr_arc
		(start 119.374412 -204.92974)
		(mid 119.519892 -204.86948)
		(end 119.580152 -204.724)
		(stroke
			(width 0.2)
			(type default)
		)
		(layer "In1.Cu")
	)
	(gr_line
		(start 119.374412 -204.16266)
		(end 119.018812 -204.16266)
		(stroke
			(width 0.2)
			(type default)
		)
		(layer "In1.Cu")
	)
	(gr_line
		(start 119.41937 -114.86134)
		(end 119.62257 -114.86134)
		(stroke
			(width 0.2)
			(type default)
		)
		(layer "In1.Cu")
	)
	(gr_line
		(start 119.41937 -114.30254)
		(end 119.62257 -114.30254)
		(stroke
			(width 0.2)
			(type default)
		)
		(layer "In1.Cu")
	)
	(gr_arc
		(start 119.41937 -114.29746)
		(mid 119.309811 -114.342841)
		(end 119.26443 -114.4524)
		(stroke
			(width 0.2)
			(type default)
		)
		(layer "In1.Cu")
	)
	(gr_arc
		(start 119.41937 -113.73866)
		(mid 119.309811 -113.784041)
		(end 119.26443 -113.8936)
		(stroke
			(width 0.2)
			(type default)
		)
		(layer "In1.Cu")
	)
	(gr_line
		(start 119.580152 -206.4766)
		(end 119.580152 -206.121)
		(stroke
			(width 0.2)
			(type default)
		)
		(layer "In1.Cu")
	)
	(gr_arc
		(start 119.580152 -206.121)
		(mid 119.519892 -205.97552)
		(end 119.374412 -205.91526)
		(stroke
			(width 0.2)
			(type default)
		)
		(layer "In1.Cu")
	)
	(gr_line
		(start 119.580152 -205.5876)
		(end 119.580152 -205.232)
		(stroke
			(width 0.2)
			(type default)
		)
		(layer "In1.Cu")
	)
	(gr_arc
		(start 119.580152 -205.232)
		(mid 119.519892 -205.08652)
		(end 119.374412 -205.02626)
		(stroke
			(width 0.2)
			(type default)
		)
		(layer "In1.Cu")
	)
	(gr_line
		(start 119.580152 -204.724)
		(end 119.580152 -204.3684)
		(stroke
			(width 0.2)
			(type default)
		)
		(layer "In1.Cu")
	)
	(gr_arc
		(start 119.580152 -204.3684)
		(mid 119.519892 -204.22292)
		(end 119.374412 -204.16266)
		(stroke
			(width 0.2)
			(type default)
		)
		(layer "In1.Cu")
	)
	(gr_arc
		(start 119.62257 -114.86134)
		(mid 119.732129 -114.815959)
		(end 119.77751 -114.7064)
		(stroke
			(width 0.2)
			(type default)
		)
		(layer "In1.Cu")
	)
	(gr_arc
		(start 119.62257 -114.30254)
		(mid 119.732129 -114.257159)
		(end 119.77751 -114.1476)
		(stroke
			(width 0.2)
			(type default)
		)
		(layer "In1.Cu")
	)
	(gr_line
		(start 119.62257 -114.29746)
		(end 119.41937 -114.29746)
		(stroke
			(width 0.2)
			(type default)
		)
		(layer "In1.Cu")
	)
	(gr_line
		(start 119.62257 -113.73866)
		(end 119.41937 -113.73866)
		(stroke
			(width 0.2)
			(type default)
		)
		(layer "In1.Cu")
	)
	(gr_line
		(start 119.77751 -114.7064)
		(end 119.77751 -114.4524)
		(stroke
			(width 0.2)
			(type default)
		)
		(layer "In1.Cu")
	)
	(gr_arc
		(start 119.77751 -114.4524)
		(mid 119.732129 -114.342841)
		(end 119.62257 -114.29746)
		(stroke
			(width 0.2)
			(type default)
		)
		(layer "In1.Cu")
	)
	(gr_line
		(start 119.77751 -114.1476)
		(end 119.77751 -113.8936)
		(stroke
			(width 0.2)
			(type default)
		)
		(layer "In1.Cu")
	)
	(gr_arc
		(start 119.77751 -113.8936)
		(mid 119.732129 -113.784041)
		(end 119.62257 -113.73866)
		(stroke
			(width 0.2)
			(type default)
		)
		(layer "In1.Cu")
	)
	(gr_arc
		(start 119.89943 -114.7064)
		(mid 119.944811 -114.815959)
		(end 120.05437 -114.86134)
		(stroke
			(width 0.2)
			(type default)
		)
		(layer "In1.Cu")
	)
	(gr_line
		(start 119.89943 -114.4524)
		(end 119.89943 -114.7064)
		(stroke
			(width 0.2)
			(type default)
		)
		(layer "In1.Cu")
	)
	(gr_arc
		(start 119.89943 -114.1476)
		(mid 119.944811 -114.257159)
		(end 120.05437 -114.30254)
		(stroke
			(width 0.2)
			(type default)
		)
		(layer "In1.Cu")
	)
	(gr_line
		(start 119.89943 -113.8936)
		(end 119.89943 -114.1476)
		(stroke
			(width 0.2)
			(type default)
		)
		(layer "In1.Cu")
	)
	(gr_arc
		(start 119.956072 -223.4946)
		(mid 120.016332 -223.64008)
		(end 120.161812 -223.70034)
		(stroke
			(width 0.2)
			(type default)
		)
		(layer "In1.Cu")
	)
	(gr_line
		(start 119.956072 -223.139)
		(end 119.956072 -223.4946)
		(stroke
			(width 0.2)
			(type default)
		)
		(layer "In1.Cu")
	)
	(gr_arc
		(start 119.956072 -222.631)
		(mid 120.016332 -222.77648)
		(end 120.161812 -222.83674)
		(stroke
			(width 0.2)
			(type default)
		)
		(layer "In1.Cu")
	)
	(gr_line
		(start 119.956072 -222.2754)
		(end 119.956072 -222.631)
		(stroke
			(width 0.2)
			(type default)
		)
		(layer "In1.Cu")
	)
	(gr_arc
		(start 119.956072 -221.742)
		(mid 120.016332 -221.88748)
		(end 120.161812 -221.94774)
		(stroke
			(width 0.2)
			(type default)
		)
		(layer "In1.Cu")
	)
	(gr_line
		(start 119.956072 -221.3864)
		(end 119.956072 -221.742)
		(stroke
			(width 0.2)
			(type default)
		)
		(layer "In1.Cu")
	)
	(gr_line
		(start 120.05437 -114.86134)
		(end 120.25757 -114.86134)
		(stroke
			(width 0.2)
			(type default)
		)
		(layer "In1.Cu")
	)
	(gr_line
		(start 120.05437 -114.30254)
		(end 120.25757 -114.30254)
		(stroke
			(width 0.2)
			(type default)
		)
		(layer "In1.Cu")
	)
	(gr_arc
		(start 120.05437 -114.29746)
		(mid 119.944811 -114.342841)
		(end 119.89943 -114.4524)
		(stroke
			(width 0.2)
			(type default)
		)
		(layer "In1.Cu")
	)
	(gr_arc
		(start 120.05437 -113.73866)
		(mid 119.944811 -113.784041)
		(end 119.89943 -113.8936)
		(stroke
			(width 0.2)
			(type default)
		)
		(layer "In1.Cu")
	)
	(gr_line
		(start 120.161812 -223.70034)
		(end 120.517412 -223.70034)
		(stroke
			(width 0.2)
			(type default)
		)
		(layer "In1.Cu")
	)
	(gr_arc
		(start 120.161812 -222.93326)
		(mid 120.016332 -222.99352)
		(end 119.956072 -223.139)
		(stroke
			(width 0.2)
			(type default)
		)
		(layer "In1.Cu")
	)
	(gr_line
		(start 120.161812 -222.83674)
		(end 120.517412 -222.83674)
		(stroke
			(width 0.2)
			(type default)
		)
		(layer "In1.Cu")
	)
	(gr_arc
		(start 120.161812 -222.06966)
		(mid 120.016332 -222.12992)
		(end 119.956072 -222.2754)
		(stroke
			(width 0.2)
			(type default)
		)
		(layer "In1.Cu")
	)
	(gr_line
		(start 120.161812 -221.94774)
		(end 120.517412 -221.94774)
		(stroke
			(width 0.2)
			(type default)
		)
		(layer "In1.Cu")
	)
	(gr_arc
		(start 120.161812 -221.18066)
		(mid 120.016332 -221.24092)
		(end 119.956072 -221.3864)
		(stroke
			(width 0.2)
			(type default)
		)
		(layer "In1.Cu")
	)
	(gr_arc
		(start 120.25757 -114.86134)
		(mid 120.367129 -114.815959)
		(end 120.41251 -114.7064)
		(stroke
			(width 0.2)
			(type default)
		)
		(layer "In1.Cu")
	)
	(gr_arc
		(start 120.25757 -114.30254)
		(mid 120.367129 -114.257159)
		(end 120.41251 -114.1476)
		(stroke
			(width 0.2)
			(type default)
		)
		(layer "In1.Cu")
	)
	(gr_line
		(start 120.25757 -114.29746)
		(end 120.05437 -114.29746)
		(stroke
			(width 0.2)
			(type default)
		)
		(layer "In1.Cu")
	)
	(gr_line
		(start 120.25757 -113.73866)
		(end 120.05437 -113.73866)
		(stroke
			(width 0.2)
			(type default)
		)
		(layer "In1.Cu")
	)
	(gr_line
		(start 120.41251 -114.7064)
		(end 120.41251 -114.4524)
		(stroke
			(width 0.2)
			(type default)
		)
		(layer "In1.Cu")
	)
	(gr_arc
		(start 120.41251 -114.4524)
		(mid 120.367129 -114.342841)
		(end 120.25757 -114.29746)
		(stroke
			(width 0.2)
			(type default)
		)
		(layer "In1.Cu")
	)
	(gr_line
		(start 120.41251 -114.1476)
		(end 120.41251 -113.8936)
		(stroke
			(width 0.2)
			(type default)
		)
		(layer "In1.Cu")
	)
	(gr_arc
		(start 120.41251 -113.8936)
		(mid 120.367129 -113.784041)
		(end 120.25757 -113.73866)
		(stroke
			(width 0.2)
			(type default)
		)
		(layer "In1.Cu")
	)
	(gr_arc
		(start 120.464072 -206.4766)
		(mid 120.524332 -206.62208)
		(end 120.669812 -206.68234)
		(stroke
			(width 0.2)
			(type default)
		)
		(layer "In1.Cu")
	)
	(gr_line
		(start 120.464072 -206.121)
		(end 120.464072 -206.4766)
		(stroke
			(width 0.2)
			(type default)
		)
		(layer "In1.Cu")
	)
	(gr_arc
		(start 120.464072 -205.5876)
		(mid 120.524332 -205.73308)
		(end 120.669812 -205.79334)
		(stroke
			(width 0.2)
			(type default)
		)
		(layer "In1.Cu")
	)
	(gr_line
		(start 120.464072 -205.232)
		(end 120.464072 -205.5876)
		(stroke
			(width 0.2)
			(type default)
		)
		(layer "In1.Cu")
	)
	(gr_arc
		(start 120.464072 -204.724)
		(mid 120.524332 -204.86948)
		(end 120.669812 -204.92974)
		(stroke
			(width 0.2)
			(type default)
		)
		(layer "In1.Cu")
	)
	(gr_line
		(start 120.464072 -204.3684)
		(end 120.464072 -204.724)
		(stroke
			(width 0.2)
			(type default)
		)
		(layer "In1.Cu")
	)
	(gr_arc
		(start 120.517412 -223.70034)
		(mid 120.662892 -223.64008)
		(end 120.723152 -223.4946)
		(stroke
			(width 0.2)
			(type default)
		)
		(layer "In1.Cu")
	)
	(gr_line
		(start 120.517412 -222.93326)
		(end 120.161812 -222.93326)
		(stroke
			(width 0.2)
			(type default)
		)
		(layer "In1.Cu")
	)
	(gr_arc
		(start 120.517412 -222.83674)
		(mid 120.662892 -222.77648)
		(end 120.723152 -222.631)
		(stroke
			(width 0.2)
			(type default)
		)
		(layer "In1.Cu")
	)
	(gr_line
		(start 120.517412 -222.06966)
		(end 120.161812 -222.06966)
		(stroke
			(width 0.2)
			(type default)
		)
		(layer "In1.Cu")
	)
	(gr_arc
		(start 120.517412 -221.94774)
		(mid 120.662892 -221.88748)
		(end 120.723152 -221.742)
		(stroke
			(width 0.2)
			(type default)
		)
		(layer "In1.Cu")
	)
	(gr_line
		(start 120.517412 -221.18066)
		(end 120.161812 -221.18066)
		(stroke
			(width 0.2)
			(type default)
		)
		(layer "In1.Cu")
	)
	(gr_line
		(start 120.669812 -206.68234)
		(end 121.025412 -206.68234)
		(stroke
			(width 0.2)
			(type default)
		)
		(layer "In1.Cu")
	)
	(gr_arc
		(start 120.669812 -205.91526)
		(mid 120.524332 -205.97552)
		(end 120.464072 -206.121)
		(stroke
			(width 0.2)
			(type default)
		)
		(layer "In1.Cu")
	)
	(gr_line
		(start 120.669812 -205.79334)
		(end 121.025412 -205.79334)
		(stroke
			(width 0.2)
			(type default)
		)
		(layer "In1.Cu")
	)
	(gr_arc
		(start 120.669812 -205.02626)
		(mid 120.524332 -205.08652)
		(end 120.464072 -205.232)
		(stroke
			(width 0.2)
			(type default)
		)
		(layer "In1.Cu")
	)
	(gr_line
		(start 120.669812 -204.92974)
		(end 121.025412 -204.92974)
		(stroke
			(width 0.2)
			(type default)
		)
		(layer "In1.Cu")
	)
	(gr_arc
		(start 120.669812 -204.16266)
		(mid 120.524332 -204.22292)
		(end 120.464072 -204.3684)
		(stroke
			(width 0.2)
			(type default)
		)
		(layer "In1.Cu")
	)
	(gr_line
		(start 120.723152 -223.4946)
		(end 120.723152 -223.139)
		(stroke
			(width 0.2)
			(type default)
		)
		(layer "In1.Cu")
	)
	(gr_arc
		(start 120.723152 -223.139)
		(mid 120.662892 -222.99352)
		(end 120.517412 -222.93326)
		(stroke
			(width 0.2)
			(type default)
		)
		(layer "In1.Cu")
	)
	(gr_line
		(start 120.723152 -222.631)
		(end 120.723152 -222.2754)
		(stroke
			(width 0.2)
			(type default)
		)
		(layer "In1.Cu")
	)
	(gr_arc
		(start 120.723152 -222.2754)
		(mid 120.662892 -222.12992)
		(end 120.517412 -222.06966)
		(stroke
			(width 0.2)
			(type default)
		)
		(layer "In1.Cu")
	)
	(gr_line
		(start 120.723152 -221.742)
		(end 120.723152 -221.3864)
		(stroke
			(width 0.2)
			(type default)
		)
		(layer "In1.Cu")
	)
	(gr_arc
		(start 120.723152 -221.3864)
		(mid 120.662892 -221.24092)
		(end 120.517412 -221.18066)
		(stroke
			(width 0.2)
			(type default)
		)
		(layer "In1.Cu")
	)
	(gr_arc
		(start 121.025412 -206.68234)
		(mid 121.170892 -206.62208)
		(end 121.231152 -206.4766)
		(stroke
			(width 0.2)
			(type default)
		)
		(layer "In1.Cu")
	)
	(gr_line
		(start 121.025412 -205.91526)
		(end 120.669812 -205.91526)
		(stroke
			(width 0.2)
			(type default)
		)
		(layer "In1.Cu")
	)
	(gr_arc
		(start 121.025412 -205.79334)
		(mid 121.170892 -205.73308)
		(end 121.231152 -205.5876)
		(stroke
			(width 0.2)
			(type default)
		)
		(layer "In1.Cu")
	)
	(gr_line
		(start 121.025412 -205.02626)
		(end 120.669812 -205.02626)
		(stroke
			(width 0.2)
			(type default)
		)
		(layer "In1.Cu")
	)
	(gr_arc
		(start 121.025412 -204.92974)
		(mid 121.170892 -204.86948)
		(end 121.231152 -204.724)
		(stroke
			(width 0.2)
			(type default)
		)
		(layer "In1.Cu")
	)
	(gr_line
		(start 121.025412 -204.16266)
		(end 120.669812 -204.16266)
		(stroke
			(width 0.2)
			(type default)
		)
		(layer "In1.Cu")
	)
	(gr_arc
		(start 121.04243 -114.7064)
		(mid 121.087811 -114.815959)
		(end 121.19737 -114.86134)
		(stroke
			(width 0.2)
			(type default)
		)
		(layer "In1.Cu")
	)
	(gr_line
		(start 121.04243 -114.4524)
		(end 121.04243 -114.7064)
		(stroke
			(width 0.2)
			(type default)
		)
		(layer "In1.Cu")
	)
	(gr_arc
		(start 121.04243 -114.1476)
		(mid 121.087811 -114.257159)
		(end 121.19737 -114.30254)
		(stroke
			(width 0.2)
			(type default)
		)
		(layer "In1.Cu")
	)
	(gr_line
		(start 121.04243 -113.8936)
		(end 121.04243 -114.1476)
		(stroke
			(width 0.2)
			(type default)
		)
		(layer "In1.Cu")
	)
	(gr_line
		(start 121.19737 -114.86134)
		(end 121.40057 -114.86134)
		(stroke
			(width 0.2)
			(type default)
		)
		(layer "In1.Cu")
	)
	(gr_line
		(start 121.19737 -114.30254)
		(end 121.40057 -114.30254)
		(stroke
			(width 0.2)
			(type default)
		)
		(layer "In1.Cu")
	)
	(gr_arc
		(start 121.19737 -114.29746)
		(mid 121.087811 -114.342841)
		(end 121.04243 -114.4524)
		(stroke
			(width 0.2)
			(type default)
		)
		(layer "In1.Cu")
	)
	(gr_arc
		(start 121.19737 -113.73866)
		(mid 121.087811 -113.784041)
		(end 121.04243 -113.8936)
		(stroke
			(width 0.2)
			(type default)
		)
		(layer "In1.Cu")
	)
	(gr_line
		(start 121.231152 -206.4766)
		(end 121.231152 -206.121)
		(stroke
			(width 0.2)
			(type default)
		)
		(layer "In1.Cu")
	)
	(gr_arc
		(start 121.231152 -206.121)
		(mid 121.170892 -205.97552)
		(end 121.025412 -205.91526)
		(stroke
			(width 0.2)
			(type default)
		)
		(layer "In1.Cu")
	)
	(gr_line
		(start 121.231152 -205.5876)
		(end 121.231152 -205.232)
		(stroke
			(width 0.2)
			(type default)
		)
		(layer "In1.Cu")
	)
	(gr_arc
		(start 121.231152 -205.232)
		(mid 121.170892 -205.08652)
		(end 121.025412 -205.02626)
		(stroke
			(width 0.2)
			(type default)
		)
		(layer "In1.Cu")
	)
	(gr_line
		(start 121.231152 -204.724)
		(end 121.231152 -204.3684)
		(stroke
			(width 0.2)
			(type default)
		)
		(layer "In1.Cu")
	)
	(gr_arc
		(start 121.231152 -204.3684)
		(mid 121.170892 -204.22292)
		(end 121.025412 -204.16266)
		(stroke
			(width 0.2)
			(type default)
		)
		(layer "In1.Cu")
	)
	(gr_arc
		(start 121.40057 -114.86134)
		(mid 121.510129 -114.815959)
		(end 121.55551 -114.7064)
		(stroke
			(width 0.2)
			(type default)
		)
		(layer "In1.Cu")
	)
	(gr_arc
		(start 121.40057 -114.30254)
		(mid 121.510129 -114.257159)
		(end 121.55551 -114.1476)
		(stroke
			(width 0.2)
			(type default)
		)
		(layer "In1.Cu")
	)
	(gr_line
		(start 121.40057 -114.29746)
		(end 121.19737 -114.29746)
		(stroke
			(width 0.2)
			(type default)
		)
		(layer "In1.Cu")
	)
	(gr_line
		(start 121.40057 -113.73866)
		(end 121.19737 -113.73866)
		(stroke
			(width 0.2)
			(type default)
		)
		(layer "In1.Cu")
	)
	(gr_line
		(start 121.55551 -114.7064)
		(end 121.55551 -114.4524)
		(stroke
			(width 0.2)
			(type default)
		)
		(layer "In1.Cu")
	)
	(gr_arc
		(start 121.55551 -114.4524)
		(mid 121.510129 -114.342841)
		(end 121.40057 -114.29746)
		(stroke
			(width 0.2)
			(type default)
		)
		(layer "In1.Cu")
	)
	(gr_line
		(start 121.55551 -114.1476)
		(end 121.55551 -113.8936)
		(stroke
			(width 0.2)
			(type default)
		)
		(layer "In1.Cu")
	)
	(gr_arc
		(start 121.55551 -113.8936)
		(mid 121.510129 -113.784041)
		(end 121.40057 -113.73866)
		(stroke
			(width 0.2)
			(type default)
		)
		(layer "In1.Cu")
	)
	(gr_arc
		(start 121.607072 -223.4946)
		(mid 121.667332 -223.64008)
		(end 121.812812 -223.70034)
		(stroke
			(width 0.2)
			(type default)
		)
		(layer "In1.Cu")
	)
	(gr_line
		(start 121.607072 -223.139)
		(end 121.607072 -223.4946)
		(stroke
			(width 0.2)
			(type default)
		)
		(layer "In1.Cu")
	)
	(gr_arc
		(start 121.607072 -222.631)
		(mid 121.667332 -222.77648)
		(end 121.812812 -222.83674)
		(stroke
			(width 0.2)
			(type default)
		)
		(layer "In1.Cu")
	)
	(gr_line
		(start 121.607072 -222.2754)
		(end 121.607072 -222.631)
		(stroke
			(width 0.2)
			(type default)
		)
		(layer "In1.Cu")
	)
	(gr_arc
		(start 121.607072 -221.742)
		(mid 121.667332 -221.88748)
		(end 121.812812 -221.94774)
		(stroke
			(width 0.2)
			(type default)
		)
		(layer "In1.Cu")
	)
	(gr_line
		(start 121.607072 -221.3864)
		(end 121.607072 -221.742)
		(stroke
			(width 0.2)
			(type default)
		)
		(layer "In1.Cu")
	)
	(gr_arc
		(start 121.67743 -114.7064)
		(mid 121.722811 -114.815959)
		(end 121.83237 -114.86134)
		(stroke
			(width 0.2)
			(type default)
		)
		(layer "In1.Cu")
	)
	(gr_line
		(start 121.67743 -114.4524)
		(end 121.67743 -114.7064)
		(stroke
			(width 0.2)
			(type default)
		)
		(layer "In1.Cu")
	)
	(gr_arc
		(start 121.67743 -114.1476)
		(mid 121.722811 -114.257159)
		(end 121.83237 -114.30254)
		(stroke
			(width 0.2)
			(type default)
		)
		(layer "In1.Cu")
	)
	(gr_line
		(start 121.67743 -113.8936)
		(end 121.67743 -114.1476)
		(stroke
			(width 0.2)
			(type default)
		)
		(layer "In1.Cu")
	)
	(gr_line
		(start 121.812812 -223.70034)
		(end 122.168412 -223.70034)
		(stroke
			(width 0.2)
			(type default)
		)
		(layer "In1.Cu")
	)
	(gr_arc
		(start 121.812812 -222.93326)
		(mid 121.667332 -222.99352)
		(end 121.607072 -223.139)
		(stroke
			(width 0.2)
			(type default)
		)
		(layer "In1.Cu")
	)
	(gr_line
		(start 121.812812 -222.83674)
		(end 122.168412 -222.83674)
		(stroke
			(width 0.2)
			(type default)
		)
		(layer "In1.Cu")
	)
	(gr_arc
		(start 121.812812 -222.06966)
		(mid 121.667332 -222.12992)
		(end 121.607072 -222.2754)
		(stroke
			(width 0.2)
			(type default)
		)
		(layer "In1.Cu")
	)
	(gr_line
		(start 121.812812 -221.94774)
		(end 122.168412 -221.94774)
		(stroke
			(width 0.2)
			(type default)
		)
		(layer "In1.Cu")
	)
	(gr_arc
		(start 121.812812 -221.18066)
		(mid 121.667332 -221.24092)
		(end 121.607072 -221.3864)
		(stroke
			(width 0.2)
			(type default)
		)
		(layer "In1.Cu")
	)
	(gr_line
		(start 121.83237 -114.86134)
		(end 122.03557 -114.86134)
		(stroke
			(width 0.2)
			(type default)
		)
		(layer "In1.Cu")
	)
	(gr_line
		(start 121.83237 -114.30254)
		(end 122.03557 -114.30254)
		(stroke
			(width 0.2)
			(type default)
		)
		(layer "In1.Cu")
	)
	(gr_arc
		(start 121.83237 -114.29746)
		(mid 121.722811 -114.342841)
		(end 121.67743 -114.4524)
		(stroke
			(width 0.2)
			(type default)
		)
		(layer "In1.Cu")
	)
	(gr_arc
		(start 121.83237 -113.73866)
		(mid 121.722811 -113.784041)
		(end 121.67743 -113.8936)
		(stroke
			(width 0.2)
			(type default)
		)
		(layer "In1.Cu")
	)
	(gr_arc
		(start 122.03557 -114.86134)
		(mid 122.145129 -114.815959)
		(end 122.19051 -114.7064)
		(stroke
			(width 0.2)
			(type default)
		)
		(layer "In1.Cu")
	)
	(gr_arc
		(start 122.03557 -114.30254)
		(mid 122.145129 -114.257159)
		(end 122.19051 -114.1476)
		(stroke
			(width 0.2)
			(type default)
		)
		(layer "In1.Cu")
	)
	(gr_line
		(start 122.03557 -114.29746)
		(end 121.83237 -114.29746)
		(stroke
			(width 0.2)
			(type default)
		)
		(layer "In1.Cu")
	)
	(gr_line
		(start 122.03557 -113.73866)
		(end 121.83237 -113.73866)
		(stroke
			(width 0.2)
			(type default)
		)
		(layer "In1.Cu")
	)
	(gr_arc
		(start 122.168412 -223.70034)
		(mid 122.313892 -223.64008)
		(end 122.374152 -223.4946)
		(stroke
			(width 0.2)
			(type default)
		)
		(layer "In1.Cu")
	)
	(gr_line
		(start 122.168412 -222.93326)
		(end 121.812812 -222.93326)
		(stroke
			(width 0.2)
			(type default)
		)
		(layer "In1.Cu")
	)
	(gr_arc
		(start 122.168412 -222.83674)
		(mid 122.313892 -222.77648)
		(end 122.374152 -222.631)
		(stroke
			(width 0.2)
			(type default)
		)
		(layer "In1.Cu")
	)
	(gr_line
		(start 122.168412 -222.06966)
		(end 121.812812 -222.06966)
		(stroke
			(width 0.2)
			(type default)
		)
		(layer "In1.Cu")
	)
	(gr_arc
		(start 122.168412 -221.94774)
		(mid 122.313892 -221.88748)
		(end 122.374152 -221.742)
		(stroke
			(width 0.2)
			(type default)
		)
		(layer "In1.Cu")
	)
	(gr_line
		(start 122.168412 -221.18066)
		(end 121.812812 -221.18066)
		(stroke
			(width 0.2)
			(type default)
		)
		(layer "In1.Cu")
	)
	(gr_line
		(start 122.19051 -114.7064)
		(end 122.19051 -114.4524)
		(stroke
			(width 0.2)
			(type default)
		)
		(layer "In1.Cu")
	)
	(gr_arc
		(start 122.19051 -114.4524)
		(mid 122.145129 -114.342841)
		(end 122.03557 -114.29746)
		(stroke
			(width 0.2)
			(type default)
		)
		(layer "In1.Cu")
	)
	(gr_line
		(start 122.19051 -114.1476)
		(end 122.19051 -113.8936)
		(stroke
			(width 0.2)
			(type default)
		)
		(layer "In1.Cu")
	)
	(gr_arc
		(start 122.19051 -113.8936)
		(mid 122.145129 -113.784041)
		(end 122.03557 -113.73866)
		(stroke
			(width 0.2)
			(type default)
		)
		(layer "In1.Cu")
	)
	(gr_line
		(start 122.374152 -223.4946)
		(end 122.374152 -223.139)
		(stroke
			(width 0.2)
			(type default)
		)
		(layer "In1.Cu")
	)
	(gr_arc
		(start 122.374152 -223.139)
		(mid 122.313892 -222.99352)
		(end 122.168412 -222.93326)
		(stroke
			(width 0.2)
			(type default)
		)
		(layer "In1.Cu")
	)
	(gr_line
		(start 122.374152 -222.631)
		(end 122.374152 -222.2754)
		(stroke
			(width 0.2)
			(type default)
		)
		(layer "In1.Cu")
	)
	(gr_arc
		(start 122.374152 -222.2754)
		(mid 122.313892 -222.12992)
		(end 122.168412 -222.06966)
		(stroke
			(width 0.2)
			(type default)
		)
		(layer "In1.Cu")
	)
	(gr_line
		(start 122.374152 -221.742)
		(end 122.374152 -221.3864)
		(stroke
			(width 0.2)
			(type default)
		)
		(layer "In1.Cu")
	)
	(gr_arc
		(start 122.374152 -221.3864)
		(mid 122.313892 -221.24092)
		(end 122.168412 -221.18066)
		(stroke
			(width 0.2)
			(type default)
		)
		(layer "In1.Cu")
	)
	(gr_line
		(start 122.492008 -91.849956)
		(end 122.492262 -92.827348)
		(stroke
			(width 0.2)
			(type default)
		)
		(layer "In1.Cu")
	)
	(gr_arc
		(start 122.492262 -92.827348)
		(mid 122.850402 -93.185742)
		(end 123.208542 -92.827348)
		(stroke
			(width 0.2)
			(type default)
		)
		(layer "In1.Cu")
	)
	(gr_arc
		(start 122.829574 -84.492084)
		(mid 122.492516 -84.87029)
		(end 122.870722 -85.207348)
		(stroke
			(width 0.2)
			(type default)
		)
		(layer "In1.Cu")
	)
	(gr_line
		(start 122.848116 -94.186502)
		(end 123.843542 -94.206822)
		(stroke
			(width 0.2)
			(type default)
		)
		(layer "In1.Cu")
	)
	(gr_line
		(start 122.850148 -91.207844)
		(end 123.850146 -91.207844)
		(stroke
			(width 0.2)
			(type default)
		)
		(layer "In1.Cu")
	)
	(gr_line
		(start 122.850148 -90.207846)
		(end 123.850146 -90.207846)
		(stroke
			(width 0.2)
			(type default)
		)
		(layer "In1.Cu")
	)
	(gr_line
		(start 122.850148 -84.207858)
		(end 123.849892 -84.207858)
		(stroke
			(width 0.2)
			(type default)
		)
		(layer "In1.Cu")
	)
	(gr_arc
		(start 122.850148 -83.491578)
		(mid 122.492008 -83.849718)
		(end 122.850148 -84.207858)
		(stroke
			(width 0.2)
			(type default)
		)
		(layer "In1.Cu")
	)
	(gr_line
		(start 122.850148 -83.20786)
		(end 123.850146 -83.20786)
		(stroke
			(width 0.2)
			(type default)
		)
		(layer "In1.Cu")
	)
	(gr_arc
		(start 122.850402 -90.491564)
		(mid 122.492008 -90.849577)
		(end 122.850148 -91.207844)
		(stroke
			(width 0.2)
			(type default)
		)
		(layer "In1.Cu")
	)
	(gr_arc
		(start 122.850402 -89.491566)
		(mid 122.492008 -89.849579)
		(end 122.850148 -90.207846)
		(stroke
			(width 0.2)
			(type default)
		)
		(layer "In1.Cu")
	)
	(gr_arc
		(start 122.850402 -82.49158)
		(mid 122.492008 -82.849593)
		(end 122.850148 -83.20786)
		(stroke
			(width 0.2)
			(type default)
		)
		(layer "In1.Cu")
	)
	(gr_arc
		(start 122.862848 -93.470222)
		(mid 122.497342 -93.820996)
		(end 122.848116 -94.186502)
		(stroke
			(width 0.2)
			(type default)
		)
		(layer "In1.Cu")
	)
	(gr_line
		(start 122.870722 -85.207348)
		(end 123.84532 -85.151214)
		(stroke
			(width 0.2)
			(type default)
		)
		(layer "In1.Cu")
	)
	(gr_line
		(start 122.924062 -81.28254)
		(end 123.831858 -81.308956)
		(stroke
			(width 0.2)
			(type default)
		)
		(layer "In1.Cu")
	)
	(gr_arc
		(start 122.92457 -81.430114)
		(mid 122.578114 -81.79943)
		(end 122.94743 -82.145886)
		(stroke
			(width 0.2)
			(type default)
		)
		(layer "In1.Cu")
	)
	(gr_line
		(start 122.92457 -81.427828)
		(end 122.92457 -81.430114)
		(stroke
			(width 0.2)
			(type default)
		)
		(layer "In1.Cu")
	)
	(gr_line
		(start 122.924824 -81.427574)
		(end 122.92457 -81.427828)
		(stroke
			(width 0.2)
			(type default)
		)
		(layer "In1.Cu")
	)
	(gr_arc
		(start 122.925332 -80.56626)
		(mid 122.566684 -80.923765)
		(end 122.924062 -81.28254)
		(stroke
			(width 0.2)
			(type default)
		)
		(layer "In1.Cu")
	)
	(gr_line
		(start 122.94743 -82.148426)
		(end 123.7488 -82.123026)
		(stroke
			(width 0.2)
			(type default)
		)
		(layer "In1.Cu")
	)
	(gr_line
		(start 122.94743 -82.145886)
		(end 122.94743 -82.148426)
		(stroke
			(width 0.2)
			(type default)
		)
		(layer "In1.Cu")
	)
	(gr_line
		(start 123.208288 -91.849956)
		(end 123.208288 -91.849702)
		(stroke
			(width 0.2)
			(type default)
		)
		(layer "In1.Cu")
	)
	(gr_arc
		(start 123.208288 -91.849702)
		(mid 122.850021 -91.491562)
		(end 122.492008 -91.849956)
		(stroke
			(width 0.2)
			(type default)
		)
		(layer "In1.Cu")
	)
	(gr_line
		(start 123.208542 -92.827348)
		(end 123.208288 -91.849956)
		(stroke
			(width 0.2)
			(type default)
		)
		(layer "In1.Cu")
	)
	(gr_line
		(start 123.72594 -81.404714)
		(end 123.72594 -81.402174)
		(stroke
			(width 0.2)
			(type default)
		)
		(layer "In1.Cu")
	)
	(gr_line
		(start 123.72594 -81.402174)
		(end 122.924824 -81.427574)
		(stroke
			(width 0.2)
			(type default)
		)
		(layer "In1.Cu")
	)
	(gr_line
		(start 123.7488 -82.123026)
		(end 123.7488 -82.12074)
		(stroke
			(width 0.2)
			(type default)
		)
		(layer "In1.Cu")
	)
	(gr_line
		(start 123.7488 -82.12074)
		(end 123.7488 -82.120486)
		(stroke
			(width 0.2)
			(type default)
		)
		(layer "In1.Cu")
	)
	(gr_arc
		(start 123.7488 -82.120486)
		(mid 124.095256 -81.75117)
		(end 123.72594 -81.404714)
		(stroke
			(width 0.2)
			(type default)
		)
		(layer "In1.Cu")
	)
	(gr_line
		(start 123.804426 -84.43595)
		(end 122.829574 -84.492084)
		(stroke
			(width 0.2)
			(type default)
		)
		(layer "In1.Cu")
	)
	(gr_arc
		(start 123.831858 -81.308956)
		(mid 123.842395 -81.309356)
		(end 123.85294 -81.309464)
		(stroke
			(width 0.2)
			(type default)
		)
		(layer "In1.Cu")
	)
	(gr_line
		(start 123.833128 -80.542892)
		(end 122.925332 -80.56626)
		(stroke
			(width 0.2)
			(type default)
		)
		(layer "In1.Cu")
	)
	(gr_arc
		(start 123.843542 -94.206822)
		(mid 124.209305 -93.856175)
		(end 123.858528 -93.490542)
		(stroke
			(width 0.2)
			(type default)
		)
		(layer "In1.Cu")
	)
	(gr_arc
		(start 123.84532 -85.151214)
		(mid 124.182625 -84.773135)
		(end 123.804426 -84.43595)
		(stroke
			(width 0.2)
			(type default)
		)
		(layer "In1.Cu")
	)
	(gr_arc
		(start 123.849892 -84.207858)
		(mid 124.208286 -83.849845)
		(end 123.850146 -83.491578)
		(stroke
			(width 0.2)
			(type default)
		)
		(layer "In1.Cu")
	)
	(gr_arc
		(start 123.850146 -91.207844)
		(mid 124.208286 -90.849704)
		(end 123.850146 -90.491564)
		(stroke
			(width 0.2)
			(type default)
		)
		(layer "In1.Cu")
	)
	(gr_line
		(start 123.850146 -90.491564)
		(end 122.850402 -90.491564)
		(stroke
			(width 0.2)
			(type default)
		)
		(layer "In1.Cu")
	)
	(gr_arc
		(start 123.850146 -90.207846)
		(mid 124.208286 -89.849706)
		(end 123.850146 -89.491566)
		(stroke
			(width 0.2)
			(type default)
		)
		(layer "In1.Cu")
	)
	(gr_line
		(start 123.850146 -89.491566)
		(end 122.850402 -89.491566)
		(stroke
			(width 0.2)
			(type default)
		)
		(layer "In1.Cu")
	)
	(gr_line
		(start 123.850146 -83.491578)
		(end 122.850148 -83.491578)
		(stroke
			(width 0.2)
			(type default)
		)
		(layer "In1.Cu")
	)
	(gr_arc
		(start 123.850146 -83.20786)
		(mid 124.208286 -82.84972)
		(end 123.850146 -82.49158)
		(stroke
			(width 0.2)
			(type default)
		)
		(layer "In1.Cu")
	)
	(gr_line
		(start 123.850146 -82.49158)
		(end 122.850402 -82.49158)
		(stroke
			(width 0.2)
			(type default)
		)
		(layer "In1.Cu")
	)
	(gr_arc
		(start 123.85294 -81.309464)
		(mid 124.236988 -80.926432)
		(end 123.853956 -80.542384)
		(stroke
			(width 0.2)
			(type default)
		)
		(layer "In1.Cu")
	)
	(gr_arc
		(start 123.853956 -80.542384)
		(mid 123.843539 -80.542498)
		(end 123.833128 -80.542892)
		(stroke
			(width 0.2)
			(type default)
		)
		(layer "In1.Cu")
	)
	(gr_line
		(start 123.858528 -93.490542)
		(end 122.862848 -93.470222)
		(stroke
			(width 0.2)
			(type default)
		)
		(layer "In1.Cu")
	)
	(gr_line
		(start 124.779278 -80.635348)
		(end 125.756162 -80.635348)
		(stroke
			(width 0.2)
			(type default)
		)
		(layer "In1.Cu")
	)
	(gr_arc
		(start 124.779532 -79.868268)
		(mid 124.395738 -80.251681)
		(end 124.779278 -80.635348)
		(stroke
			(width 0.2)
			(type default)
		)
		(layer "In1.Cu")
	)
	(gr_arc
		(start 125.756162 -80.635348)
		(mid 126.139702 -80.251808)
		(end 125.756162 -79.868268)
		(stroke
			(width 0.2)
			(type default)
		)
		(layer "In1.Cu")
	)
	(gr_line
		(start 125.756162 -79.868268)
		(end 124.779532 -79.868268)
		(stroke
			(width 0.2)
			(type default)
		)
		(layer "In1.Cu")
	)
	(gr_line
		(start 127.154178 -80.19034)
		(end 128.130808 -80.19034)
		(stroke
			(width 0.2)
			(type default)
		)
		(layer "In1.Cu")
	)
	(gr_arc
		(start 127.154178 -79.42326)
		(mid 126.770638 -79.8068)
		(end 127.154178 -80.19034)
		(stroke
			(width 0.2)
			(type default)
		)
		(layer "In1.Cu")
	)
	(gr_arc
		(start 128.130808 -80.19034)
		(mid 128.514602 -79.806927)
		(end 128.131062 -79.42326)
		(stroke
			(width 0.2)
			(type default)
		)
		(layer "In1.Cu")
	)
	(gr_line
		(start 128.131062 -79.42326)
		(end 127.154178 -79.42326)
		(stroke
			(width 0.2)
			(type default)
		)
		(layer "In1.Cu")
	)
	(gr_line
		(start 129.159 -81.66354)
		(end 130.047746 -81.66354)
		(stroke
			(width 0.2)
			(type default)
		)
		(layer "In1.Cu")
	)
	(gr_arc
		(start 129.159 -80.89646)
		(mid 128.77546 -81.28)
		(end 129.159 -81.66354)
		(stroke
			(width 0.2)
			(type default)
		)
		(layer "In1.Cu")
	)
	(gr_arc
		(start 130.047746 -81.66354)
		(mid 130.43154 -81.280127)
		(end 130.048 -80.89646)
		(stroke
			(width 0.2)
			(type default)
		)
		(layer "In1.Cu")
	)
	(gr_line
		(start 130.048 -80.89646)
		(end 129.159 -80.89646)
		(stroke
			(width 0.2)
			(type default)
		)
		(layer "In1.Cu")
	)
	(gr_arc
		(start 130.508502 -85.136482)
		(mid 130.553883 -85.246041)
		(end 130.663442 -85.291422)
		(stroke
			(width 0.2)
			(type default)
		)
		(layer "In1.Cu")
	)
	(gr_line
		(start 130.508502 -84.933282)
		(end 130.508502 -85.136482)
		(stroke
			(width 0.2)
			(type default)
		)
		(layer "In1.Cu")
	)
	(gr_arc
		(start 130.508502 -84.501482)
		(mid 130.553883 -84.611041)
		(end 130.663442 -84.656422)
		(stroke
			(width 0.2)
			(type default)
		)
		(layer "In1.Cu")
	)
	(gr_line
		(start 130.508502 -84.298282)
		(end 130.508502 -84.501482)
		(stroke
			(width 0.2)
			(type default)
		)
		(layer "In1.Cu")
	)
	(gr_line
		(start 130.663442 -85.291422)
		(end 130.917442 -85.291422)
		(stroke
			(width 0.2)
			(type default)
		)
		(layer "In1.Cu")
	)
	(gr_arc
		(start 130.663442 -84.778342)
		(mid 130.553883 -84.823723)
		(end 130.508502 -84.933282)
		(stroke
			(width 0.2)
			(type default)
		)
		(layer "In1.Cu")
	)
	(gr_line
		(start 130.663442 -84.656422)
		(end 130.917442 -84.656422)
		(stroke
			(width 0.2)
			(type default)
		)
		(layer "In1.Cu")
	)
	(gr_arc
		(start 130.663442 -84.143342)
		(mid 130.553883 -84.188723)
		(end 130.508502 -84.298282)
		(stroke
			(width 0.2)
			(type default)
		)
		(layer "In1.Cu")
	)
	(gr_arc
		(start 130.75666 -92.0496)
		(mid 130.802041 -92.159159)
		(end 130.9116 -92.20454)
		(stroke
			(width 0.2)
			(type default)
		)
		(layer "In1.Cu")
	)
	(gr_line
		(start 130.75666 -91.8464)
		(end 130.75666 -92.0496)
		(stroke
			(width 0.2)
			(type default)
		)
		(layer "In1.Cu")
	)
	(gr_arc
		(start 130.75666 -91.4146)
		(mid 130.802041 -91.524159)
		(end 130.9116 -91.56954)
		(stroke
			(width 0.2)
			(type default)
		)
		(layer "In1.Cu")
	)
	(gr_line
		(start 130.75666 -91.2114)
		(end 130.75666 -91.4146)
		(stroke
			(width 0.2)
			(type default)
		)
		(layer "In1.Cu")
	)
	(gr_arc
		(start 130.75666 -90.5256)
		(mid 130.802041 -90.635159)
		(end 130.9116 -90.68054)
		(stroke
			(width 0.2)
			(type default)
		)
		(layer "In1.Cu")
	)
	(gr_line
		(start 130.75666 -90.3224)
		(end 130.75666 -90.5256)
		(stroke
			(width 0.2)
			(type default)
		)
		(layer "In1.Cu")
	)
	(gr_arc
		(start 130.75666 -89.8906)
		(mid 130.802041 -90.000159)
		(end 130.9116 -90.04554)
		(stroke
			(width 0.2)
			(type default)
		)
		(layer "In1.Cu")
	)
	(gr_line
		(start 130.75666 -89.6874)
		(end 130.75666 -89.8906)
		(stroke
			(width 0.2)
			(type default)
		)
		(layer "In1.Cu")
	)
	(gr_arc
		(start 130.75666 -89.2556)
		(mid 130.802041 -89.365159)
		(end 130.9116 -89.41054)
		(stroke
			(width 0.2)
			(type default)
		)
		(layer "In1.Cu")
	)
	(gr_line
		(start 130.75666 -89.0524)
		(end 130.75666 -89.2556)
		(stroke
			(width 0.2)
			(type default)
		)
		(layer "In1.Cu")
	)
	(gr_arc
		(start 130.75666 -88.6206)
		(mid 130.802041 -88.730159)
		(end 130.9116 -88.77554)
		(stroke
			(width 0.2)
			(type default)
		)
		(layer "In1.Cu")
	)
	(gr_line
		(start 130.75666 -88.4174)
		(end 130.75666 -88.6206)
		(stroke
			(width 0.2)
			(type default)
		)
		(layer "In1.Cu")
	)
	(gr_arc
		(start 130.75666 -87.9856)
		(mid 130.802041 -88.095159)
		(end 130.9116 -88.14054)
		(stroke
			(width 0.2)
			(type default)
		)
		(layer "In1.Cu")
	)
	(gr_line
		(start 130.75666 -87.7824)
		(end 130.75666 -87.9856)
		(stroke
			(width 0.2)
			(type default)
		)
		(layer "In1.Cu")
	)
	(gr_arc
		(start 130.75666 -87.3506)
		(mid 130.802041 -87.460159)
		(end 130.9116 -87.50554)
		(stroke
			(width 0.2)
			(type default)
		)
		(layer "In1.Cu")
	)
	(gr_line
		(start 130.75666 -87.1474)
		(end 130.75666 -87.3506)
		(stroke
			(width 0.2)
			(type default)
		)
		(layer "In1.Cu")
	)
	(gr_arc
		(start 130.77317 -99.32924)
		(mid 130.818551 -99.438799)
		(end 130.92811 -99.48418)
		(stroke
			(width 0.2)
			(type default)
		)
		(layer "In1.Cu")
	)
	(gr_line
		(start 130.77317 -99.07524)
		(end 130.77317 -99.32924)
		(stroke
			(width 0.2)
			(type default)
		)
		(layer "In1.Cu")
	)
	(gr_arc
		(start 130.77317 -98.77044)
		(mid 130.818551 -98.879999)
		(end 130.92811 -98.92538)
		(stroke
			(width 0.2)
			(type default)
		)
		(layer "In1.Cu")
	)
	(gr_line
		(start 130.77317 -98.51644)
		(end 130.77317 -98.77044)
		(stroke
			(width 0.2)
			(type default)
		)
		(layer "In1.Cu")
	)
	(gr_arc
		(start 130.879342 -81.553558)
		(mid 130.924723 -81.663117)
		(end 131.034282 -81.708498)
		(stroke
			(width 0.2)
			(type default)
		)
		(layer "In1.Cu")
	)
	(gr_line
		(start 130.879342 -81.299558)
		(end 130.879342 -81.553558)
		(stroke
			(width 0.2)
			(type default)
		)
		(layer "In1.Cu")
	)
	(gr_arc
		(start 130.879342 -80.994758)
		(mid 130.924723 -81.104317)
		(end 131.034282 -81.149698)
		(stroke
			(width 0.2)
			(type default)
		)
		(layer "In1.Cu")
	)
	(gr_line
		(start 130.879342 -80.740758)
		(end 130.879342 -80.994758)
		(stroke
			(width 0.2)
			(type default)
		)
		(layer "In1.Cu")
	)
	(gr_line
		(start 130.9116 -92.20454)
		(end 131.1656 -92.20454)
		(stroke
			(width 0.2)
			(type default)
		)
		(layer "In1.Cu")
	)
	(gr_arc
		(start 130.9116 -91.69146)
		(mid 130.802041 -91.736841)
		(end 130.75666 -91.8464)
		(stroke
			(width 0.2)
			(type default)
		)
		(layer "In1.Cu")
	)
	(gr_line
		(start 130.9116 -91.56954)
		(end 131.1656 -91.56954)
		(stroke
			(width 0.2)
			(type default)
		)
		(layer "In1.Cu")
	)
	(gr_arc
		(start 130.9116 -91.05646)
		(mid 130.802041 -91.101841)
		(end 130.75666 -91.2114)
		(stroke
			(width 0.2)
			(type default)
		)
		(layer "In1.Cu")
	)
	(gr_line
		(start 130.9116 -90.68054)
		(end 131.1656 -90.68054)
		(stroke
			(width 0.2)
			(type default)
		)
		(layer "In1.Cu")
	)
	(gr_arc
		(start 130.9116 -90.16746)
		(mid 130.802041 -90.212841)
		(end 130.75666 -90.3224)
		(stroke
			(width 0.2)
			(type default)
		)
		(layer "In1.Cu")
	)
	(gr_line
		(start 130.9116 -90.04554)
		(end 131.1656 -90.04554)
		(stroke
			(width 0.2)
			(type default)
		)
		(layer "In1.Cu")
	)
	(gr_arc
		(start 130.9116 -89.53246)
		(mid 130.802041 -89.577841)
		(end 130.75666 -89.6874)
		(stroke
			(width 0.2)
			(type default)
		)
		(layer "In1.Cu")
	)
	(gr_line
		(start 130.9116 -89.41054)
		(end 131.1656 -89.41054)
		(stroke
			(width 0.2)
			(type default)
		)
		(layer "In1.Cu")
	)
	(gr_arc
		(start 130.9116 -88.89746)
		(mid 130.802041 -88.942841)
		(end 130.75666 -89.0524)
		(stroke
			(width 0.2)
			(type default)
		)
		(layer "In1.Cu")
	)
	(gr_line
		(start 130.9116 -88.77554)
		(end 131.1656 -88.77554)
		(stroke
			(width 0.2)
			(type default)
		)
		(layer "In1.Cu")
	)
	(gr_arc
		(start 130.9116 -88.26246)
		(mid 130.802041 -88.307841)
		(end 130.75666 -88.4174)
		(stroke
			(width 0.2)
			(type default)
		)
		(layer "In1.Cu")
	)
	(gr_line
		(start 130.9116 -88.14054)
		(end 131.1656 -88.14054)
		(stroke
			(width 0.2)
			(type default)
		)
		(layer "In1.Cu")
	)
	(gr_arc
		(start 130.9116 -87.62746)
		(mid 130.802041 -87.672841)
		(end 130.75666 -87.7824)
		(stroke
			(width 0.2)
			(type default)
		)
		(layer "In1.Cu")
	)
	(gr_line
		(start 130.9116 -87.50554)
		(end 131.1656 -87.50554)
		(stroke
			(width 0.2)
			(type default)
		)
		(layer "In1.Cu")
	)
	(gr_arc
		(start 130.9116 -86.99246)
		(mid 130.802041 -87.037841)
		(end 130.75666 -87.1474)
		(stroke
			(width 0.2)
			(type default)
		)
		(layer "In1.Cu")
	)
	(gr_arc
		(start 130.917442 -85.291422)
		(mid 131.027001 -85.246041)
		(end 131.072382 -85.136482)
		(stroke
			(width 0.2)
			(type default)
		)
		(layer "In1.Cu")
	)
	(gr_line
		(start 130.917442 -84.778342)
		(end 130.663442 -84.778342)
		(stroke
			(width 0.2)
			(type default)
		)
		(layer "In1.Cu")
	)
	(gr_arc
		(start 130.917442 -84.656422)
		(mid 131.027001 -84.611041)
		(end 131.072382 -84.501482)
		(stroke
			(width 0.2)
			(type default)
		)
		(layer "In1.Cu")
	)
	(gr_line
		(start 130.917442 -84.143342)
		(end 130.663442 -84.143342)
		(stroke
			(width 0.2)
			(type default)
		)
		(layer "In1.Cu")
	)
	(gr_line
		(start 130.92811 -99.48418)
		(end 131.13131 -99.48418)
		(stroke
			(width 0.2)
			(type default)
		)
		(layer "In1.Cu")
	)
	(gr_line
		(start 130.92811 -98.92538)
		(end 131.13131 -98.92538)
		(stroke
			(width 0.2)
			(type default)
		)
		(layer "In1.Cu")
	)
	(gr_arc
		(start 130.92811 -98.9203)
		(mid 130.818551 -98.965681)
		(end 130.77317 -99.07524)
		(stroke
			(width 0.2)
			(type default)
		)
		(layer "In1.Cu")
	)
	(gr_arc
		(start 130.92811 -98.3615)
		(mid 130.818551 -98.406881)
		(end 130.77317 -98.51644)
		(stroke
			(width 0.2)
			(type default)
		)
		(layer "In1.Cu")
	)
	(gr_line
		(start 131.02844 -80.13954)
		(end 132.00507 -80.13954)
		(stroke
			(width 0.2)
			(type default)
		)
		(layer "In1.Cu")
	)
	(gr_arc
		(start 131.02844 -79.37246)
		(mid 130.6449 -79.756)
		(end 131.02844 -80.13954)
		(stroke
			(width 0.2)
			(type default)
		)
		(layer "In1.Cu")
	)
	(gr_line
		(start 131.034282 -81.708498)
		(end 131.237482 -81.708498)
		(stroke
			(width 0.2)
			(type default)
		)
		(layer "In1.Cu")
	)
	(gr_line
		(start 131.034282 -81.149698)
		(end 131.237482 -81.149698)
		(stroke
			(width 0.2)
			(type default)
		)
		(layer "In1.Cu")
	)
	(gr_arc
		(start 131.034282 -81.144618)
		(mid 130.924723 -81.189999)
		(end 130.879342 -81.299558)
		(stroke
			(width 0.2)
			(type default)
		)
		(layer "In1.Cu")
	)
	(gr_arc
		(start 131.034282 -80.585818)
		(mid 130.924723 -80.631199)
		(end 130.879342 -80.740758)
		(stroke
			(width 0.2)
			(type default)
		)
		(layer "In1.Cu")
	)
	(gr_arc
		(start 131.067302 -85.136482)
		(mid 131.112683 -85.246041)
		(end 131.222242 -85.291422)
		(stroke
			(width 0.2)
			(type default)
		)
		(layer "In1.Cu")
	)
	(gr_line
		(start 131.067302 -84.933282)
		(end 131.067302 -85.136482)
		(stroke
			(width 0.2)
			(type default)
		)
		(layer "In1.Cu")
	)
	(gr_arc
		(start 131.067302 -84.501482)
		(mid 131.112683 -84.611041)
		(end 131.222242 -84.656422)
		(stroke
			(width 0.2)
			(type default)
		)
		(layer "In1.Cu")
	)
	(gr_line
		(start 131.067302 -84.298282)
		(end 131.067302 -84.501482)
		(stroke
			(width 0.2)
			(type default)
		)
		(layer "In1.Cu")
	)
	(gr_line
		(start 131.072382 -85.136482)
		(end 131.072382 -84.933282)
		(stroke
			(width 0.2)
			(type default)
		)
		(layer "In1.Cu")
	)
	(gr_arc
		(start 131.072382 -84.933282)
		(mid 131.027001 -84.823723)
		(end 130.917442 -84.778342)
		(stroke
			(width 0.2)
			(type default)
		)
		(layer "In1.Cu")
	)
	(gr_line
		(start 131.072382 -84.501482)
		(end 131.072382 -84.298282)
		(stroke
			(width 0.2)
			(type default)
		)
		(layer "In1.Cu")
	)
	(gr_arc
		(start 131.072382 -84.298282)
		(mid 131.027001 -84.188723)
		(end 130.917442 -84.143342)
		(stroke
			(width 0.2)
			(type default)
		)
		(layer "In1.Cu")
	)
	(gr_arc
		(start 131.13131 -99.48418)
		(mid 131.240869 -99.438799)
		(end 131.28625 -99.32924)
		(stroke
			(width 0.2)
			(type default)
		)
		(layer "In1.Cu")
	)
	(gr_arc
		(start 131.13131 -98.92538)
		(mid 131.240869 -98.879999)
		(end 131.28625 -98.77044)
		(stroke
			(width 0.2)
			(type default)
		)
		(layer "In1.Cu")
	)
	(gr_line
		(start 131.13131 -98.9203)
		(end 130.92811 -98.9203)
		(stroke
			(width 0.2)
			(type default)
		)
		(layer "In1.Cu")
	)
	(gr_line
		(start 131.13131 -98.3615)
		(end 130.92811 -98.3615)
		(stroke
			(width 0.2)
			(type default)
		)
		(layer "In1.Cu")
	)
	(gr_arc
		(start 131.1656 -92.20454)
		(mid 131.275159 -92.159159)
		(end 131.32054 -92.0496)
		(stroke
			(width 0.2)
			(type default)
		)
		(layer "In1.Cu")
	)
	(gr_line
		(start 131.1656 -91.69146)
		(end 130.9116 -91.69146)
		(stroke
			(width 0.2)
			(type default)
		)
		(layer "In1.Cu")
	)
	(gr_arc
		(start 131.1656 -91.56954)
		(mid 131.275159 -91.524159)
		(end 131.32054 -91.4146)
		(stroke
			(width 0.2)
			(type default)
		)
		(layer "In1.Cu")
	)
	(gr_line
		(start 131.1656 -91.05646)
		(end 130.9116 -91.05646)
		(stroke
			(width 0.2)
			(type default)
		)
		(layer "In1.Cu")
	)
	(gr_arc
		(start 131.1656 -90.68054)
		(mid 131.275159 -90.635159)
		(end 131.32054 -90.5256)
		(stroke
			(width 0.2)
			(type default)
		)
		(layer "In1.Cu")
	)
	(gr_line
		(start 131.1656 -90.16746)
		(end 130.9116 -90.16746)
		(stroke
			(width 0.2)
			(type default)
		)
		(layer "In1.Cu")
	)
	(gr_arc
		(start 131.1656 -90.04554)
		(mid 131.275159 -90.000159)
		(end 131.32054 -89.8906)
		(stroke
			(width 0.2)
			(type default)
		)
		(layer "In1.Cu")
	)
	(gr_line
		(start 131.1656 -89.53246)
		(end 130.9116 -89.53246)
		(stroke
			(width 0.2)
			(type default)
		)
		(layer "In1.Cu")
	)
	(gr_arc
		(start 131.1656 -89.41054)
		(mid 131.275159 -89.365159)
		(end 131.32054 -89.2556)
		(stroke
			(width 0.2)
			(type default)
		)
		(layer "In1.Cu")
	)
	(gr_line
		(start 131.1656 -88.89746)
		(end 130.9116 -88.89746)
		(stroke
			(width 0.2)
			(type default)
		)
		(layer "In1.Cu")
	)
	(gr_arc
		(start 131.1656 -88.77554)
		(mid 131.275159 -88.730159)
		(end 131.32054 -88.6206)
		(stroke
			(width 0.2)
			(type default)
		)
		(layer "In1.Cu")
	)
	(gr_line
		(start 131.1656 -88.26246)
		(end 130.9116 -88.26246)
		(stroke
			(width 0.2)
			(type default)
		)
		(layer "In1.Cu")
	)
	(gr_arc
		(start 131.1656 -88.14054)
		(mid 131.275159 -88.095159)
		(end 131.32054 -87.9856)
		(stroke
			(width 0.2)
			(type default)
		)
		(layer "In1.Cu")
	)
	(gr_line
		(start 131.1656 -87.62746)
		(end 130.9116 -87.62746)
		(stroke
			(width 0.2)
			(type default)
		)
		(layer "In1.Cu")
	)
	(gr_arc
		(start 131.1656 -87.50554)
		(mid 131.275159 -87.460159)
		(end 131.32054 -87.3506)
		(stroke
			(width 0.2)
			(type default)
		)
		(layer "In1.Cu")
	)
	(gr_line
		(start 131.1656 -86.99246)
		(end 130.9116 -86.99246)
		(stroke
			(width 0.2)
			(type default)
		)
		(layer "In1.Cu")
	)
	(gr_line
		(start 131.222242 -85.291422)
		(end 131.476242 -85.291422)
		(stroke
			(width 0.2)
			(type default)
		)
		(layer "In1.Cu")
	)
	(gr_arc
		(start 131.222242 -84.778342)
		(mid 131.112683 -84.823723)
		(end 131.067302 -84.933282)
		(stroke
			(width 0.2)
			(type default)
		)
		(layer "In1.Cu")
	)
	(gr_line
		(start 131.222242 -84.656422)
		(end 131.476242 -84.656422)
		(stroke
			(width 0.2)
			(type default)
		)
		(layer "In1.Cu")
	)
	(gr_arc
		(start 131.222242 -84.143342)
		(mid 131.112683 -84.188723)
		(end 131.067302 -84.298282)
		(stroke
			(width 0.2)
			(type default)
		)
		(layer "In1.Cu")
	)
	(gr_arc
		(start 131.237482 -81.708498)
		(mid 131.347041 -81.663117)
		(end 131.392422 -81.553558)
		(stroke
			(width 0.2)
			(type default)
		)
		(layer "In1.Cu")
	)
	(gr_arc
		(start 131.237482 -81.149698)
		(mid 131.347041 -81.104317)
		(end 131.392422 -80.994758)
		(stroke
			(width 0.2)
			(type default)
		)
		(layer "In1.Cu")
	)
	(gr_line
		(start 131.237482 -81.144618)
		(end 131.034282 -81.144618)
		(stroke
			(width 0.2)
			(type default)
		)
		(layer "In1.Cu")
	)
	(gr_line
		(start 131.237482 -80.585818)
		(end 131.034282 -80.585818)
		(stroke
			(width 0.2)
			(type default)
		)
		(layer "In1.Cu")
	)
	(gr_line
		(start 131.28625 -99.32924)
		(end 131.28625 -99.07524)
		(stroke
			(width 0.2)
			(type default)
		)
		(layer "In1.Cu")
	)
	(gr_arc
		(start 131.28625 -99.07524)
		(mid 131.240869 -98.965681)
		(end 131.13131 -98.9203)
		(stroke
			(width 0.2)
			(type default)
		)
		(layer "In1.Cu")
	)
	(gr_line
		(start 131.28625 -98.77044)
		(end 131.28625 -98.51644)
		(stroke
			(width 0.2)
			(type default)
		)
		(layer "In1.Cu")
	)
	(gr_arc
		(start 131.28625 -98.51644)
		(mid 131.240869 -98.406881)
		(end 131.13131 -98.3615)
		(stroke
			(width 0.2)
			(type default)
		)
		(layer "In1.Cu")
	)
	(gr_arc
		(start 131.31546 -92.0496)
		(mid 131.360841 -92.159159)
		(end 131.4704 -92.20454)
		(stroke
			(width 0.2)
			(type default)
		)
		(layer "In1.Cu")
	)
	(gr_line
		(start 131.31546 -91.8464)
		(end 131.31546 -92.0496)
		(stroke
			(width 0.2)
			(type default)
		)
		(layer "In1.Cu")
	)
	(gr_arc
		(start 131.31546 -91.4146)
		(mid 131.360841 -91.524159)
		(end 131.4704 -91.56954)
		(stroke
			(width 0.2)
			(type default)
		)
		(layer "In1.Cu")
	)
	(gr_line
		(start 131.31546 -91.2114)
		(end 131.31546 -91.4146)
		(stroke
			(width 0.2)
			(type default)
		)
		(layer "In1.Cu")
	)
	(gr_arc
		(start 131.31546 -90.5256)
		(mid 131.360841 -90.635159)
		(end 131.4704 -90.68054)
		(stroke
			(width 0.2)
			(type default)
		)
		(layer "In1.Cu")
	)
	(gr_line
		(start 131.31546 -90.3224)
		(end 131.31546 -90.5256)
		(stroke
			(width 0.2)
			(type default)
		)
		(layer "In1.Cu")
	)
	(gr_arc
		(start 131.31546 -89.8906)
		(mid 131.360841 -90.000159)
		(end 131.4704 -90.04554)
		(stroke
			(width 0.2)
			(type default)
		)
		(layer "In1.Cu")
	)
	(gr_line
		(start 131.31546 -89.6874)
		(end 131.31546 -89.8906)
		(stroke
			(width 0.2)
			(type default)
		)
		(layer "In1.Cu")
	)
	(gr_arc
		(start 131.31546 -89.2556)
		(mid 131.360841 -89.365159)
		(end 131.4704 -89.41054)
		(stroke
			(width 0.2)
			(type default)
		)
		(layer "In1.Cu")
	)
	(gr_line
		(start 131.31546 -89.0524)
		(end 131.31546 -89.2556)
		(stroke
			(width 0.2)
			(type default)
		)
		(layer "In1.Cu")
	)
	(gr_arc
		(start 131.31546 -88.6206)
		(mid 131.360841 -88.730159)
		(end 131.4704 -88.77554)
		(stroke
			(width 0.2)
			(type default)
		)
		(layer "In1.Cu")
	)
	(gr_line
		(start 131.31546 -88.4174)
		(end 131.31546 -88.6206)
		(stroke
			(width 0.2)
			(type default)
		)
		(layer "In1.Cu")
	)
	(gr_arc
		(start 131.31546 -87.9856)
		(mid 131.360841 -88.095159)
		(end 131.4704 -88.14054)
		(stroke
			(width 0.2)
			(type default)
		)
		(layer "In1.Cu")
	)
	(gr_line
		(start 131.31546 -87.7824)
		(end 131.31546 -87.9856)
		(stroke
			(width 0.2)
			(type default)
		)
		(layer "In1.Cu")
	)
	(gr_arc
		(start 131.31546 -87.3506)
		(mid 131.360841 -87.460159)
		(end 131.4704 -87.50554)
		(stroke
			(width 0.2)
			(type default)
		)
		(layer "In1.Cu")
	)
	(gr_line
		(start 131.31546 -87.1474)
		(end 131.31546 -87.3506)
		(stroke
			(width 0.2)
			(type default)
		)
		(layer "In1.Cu")
	)
	(gr_line
		(start 131.32054 -92.0496)
		(end 131.32054 -91.8464)
		(stroke
			(width 0.2)
			(type default)
		)
		(layer "In1.Cu")
	)
	(gr_arc
		(start 131.32054 -91.8464)
		(mid 131.275159 -91.736841)
		(end 131.1656 -91.69146)
		(stroke
			(width 0.2)
			(type default)
		)
		(layer "In1.Cu")
	)
	(gr_line
		(start 131.32054 -91.4146)
		(end 131.32054 -91.2114)
		(stroke
			(width 0.2)
			(type default)
		)
		(layer "In1.Cu")
	)
	(gr_arc
		(start 131.32054 -91.2114)
		(mid 131.275159 -91.101841)
		(end 131.1656 -91.05646)
		(stroke
			(width 0.2)
			(type default)
		)
		(layer "In1.Cu")
	)
	(gr_line
		(start 131.32054 -90.5256)
		(end 131.32054 -90.3224)
		(stroke
			(width 0.2)
			(type default)
		)
		(layer "In1.Cu")
	)
	(gr_arc
		(start 131.32054 -90.3224)
		(mid 131.275159 -90.212841)
		(end 131.1656 -90.16746)
		(stroke
			(width 0.2)
			(type default)
		)
		(layer "In1.Cu")
	)
	(gr_line
		(start 131.32054 -89.8906)
		(end 131.32054 -89.6874)
		(stroke
			(width 0.2)
			(type default)
		)
		(layer "In1.Cu")
	)
	(gr_arc
		(start 131.32054 -89.6874)
		(mid 131.275159 -89.577841)
		(end 131.1656 -89.53246)
		(stroke
			(width 0.2)
			(type default)
		)
		(layer "In1.Cu")
	)
	(gr_line
		(start 131.32054 -89.2556)
		(end 131.32054 -89.0524)
		(stroke
			(width 0.2)
			(type default)
		)
		(layer "In1.Cu")
	)
	(gr_arc
		(start 131.32054 -89.0524)
		(mid 131.275159 -88.942841)
		(end 131.1656 -88.89746)
		(stroke
			(width 0.2)
			(type default)
		)
		(layer "In1.Cu")
	)
	(gr_line
		(start 131.32054 -88.6206)
		(end 131.32054 -88.4174)
		(stroke
			(width 0.2)
			(type default)
		)
		(layer "In1.Cu")
	)
	(gr_arc
		(start 131.32054 -88.4174)
		(mid 131.275159 -88.307841)
		(end 131.1656 -88.26246)
		(stroke
			(width 0.2)
			(type default)
		)
		(layer "In1.Cu")
	)
	(gr_line
		(start 131.32054 -87.9856)
		(end 131.32054 -87.7824)
		(stroke
			(width 0.2)
			(type default)
		)
		(layer "In1.Cu")
	)
	(gr_arc
		(start 131.32054 -87.7824)
		(mid 131.275159 -87.672841)
		(end 131.1656 -87.62746)
		(stroke
			(width 0.2)
			(type default)
		)
		(layer "In1.Cu")
	)
	(gr_line
		(start 131.32054 -87.3506)
		(end 131.32054 -87.1474)
		(stroke
			(width 0.2)
			(type default)
		)
		(layer "In1.Cu")
	)
	(gr_arc
		(start 131.32054 -87.1474)
		(mid 131.275159 -87.037841)
		(end 131.1656 -86.99246)
		(stroke
			(width 0.2)
			(type default)
		)
		(layer "In1.Cu")
	)
	(gr_line
		(start 131.392422 -81.553558)
		(end 131.392422 -81.299558)
		(stroke
			(width 0.2)
			(type default)
		)
		(layer "In1.Cu")
	)
	(gr_arc
		(start 131.392422 -81.299558)
		(mid 131.347041 -81.189999)
		(end 131.237482 -81.144618)
		(stroke
			(width 0.2)
			(type default)
		)
		(layer "In1.Cu")
	)
	(gr_line
		(start 131.392422 -80.994758)
		(end 131.392422 -80.740758)
		(stroke
			(width 0.2)
			(type default)
		)
		(layer "In1.Cu")
	)
	(gr_arc
		(start 131.392422 -80.740758)
		(mid 131.347041 -80.631199)
		(end 131.237482 -80.585818)
		(stroke
			(width 0.2)
			(type default)
		)
		(layer "In1.Cu")
	)
	(gr_arc
		(start 131.40817 -99.32924)
		(mid 131.453551 -99.438799)
		(end 131.56311 -99.48418)
		(stroke
			(width 0.2)
			(type default)
		)
		(layer "In1.Cu")
	)
	(gr_line
		(start 131.40817 -99.07524)
		(end 131.40817 -99.32924)
		(stroke
			(width 0.2)
			(type default)
		)
		(layer "In1.Cu")
	)
	(gr_arc
		(start 131.40817 -98.77044)
		(mid 131.453551 -98.879999)
		(end 131.56311 -98.92538)
		(stroke
			(width 0.2)
			(type default)
		)
		(layer "In1.Cu")
	)
	(gr_line
		(start 131.40817 -98.51644)
		(end 131.40817 -98.77044)
		(stroke
			(width 0.2)
			(type default)
		)
		(layer "In1.Cu")
	)
	(gr_line
		(start 131.4704 -92.20454)
		(end 131.7244 -92.20454)
		(stroke
			(width 0.2)
			(type default)
		)
		(layer "In1.Cu")
	)
	(gr_arc
		(start 131.4704 -91.69146)
		(mid 131.360841 -91.736841)
		(end 131.31546 -91.8464)
		(stroke
			(width 0.2)
			(type default)
		)
		(layer "In1.Cu")
	)
	(gr_line
		(start 131.4704 -91.56954)
		(end 131.7244 -91.56954)
		(stroke
			(width 0.2)
			(type default)
		)
		(layer "In1.Cu")
	)
	(gr_arc
		(start 131.4704 -91.05646)
		(mid 131.360841 -91.101841)
		(end 131.31546 -91.2114)
		(stroke
			(width 0.2)
			(type default)
		)
		(layer "In1.Cu")
	)
	(gr_line
		(start 131.4704 -90.68054)
		(end 131.7244 -90.68054)
		(stroke
			(width 0.2)
			(type default)
		)
		(layer "In1.Cu")
	)
	(gr_arc
		(start 131.4704 -90.16746)
		(mid 131.360841 -90.212841)
		(end 131.31546 -90.3224)
		(stroke
			(width 0.2)
			(type default)
		)
		(layer "In1.Cu")
	)
	(gr_line
		(start 131.4704 -90.04554)
		(end 131.7244 -90.04554)
		(stroke
			(width 0.2)
			(type default)
		)
		(layer "In1.Cu")
	)
	(gr_arc
		(start 131.4704 -89.53246)
		(mid 131.360841 -89.577841)
		(end 131.31546 -89.6874)
		(stroke
			(width 0.2)
			(type default)
		)
		(layer "In1.Cu")
	)
	(gr_line
		(start 131.4704 -89.41054)
		(end 131.7244 -89.41054)
		(stroke
			(width 0.2)
			(type default)
		)
		(layer "In1.Cu")
	)
	(gr_arc
		(start 131.4704 -88.89746)
		(mid 131.360841 -88.942841)
		(end 131.31546 -89.0524)
		(stroke
			(width 0.2)
			(type default)
		)
		(layer "In1.Cu")
	)
	(gr_line
		(start 131.4704 -88.77554)
		(end 131.7244 -88.77554)
		(stroke
			(width 0.2)
			(type default)
		)
		(layer "In1.Cu")
	)
	(gr_arc
		(start 131.4704 -88.26246)
		(mid 131.360841 -88.307841)
		(end 131.31546 -88.4174)
		(stroke
			(width 0.2)
			(type default)
		)
		(layer "In1.Cu")
	)
	(gr_line
		(start 131.4704 -88.14054)
		(end 131.7244 -88.14054)
		(stroke
			(width 0.2)
			(type default)
		)
		(layer "In1.Cu")
	)
	(gr_arc
		(start 131.4704 -87.62746)
		(mid 131.360841 -87.672841)
		(end 131.31546 -87.7824)
		(stroke
			(width 0.2)
			(type default)
		)
		(layer "In1.Cu")
	)
	(gr_line
		(start 131.4704 -87.50554)
		(end 131.7244 -87.50554)
		(stroke
			(width 0.2)
			(type default)
		)
		(layer "In1.Cu")
	)
	(gr_arc
		(start 131.4704 -86.99246)
		(mid 131.360841 -87.037841)
		(end 131.31546 -87.1474)
		(stroke
			(width 0.2)
			(type default)
		)
		(layer "In1.Cu")
	)
	(gr_arc
		(start 131.476242 -85.291422)
		(mid 131.585801 -85.246041)
		(end 131.631182 -85.136482)
		(stroke
			(width 0.2)
			(type default)
		)
		(layer "In1.Cu")
	)
	(gr_line
		(start 131.476242 -84.778342)
		(end 131.222242 -84.778342)
		(stroke
			(width 0.2)
			(type default)
		)
		(layer "In1.Cu")
	)
	(gr_arc
		(start 131.476242 -84.656422)
		(mid 131.585801 -84.611041)
		(end 131.631182 -84.501482)
		(stroke
			(width 0.2)
			(type default)
		)
		(layer "In1.Cu")
	)
	(gr_line
		(start 131.476242 -84.143342)
		(end 131.222242 -84.143342)
		(stroke
			(width 0.2)
			(type default)
		)
		(layer "In1.Cu")
	)
	(gr_line
		(start 131.56311 -99.48418)
		(end 131.76631 -99.48418)
		(stroke
			(width 0.2)
			(type default)
		)
		(layer "In1.Cu")
	)
	(gr_line
		(start 131.56311 -98.92538)
		(end 131.76631 -98.92538)
		(stroke
			(width 0.2)
			(type default)
		)
		(layer "In1.Cu")
	)
	(gr_arc
		(start 131.56311 -98.9203)
		(mid 131.453551 -98.965681)
		(end 131.40817 -99.07524)
		(stroke
			(width 0.2)
			(type default)
		)
		(layer "In1.Cu")
	)
	(gr_arc
		(start 131.56311 -98.3615)
		(mid 131.453551 -98.406881)
		(end 131.40817 -98.51644)
		(stroke
			(width 0.2)
			(type default)
		)
		(layer "In1.Cu")
	)
	(gr_line
		(start 131.631182 -85.136482)
		(end 131.631182 -84.933282)
		(stroke
			(width 0.2)
			(type default)
		)
		(layer "In1.Cu")
	)
	(gr_arc
		(start 131.631182 -84.933282)
		(mid 131.585801 -84.823723)
		(end 131.476242 -84.778342)
		(stroke
			(width 0.2)
			(type default)
		)
		(layer "In1.Cu")
	)
	(gr_line
		(start 131.631182 -84.501482)
		(end 131.631182 -84.298282)
		(stroke
			(width 0.2)
			(type default)
		)
		(layer "In1.Cu")
	)
	(gr_arc
		(start 131.631182 -84.298282)
		(mid 131.585801 -84.188723)
		(end 131.476242 -84.143342)
		(stroke
			(width 0.2)
			(type default)
		)
		(layer "In1.Cu")
	)
	(gr_arc
		(start 131.641342 -81.553558)
		(mid 131.686723 -81.663117)
		(end 131.796282 -81.708498)
		(stroke
			(width 0.2)
			(type default)
		)
		(layer "In1.Cu")
	)
	(gr_line
		(start 131.641342 -81.299558)
		(end 131.641342 -81.553558)
		(stroke
			(width 0.2)
			(type default)
		)
		(layer "In1.Cu")
	)
	(gr_arc
		(start 131.641342 -80.994758)
		(mid 131.686723 -81.104317)
		(end 131.796282 -81.149698)
		(stroke
			(width 0.2)
			(type default)
		)
		(layer "In1.Cu")
	)
	(gr_line
		(start 131.641342 -80.740758)
		(end 131.641342 -80.994758)
		(stroke
			(width 0.2)
			(type default)
		)
		(layer "In1.Cu")
	)
	(gr_arc
		(start 131.651502 -83.231482)
		(mid 131.696883 -83.341041)
		(end 131.806442 -83.386422)
		(stroke
			(width 0.2)
			(type default)
		)
		(layer "In1.Cu")
	)
	(gr_line
		(start 131.651502 -83.028282)
		(end 131.651502 -83.231482)
		(stroke
			(width 0.2)
			(type default)
		)
		(layer "In1.Cu")
	)
	(gr_arc
		(start 131.651502 -82.596482)
		(mid 131.696883 -82.706041)
		(end 131.806442 -82.751422)
		(stroke
			(width 0.2)
			(type default)
		)
		(layer "In1.Cu")
	)
	(gr_line
		(start 131.651502 -82.393282)
		(end 131.651502 -82.596482)
		(stroke
			(width 0.2)
			(type default)
		)
		(layer "In1.Cu")
	)
	(gr_arc
		(start 131.7244 -92.20454)
		(mid 131.833959 -92.159159)
		(end 131.87934 -92.0496)
		(stroke
			(width 0.2)
			(type default)
		)
		(layer "In1.Cu")
	)
	(gr_line
		(start 131.7244 -91.69146)
		(end 131.4704 -91.69146)
		(stroke
			(width 0.2)
			(type default)
		)
		(layer "In1.Cu")
	)
	(gr_arc
		(start 131.7244 -91.56954)
		(mid 131.833959 -91.524159)
		(end 131.87934 -91.4146)
		(stroke
			(width 0.2)
			(type default)
		)
		(layer "In1.Cu")
	)
	(gr_line
		(start 131.7244 -91.05646)
		(end 131.4704 -91.05646)
		(stroke
			(width 0.2)
			(type default)
		)
		(layer "In1.Cu")
	)
	(gr_arc
		(start 131.7244 -90.68054)
		(mid 131.833959 -90.635159)
		(end 131.87934 -90.5256)
		(stroke
			(width 0.2)
			(type default)
		)
		(layer "In1.Cu")
	)
	(gr_line
		(start 131.7244 -90.16746)
		(end 131.4704 -90.16746)
		(stroke
			(width 0.2)
			(type default)
		)
		(layer "In1.Cu")
	)
	(gr_arc
		(start 131.7244 -90.04554)
		(mid 131.833959 -90.000159)
		(end 131.87934 -89.8906)
		(stroke
			(width 0.2)
			(type default)
		)
		(layer "In1.Cu")
	)
	(gr_line
		(start 131.7244 -89.53246)
		(end 131.4704 -89.53246)
		(stroke
			(width 0.2)
			(type default)
		)
		(layer "In1.Cu")
	)
	(gr_arc
		(start 131.7244 -89.41054)
		(mid 131.833959 -89.365159)
		(end 131.87934 -89.2556)
		(stroke
			(width 0.2)
			(type default)
		)
		(layer "In1.Cu")
	)
	(gr_line
		(start 131.7244 -88.89746)
		(end 131.4704 -88.89746)
		(stroke
			(width 0.2)
			(type default)
		)
		(layer "In1.Cu")
	)
	(gr_arc
		(start 131.7244 -88.77554)
		(mid 131.833959 -88.730159)
		(end 131.87934 -88.6206)
		(stroke
			(width 0.2)
			(type default)
		)
		(layer "In1.Cu")
	)
	(gr_line
		(start 131.7244 -88.26246)
		(end 131.4704 -88.26246)
		(stroke
			(width 0.2)
			(type default)
		)
		(layer "In1.Cu")
	)
	(gr_arc
		(start 131.7244 -88.14054)
		(mid 131.833959 -88.095159)
		(end 131.87934 -87.9856)
		(stroke
			(width 0.2)
			(type default)
		)
		(layer "In1.Cu")
	)
	(gr_line
		(start 131.7244 -87.62746)
		(end 131.4704 -87.62746)
		(stroke
			(width 0.2)
			(type default)
		)
		(layer "In1.Cu")
	)
	(gr_arc
		(start 131.7244 -87.50554)
		(mid 131.833959 -87.460159)
		(end 131.87934 -87.3506)
		(stroke
			(width 0.2)
			(type default)
		)
		(layer "In1.Cu")
	)
	(gr_line
		(start 131.7244 -86.99246)
		(end 131.4704 -86.99246)
		(stroke
			(width 0.2)
			(type default)
		)
		(layer "In1.Cu")
	)
	(gr_arc
		(start 131.76631 -99.48418)
		(mid 131.875869 -99.438799)
		(end 131.92125 -99.32924)
		(stroke
			(width 0.2)
			(type default)
		)
		(layer "In1.Cu")
	)
	(gr_arc
		(start 131.76631 -98.92538)
		(mid 131.875869 -98.879999)
		(end 131.92125 -98.77044)
		(stroke
			(width 0.2)
			(type default)
		)
		(layer "In1.Cu")
	)
	(gr_line
		(start 131.76631 -98.9203)
		(end 131.56311 -98.9203)
		(stroke
			(width 0.2)
			(type default)
		)
		(layer "In1.Cu")
	)
	(gr_line
		(start 131.76631 -98.3615)
		(end 131.56311 -98.3615)
		(stroke
			(width 0.2)
			(type default)
		)
		(layer "In1.Cu")
	)
	(gr_line
		(start 131.796282 -81.708498)
		(end 131.999482 -81.708498)
		(stroke
			(width 0.2)
			(type default)
		)
		(layer "In1.Cu")
	)
	(gr_line
		(start 131.796282 -81.149698)
		(end 131.999482 -81.149698)
		(stroke
			(width 0.2)
			(type default)
		)
		(layer "In1.Cu")
	)
	(gr_arc
		(start 131.796282 -81.144618)
		(mid 131.686723 -81.189999)
		(end 131.641342 -81.299558)
		(stroke
			(width 0.2)
			(type default)
		)
		(layer "In1.Cu")
	)
	(gr_arc
		(start 131.796282 -80.585818)
		(mid 131.686723 -80.631199)
		(end 131.641342 -80.740758)
		(stroke
			(width 0.2)
			(type default)
		)
		(layer "In1.Cu")
	)
	(gr_line
		(start 131.806442 -83.386422)
		(end 132.060442 -83.386422)
		(stroke
			(width 0.2)
			(type default)
		)
		(layer "In1.Cu")
	)
	(gr_arc
		(start 131.806442 -82.873342)
		(mid 131.696883 -82.918723)
		(end 131.651502 -83.028282)
		(stroke
			(width 0.2)
			(type default)
		)
		(layer "In1.Cu")
	)
	(gr_line
		(start 131.806442 -82.751422)
		(end 132.060442 -82.751422)
		(stroke
			(width 0.2)
			(type default)
		)
		(layer "In1.Cu")
	)
	(gr_arc
		(start 131.806442 -82.238342)
		(mid 131.696883 -82.283723)
		(end 131.651502 -82.393282)
		(stroke
			(width 0.2)
			(type default)
		)
		(layer "In1.Cu")
	)
	(gr_arc
		(start 131.82346 -92.075)
		(mid 132.207 -92.45854)
		(end 132.59054 -92.075)
		(stroke
			(width 0.2)
			(type default)
		)
		(layer "In1.Cu")
	)
	(gr_line
		(start 131.82346 -91.169998)
		(end 131.82346 -92.075)
		(stroke
			(width 0.2)
			(type default)
		)
		(layer "In1.Cu")
	)
	(gr_arc
		(start 131.82346 -89.281)
		(mid 132.207 -89.66454)
		(end 132.59054 -89.281)
		(stroke
			(width 0.2)
			(type default)
		)
		(layer "In1.Cu")
	)
	(gr_line
		(start 131.82346 -88.375998)
		(end 131.82346 -89.281)
		(stroke
			(width 0.2)
			(type default)
		)
		(layer "In1.Cu")
	)
	(gr_line
		(start 131.87934 -92.0496)
		(end 131.87934 -91.8464)
		(stroke
			(width 0.2)
			(type default)
		)
		(layer "In1.Cu")
	)
	(gr_arc
		(start 131.87934 -91.8464)
		(mid 131.833959 -91.736841)
		(end 131.7244 -91.69146)
		(stroke
			(width 0.2)
			(type default)
		)
		(layer "In1.Cu")
	)
	(gr_line
		(start 131.87934 -91.4146)
		(end 131.87934 -91.2114)
		(stroke
			(width 0.2)
			(type default)
		)
		(layer "In1.Cu")
	)
	(gr_arc
		(start 131.87934 -91.2114)
		(mid 131.833959 -91.101841)
		(end 131.7244 -91.05646)
		(stroke
			(width 0.2)
			(type default)
		)
		(layer "In1.Cu")
	)
	(gr_line
		(start 131.87934 -90.5256)
		(end 131.87934 -90.3224)
		(stroke
			(width 0.2)
			(type default)
		)
		(layer "In1.Cu")
	)
	(gr_arc
		(start 131.87934 -90.3224)
		(mid 131.833959 -90.212841)
		(end 131.7244 -90.16746)
		(stroke
			(width 0.2)
			(type default)
		)
		(layer "In1.Cu")
	)
	(gr_line
		(start 131.87934 -89.8906)
		(end 131.87934 -89.6874)
		(stroke
			(width 0.2)
			(type default)
		)
		(layer "In1.Cu")
	)
	(gr_arc
		(start 131.87934 -89.6874)
		(mid 131.833959 -89.577841)
		(end 131.7244 -89.53246)
		(stroke
			(width 0.2)
			(type default)
		)
		(layer "In1.Cu")
	)
	(gr_line
		(start 131.87934 -89.2556)
		(end 131.87934 -89.0524)
		(stroke
			(width 0.2)
			(type default)
		)
		(layer "In1.Cu")
	)
	(gr_arc
		(start 131.87934 -89.0524)
		(mid 131.833959 -88.942841)
		(end 131.7244 -88.89746)
		(stroke
			(width 0.2)
			(type default)
		)
		(layer "In1.Cu")
	)
	(gr_line
		(start 131.87934 -88.6206)
		(end 131.87934 -88.4174)
		(stroke
			(width 0.2)
			(type default)
		)
		(layer "In1.Cu")
	)
	(gr_arc
		(start 131.87934 -88.4174)
		(mid 131.833959 -88.307841)
		(end 131.7244 -88.26246)
		(stroke
			(width 0.2)
			(type default)
		)
		(layer "In1.Cu")
	)
	(gr_line
		(start 131.87934 -87.9856)
		(end 131.87934 -87.7824)
		(stroke
			(width 0.2)
			(type default)
		)
		(layer "In1.Cu")
	)
	(gr_arc
		(start 131.87934 -87.7824)
		(mid 131.833959 -87.672841)
		(end 131.7244 -87.62746)
		(stroke
			(width 0.2)
			(type default)
		)
		(layer "In1.Cu")
	)
	(gr_line
		(start 131.87934 -87.3506)
		(end 131.87934 -87.1474)
		(stroke
			(width 0.2)
			(type default)
		)
		(layer "In1.Cu")
	)
	(gr_arc
		(start 131.87934 -87.1474)
		(mid 131.833959 -87.037841)
		(end 131.7244 -86.99246)
		(stroke
			(width 0.2)
			(type default)
		)
		(layer "In1.Cu")
	)
	(gr_line
		(start 131.92125 -99.32924)
		(end 131.92125 -99.07524)
		(stroke
			(width 0.2)
			(type default)
		)
		(layer "In1.Cu")
	)
	(gr_arc
		(start 131.92125 -99.07524)
		(mid 131.875869 -98.965681)
		(end 131.76631 -98.9203)
		(stroke
			(width 0.2)
			(type default)
		)
		(layer "In1.Cu")
	)
	(gr_line
		(start 131.92125 -98.77044)
		(end 131.92125 -98.51644)
		(stroke
			(width 0.2)
			(type default)
		)
		(layer "In1.Cu")
	)
	(gr_arc
		(start 131.92125 -98.51644)
		(mid 131.875869 -98.406881)
		(end 131.76631 -98.3615)
		(stroke
			(width 0.2)
			(type default)
		)
		(layer "In1.Cu")
	)
	(gr_arc
		(start 131.999482 -81.708498)
		(mid 132.109041 -81.663117)
		(end 132.154422 -81.553558)
		(stroke
			(width 0.2)
			(type default)
		)
		(layer "In1.Cu")
	)
	(gr_arc
		(start 131.999482 -81.149698)
		(mid 132.109041 -81.104317)
		(end 132.154422 -80.994758)
		(stroke
			(width 0.2)
			(type default)
		)
		(layer "In1.Cu")
	)
	(gr_line
		(start 131.999482 -81.144618)
		(end 131.796282 -81.144618)
		(stroke
			(width 0.2)
			(type default)
		)
		(layer "In1.Cu")
	)
	(gr_line
		(start 131.999482 -80.585818)
		(end 131.796282 -80.585818)
		(stroke
			(width 0.2)
			(type default)
		)
		(layer "In1.Cu")
	)
	(gr_arc
		(start 132.00507 -80.13954)
		(mid 132.388864 -79.756127)
		(end 132.005324 -79.37246)
		(stroke
			(width 0.2)
			(type default)
		)
		(layer "In1.Cu")
	)
	(gr_line
		(start 132.005324 -79.37246)
		(end 131.02844 -79.37246)
		(stroke
			(width 0.2)
			(type default)
		)
		(layer "In1.Cu")
	)
	(gr_arc
		(start 132.060442 -83.386422)
		(mid 132.170001 -83.341041)
		(end 132.215382 -83.231482)
		(stroke
			(width 0.2)
			(type default)
		)
		(layer "In1.Cu")
	)
	(gr_line
		(start 132.060442 -82.873342)
		(end 131.806442 -82.873342)
		(stroke
			(width 0.2)
			(type default)
		)
		(layer "In1.Cu")
	)
	(gr_arc
		(start 132.060442 -82.751422)
		(mid 132.170001 -82.706041)
		(end 132.215382 -82.596482)
		(stroke
			(width 0.2)
			(type default)
		)
		(layer "In1.Cu")
	)
	(gr_line
		(start 132.060442 -82.238342)
		(end 131.806442 -82.238342)
		(stroke
			(width 0.2)
			(type default)
		)
		(layer "In1.Cu")
	)
	(gr_line
		(start 132.154422 -81.553558)
		(end 132.154422 -81.299558)
		(stroke
			(width 0.2)
			(type default)
		)
		(layer "In1.Cu")
	)
	(gr_arc
		(start 132.154422 -81.299558)
		(mid 132.109041 -81.189999)
		(end 131.999482 -81.144618)
		(stroke
			(width 0.2)
			(type default)
		)
		(layer "In1.Cu")
	)
	(gr_line
		(start 132.154422 -80.994758)
		(end 132.154422 -80.740758)
		(stroke
			(width 0.2)
			(type default)
		)
		(layer "In1.Cu")
	)
	(gr_arc
		(start 132.154422 -80.740758)
		(mid 132.109041 -80.631199)
		(end 131.999482 -80.585818)
		(stroke
			(width 0.2)
			(type default)
		)
		(layer "In1.Cu")
	)
	(gr_arc
		(start 132.210302 -83.231482)
		(mid 132.255683 -83.341041)
		(end 132.365242 -83.386422)
		(stroke
			(width 0.2)
			(type default)
		)
		(layer "In1.Cu")
	)
	(gr_line
		(start 132.210302 -83.028282)
		(end 132.210302 -83.231482)
		(stroke
			(width 0.2)
			(type default)
		)
		(layer "In1.Cu")
	)
	(gr_arc
		(start 132.210302 -82.596482)
		(mid 132.255683 -82.706041)
		(end 132.365242 -82.751422)
		(stroke
			(width 0.2)
			(type default)
		)
		(layer "In1.Cu")
	)
	(gr_line
		(start 132.210302 -82.393282)
		(end 132.210302 -82.596482)
		(stroke
			(width 0.2)
			(type default)
		)
		(layer "In1.Cu")
	)
	(gr_line
		(start 132.215382 -83.231482)
		(end 132.215382 -83.028282)
		(stroke
			(width 0.2)
			(type default)
		)
		(layer "In1.Cu")
	)
	(gr_arc
		(start 132.215382 -83.028282)
		(mid 132.170001 -82.918723)
		(end 132.060442 -82.873342)
		(stroke
			(width 0.2)
			(type default)
		)
		(layer "In1.Cu")
	)
	(gr_line
		(start 132.215382 -82.596482)
		(end 132.215382 -82.393282)
		(stroke
			(width 0.2)
			(type default)
		)
		(layer "In1.Cu")
	)
	(gr_arc
		(start 132.215382 -82.393282)
		(mid 132.170001 -82.283723)
		(end 132.060442 -82.238342)
		(stroke
			(width 0.2)
			(type default)
		)
		(layer "In1.Cu")
	)
	(gr_line
		(start 132.365242 -83.386422)
		(end 132.619242 -83.386422)
		(stroke
			(width 0.2)
			(type default)
		)
		(layer "In1.Cu")
	)
	(gr_arc
		(start 132.365242 -82.873342)
		(mid 132.255683 -82.918723)
		(end 132.210302 -83.028282)
		(stroke
			(width 0.2)
			(type default)
		)
		(layer "In1.Cu")
	)
	(gr_line
		(start 132.365242 -82.751422)
		(end 132.619242 -82.751422)
		(stroke
			(width 0.2)
			(type default)
		)
		(layer "In1.Cu")
	)
	(gr_arc
		(start 132.365242 -82.238342)
		(mid 132.255683 -82.283723)
		(end 132.210302 -82.393282)
		(stroke
			(width 0.2)
			(type default)
		)
		(layer "In1.Cu")
	)
	(gr_arc
		(start 132.47243 -99.2124)
		(mid 132.517811 -99.321959)
		(end 132.62737 -99.36734)
		(stroke
			(width 0.2)
			(type default)
		)
		(layer "In1.Cu")
	)
	(gr_line
		(start 132.47243 -98.9584)
		(end 132.47243 -99.2124)
		(stroke
			(width 0.2)
			(type default)
		)
		(layer "In1.Cu")
	)
	(gr_arc
		(start 132.47243 -98.6536)
		(mid 132.517811 -98.763159)
		(end 132.62737 -98.80854)
		(stroke
			(width 0.2)
			(type default)
		)
		(layer "In1.Cu")
	)
	(gr_line
		(start 132.47243 -98.3996)
		(end 132.47243 -98.6536)
		(stroke
			(width 0.2)
			(type default)
		)
		(layer "In1.Cu")
	)
	(gr_line
		(start 132.59054 -92.075)
		(end 132.59054 -91.170252)
		(stroke
			(width 0.2)
			(type default)
		)
		(layer "In1.Cu")
	)
	(gr_arc
		(start 132.59054 -91.170252)
		(mid 132.207127 -90.786458)
		(end 131.82346 -91.169998)
		(stroke
			(width 0.2)
			(type default)
		)
		(layer "In1.Cu")
	)
	(gr_line
		(start 132.59054 -89.281)
		(end 132.59054 -88.376252)
		(stroke
			(width 0.2)
			(type default)
		)
		(layer "In1.Cu")
	)
	(gr_arc
		(start 132.59054 -88.376252)
		(mid 132.207127 -87.992458)
		(end 131.82346 -88.375998)
		(stroke
			(width 0.2)
			(type default)
		)
		(layer "In1.Cu")
	)
	(gr_arc
		(start 132.619242 -83.386422)
		(mid 132.728801 -83.341041)
		(end 132.774182 -83.231482)
		(stroke
			(width 0.2)
			(type default)
		)
		(layer "In1.Cu")
	)
	(gr_line
		(start 132.619242 -82.873342)
		(end 132.365242 -82.873342)
		(stroke
			(width 0.2)
			(type default)
		)
		(layer "In1.Cu")
	)
	(gr_arc
		(start 132.619242 -82.751422)
		(mid 132.728801 -82.706041)
		(end 132.774182 -82.596482)
		(stroke
			(width 0.2)
			(type default)
		)
		(layer "In1.Cu")
	)
	(gr_line
		(start 132.619242 -82.238342)
		(end 132.365242 -82.238342)
		(stroke
			(width 0.2)
			(type default)
		)
		(layer "In1.Cu")
	)
	(gr_line
		(start 132.62737 -99.36734)
		(end 132.83057 -99.36734)
		(stroke
			(width 0.2)
			(type default)
		)
		(layer "In1.Cu")
	)
	(gr_line
		(start 132.62737 -98.80854)
		(end 132.83057 -98.80854)
		(stroke
			(width 0.2)
			(type default)
		)
		(layer "In1.Cu")
	)
	(gr_arc
		(start 132.62737 -98.80346)
		(mid 132.517811 -98.848841)
		(end 132.47243 -98.9584)
		(stroke
			(width 0.2)
			(type default)
		)
		(layer "In1.Cu")
	)
	(gr_arc
		(start 132.62737 -98.24466)
		(mid 132.517811 -98.290041)
		(end 132.47243 -98.3996)
		(stroke
			(width 0.2)
			(type default)
		)
		(layer "In1.Cu")
	)
	(gr_line
		(start 132.774182 -83.231482)
		(end 132.774182 -83.028282)
		(stroke
			(width 0.2)
			(type default)
		)
		(layer "In1.Cu")
	)
	(gr_arc
		(start 132.774182 -83.028282)
		(mid 132.728801 -82.918723)
		(end 132.619242 -82.873342)
		(stroke
			(width 0.2)
			(type default)
		)
		(layer "In1.Cu")
	)
	(gr_line
		(start 132.774182 -82.596482)
		(end 132.774182 -82.393282)
		(stroke
			(width 0.2)
			(type default)
		)
		(layer "In1.Cu")
	)
	(gr_arc
		(start 132.774182 -82.393282)
		(mid 132.728801 -82.283723)
		(end 132.619242 -82.238342)
		(stroke
			(width 0.2)
			(type default)
		)
		(layer "In1.Cu")
	)
	(gr_arc
		(start 132.83057 -99.36734)
		(mid 132.940129 -99.321959)
		(end 132.98551 -99.2124)
		(stroke
			(width 0.2)
			(type default)
		)
		(layer "In1.Cu")
	)
	(gr_arc
		(start 132.83057 -98.80854)
		(mid 132.940129 -98.763159)
		(end 132.98551 -98.6536)
		(stroke
			(width 0.2)
			(type default)
		)
		(layer "In1.Cu")
	)
	(gr_line
		(start 132.83057 -98.80346)
		(end 132.62737 -98.80346)
		(stroke
			(width 0.2)
			(type default)
		)
		(layer "In1.Cu")
	)
	(gr_line
		(start 132.83057 -98.24466)
		(end 132.62737 -98.24466)
		(stroke
			(width 0.2)
			(type default)
		)
		(layer "In1.Cu")
	)
	(gr_line
		(start 132.930392 -81.500726)
		(end 133.858254 -81.500726)
		(stroke
			(width 0.2)
			(type default)
		)
		(layer "In1.Cu")
	)
	(gr_arc
		(start 132.930392 -80.733646)
		(mid 132.546852 -81.117186)
		(end 132.930392 -81.500726)
		(stroke
			(width 0.2)
			(type default)
		)
		(layer "In1.Cu")
	)
	(gr_line
		(start 132.98551 -99.2124)
		(end 132.98551 -98.9584)
		(stroke
			(width 0.2)
			(type default)
		)
		(layer "In1.Cu")
	)
	(gr_arc
		(start 132.98551 -98.9584)
		(mid 132.940129 -98.848841)
		(end 132.83057 -98.80346)
		(stroke
			(width 0.2)
			(type default)
		)
		(layer "In1.Cu")
	)
	(gr_line
		(start 132.98551 -98.6536)
		(end 132.98551 -98.3996)
		(stroke
			(width 0.2)
			(type default)
		)
		(layer "In1.Cu")
	)
	(gr_arc
		(start 132.98551 -98.3996)
		(mid 132.940129 -98.290041)
		(end 132.83057 -98.24466)
		(stroke
			(width 0.2)
			(type default)
		)
		(layer "In1.Cu")
	)
	(gr_arc
		(start 133.10743 -99.2124)
		(mid 133.152811 -99.321959)
		(end 133.26237 -99.36734)
		(stroke
			(width 0.2)
			(type default)
		)
		(layer "In1.Cu")
	)
	(gr_line
		(start 133.10743 -98.9584)
		(end 133.10743 -99.2124)
		(stroke
			(width 0.2)
			(type default)
		)
		(layer "In1.Cu")
	)
	(gr_arc
		(start 133.10743 -98.6536)
		(mid 133.152811 -98.763159)
		(end 133.26237 -98.80854)
		(stroke
			(width 0.2)
			(type default)
		)
		(layer "In1.Cu")
	)
	(gr_line
		(start 133.10743 -98.3996)
		(end 133.10743 -98.6536)
		(stroke
			(width 0.2)
			(type default)
		)
		(layer "In1.Cu")
	)
	(gr_arc
		(start 133.175502 -84.628482)
		(mid 133.220883 -84.738041)
		(end 133.330442 -84.783422)
		(stroke
			(width 0.2)
			(type default)
		)
		(layer "In1.Cu")
	)
	(gr_line
		(start 133.175502 -84.425282)
		(end 133.175502 -84.628482)
		(stroke
			(width 0.2)
			(type default)
		)
		(layer "In1.Cu")
	)
	(gr_arc
		(start 133.175502 -83.993482)
		(mid 133.220883 -84.103041)
		(end 133.330442 -84.148422)
		(stroke
			(width 0.2)
			(type default)
		)
		(layer "In1.Cu")
	)
	(gr_line
		(start 133.175502 -83.790282)
		(end 133.175502 -83.993482)
		(stroke
			(width 0.2)
			(type default)
		)
		(layer "In1.Cu")
	)
	(gr_line
		(start 133.26237 -99.36734)
		(end 133.46557 -99.36734)
		(stroke
			(width 0.2)
			(type default)
		)
		(layer "In1.Cu")
	)
	(gr_line
		(start 133.26237 -98.80854)
		(end 133.46557 -98.80854)
		(stroke
			(width 0.2)
			(type default)
		)
		(layer "In1.Cu")
	)
	(gr_arc
		(start 133.26237 -98.80346)
		(mid 133.152811 -98.848841)
		(end 133.10743 -98.9584)
		(stroke
			(width 0.2)
			(type default)
		)
		(layer "In1.Cu")
	)
	(gr_arc
		(start 133.26237 -98.24466)
		(mid 133.152811 -98.290041)
		(end 133.10743 -98.3996)
		(stroke
			(width 0.2)
			(type default)
		)
		(layer "In1.Cu")
	)
	(gr_line
		(start 133.330442 -84.783422)
		(end 133.584442 -84.783422)
		(stroke
			(width 0.2)
			(type default)
		)
		(layer "In1.Cu")
	)
	(gr_arc
		(start 133.330442 -84.270342)
		(mid 133.220883 -84.315723)
		(end 133.175502 -84.425282)
		(stroke
			(width 0.2)
			(type default)
		)
		(layer "In1.Cu")
	)
	(gr_line
		(start 133.330442 -84.148422)
		(end 133.584442 -84.148422)
		(stroke
			(width 0.2)
			(type default)
		)
		(layer "In1.Cu")
	)
	(gr_arc
		(start 133.330442 -83.635342)
		(mid 133.220883 -83.680723)
		(end 133.175502 -83.790282)
		(stroke
			(width 0.2)
			(type default)
		)
		(layer "In1.Cu")
	)
	(gr_arc
		(start 133.34746 -90.558874)
		(mid 133.730873 -90.942668)
		(end 134.11454 -90.559128)
		(stroke
			(width 0.2)
			(type default)
		)
		(layer "In1.Cu")
	)
	(gr_line
		(start 133.34746 -89.654126)
		(end 133.34746 -90.558874)
		(stroke
			(width 0.2)
			(type default)
		)
		(layer "In1.Cu")
	)
	(gr_arc
		(start 133.34746 -88.019128)
		(mid 133.731 -88.402668)
		(end 134.11454 -88.019128)
		(stroke
			(width 0.2)
			(type default)
		)
		(layer "In1.Cu")
	)
	(gr_line
		(start 133.34746 -87.114126)
		(end 133.34746 -88.019128)
		(stroke
			(width 0.2)
			(type default)
		)
		(layer "In1.Cu")
	)
	(gr_arc
		(start 133.46557 -99.36734)
		(mid 133.575129 -99.321959)
		(end 133.62051 -99.2124)
		(stroke
			(width 0.2)
			(type default)
		)
		(layer "In1.Cu")
	)
	(gr_arc
		(start 133.46557 -98.80854)
		(mid 133.575129 -98.763159)
		(end 133.62051 -98.6536)
		(stroke
			(width 0.2)
			(type default)
		)
		(layer "In1.Cu")
	)
	(gr_line
		(start 133.46557 -98.80346)
		(end 133.26237 -98.80346)
		(stroke
			(width 0.2)
			(type default)
		)
		(layer "In1.Cu")
	)
	(gr_line
		(start 133.46557 -98.24466)
		(end 133.26237 -98.24466)
		(stroke
			(width 0.2)
			(type default)
		)
		(layer "In1.Cu")
	)
	(gr_arc
		(start 133.584442 -84.783422)
		(mid 133.694001 -84.738041)
		(end 133.739382 -84.628482)
		(stroke
			(width 0.2)
			(type default)
		)
		(layer "In1.Cu")
	)
	(gr_line
		(start 133.584442 -84.270342)
		(end 133.330442 -84.270342)
		(stroke
			(width 0.2)
			(type default)
		)
		(layer "In1.Cu")
	)
	(gr_arc
		(start 133.584442 -84.148422)
		(mid 133.694001 -84.103041)
		(end 133.739382 -83.993482)
		(stroke
			(width 0.2)
			(type default)
		)
		(layer "In1.Cu")
	)
	(gr_line
		(start 133.584442 -83.635342)
		(end 133.330442 -83.635342)
		(stroke
			(width 0.2)
			(type default)
		)
		(layer "In1.Cu")
	)
	(gr_line
		(start 133.62051 -99.2124)
		(end 133.62051 -98.9584)
		(stroke
			(width 0.2)
			(type default)
		)
		(layer "In1.Cu")
	)
	(gr_arc
		(start 133.62051 -98.9584)
		(mid 133.575129 -98.848841)
		(end 133.46557 -98.80346)
		(stroke
			(width 0.2)
			(type default)
		)
		(layer "In1.Cu")
	)
	(gr_line
		(start 133.62051 -98.6536)
		(end 133.62051 -98.3996)
		(stroke
			(width 0.2)
			(type default)
		)
		(layer "In1.Cu")
	)
	(gr_arc
		(start 133.62051 -98.3996)
		(mid 133.575129 -98.290041)
		(end 133.46557 -98.24466)
		(stroke
			(width 0.2)
			(type default)
		)
		(layer "In1.Cu")
	)
	(gr_arc
		(start 133.734302 -84.628482)
		(mid 133.779683 -84.738041)
		(end 133.889242 -84.783422)
		(stroke
			(width 0.2)
			(type default)
		)
		(layer "In1.Cu")
	)
	(gr_line
		(start 133.734302 -84.425282)
		(end 133.734302 -84.628482)
		(stroke
			(width 0.2)
			(type default)
		)
		(layer "In1.Cu")
	)
	(gr_arc
		(start 133.734302 -83.993482)
		(mid 133.779683 -84.103041)
		(end 133.889242 -84.148422)
		(stroke
			(width 0.2)
			(type default)
		)
		(layer "In1.Cu")
	)
	(gr_line
		(start 133.734302 -83.790282)
		(end 133.734302 -83.993482)
		(stroke
			(width 0.2)
			(type default)
		)
		(layer "In1.Cu")
	)
	(gr_line
		(start 133.739382 -84.628482)
		(end 133.739382 -84.425282)
		(stroke
			(width 0.2)
			(type default)
		)
		(layer "In1.Cu")
	)
	(gr_arc
		(start 133.739382 -84.425282)
		(mid 133.694001 -84.315723)
		(end 133.584442 -84.270342)
		(stroke
			(width 0.2)
			(type default)
		)
		(layer "In1.Cu")
	)
	(gr_line
		(start 133.739382 -83.993482)
		(end 133.739382 -83.790282)
		(stroke
			(width 0.2)
			(type default)
		)
		(layer "In1.Cu")
	)
	(gr_arc
		(start 133.739382 -83.790282)
		(mid 133.694001 -83.680723)
		(end 133.584442 -83.635342)
		(stroke
			(width 0.2)
			(type default)
		)
		(layer "In1.Cu")
	)
	(gr_arc
		(start 133.858254 -81.500726)
		(mid 134.242048 -81.117313)
		(end 133.858508 -80.733646)
		(stroke
			(width 0.2)
			(type default)
		)
		(layer "In1.Cu")
	)
	(gr_line
		(start 133.858508 -80.733646)
		(end 132.930392 -80.733646)
		(stroke
			(width 0.2)
			(type default)
		)
		(layer "In1.Cu")
	)
	(gr_line
		(start 133.889242 -84.783422)
		(end 134.143242 -84.783422)
		(stroke
			(width 0.2)
			(type default)
		)
		(layer "In1.Cu")
	)
	(gr_arc
		(start 133.889242 -84.270342)
		(mid 133.779683 -84.315723)
		(end 133.734302 -84.425282)
		(stroke
			(width 0.2)
			(type default)
		)
		(layer "In1.Cu")
	)
	(gr_line
		(start 133.889242 -84.148422)
		(end 134.143242 -84.148422)
		(stroke
			(width 0.2)
			(type default)
		)
		(layer "In1.Cu")
	)
	(gr_arc
		(start 133.889242 -83.635342)
		(mid 133.779683 -83.680723)
		(end 133.734302 -83.790282)
		(stroke
			(width 0.2)
			(type default)
		)
		(layer "In1.Cu")
	)
	(gr_line
		(start 134.11454 -90.559128)
		(end 134.11454 -89.654126)
		(stroke
			(width 0.2)
			(type default)
		)
		(layer "In1.Cu")
	)
	(gr_arc
		(start 134.11454 -89.654126)
		(mid 133.731 -89.270586)
		(end 133.34746 -89.654126)
		(stroke
			(width 0.2)
			(type default)
		)
		(layer "In1.Cu")
	)
	(gr_line
		(start 134.11454 -88.019128)
		(end 134.11454 -87.11438)
		(stroke
			(width 0.2)
			(type default)
		)
		(layer "In1.Cu")
	)
	(gr_arc
		(start 134.11454 -87.11438)
		(mid 133.731127 -86.730586)
		(end 133.34746 -87.114126)
		(stroke
			(width 0.2)
			(type default)
		)
		(layer "In1.Cu")
	)
	(gr_arc
		(start 134.143242 -84.783422)
		(mid 134.252801 -84.738041)
		(end 134.298182 -84.628482)
		(stroke
			(width 0.2)
			(type default)
		)
		(layer "In1.Cu")
	)
	(gr_line
		(start 134.143242 -84.270342)
		(end 133.889242 -84.270342)
		(stroke
			(width 0.2)
			(type default)
		)
		(layer "In1.Cu")
	)
	(gr_arc
		(start 134.143242 -84.148422)
		(mid 134.252801 -84.103041)
		(end 134.298182 -83.993482)
		(stroke
			(width 0.2)
			(type default)
		)
		(layer "In1.Cu")
	)
	(gr_line
		(start 134.143242 -83.635342)
		(end 133.889242 -83.635342)
		(stroke
			(width 0.2)
			(type default)
		)
		(layer "In1.Cu")
	)
	(gr_arc
		(start 134.25043 -99.2124)
		(mid 134.295811 -99.321959)
		(end 134.40537 -99.36734)
		(stroke
			(width 0.2)
			(type default)
		)
		(layer "In1.Cu")
	)
	(gr_line
		(start 134.25043 -98.9584)
		(end 134.25043 -99.2124)
		(stroke
			(width 0.2)
			(type default)
		)
		(layer "In1.Cu")
	)
	(gr_arc
		(start 134.25043 -98.6536)
		(mid 134.295811 -98.763159)
		(end 134.40537 -98.80854)
		(stroke
			(width 0.2)
			(type default)
		)
		(layer "In1.Cu")
	)
	(gr_line
		(start 134.25043 -98.3996)
		(end 134.25043 -98.6536)
		(stroke
			(width 0.2)
			(type default)
		)
		(layer "In1.Cu")
	)
	(gr_line
		(start 134.298182 -84.628482)
		(end 134.298182 -84.425282)
		(stroke
			(width 0.2)
			(type default)
		)
		(layer "In1.Cu")
	)
	(gr_arc
		(start 134.298182 -84.425282)
		(mid 134.252801 -84.315723)
		(end 134.143242 -84.270342)
		(stroke
			(width 0.2)
			(type default)
		)
		(layer "In1.Cu")
	)
	(gr_line
		(start 134.298182 -83.993482)
		(end 134.298182 -83.790282)
		(stroke
			(width 0.2)
			(type default)
		)
		(layer "In1.Cu")
	)
	(gr_arc
		(start 134.298182 -83.790282)
		(mid 134.252801 -83.680723)
		(end 134.143242 -83.635342)
		(stroke
			(width 0.2)
			(type default)
		)
		(layer "In1.Cu")
	)
	(gr_line
		(start 134.40537 -99.36734)
		(end 134.60857 -99.36734)
		(stroke
			(width 0.2)
			(type default)
		)
		(layer "In1.Cu")
	)
	(gr_line
		(start 134.40537 -98.80854)
		(end 134.60857 -98.80854)
		(stroke
			(width 0.2)
			(type default)
		)
		(layer "In1.Cu")
	)
	(gr_arc
		(start 134.40537 -98.80346)
		(mid 134.295811 -98.848841)
		(end 134.25043 -98.9584)
		(stroke
			(width 0.2)
			(type default)
		)
		(layer "In1.Cu")
	)
	(gr_arc
		(start 134.40537 -98.24466)
		(mid 134.295811 -98.290041)
		(end 134.25043 -98.3996)
		(stroke
			(width 0.2)
			(type default)
		)
		(layer "In1.Cu")
	)
	(gr_line
		(start 134.581392 -83.06054)
		(end 135.509508 -83.06054)
		(stroke
			(width 0.2)
			(type default)
		)
		(layer "In1.Cu")
	)
	(gr_arc
		(start 134.581646 -82.29346)
		(mid 134.197852 -82.676873)
		(end 134.581392 -83.06054)
		(stroke
			(width 0.2)
			(type default)
		)
		(layer "In1.Cu")
	)
	(gr_arc
		(start 134.60857 -99.36734)
		(mid 134.718129 -99.321959)
		(end 134.76351 -99.2124)
		(stroke
			(width 0.2)
			(type default)
		)
		(layer "In1.Cu")
	)
	(gr_arc
		(start 134.60857 -98.80854)
		(mid 134.718129 -98.763159)
		(end 134.76351 -98.6536)
		(stroke
			(width 0.2)
			(type default)
		)
		(layer "In1.Cu")
	)
	(gr_line
		(start 134.60857 -98.80346)
		(end 134.40537 -98.80346)
		(stroke
			(width 0.2)
			(type default)
		)
		(layer "In1.Cu")
	)
	(gr_line
		(start 134.60857 -98.24466)
		(end 134.40537 -98.24466)
		(stroke
			(width 0.2)
			(type default)
		)
		(layer "In1.Cu")
	)
	(gr_line
		(start 134.76351 -99.2124)
		(end 134.76351 -98.9584)
		(stroke
			(width 0.2)
			(type default)
		)
		(layer "In1.Cu")
	)
	(gr_arc
		(start 134.76351 -98.9584)
		(mid 134.718129 -98.848841)
		(end 134.60857 -98.80346)
		(stroke
			(width 0.2)
			(type default)
		)
		(layer "In1.Cu")
	)
	(gr_line
		(start 134.76351 -98.6536)
		(end 134.76351 -98.3996)
		(stroke
			(width 0.2)
			(type default)
		)
		(layer "In1.Cu")
	)
	(gr_arc
		(start 134.76351 -98.3996)
		(mid 134.718129 -98.290041)
		(end 134.60857 -98.24466)
		(stroke
			(width 0.2)
			(type default)
		)
		(layer "In1.Cu")
	)
	(gr_arc
		(start 134.88543 -99.2124)
		(mid 134.930811 -99.321959)
		(end 135.04037 -99.36734)
		(stroke
			(width 0.2)
			(type default)
		)
		(layer "In1.Cu")
	)
	(gr_line
		(start 134.88543 -98.9584)
		(end 134.88543 -99.2124)
		(stroke
			(width 0.2)
			(type default)
		)
		(layer "In1.Cu")
	)
	(gr_arc
		(start 134.88543 -98.6536)
		(mid 134.930811 -98.763159)
		(end 135.04037 -98.80854)
		(stroke
			(width 0.2)
			(type default)
		)
		(layer "In1.Cu")
	)
	(gr_line
		(start 134.88543 -98.3996)
		(end 134.88543 -98.6536)
		(stroke
			(width 0.2)
			(type default)
		)
		(layer "In1.Cu")
	)
	(gr_line
		(start 135.04037 -99.36734)
		(end 135.24357 -99.36734)
		(stroke
			(width 0.2)
			(type default)
		)
		(layer "In1.Cu")
	)
	(gr_line
		(start 135.04037 -98.80854)
		(end 135.24357 -98.80854)
		(stroke
			(width 0.2)
			(type default)
		)
		(layer "In1.Cu")
	)
	(gr_arc
		(start 135.04037 -98.80346)
		(mid 134.930811 -98.848841)
		(end 134.88543 -98.9584)
		(stroke
			(width 0.2)
			(type default)
		)
		(layer "In1.Cu")
	)
	(gr_arc
		(start 135.04037 -98.24466)
		(mid 134.930811 -98.290041)
		(end 134.88543 -98.3996)
		(stroke
			(width 0.2)
			(type default)
		)
		(layer "In1.Cu")
	)
	(gr_arc
		(start 135.24357 -99.36734)
		(mid 135.353129 -99.321959)
		(end 135.39851 -99.2124)
		(stroke
			(width 0.2)
			(type default)
		)
		(layer "In1.Cu")
	)
	(gr_arc
		(start 135.24357 -98.80854)
		(mid 135.353129 -98.763159)
		(end 135.39851 -98.6536)
		(stroke
			(width 0.2)
			(type default)
		)
		(layer "In1.Cu")
	)
	(gr_line
		(start 135.24357 -98.80346)
		(end 135.04037 -98.80346)
		(stroke
			(width 0.2)
			(type default)
		)
		(layer "In1.Cu")
	)
	(gr_line
		(start 135.24357 -98.24466)
		(end 135.04037 -98.24466)
		(stroke
			(width 0.2)
			(type default)
		)
		(layer "In1.Cu")
	)
	(gr_line
		(start 135.39851 -99.2124)
		(end 135.39851 -98.9584)
		(stroke
			(width 0.2)
			(type default)
		)
		(layer "In1.Cu")
	)
	(gr_arc
		(start 135.39851 -98.9584)
		(mid 135.353129 -98.848841)
		(end 135.24357 -98.80346)
		(stroke
			(width 0.2)
			(type default)
		)
		(layer "In1.Cu")
	)
	(gr_line
		(start 135.39851 -98.6536)
		(end 135.39851 -98.3996)
		(stroke
			(width 0.2)
			(type default)
		)
		(layer "In1.Cu")
	)
	(gr_arc
		(start 135.39851 -98.3996)
		(mid 135.353129 -98.290041)
		(end 135.24357 -98.24466)
		(stroke
			(width 0.2)
			(type default)
		)
		(layer "In1.Cu")
	)
	(gr_arc
		(start 135.509508 -83.06054)
		(mid 135.893048 -82.677)
		(end 135.509508 -82.29346)
		(stroke
			(width 0.2)
			(type default)
		)
		(layer "In1.Cu")
	)
	(gr_line
		(start 135.509508 -82.29346)
		(end 134.581646 -82.29346)
		(stroke
			(width 0.2)
			(type default)
		)
		(layer "In1.Cu")
	)
	(gr_line
		(start 135.87984 -81.91754)
		(end 136.807956 -81.91754)
		(stroke
			(width 0.2)
			(type default)
		)
		(layer "In1.Cu")
	)
	(gr_arc
		(start 135.880094 -81.15046)
		(mid 135.4963 -81.533873)
		(end 135.87984 -81.91754)
		(stroke
			(width 0.2)
			(type default)
		)
		(layer "In1.Cu")
	)
	(gr_arc
		(start 136.01446 -99.2124)
		(mid 136.059841 -99.321959)
		(end 136.1694 -99.36734)
		(stroke
			(width 0.2)
			(type default)
		)
		(layer "In1.Cu")
	)
	(gr_line
		(start 136.01446 -98.9584)
		(end 136.01446 -99.2124)
		(stroke
			(width 0.2)
			(type default)
		)
		(layer "In1.Cu")
	)
	(gr_arc
		(start 136.01446 -98.6536)
		(mid 136.059841 -98.763159)
		(end 136.1694 -98.80854)
		(stroke
			(width 0.2)
			(type default)
		)
		(layer "In1.Cu")
	)
	(gr_line
		(start 136.01446 -98.3996)
		(end 136.01446 -98.6536)
		(stroke
			(width 0.2)
			(type default)
		)
		(layer "In1.Cu")
	)
	(gr_line
		(start 136.1694 -99.36734)
		(end 136.3726 -99.36734)
		(stroke
			(width 0.2)
			(type default)
		)
		(layer "In1.Cu")
	)
	(gr_line
		(start 136.1694 -98.80854)
		(end 136.3726 -98.80854)
		(stroke
			(width 0.2)
			(type default)
		)
		(layer "In1.Cu")
	)
	(gr_arc
		(start 136.1694 -98.80346)
		(mid 136.059841 -98.848841)
		(end 136.01446 -98.9584)
		(stroke
			(width 0.2)
			(type default)
		)
		(layer "In1.Cu")
	)
	(gr_arc
		(start 136.1694 -98.24466)
		(mid 136.059841 -98.290041)
		(end 136.01446 -98.3996)
		(stroke
			(width 0.2)
			(type default)
		)
		(layer "In1.Cu")
	)
	(gr_arc
		(start 136.3726 -99.36734)
		(mid 136.482159 -99.321959)
		(end 136.52754 -99.2124)
		(stroke
			(width 0.2)
			(type default)
		)
		(layer "In1.Cu")
	)
	(gr_arc
		(start 136.3726 -98.80854)
		(mid 136.482159 -98.763159)
		(end 136.52754 -98.6536)
		(stroke
			(width 0.2)
			(type default)
		)
		(layer "In1.Cu")
	)
	(gr_line
		(start 136.3726 -98.80346)
		(end 136.1694 -98.80346)
		(stroke
			(width 0.2)
			(type default)
		)
		(layer "In1.Cu")
	)
	(gr_line
		(start 136.3726 -98.24466)
		(end 136.1694 -98.24466)
		(stroke
			(width 0.2)
			(type default)
		)
		(layer "In1.Cu")
	)
	(gr_line
		(start 136.52754 -99.2124)
		(end 136.52754 -98.9584)
		(stroke
			(width 0.2)
			(type default)
		)
		(layer "In1.Cu")
	)
	(gr_arc
		(start 136.52754 -98.9584)
		(mid 136.482159 -98.848841)
		(end 136.3726 -98.80346)
		(stroke
			(width 0.2)
			(type default)
		)
		(layer "In1.Cu")
	)
	(gr_line
		(start 136.52754 -98.6536)
		(end 136.52754 -98.3996)
		(stroke
			(width 0.2)
			(type default)
		)
		(layer "In1.Cu")
	)
	(gr_arc
		(start 136.52754 -98.3996)
		(mid 136.482159 -98.290041)
		(end 136.3726 -98.24466)
		(stroke
			(width 0.2)
			(type default)
		)
		(layer "In1.Cu")
	)
	(gr_arc
		(start 136.64946 -99.2124)
		(mid 136.694841 -99.321959)
		(end 136.8044 -99.36734)
		(stroke
			(width 0.2)
			(type default)
		)
		(layer "In1.Cu")
	)
	(gr_line
		(start 136.64946 -98.9584)
		(end 136.64946 -99.2124)
		(stroke
			(width 0.2)
			(type default)
		)
		(layer "In1.Cu")
	)
	(gr_arc
		(start 136.64946 -98.6536)
		(mid 136.694841 -98.763159)
		(end 136.8044 -98.80854)
		(stroke
			(width 0.2)
			(type default)
		)
		(layer "In1.Cu")
	)
	(gr_line
		(start 136.64946 -98.3996)
		(end 136.64946 -98.6536)
		(stroke
			(width 0.2)
			(type default)
		)
		(layer "In1.Cu")
	)
	(gr_line
		(start 136.8044 -99.36734)
		(end 137.0076 -99.36734)
		(stroke
			(width 0.2)
			(type default)
		)
		(layer "In1.Cu")
	)
	(gr_line
		(start 136.8044 -98.80854)
		(end 137.0076 -98.80854)
		(stroke
			(width 0.2)
			(type default)
		)
		(layer "In1.Cu")
	)
	(gr_arc
		(start 136.8044 -98.80346)
		(mid 136.694841 -98.848841)
		(end 136.64946 -98.9584)
		(stroke
			(width 0.2)
			(type default)
		)
		(layer "In1.Cu")
	)
	(gr_arc
		(start 136.8044 -98.24466)
		(mid 136.694841 -98.290041)
		(end 136.64946 -98.3996)
		(stroke
			(width 0.2)
			(type default)
		)
		(layer "In1.Cu")
	)
	(gr_arc
		(start 136.807956 -81.91754)
		(mid 137.191496 -81.534)
		(end 136.807956 -81.15046)
		(stroke
			(width 0.2)
			(type default)
		)
		(layer "In1.Cu")
	)
	(gr_line
		(start 136.807956 -81.15046)
		(end 135.880094 -81.15046)
		(stroke
			(width 0.2)
			(type default)
		)
		(layer "In1.Cu")
	)
	(gr_arc
		(start 137.0076 -99.36734)
		(mid 137.117159 -99.321959)
		(end 137.16254 -99.2124)
		(stroke
			(width 0.2)
			(type default)
		)
		(layer "In1.Cu")
	)
	(gr_arc
		(start 137.0076 -98.80854)
		(mid 137.117159 -98.763159)
		(end 137.16254 -98.6536)
		(stroke
			(width 0.2)
			(type default)
		)
		(layer "In1.Cu")
	)
	(gr_line
		(start 137.0076 -98.80346)
		(end 136.8044 -98.80346)
		(stroke
			(width 0.2)
			(type default)
		)
		(layer "In1.Cu")
	)
	(gr_line
		(start 137.0076 -98.24466)
		(end 136.8044 -98.24466)
		(stroke
			(width 0.2)
			(type default)
		)
		(layer "In1.Cu")
	)
	(gr_line
		(start 137.16254 -99.2124)
		(end 137.16254 -98.9584)
		(stroke
			(width 0.2)
			(type default)
		)
		(layer "In1.Cu")
	)
	(gr_arc
		(start 137.16254 -98.9584)
		(mid 137.117159 -98.848841)
		(end 137.0076 -98.80346)
		(stroke
			(width 0.2)
			(type default)
		)
		(layer "In1.Cu")
	)
	(gr_line
		(start 137.16254 -98.6536)
		(end 137.16254 -98.3996)
		(stroke
			(width 0.2)
			(type default)
		)
		(layer "In1.Cu")
	)
	(gr_arc
		(start 137.16254 -98.3996)
		(mid 137.117159 -98.290041)
		(end 137.0076 -98.24466)
		(stroke
			(width 0.2)
			(type default)
		)
		(layer "In1.Cu")
	)
	(gr_line
		(start 138.549888 -258.59994)
		(end 67.349878 -258.59994)
		(stroke
			(width 5.08)
			(type default)
		)
		(layer "In1.Cu")
	)
	(gr_line
		(start 138.549888 -252.549914)
		(end 138.549888 -258.59994)
		(stroke
			(width 1.524)
			(type default)
		)
		(layer "In1.Cu")
	)
	(gr_line
		(start 140.450062 -258.59994)
		(end 140.450062 -252.549914)
		(stroke
			(width 1.524)
			(type default)
		)
		(layer "In1.Cu")
	)
	(gr_arc
		(start 140.450062 -252.549914)
		(mid 139.500102 -251.599954)
		(end 138.549888 -252.549914)
		(stroke
			(width 1.524)
			(type default)
		)
		(layer "In1.Cu")
	)
	(gr_line
		(start 151.649938 -258.59994)
		(end 140.450062 -258.59994)
		(stroke
			(width 5.08)
			(type default)
		)
		(layer "In1.Cu")
	)
	(gr_line
		(start 151.649938 -252.000004)
		(end 151.649938 -258.59994)
		(stroke
			(width 1.524)
			(type default)
		)
		(layer "In1.Cu")
	)
	(gr_arc
		(start 152.649936 -251.000006)
		(mid 151.942831 -251.292899)
		(end 151.649938 -252.000004)
		(stroke
			(width 1.524)
			(type default)
		)
		(layer "In1.Cu")
	)
	(gr_line
		(start 155.946348 -77.40904)
		(end 156.928312 -77.40904)
		(stroke
			(width 0.2)
			(type default)
		)
		(layer "In1.Cu")
	)
	(gr_arc
		(start 155.946602 -76.64196)
		(mid 155.562808 -77.025373)
		(end 155.946348 -77.40904)
		(stroke
			(width 0.2)
			(type default)
		)
		(layer "In1.Cu")
	)
	(gr_arc
		(start 156.928312 -77.40904)
		(mid 157.311852 -77.0255)
		(end 156.928312 -76.64196)
		(stroke
			(width 0.2)
			(type default)
		)
		(layer "In1.Cu")
	)
	(gr_line
		(start 156.928312 -76.64196)
		(end 155.946602 -76.64196)
		(stroke
			(width 0.2)
			(type default)
		)
		(layer "In1.Cu")
	)
	(gr_line
		(start 159.946848 -77.40904)
		(end 160.928812 -77.40904)
		(stroke
			(width 0.2)
			(type default)
		)
		(layer "In1.Cu")
	)
	(gr_arc
		(start 159.947102 -76.64196)
		(mid 159.563308 -77.025373)
		(end 159.946848 -77.40904)
		(stroke
			(width 0.2)
			(type default)
		)
		(layer "In1.Cu")
	)
	(gr_arc
		(start 160.928812 -77.40904)
		(mid 161.312352 -77.0255)
		(end 160.928812 -76.64196)
		(stroke
			(width 0.2)
			(type default)
		)
		(layer "In1.Cu")
	)
	(gr_line
		(start 160.928812 -76.64196)
		(end 159.947102 -76.64196)
		(stroke
			(width 0.2)
			(type default)
		)
		(layer "In1.Cu")
	)
	(gr_line
		(start 163.946078 -77.40904)
		(end 164.928042 -77.40904)
		(stroke
			(width 0.2)
			(type default)
		)
		(layer "In1.Cu")
	)
	(gr_arc
		(start 163.946332 -76.64196)
		(mid 163.562538 -77.025373)
		(end 163.946078 -77.40904)
		(stroke
			(width 0.2)
			(type default)
		)
		(layer "In1.Cu")
	)
	(gr_arc
		(start 164.928042 -77.40904)
		(mid 165.311582 -77.0255)
		(end 164.928042 -76.64196)
		(stroke
			(width 0.2)
			(type default)
		)
		(layer "In1.Cu")
	)
	(gr_line
		(start 164.928042 -76.64196)
		(end 163.946332 -76.64196)
		(stroke
			(width 0.2)
			(type default)
		)
		(layer "In1.Cu")
	)
	(gr_line
		(start 167.946578 -77.40904)
		(end 168.928542 -77.40904)
		(stroke
			(width 0.2)
			(type default)
		)
		(layer "In1.Cu")
	)
	(gr_arc
		(start 167.946832 -76.64196)
		(mid 167.563038 -77.025373)
		(end 167.946578 -77.40904)
		(stroke
			(width 0.2)
			(type default)
		)
		(layer "In1.Cu")
	)
	(gr_arc
		(start 168.928542 -77.40904)
		(mid 169.312082 -77.0255)
		(end 168.928542 -76.64196)
		(stroke
			(width 0.2)
			(type default)
		)
		(layer "In1.Cu")
	)
	(gr_line
		(start 168.928542 -76.64196)
		(end 167.946832 -76.64196)
		(stroke
			(width 0.2)
			(type default)
		)
		(layer "In1.Cu")
	)
	(gr_line
		(start 181.150006 -251.000006)
		(end 152.649936 -251.000006)
		(stroke
			(width 1.524)
			(type default)
		)
		(layer "In1.Cu")
	)
	(gr_line
		(start 182.150004 -258.59994)
		(end 182.150004 -252.000004)
		(stroke
			(width 1.524)
			(type default)
		)
		(layer "In1.Cu")
	)
	(gr_arc
		(start 182.150004 -252.000004)
		(mid 181.857111 -251.292899)
		(end 181.150006 -251.000006)
		(stroke
			(width 1.524)
			(type default)
		)
		(layer "In1.Cu")
	)
	(gr_line
		(start 189.349888 -258.59994)
		(end 182.150004 -258.59994)
		(stroke
			(width 5.08)
			(type default)
		)
		(layer "In1.Cu")
	)
	(gr_line
		(start 189.349888 -252.549914)
		(end 189.349888 -258.59994)
		(stroke
			(width 1.524)
			(type default)
		)
		(layer "In1.Cu")
	)
	(gr_line
		(start 191.250062 -258.59994)
		(end 191.250062 -252.549914)
		(stroke
			(width 1.524)
			(type default)
		)
		(layer "In1.Cu")
	)
	(gr_arc
		(start 191.250062 -252.549914)
		(mid 190.300102 -251.599954)
		(end 189.349888 -252.549914)
		(stroke
			(width 1.524)
			(type default)
		)
		(layer "In1.Cu")
	)
	(gr_line
		(start 191.947038 -77.40904)
		(end 192.928748 -77.40904)
		(stroke
			(width 0.2)
			(type default)
		)
		(layer "In1.Cu")
	)
	(gr_arc
		(start 191.947038 -76.64196)
		(mid 191.563498 -77.0255)
		(end 191.947038 -77.40904)
		(stroke
			(width 0.2)
			(type default)
		)
		(layer "In1.Cu")
	)
	(gr_arc
		(start 192.928748 -77.40904)
		(mid 193.312542 -77.025627)
		(end 192.929002 -76.64196)
		(stroke
			(width 0.2)
			(type default)
		)
		(layer "In1.Cu")
	)
	(gr_line
		(start 192.929002 -76.64196)
		(end 191.947038 -76.64196)
		(stroke
			(width 0.2)
			(type default)
		)
		(layer "In1.Cu")
	)
	(gr_line
		(start 195.947538 -77.40904)
		(end 196.929502 -77.40904)
		(stroke
			(width 0.2)
			(type default)
		)
		(layer "In1.Cu")
	)
	(gr_arc
		(start 195.947792 -76.64196)
		(mid 195.563998 -77.025373)
		(end 195.947538 -77.40904)
		(stroke
			(width 0.2)
			(type default)
		)
		(layer "In1.Cu")
	)
	(gr_arc
		(start 196.929502 -77.40904)
		(mid 197.313042 -77.0255)
		(end 196.929502 -76.64196)
		(stroke
			(width 0.2)
			(type default)
		)
		(layer "In1.Cu")
	)
	(gr_line
		(start 196.929502 -76.64196)
		(end 195.947792 -76.64196)
		(stroke
			(width 0.2)
			(type default)
		)
		(layer "In1.Cu")
	)
	(gr_line
		(start 199.946768 -77.40904)
		(end 200.928478 -77.40904)
		(stroke
			(width 0.2)
			(type default)
		)
		(layer "In1.Cu")
	)
	(gr_arc
		(start 199.946768 -76.64196)
		(mid 199.563228 -77.0255)
		(end 199.946768 -77.40904)
		(stroke
			(width 0.2)
			(type default)
		)
		(layer "In1.Cu")
	)
	(gr_arc
		(start 200.928478 -77.40904)
		(mid 201.312272 -77.025627)
		(end 200.928732 -76.64196)
		(stroke
			(width 0.2)
			(type default)
		)
		(layer "In1.Cu")
	)
	(gr_line
		(start 200.928732 -76.64196)
		(end 199.946768 -76.64196)
		(stroke
			(width 0.2)
			(type default)
		)
		(layer "In1.Cu")
	)
	(gr_line
		(start 202.449938 -258.59994)
		(end 191.250062 -258.59994)
		(stroke
			(width 5.08)
			(type default)
		)
		(layer "In1.Cu")
	)
	(gr_line
		(start 202.449938 -252.000004)
		(end 202.449938 -258.59994)
		(stroke
			(width 1.524)
			(type default)
		)
		(layer "In1.Cu")
	)
	(gr_arc
		(start 203.449936 -251.000006)
		(mid 202.742831 -251.292899)
		(end 202.449938 -252.000004)
		(stroke
			(width 1.524)
			(type default)
		)
		(layer "In1.Cu")
	)
	(gr_line
		(start 203.947268 -77.40904)
		(end 204.929232 -77.40904)
		(stroke
			(width 0.2)
			(type default)
		)
		(layer "In1.Cu")
	)
	(gr_arc
		(start 203.947522 -76.64196)
		(mid 203.563728 -77.025373)
		(end 203.947268 -77.40904)
		(stroke
			(width 0.2)
			(type default)
		)
		(layer "In1.Cu")
	)
	(gr_arc
		(start 204.929232 -77.40904)
		(mid 205.312772 -77.0255)
		(end 204.929232 -76.64196)
		(stroke
			(width 0.2)
			(type default)
		)
		(layer "In1.Cu")
	)
	(gr_line
		(start 204.929232 -76.64196)
		(end 203.947522 -76.64196)
		(stroke
			(width 0.2)
			(type default)
		)
		(layer "In1.Cu")
	)
	(gr_line
		(start 229.14991 -251.000006)
		(end 203.449936 -251.000006)
		(stroke
			(width 1.524)
			(type default)
		)
		(layer "In1.Cu")
	)
	(gr_arc
		(start 229.14991 -251.000006)
		(mid 232.685436 -249.53554)
		(end 234.1499 -246.000016)
		(stroke
			(width 1.524)
			(type default)
		)
		(layer "In1.Cu")
	)
	(gr_line
		(start 234.1499 -197.000114)
		(end 234.1499 -246.000016)
		(stroke
			(width 1.524)
			(type default)
		)
		(layer "In1.Cu")
	)
	(gr_arc
		(start 235.149898 -196.000116)
		(mid 234.442793 -196.293009)
		(end 234.1499 -197.000114)
		(stroke
			(width 1.524)
			(type default)
		)
		(layer "In1.Cu")
	)
	(gr_line
		(start 250.150122 -196.000116)
		(end 235.149898 -196.000116)
		(stroke
			(width 1.524)
			(type default)
		)
		(layer "In1.Cu")
	)
	(gr_line
		(start 251.15012 -246.000016)
		(end 251.15012 -197.000114)
		(stroke
			(width 1.524)
			(type default)
		)
		(layer "In1.Cu")
	)
	(gr_arc
		(start 251.15012 -246.000016)
		(mid 252.614589 -249.535529)
		(end 256.15011 -251.000006)
		(stroke
			(width 1.524)
			(type default)
		)
		(layer "In1.Cu")
	)
	(gr_arc
		(start 251.15012 -197.000114)
		(mid 250.857227 -196.293009)
		(end 250.150122 -196.000116)
		(stroke
			(width 1.524)
			(type default)
		)
		(layer "In1.Cu")
	)
	(gr_line
		(start 270.999966 -11.779758)
		(end 272.999962 -11.779758)
		(stroke
			(width 0.2)
			(type default)
		)
		(layer "In1.Cu")
	)
	(gr_arc
		(start 270.999966 -10.199878)
		(mid 270.210026 -10.989818)
		(end 270.999966 -11.779758)
		(stroke
			(width 0.2)
			(type default)
		)
		(layer "In1.Cu")
	)
	(gr_arc
		(start 272.999962 -11.779758)
		(mid 273.789902 -10.989818)
		(end 272.999962 -10.199878)
		(stroke
			(width 0.2)
			(type default)
		)
		(layer "In1.Cu")
	)
	(gr_line
		(start 272.999962 -10.199878)
		(end 270.999966 -10.199878)
		(stroke
			(width 0.2)
			(type default)
		)
		(layer "In1.Cu")
	)
	(gr_rect
		(start 276.441154 -26.068528)
		(end 277.309834 -27.191208)
		(stroke
			(width 0)
			(type default)
		)
		(fill no)
		(layer "In1.Cu")
	)
	(gr_rect
		(start 276.441154 -24.392128)
		(end 277.309834 -25.514808)
		(stroke
			(width 0)
			(type default)
		)
		(fill no)
		(layer "In1.Cu")
	)
	(gr_arc
		(start 276.466554 -26.401268)
		(mid 276.526814 -26.546748)
		(end 276.672294 -26.607008)
		(stroke
			(width 0.2)
			(type default)
		)
		(layer "In1.Cu")
	)
	(gr_line
		(start 276.466554 -26.045668)
		(end 276.466554 -26.401268)
		(stroke
			(width 0.2)
			(type default)
		)
		(layer "In1.Cu")
	)
	(gr_arc
		(start 276.466554 -25.537668)
		(mid 276.526814 -25.683148)
		(end 276.672294 -25.743408)
		(stroke
			(width 0.2)
			(type default)
		)
		(layer "In1.Cu")
	)
	(gr_line
		(start 276.466554 -25.182068)
		(end 276.466554 -25.537668)
		(stroke
			(width 0.2)
			(type default)
		)
		(layer "In1.Cu")
	)
	(gr_line
		(start 276.672294 -26.607008)
		(end 277.027894 -26.607008)
		(stroke
			(width 0.2)
			(type default)
		)
		(layer "In1.Cu")
	)
	(gr_arc
		(start 276.672294 -25.839928)
		(mid 276.526814 -25.900188)
		(end 276.466554 -26.045668)
		(stroke
			(width 0.2)
			(type default)
		)
		(layer "In1.Cu")
	)
	(gr_line
		(start 276.672294 -25.743408)
		(end 277.027894 -25.743408)
		(stroke
			(width 0.2)
			(type default)
		)
		(layer "In1.Cu")
	)
	(gr_arc
		(start 276.672294 -24.976328)
		(mid 276.526814 -25.036588)
		(end 276.466554 -25.182068)
		(stroke
			(width 0.2)
			(type default)
		)
		(layer "In1.Cu")
	)
	(gr_line
		(start 276.867112 -32.51454)
		(end 277.848822 -32.51454)
		(stroke
			(width 0.2)
			(type default)
		)
		(layer "In1.Cu")
	)
	(gr_arc
		(start 276.867112 -31.74746)
		(mid 276.483572 -32.131)
		(end 276.867112 -32.51454)
		(stroke
			(width 0.2)
			(type default)
		)
		(layer "In1.Cu")
	)
	(gr_arc
		(start 277.027894 -26.607008)
		(mid 277.173374 -26.546748)
		(end 277.233634 -26.401268)
		(stroke
			(width 0.2)
			(type default)
		)
		(layer "In1.Cu")
	)
	(gr_line
		(start 277.027894 -25.839928)
		(end 276.672294 -25.839928)
		(stroke
			(width 0.2)
			(type default)
		)
		(layer "In1.Cu")
	)
	(gr_arc
		(start 277.027894 -25.743408)
		(mid 277.173374 -25.683148)
		(end 277.233634 -25.537668)
		(stroke
			(width 0.2)
			(type default)
		)
		(layer "In1.Cu")
	)
	(gr_line
		(start 277.027894 -24.976328)
		(end 276.672294 -24.976328)
		(stroke
			(width 0.2)
			(type default)
		)
		(layer "In1.Cu")
	)
	(gr_line
		(start 277.233634 -26.401268)
		(end 277.233634 -26.045668)
		(stroke
			(width 0.2)
			(type default)
		)
		(layer "In1.Cu")
	)
	(gr_arc
		(start 277.233634 -26.045668)
		(mid 277.173374 -25.900188)
		(end 277.027894 -25.839928)
		(stroke
			(width 0.2)
			(type default)
		)
		(layer "In1.Cu")
	)
	(gr_line
		(start 277.233634 -25.537668)
		(end 277.233634 -25.182068)
		(stroke
			(width 0.2)
			(type default)
		)
		(layer "In1.Cu")
	)
	(gr_arc
		(start 277.233634 -25.182068)
		(mid 277.173374 -25.036588)
		(end 277.027894 -24.976328)
		(stroke
			(width 0.2)
			(type default)
		)
		(layer "In1.Cu")
	)
	(gr_rect
		(start 277.406354 -26.068528)
		(end 278.275034 -27.191208)
		(stroke
			(width 0)
			(type default)
		)
		(fill no)
		(layer "In1.Cu")
	)
	(gr_rect
		(start 277.406354 -24.392128)
		(end 278.275034 -25.514808)
		(stroke
			(width 0)
			(type default)
		)
		(fill no)
		(layer "In1.Cu")
	)
	(gr_arc
		(start 277.482554 -26.401268)
		(mid 277.542814 -26.546748)
		(end 277.688294 -26.607008)
		(stroke
			(width 0.2)
			(type default)
		)
		(layer "In1.Cu")
	)
	(gr_line
		(start 277.482554 -26.045668)
		(end 277.482554 -26.401268)
		(stroke
			(width 0.2)
			(type default)
		)
		(layer "In1.Cu")
	)
	(gr_arc
		(start 277.482554 -25.537668)
		(mid 277.542814 -25.683148)
		(end 277.688294 -25.743408)
		(stroke
			(width 0.2)
			(type default)
		)
		(layer "In1.Cu")
	)
	(gr_line
		(start 277.482554 -25.182068)
		(end 277.482554 -25.537668)
		(stroke
			(width 0.2)
			(type default)
		)
		(layer "In1.Cu")
	)
	(gr_rect
		(start 277.54326 -22.32406)
		(end 278.33574 -23.54834)
		(stroke
			(width 0)
			(type default)
		)
		(fill no)
		(layer "In1.Cu")
	)
	(gr_rect
		(start 277.54326 -19.63166)
		(end 278.33574 -20.85594)
		(stroke
			(width 0)
			(type default)
		)
		(fill no)
		(layer "In1.Cu")
	)
	(gr_line
		(start 277.688294 -26.607008)
		(end 278.043894 -26.607008)
		(stroke
			(width 0.2)
			(type default)
		)
		(layer "In1.Cu")
	)
	(gr_arc
		(start 277.688294 -25.839928)
		(mid 277.542814 -25.900188)
		(end 277.482554 -26.045668)
		(stroke
			(width 0.2)
			(type default)
		)
		(layer "In1.Cu")
	)
	(gr_line
		(start 277.688294 -25.743408)
		(end 278.043894 -25.743408)
		(stroke
			(width 0.2)
			(type default)
		)
		(layer "In1.Cu")
	)
	(gr_arc
		(start 277.688294 -24.976328)
		(mid 277.542814 -25.036588)
		(end 277.482554 -25.182068)
		(stroke
			(width 0.2)
			(type default)
		)
		(layer "In1.Cu")
	)
	(gr_arc
		(start 277.848822 -32.51454)
		(mid 278.232616 -32.131127)
		(end 277.849076 -31.74746)
		(stroke
			(width 0.2)
			(type default)
		)
		(layer "In1.Cu")
	)
	(gr_line
		(start 277.849076 -31.74746)
		(end 276.867112 -31.74746)
		(stroke
			(width 0.2)
			(type default)
		)
		(layer "In1.Cu")
	)
	(gr_arc
		(start 278.043894 -26.607008)
		(mid 278.189374 -26.546748)
		(end 278.249634 -26.401268)
		(stroke
			(width 0.2)
			(type default)
		)
		(layer "In1.Cu")
	)
	(gr_line
		(start 278.043894 -25.839928)
		(end 277.688294 -25.839928)
		(stroke
			(width 0.2)
			(type default)
		)
		(layer "In1.Cu")
	)
	(gr_arc
		(start 278.043894 -25.743408)
		(mid 278.189374 -25.683148)
		(end 278.249634 -25.537668)
		(stroke
			(width 0.2)
			(type default)
		)
		(layer "In1.Cu")
	)
	(gr_line
		(start 278.043894 -24.976328)
		(end 277.688294 -24.976328)
		(stroke
			(width 0.2)
			(type default)
		)
		(layer "In1.Cu")
	)
	(gr_line
		(start 278.249634 -26.401268)
		(end 278.249634 -26.045668)
		(stroke
			(width 0.2)
			(type default)
		)
		(layer "In1.Cu")
	)
	(gr_arc
		(start 278.249634 -26.045668)
		(mid 278.189374 -25.900188)
		(end 278.043894 -25.839928)
		(stroke
			(width 0.2)
			(type default)
		)
		(layer "In1.Cu")
	)
	(gr_line
		(start 278.249634 -25.537668)
		(end 278.249634 -25.182068)
		(stroke
			(width 0.2)
			(type default)
		)
		(layer "In1.Cu")
	)
	(gr_arc
		(start 278.249634 -25.182068)
		(mid 278.189374 -25.036588)
		(end 278.043894 -24.976328)
		(stroke
			(width 0.2)
			(type default)
		)
		(layer "In1.Cu")
	)
	(gr_arc
		(start 282.485084 -53.50002)
		(mid 282.777977 -54.207125)
		(end 283.485082 -54.500018)
		(stroke
			(width 1.524)
			(type default)
		)
		(layer "In1.Cu")
	)
	(gr_arc
		(start 282.485084 -0.999998)
		(mid 282.19219 -0.292899)
		(end 281.485086 0)
		(stroke
			(width 1.524)
			(type default)
		)
		(layer "In1.Cu")
	)
	(gr_line
		(start 282.485084 -0.999998)
		(end 282.485084 -53.50002)
		(stroke
			(width 1.524)
			(type default)
		)
		(layer "In1.Cu")
	)
	(gr_line
		(start 283.485082 -54.500018)
		(end 303.485042 -54.500018)
		(stroke
			(width 1.524)
			(type default)
		)
		(layer "In1.Cu")
	)
	(gr_arc
		(start 284.552898 -184.91327)
		(mid 284.227506 -185.347232)
		(end 284.661356 -185.67273)
		(stroke
			(width 0.2)
			(type default)
		)
		(layer "In1.Cu")
	)
	(gr_line
		(start 284.661356 -185.67273)
		(end 285.550356 -185.54573)
		(stroke
			(width 0.2)
			(type default)
		)
		(layer "In1.Cu")
	)
	(gr_line
		(start 285.441644 -184.78627)
		(end 284.552898 -184.91327)
		(stroke
			(width 0.2)
			(type default)
		)
		(layer "In1.Cu")
	)
	(gr_arc
		(start 285.550356 -185.54573)
		(mid 285.87573 -185.111644)
		(end 285.441644 -184.78627)
		(stroke
			(width 0.2)
			(type default)
		)
		(layer "In1.Cu")
	)
	(gr_arc
		(start 293.26586 -80.366616)
		(mid 293.649273 -80.75041)
		(end 294.03294 -80.36687)
		(stroke
			(width 0.2)
			(type default)
		)
		(layer "In1.Cu")
	)
	(gr_line
		(start 293.26586 -79.44993)
		(end 293.26586 -80.366616)
		(stroke
			(width 0.2)
			(type default)
		)
		(layer "In1.Cu")
	)
	(gr_line
		(start 294.03294 -80.36687)
		(end 294.03294 -79.44993)
		(stroke
			(width 0.2)
			(type default)
		)
		(layer "In1.Cu")
	)
	(gr_arc
		(start 294.03294 -79.44993)
		(mid 293.6494 -79.06639)
		(end 293.26586 -79.44993)
		(stroke
			(width 0.2)
			(type default)
		)
		(layer "In1.Cu")
	)
	(gr_arc
		(start 295.52646 -78.276196)
		(mid 295.909873 -78.65999)
		(end 296.29354 -78.27645)
		(stroke
			(width 0.2)
			(type default)
		)
		(layer "In1.Cu")
	)
	(gr_line
		(start 295.52646 -77.35951)
		(end 295.52646 -78.276196)
		(stroke
			(width 0.2)
			(type default)
		)
		(layer "In1.Cu")
	)
	(gr_line
		(start 296.29354 -78.27645)
		(end 296.29354 -77.35951)
		(stroke
			(width 0.2)
			(type default)
		)
		(layer "In1.Cu")
	)
	(gr_arc
		(start 296.29354 -77.35951)
		(mid 295.91 -76.97597)
		(end 295.52646 -77.35951)
		(stroke
			(width 0.2)
			(type default)
		)
		(layer "In1.Cu")
	)
	(gr_line
		(start 297.05681 -82.607404)
		(end 297.973496 -82.607404)
		(stroke
			(width 0.2)
			(type default)
		)
		(layer "In1.Cu")
	)
	(gr_arc
		(start 297.05681 -81.840324)
		(mid 296.67327 -82.223864)
		(end 297.05681 -82.607404)
		(stroke
			(width 0.2)
			(type default)
		)
		(layer "In1.Cu")
	)
	(gr_line
		(start 297.123358 -74.07529)
		(end 298.139104 -74.07529)
		(stroke
			(width 0.2)
			(type default)
		)
		(layer "In1.Cu")
	)
	(gr_arc
		(start 297.123358 -73.30821)
		(mid 296.739818 -73.69175)
		(end 297.123358 -74.07529)
		(stroke
			(width 0.2)
			(type default)
		)
		(layer "In1.Cu")
	)
	(gr_arc
		(start 297.973496 -82.607404)
		(mid 298.35729 -82.223991)
		(end 297.97375 -81.840324)
		(stroke
			(width 0.2)
			(type default)
		)
		(layer "In1.Cu")
	)
	(gr_line
		(start 297.97375 -81.840324)
		(end 297.05681 -81.840324)
		(stroke
			(width 0.2)
			(type default)
		)
		(layer "In1.Cu")
	)
	(gr_arc
		(start 298.139104 -74.07529)
		(mid 298.522898 -73.691877)
		(end 298.139358 -73.30821)
		(stroke
			(width 0.2)
			(type default)
		)
		(layer "In1.Cu")
	)
	(gr_line
		(start 298.139358 -73.30821)
		(end 297.123358 -73.30821)
		(stroke
			(width 0.2)
			(type default)
		)
		(layer "In1.Cu")
	)
	(gr_line
		(start 299.633132 -175.392334)
		(end 300.430438 -175.40351)
		(stroke
			(width 0.2)
			(type default)
		)
		(layer "In1.Cu")
	)
	(gr_arc
		(start 299.643546 -174.676054)
		(mid 299.280328 -175.028987)
		(end 299.633132 -175.392334)
		(stroke
			(width 0.2)
			(type default)
		)
		(layer "In1.Cu")
	)
	(gr_arc
		(start 300.430438 -175.40351)
		(mid 300.793658 -175.05045)
		(end 300.440598 -174.68723)
		(stroke
			(width 0.2)
			(type default)
		)
		(layer "In1.Cu")
	)
	(gr_line
		(start 300.440598 -174.68723)
		(end 299.643546 -174.676054)
		(stroke
			(width 0.2)
			(type default)
		)
		(layer "In1.Cu")
	)
	(gr_line
		(start 301.974758 -73.99274)
		(end 302.956722 -73.99274)
		(stroke
			(width 0.2)
			(type default)
		)
		(layer "In1.Cu")
	)
	(gr_arc
		(start 301.975012 -73.22566)
		(mid 301.591218 -73.609073)
		(end 301.974758 -73.99274)
		(stroke
			(width 0.2)
			(type default)
		)
		(layer "In1.Cu")
	)
	(gr_arc
		(start 302.214026 -173.36643)
		(mid 301.849028 -173.767496)
		(end 302.250094 -174.132494)
		(stroke
			(width 0.2)
			(type default)
		)
		(layer "In1.Cu")
	)
	(gr_line
		(start 302.214026 -173.364144)
		(end 302.214026 -173.36643)
		(stroke
			(width 0.2)
			(type default)
		)
		(layer "In1.Cu")
	)
	(gr_line
		(start 302.21428 -173.36389)
		(end 302.214026 -173.364144)
		(stroke
			(width 0.2)
			(type default)
		)
		(layer "In1.Cu")
	)
	(gr_line
		(start 302.250094 -174.135034)
		(end 303.024032 -174.098966)
		(stroke
			(width 0.2)
			(type default)
		)
		(layer "In1.Cu")
	)
	(gr_line
		(start 302.250094 -174.132494)
		(end 302.250094 -174.135034)
		(stroke
			(width 0.2)
			(type default)
		)
		(layer "In1.Cu")
	)
	(gr_arc
		(start 302.503332 -68.39204)
		(mid 302.563592 -68.53752)
		(end 302.709072 -68.59778)
		(stroke
			(width 0.2)
			(type default)
		)
		(layer "In1.Cu")
	)
	(gr_line
		(start 302.503332 -68.03644)
		(end 302.503332 -68.39204)
		(stroke
			(width 0.2)
			(type default)
		)
		(layer "In1.Cu")
	)
	(gr_arc
		(start 302.503332 -67.24904)
		(mid 302.563592 -67.39452)
		(end 302.709072 -67.45478)
		(stroke
			(width 0.2)
			(type default)
		)
		(layer "In1.Cu")
	)
	(gr_line
		(start 302.503332 -66.89344)
		(end 302.503332 -67.24904)
		(stroke
			(width 0.2)
			(type default)
		)
		(layer "In1.Cu")
	)
	(gr_line
		(start 302.709072 -68.59778)
		(end 303.064672 -68.59778)
		(stroke
			(width 0.2)
			(type default)
		)
		(layer "In1.Cu")
	)
	(gr_arc
		(start 302.709072 -67.8307)
		(mid 302.563592 -67.89096)
		(end 302.503332 -68.03644)
		(stroke
			(width 0.2)
			(type default)
		)
		(layer "In1.Cu")
	)
	(gr_line
		(start 302.709072 -67.45478)
		(end 303.064672 -67.45478)
		(stroke
			(width 0.2)
			(type default)
		)
		(layer "In1.Cu")
	)
	(gr_arc
		(start 302.709072 -66.6877)
		(mid 302.563592 -66.74796)
		(end 302.503332 -66.89344)
		(stroke
			(width 0.2)
			(type default)
		)
		(layer "In1.Cu")
	)
	(gr_arc
		(start 302.956722 -73.99274)
		(mid 303.340262 -73.6092)
		(end 302.956722 -73.22566)
		(stroke
			(width 0.2)
			(type default)
		)
		(layer "In1.Cu")
	)
	(gr_line
		(start 302.956722 -73.22566)
		(end 301.975012 -73.22566)
		(stroke
			(width 0.2)
			(type default)
		)
		(layer "In1.Cu")
	)
	(gr_line
		(start 302.987964 -173.330362)
		(end 302.987964 -173.327822)
		(stroke
			(width 0.2)
			(type default)
		)
		(layer "In1.Cu")
	)
	(gr_line
		(start 302.987964 -173.327822)
		(end 302.21428 -173.36389)
		(stroke
			(width 0.2)
			(type default)
		)
		(layer "In1.Cu")
	)
	(gr_line
		(start 303.024032 -174.098966)
		(end 303.024032 -174.096934)
		(stroke
			(width 0.2)
			(type default)
		)
		(layer "In1.Cu")
	)
	(gr_line
		(start 303.024032 -174.096934)
		(end 303.024032 -174.096426)
		(stroke
			(width 0.2)
			(type default)
		)
		(layer "In1.Cu")
	)
	(gr_arc
		(start 303.024032 -174.096426)
		(mid 303.38903 -173.69536)
		(end 302.987964 -173.330362)
		(stroke
			(width 0.2)
			(type default)
		)
		(layer "In1.Cu")
	)
	(gr_arc
		(start 303.064672 -68.59778)
		(mid 303.210152 -68.53752)
		(end 303.270412 -68.39204)
		(stroke
			(width 0.2)
			(type default)
		)
		(layer "In1.Cu")
	)
	(gr_line
		(start 303.064672 -67.8307)
		(end 302.709072 -67.8307)
		(stroke
			(width 0.2)
			(type default)
		)
		(layer "In1.Cu")
	)
	(gr_arc
		(start 303.064672 -67.45478)
		(mid 303.210152 -67.39452)
		(end 303.270412 -67.24904)
		(stroke
			(width 0.2)
			(type default)
		)
		(layer "In1.Cu")
	)
	(gr_line
		(start 303.064672 -66.6877)
		(end 302.709072 -66.6877)
		(stroke
			(width 0.2)
			(type default)
		)
		(layer "In1.Cu")
	)
	(gr_line
		(start 303.270412 -68.39204)
		(end 303.270412 -68.03644)
		(stroke
			(width 0.2)
			(type default)
		)
		(layer "In1.Cu")
	)
	(gr_arc
		(start 303.270412 -68.03644)
		(mid 303.210152 -67.89096)
		(end 303.064672 -67.8307)
		(stroke
			(width 0.2)
			(type default)
		)
		(layer "In1.Cu")
	)
	(gr_line
		(start 303.270412 -67.24904)
		(end 303.270412 -66.89344)
		(stroke
			(width 0.2)
			(type default)
		)
		(layer "In1.Cu")
	)
	(gr_arc
		(start 303.270412 -66.89344)
		(mid 303.210152 -66.74796)
		(end 303.064672 -66.6877)
		(stroke
			(width 0.2)
			(type default)
		)
		(layer "In1.Cu")
	)
	(gr_arc
		(start 303.366932 -68.39204)
		(mid 303.427192 -68.53752)
		(end 303.572672 -68.59778)
		(stroke
			(width 0.2)
			(type default)
		)
		(layer "In1.Cu")
	)
	(gr_line
		(start 303.366932 -68.03644)
		(end 303.366932 -68.39204)
		(stroke
			(width 0.2)
			(type default)
		)
		(layer "In1.Cu")
	)
	(gr_arc
		(start 303.366932 -67.24904)
		(mid 303.427192 -67.39452)
		(end 303.572672 -67.45478)
		(stroke
			(width 0.2)
			(type default)
		)
		(layer "In1.Cu")
	)
	(gr_line
		(start 303.366932 -66.89344)
		(end 303.366932 -67.24904)
		(stroke
			(width 0.2)
			(type default)
		)
		(layer "In1.Cu")
	)
	(gr_arc
		(start 303.485042 -54.500018)
		(mid 304.192147 -54.207125)
		(end 304.48504 -53.50002)
		(stroke
			(width 1.524)
			(type default)
		)
		(layer "In1.Cu")
	)
	(gr_line
		(start 303.572672 -68.59778)
		(end 303.928272 -68.59778)
		(stroke
			(width 0.2)
			(type default)
		)
		(layer "In1.Cu")
	)
	(gr_arc
		(start 303.572672 -67.8307)
		(mid 303.427192 -67.89096)
		(end 303.366932 -68.03644)
		(stroke
			(width 0.2)
			(type default)
		)
		(layer "In1.Cu")
	)
	(gr_line
		(start 303.572672 -67.45478)
		(end 303.928272 -67.45478)
		(stroke
			(width 0.2)
			(type default)
		)
		(layer "In1.Cu")
	)
	(gr_arc
		(start 303.572672 -66.6877)
		(mid 303.427192 -66.74796)
		(end 303.366932 -66.89344)
		(stroke
			(width 0.2)
			(type default)
		)
		(layer "In1.Cu")
	)
	(gr_line
		(start 303.80305 -87.908892)
		(end 304.719736 -87.908892)
		(stroke
			(width 0.2)
			(type default)
		)
		(layer "In1.Cu")
	)
	(gr_arc
		(start 303.80305 -87.141812)
		(mid 303.41951 -87.525352)
		(end 303.80305 -87.908892)
		(stroke
			(width 0.2)
			(type default)
		)
		(layer "In1.Cu")
	)
	(gr_arc
		(start 303.928272 -68.59778)
		(mid 304.073752 -68.53752)
		(end 304.134012 -68.39204)
		(stroke
			(width 0.2)
			(type default)
		)
		(layer "In1.Cu")
	)
	(gr_line
		(start 303.928272 -67.8307)
		(end 303.572672 -67.8307)
		(stroke
			(width 0.2)
			(type default)
		)
		(layer "In1.Cu")
	)
	(gr_arc
		(start 303.928272 -67.45478)
		(mid 304.073752 -67.39452)
		(end 304.134012 -67.24904)
		(stroke
			(width 0.2)
			(type default)
		)
		(layer "In1.Cu")
	)
	(gr_line
		(start 303.928272 -66.6877)
		(end 303.572672 -66.6877)
		(stroke
			(width 0.2)
			(type default)
		)
		(layer "In1.Cu")
	)
	(gr_line
		(start 304.134012 -68.39204)
		(end 304.134012 -68.03644)
		(stroke
			(width 0.2)
			(type default)
		)
		(layer "In1.Cu")
	)
	(gr_arc
		(start 304.134012 -68.03644)
		(mid 304.073752 -67.89096)
		(end 303.928272 -67.8307)
		(stroke
			(width 0.2)
			(type default)
		)
		(layer "In1.Cu")
	)
	(gr_line
		(start 304.134012 -67.24904)
		(end 304.134012 -66.89344)
		(stroke
			(width 0.2)
			(type default)
		)
		(layer "In1.Cu")
	)
	(gr_arc
		(start 304.134012 -66.89344)
		(mid 304.073752 -66.74796)
		(end 303.928272 -66.6877)
		(stroke
			(width 0.2)
			(type default)
		)
		(layer "In1.Cu")
	)
	(gr_line
		(start 304.48504 -53.50002)
		(end 304.48504 -45.500036)
		(stroke
			(width 1.524)
			(type default)
		)
		(layer "In1.Cu")
	)
	(gr_arc
		(start 304.719736 -87.908892)
		(mid 305.10353 -87.525479)
		(end 304.71999 -87.141812)
		(stroke
			(width 0.2)
			(type default)
		)
		(layer "In1.Cu")
	)
	(gr_line
		(start 304.71999 -87.141812)
		(end 303.80305 -87.141812)
		(stroke
			(width 0.2)
			(type default)
		)
		(layer "In1.Cu")
	)
	(gr_arc
		(start 305.485038 -44.500038)
		(mid 304.777921 -44.792919)
		(end 304.48504 -45.500036)
		(stroke
			(width 1.524)
			(type default)
		)
		(layer "In1.Cu")
	)
	(gr_arc
		(start 305.485038 -44.500038)
		(mid 306.192143 -44.207145)
		(end 306.485036 -43.50004)
		(stroke
			(width 1.524)
			(type default)
		)
		(layer "In1.Cu")
	)
	(gr_line
		(start 306.485036 -43.50004)
		(end 306.485036 -0.999998)
		(stroke
			(width 1.524)
			(type default)
		)
		(layer "In1.Cu")
	)
	(gr_arc
		(start 307.485034 0)
		(mid 306.777906 -0.29288)
		(end 306.485036 -0.999998)
		(stroke
			(width 1.524)
			(type default)
		)
		(layer "In1.Cu")
	)
	(gr_line
		(start 307.485034 0)
		(end 354.600002 0)
		(stroke
			(width 1.524)
			(type default)
		)
		(layer "In1.Cu")
	)
	(gr_line
		(start 307.594 -80.6958)
		(end 307.594 -79.2988)
		(stroke
			(width 0.2)
			(type default)
		)
		(layer "In1.Cu")
	)
	(gr_line
		(start 307.594 -79.2988)
		(end 309.753 -79.2988)
		(stroke
			(width 0.2)
			(type default)
		)
		(layer "In1.Cu")
	)
	(gr_line
		(start 307.594 -77.4954)
		(end 307.594 -76.0984)
		(stroke
			(width 0.2)
			(type default)
		)
		(layer "In1.Cu")
	)
	(gr_line
		(start 307.594 -76.0984)
		(end 309.753 -76.0984)
		(stroke
			(width 0.2)
			(type default)
		)
		(layer "In1.Cu")
	)
	(gr_line
		(start 307.594 -74.295)
		(end 307.594 -72.898)
		(stroke
			(width 0.2)
			(type default)
		)
		(layer "In1.Cu")
	)
	(gr_line
		(start 307.594 -72.898)
		(end 309.753 -72.898)
		(stroke
			(width 0.2)
			(type default)
		)
		(layer "In1.Cu")
	)
	(gr_line
		(start 307.594 -71.12)
		(end 307.594 -69.723)
		(stroke
			(width 0.2)
			(type default)
		)
		(layer "In1.Cu")
	)
	(gr_line
		(start 307.594 -69.723)
		(end 309.753 -69.723)
		(stroke
			(width 0.2)
			(type default)
		)
		(layer "In1.Cu")
	)
	(gr_line
		(start 307.594 -67.8942)
		(end 307.594 -66.4972)
		(stroke
			(width 0.2)
			(type default)
		)
		(layer "In1.Cu")
	)
	(gr_line
		(start 307.594 -66.4972)
		(end 309.753 -66.4972)
		(stroke
			(width 0.2)
			(type default)
		)
		(layer "In1.Cu")
	)
	(gr_line
		(start 309.753 -80.6958)
		(end 307.594 -80.6958)
		(stroke
			(width 0.2)
			(type default)
		)
		(layer "In1.Cu")
	)
	(gr_line
		(start 309.753 -79.2988)
		(end 309.753 -80.6958)
		(stroke
			(width 0.2)
			(type default)
		)
		(layer "In1.Cu")
	)
	(gr_line
		(start 309.753 -77.4954)
		(end 307.594 -77.4954)
		(stroke
			(width 0.2)
			(type default)
		)
		(layer "In1.Cu")
	)
	(gr_line
		(start 309.753 -76.0984)
		(end 309.753 -77.4954)
		(stroke
			(width 0.2)
			(type default)
		)
		(layer "In1.Cu")
	)
	(gr_line
		(start 309.753 -74.295)
		(end 307.594 -74.295)
		(stroke
			(width 0.2)
			(type default)
		)
		(layer "In1.Cu")
	)
	(gr_line
		(start 309.753 -72.898)
		(end 309.753 -74.295)
		(stroke
			(width 0.2)
			(type default)
		)
		(layer "In1.Cu")
	)
	(gr_line
		(start 309.753 -71.12)
		(end 307.594 -71.12)
		(stroke
			(width 0.2)
			(type default)
		)
		(layer "In1.Cu")
	)
	(gr_line
		(start 309.753 -69.723)
		(end 309.753 -71.12)
		(stroke
			(width 0.2)
			(type default)
		)
		(layer "In1.Cu")
	)
	(gr_line
		(start 309.753 -67.8942)
		(end 307.594 -67.8942)
		(stroke
			(width 0.2)
			(type default)
		)
		(layer "In1.Cu")
	)
	(gr_line
		(start 309.753 -66.4972)
		(end 309.753 -67.8942)
		(stroke
			(width 0.2)
			(type default)
		)
		(layer "In1.Cu")
	)
	(gr_line
		(start 312.039 -82.296)
		(end 312.039 -80.899)
		(stroke
			(width 0.2)
			(type default)
		)
		(layer "In1.Cu")
	)
	(gr_line
		(start 312.039 -80.899)
		(end 314.198 -80.899)
		(stroke
			(width 0.2)
			(type default)
		)
		(layer "In1.Cu")
	)
	(gr_line
		(start 312.039 -79.0956)
		(end 312.039 -77.6986)
		(stroke
			(width 0.2)
			(type default)
		)
		(layer "In1.Cu")
	)
	(gr_line
		(start 312.039 -77.6986)
		(end 314.198 -77.6986)
		(stroke
			(width 0.2)
			(type default)
		)
		(layer "In1.Cu")
	)
	(gr_line
		(start 312.039 -75.8952)
		(end 312.039 -74.4982)
		(stroke
			(width 0.2)
			(type default)
		)
		(layer "In1.Cu")
	)
	(gr_line
		(start 312.039 -74.4982)
		(end 314.198 -74.4982)
		(stroke
			(width 0.2)
			(type default)
		)
		(layer "In1.Cu")
	)
	(gr_line
		(start 312.039 -72.6948)
		(end 312.039 -71.2978)
		(stroke
			(width 0.2)
			(type default)
		)
		(layer "In1.Cu")
	)
	(gr_line
		(start 312.039 -71.2978)
		(end 314.198 -71.2978)
		(stroke
			(width 0.2)
			(type default)
		)
		(layer "In1.Cu")
	)
	(gr_line
		(start 312.039 -69.4944)
		(end 312.039 -68.0974)
		(stroke
			(width 0.2)
			(type default)
		)
		(layer "In1.Cu")
	)
	(gr_line
		(start 312.039 -68.0974)
		(end 314.198 -68.0974)
		(stroke
			(width 0.2)
			(type default)
		)
		(layer "In1.Cu")
	)
	(gr_line
		(start 314.198 -82.296)
		(end 312.039 -82.296)
		(stroke
			(width 0.2)
			(type default)
		)
		(layer "In1.Cu")
	)
	(gr_line
		(start 314.198 -80.899)
		(end 314.198 -82.296)
		(stroke
			(width 0.2)
			(type default)
		)
		(layer "In1.Cu")
	)
	(gr_line
		(start 314.198 -79.0956)
		(end 312.039 -79.0956)
		(stroke
			(width 0.2)
			(type default)
		)
		(layer "In1.Cu")
	)
	(gr_line
		(start 314.198 -77.6986)
		(end 314.198 -79.0956)
		(stroke
			(width 0.2)
			(type default)
		)
		(layer "In1.Cu")
	)
	(gr_line
		(start 314.198 -75.8952)
		(end 312.039 -75.8952)
		(stroke
			(width 0.2)
			(type default)
		)
		(layer "In1.Cu")
	)
	(gr_line
		(start 314.198 -74.4982)
		(end 314.198 -75.8952)
		(stroke
			(width 0.2)
			(type default)
		)
		(layer "In1.Cu")
	)
	(gr_line
		(start 314.198 -72.6948)
		(end 312.039 -72.6948)
		(stroke
			(width 0.2)
			(type default)
		)
		(layer "In1.Cu")
	)
	(gr_line
		(start 314.198 -71.2978)
		(end 314.198 -72.6948)
		(stroke
			(width 0.2)
			(type default)
		)
		(layer "In1.Cu")
	)
	(gr_line
		(start 314.198 -69.4944)
		(end 312.039 -69.4944)
		(stroke
			(width 0.2)
			(type default)
		)
		(layer "In1.Cu")
	)
	(gr_line
		(start 314.198 -68.0974)
		(end 314.198 -69.4944)
		(stroke
			(width 0.2)
			(type default)
		)
		(layer "In1.Cu")
	)
	(gr_arc
		(start 315.66866 -69.3928)
		(mid 315.72892 -69.53828)
		(end 315.8744 -69.59854)
		(stroke
			(width 0.2)
			(type default)
		)
		(layer "In1.Cu")
	)
	(gr_line
		(start 315.66866 -69.0372)
		(end 315.66866 -69.3928)
		(stroke
			(width 0.2)
			(type default)
		)
		(layer "In1.Cu")
	)
	(gr_arc
		(start 315.66866 -68.3768)
		(mid 315.72892 -68.52228)
		(end 315.8744 -68.58254)
		(stroke
			(width 0.2)
			(type default)
		)
		(layer "In1.Cu")
	)
	(gr_line
		(start 315.66866 -68.0212)
		(end 315.66866 -68.3768)
		(stroke
			(width 0.2)
			(type default)
		)
		(layer "In1.Cu")
	)
	(gr_line
		(start 315.8744 -69.59854)
		(end 316.23 -69.59854)
		(stroke
			(width 0.2)
			(type default)
		)
		(layer "In1.Cu")
	)
	(gr_arc
		(start 315.8744 -68.83146)
		(mid 315.72892 -68.89172)
		(end 315.66866 -69.0372)
		(stroke
			(width 0.2)
			(type default)
		)
		(layer "In1.Cu")
	)
	(gr_line
		(start 315.8744 -68.58254)
		(end 316.23 -68.58254)
		(stroke
			(width 0.2)
			(type default)
		)
		(layer "In1.Cu")
	)
	(gr_arc
		(start 315.8744 -67.81546)
		(mid 315.72892 -67.87572)
		(end 315.66866 -68.0212)
		(stroke
			(width 0.2)
			(type default)
		)
		(layer "In1.Cu")
	)
	(gr_arc
		(start 316.23 -69.59854)
		(mid 316.37548 -69.53828)
		(end 316.43574 -69.3928)
		(stroke
			(width 0.2)
			(type default)
		)
		(layer "In1.Cu")
	)
	(gr_line
		(start 316.23 -68.83146)
		(end 315.8744 -68.83146)
		(stroke
			(width 0.2)
			(type default)
		)
		(layer "In1.Cu")
	)
	(gr_arc
		(start 316.23 -68.58254)
		(mid 316.37548 -68.52228)
		(end 316.43574 -68.3768)
		(stroke
			(width 0.2)
			(type default)
		)
		(layer "In1.Cu")
	)
	(gr_line
		(start 316.23 -67.81546)
		(end 315.8744 -67.81546)
		(stroke
			(width 0.2)
			(type default)
		)
		(layer "In1.Cu")
	)
	(gr_line
		(start 316.43574 -69.3928)
		(end 316.43574 -69.0372)
		(stroke
			(width 0.2)
			(type default)
		)
		(layer "In1.Cu")
	)
	(gr_arc
		(start 316.43574 -69.0372)
		(mid 316.37548 -68.89172)
		(end 316.23 -68.83146)
		(stroke
			(width 0.2)
			(type default)
		)
		(layer "In1.Cu")
	)
	(gr_line
		(start 316.43574 -68.3768)
		(end 316.43574 -68.0212)
		(stroke
			(width 0.2)
			(type default)
		)
		(layer "In1.Cu")
	)
	(gr_arc
		(start 316.43574 -68.0212)
		(mid 316.37548 -67.87572)
		(end 316.23 -67.81546)
		(stroke
			(width 0.2)
			(type default)
		)
		(layer "In1.Cu")
	)
	(gr_arc
		(start 316.53226 -69.3928)
		(mid 316.59252 -69.53828)
		(end 316.738 -69.59854)
		(stroke
			(width 0.2)
			(type default)
		)
		(layer "In1.Cu")
	)
	(gr_line
		(start 316.53226 -69.0372)
		(end 316.53226 -69.3928)
		(stroke
			(width 0.2)
			(type default)
		)
		(layer "In1.Cu")
	)
	(gr_arc
		(start 316.53226 -68.3768)
		(mid 316.59252 -68.52228)
		(end 316.738 -68.58254)
		(stroke
			(width 0.2)
			(type default)
		)
		(layer "In1.Cu")
	)
	(gr_line
		(start 316.53226 -68.0212)
		(end 316.53226 -68.3768)
		(stroke
			(width 0.2)
			(type default)
		)
		(layer "In1.Cu")
	)
	(gr_line
		(start 316.738 -69.59854)
		(end 317.0936 -69.59854)
		(stroke
			(width 0.2)
			(type default)
		)
		(layer "In1.Cu")
	)
	(gr_arc
		(start 316.738 -68.83146)
		(mid 316.59252 -68.89172)
		(end 316.53226 -69.0372)
		(stroke
			(width 0.2)
			(type default)
		)
		(layer "In1.Cu")
	)
	(gr_line
		(start 316.738 -68.58254)
		(end 317.0936 -68.58254)
		(stroke
			(width 0.2)
			(type default)
		)
		(layer "In1.Cu")
	)
	(gr_arc
		(start 316.738 -67.81546)
		(mid 316.59252 -67.87572)
		(end 316.53226 -68.0212)
		(stroke
			(width 0.2)
			(type default)
		)
		(layer "In1.Cu")
	)
	(gr_arc
		(start 317.0936 -69.59854)
		(mid 317.23908 -69.53828)
		(end 317.29934 -69.3928)
		(stroke
			(width 0.2)
			(type default)
		)
		(layer "In1.Cu")
	)
	(gr_line
		(start 317.0936 -68.83146)
		(end 316.738 -68.83146)
		(stroke
			(width 0.2)
			(type default)
		)
		(layer "In1.Cu")
	)
	(gr_arc
		(start 317.0936 -68.58254)
		(mid 317.23908 -68.52228)
		(end 317.29934 -68.3768)
		(stroke
			(width 0.2)
			(type default)
		)
		(layer "In1.Cu")
	)
	(gr_line
		(start 317.0936 -67.81546)
		(end 316.738 -67.81546)
		(stroke
			(width 0.2)
			(type default)
		)
		(layer "In1.Cu")
	)
	(gr_arc
		(start 317.263018 -73.024746)
		(mid 317.671831 -73.43394)
		(end 318.080898 -73.025)
		(stroke
			(width 0.2)
			(type default)
		)
		(layer "In1.Cu")
	)
	(gr_line
		(start 317.263018 -72.009)
		(end 317.263018 -73.024746)
		(stroke
			(width 0.2)
			(type default)
		)
		(layer "In1.Cu")
	)
	(gr_line
		(start 317.29934 -69.3928)
		(end 317.29934 -69.0372)
		(stroke
			(width 0.2)
			(type default)
		)
		(layer "In1.Cu")
	)
	(gr_arc
		(start 317.29934 -69.0372)
		(mid 317.23908 -68.89172)
		(end 317.0936 -68.83146)
		(stroke
			(width 0.2)
			(type default)
		)
		(layer "In1.Cu")
	)
	(gr_line
		(start 317.29934 -68.3768)
		(end 317.29934 -68.0212)
		(stroke
			(width 0.2)
			(type default)
		)
		(layer "In1.Cu")
	)
	(gr_arc
		(start 317.29934 -68.0212)
		(mid 317.23908 -67.87572)
		(end 317.0936 -67.81546)
		(stroke
			(width 0.2)
			(type default)
		)
		(layer "In1.Cu")
	)
	(gr_arc
		(start 317.898018 -82.422746)
		(mid 318.306831 -82.83194)
		(end 318.715898 -82.423)
		(stroke
			(width 0.2)
			(type default)
		)
		(layer "In1.Cu")
	)
	(gr_line
		(start 317.898018 -81.407)
		(end 317.898018 -82.422746)
		(stroke
			(width 0.2)
			(type default)
		)
		(layer "In1.Cu")
	)
	(gr_line
		(start 317.971932 -79.440786)
		(end 317.972186 -79.44104)
		(stroke
			(width 0.2)
			(type default)
		)
		(layer "In1.Cu")
	)
	(gr_line
		(start 317.972186 -79.44104)
		(end 317.974218 -79.44104)
		(stroke
			(width 0.2)
			(type default)
		)
		(layer "In1.Cu")
	)
	(gr_arc
		(start 317.974218 -79.44104)
		(mid 318.372998 -79.86014)
		(end 318.792098 -79.46136)
		(stroke
			(width 0.2)
			(type default)
		)
		(layer "In1.Cu")
	)
	(gr_line
		(start 317.997332 -78.42504)
		(end 317.971932 -79.440786)
		(stroke
			(width 0.2)
			(type default)
		)
		(layer "In1.Cu")
	)
	(gr_line
		(start 317.999618 -78.42504)
		(end 317.997332 -78.42504)
		(stroke
			(width 0.2)
			(type default)
		)
		(layer "In1.Cu")
	)
	(gr_line
		(start 318.080898 -73.025)
		(end 318.080898 -72.009)
		(stroke
			(width 0.2)
			(type default)
		)
		(layer "In1.Cu")
	)
	(gr_arc
		(start 318.080898 -72.009)
		(mid 317.671958 -71.60006)
		(end 317.263018 -72.009)
		(stroke
			(width 0.2)
			(type default)
		)
		(layer "In1.Cu")
	)
	(gr_arc
		(start 318.372236 -69.197982)
		(mid 318.755776 -69.581522)
		(end 319.139316 -69.197982)
		(stroke
			(width 0.2)
			(type default)
		)
		(layer "In1.Cu")
	)
	(gr_line
		(start 318.372236 -68.216018)
		(end 318.372236 -69.197982)
		(stroke
			(width 0.2)
			(type default)
		)
		(layer "In1.Cu")
	)
	(gr_line
		(start 318.715898 -82.423)
		(end 318.715898 -81.407)
		(stroke
			(width 0.2)
			(type default)
		)
		(layer "In1.Cu")
	)
	(gr_arc
		(start 318.715898 -81.407)
		(mid 318.306958 -80.99806)
		(end 317.898018 -81.407)
		(stroke
			(width 0.2)
			(type default)
		)
		(layer "In1.Cu")
	)
	(gr_line
		(start 318.792098 -79.46136)
		(end 318.794384 -79.46136)
		(stroke
			(width 0.2)
			(type default)
		)
		(layer "In1.Cu")
	)
	(gr_line
		(start 318.794384 -79.46136)
		(end 318.819784 -78.44536)
		(stroke
			(width 0.2)
			(type default)
		)
		(layer "In1.Cu")
	)
	(gr_arc
		(start 318.817498 -78.44536)
		(mid 318.418718 -78.02626)
		(end 317.999618 -78.42504)
		(stroke
			(width 0.2)
			(type default)
		)
		(layer "In1.Cu")
	)
	(gr_line
		(start 318.819784 -78.44536)
		(end 318.817498 -78.44536)
		(stroke
			(width 0.2)
			(type default)
		)
		(layer "In1.Cu")
	)
	(gr_line
		(start 319.139316 -69.197982)
		(end 319.139316 -68.216272)
		(stroke
			(width 0.2)
			(type default)
		)
		(layer "In1.Cu")
	)
	(gr_arc
		(start 319.139316 -68.216272)
		(mid 318.755903 -67.832478)
		(end 318.372236 -68.216018)
		(stroke
			(width 0.2)
			(type default)
		)
		(layer "In1.Cu")
	)
	(gr_arc
		(start 319.777618 -76.191618)
		(mid 320.186431 -76.600812)
		(end 320.595498 -76.191872)
		(stroke
			(width 0.2)
			(type default)
		)
		(layer "In1.Cu")
	)
	(gr_line
		(start 319.777618 -75.209908)
		(end 319.777618 -76.191618)
		(stroke
			(width 0.2)
			(type default)
		)
		(layer "In1.Cu")
	)
	(gr_line
		(start 320.595498 -76.191872)
		(end 320.595498 -75.209908)
		(stroke
			(width 0.2)
			(type default)
		)
		(layer "In1.Cu")
	)
	(gr_arc
		(start 320.595498 -75.209908)
		(mid 320.186558 -74.800968)
		(end 319.777618 -75.209908)
		(stroke
			(width 0.2)
			(type default)
		)
		(layer "In1.Cu")
	)
	(gr_arc
		(start 347.575378 -155.476448)
		(mid 347.635638 -155.621928)
		(end 347.781118 -155.682188)
		(stroke
			(width 0.2)
			(type default)
		)
		(layer "In1.Cu")
	)
	(gr_line
		(start 347.575378 -155.120848)
		(end 347.575378 -155.476448)
		(stroke
			(width 0.2)
			(type default)
		)
		(layer "In1.Cu")
	)
	(gr_arc
		(start 347.575378 -154.333448)
		(mid 347.635638 -154.478928)
		(end 347.781118 -154.539188)
		(stroke
			(width 0.2)
			(type default)
		)
		(layer "In1.Cu")
	)
	(gr_line
		(start 347.575378 -153.977848)
		(end 347.575378 -154.333448)
		(stroke
			(width 0.2)
			(type default)
		)
		(layer "In1.Cu")
	)
	(gr_arc
		(start 347.575378 -153.190448)
		(mid 347.635638 -153.335928)
		(end 347.781118 -153.396188)
		(stroke
			(width 0.2)
			(type default)
		)
		(layer "In1.Cu")
	)
	(gr_line
		(start 347.575378 -152.834848)
		(end 347.575378 -153.190448)
		(stroke
			(width 0.2)
			(type default)
		)
		(layer "In1.Cu")
	)
	(gr_arc
		(start 347.575378 -152.047448)
		(mid 347.635638 -152.192928)
		(end 347.781118 -152.253188)
		(stroke
			(width 0.2)
			(type default)
		)
		(layer "In1.Cu")
	)
	(gr_line
		(start 347.575378 -151.691848)
		(end 347.575378 -152.047448)
		(stroke
			(width 0.2)
			(type default)
		)
		(layer "In1.Cu")
	)
	(gr_arc
		(start 347.575378 -150.015448)
		(mid 347.635638 -150.160928)
		(end 347.781118 -150.221188)
		(stroke
			(width 0.2)
			(type default)
		)
		(layer "In1.Cu")
	)
	(gr_line
		(start 347.575378 -149.659848)
		(end 347.575378 -150.015448)
		(stroke
			(width 0.2)
			(type default)
		)
		(layer "In1.Cu")
	)
	(gr_arc
		(start 347.575378 -148.872448)
		(mid 347.635638 -149.017928)
		(end 347.781118 -149.078188)
		(stroke
			(width 0.2)
			(type default)
		)
		(layer "In1.Cu")
	)
	(gr_line
		(start 347.575378 -148.516848)
		(end 347.575378 -148.872448)
		(stroke
			(width 0.2)
			(type default)
		)
		(layer "In1.Cu")
	)
	(gr_line
		(start 347.781118 -155.682188)
		(end 348.136718 -155.682188)
		(stroke
			(width 0.2)
			(type default)
		)
		(layer "In1.Cu")
	)
	(gr_arc
		(start 347.781118 -154.915108)
		(mid 347.635638 -154.975368)
		(end 347.575378 -155.120848)
		(stroke
			(width 0.2)
			(type default)
		)
		(layer "In1.Cu")
	)
	(gr_line
		(start 347.781118 -154.539188)
		(end 348.136718 -154.539188)
		(stroke
			(width 0.2)
			(type default)
		)
		(layer "In1.Cu")
	)
	(gr_arc
		(start 347.781118 -153.772108)
		(mid 347.635638 -153.832368)
		(end 347.575378 -153.977848)
		(stroke
			(width 0.2)
			(type default)
		)
		(layer "In1.Cu")
	)
	(gr_line
		(start 347.781118 -153.396188)
		(end 348.136718 -153.396188)
		(stroke
			(width 0.2)
			(type default)
		)
		(layer "In1.Cu")
	)
	(gr_arc
		(start 347.781118 -152.629108)
		(mid 347.635638 -152.689368)
		(end 347.575378 -152.834848)
		(stroke
			(width 0.2)
			(type default)
		)
		(layer "In1.Cu")
	)
	(gr_line
		(start 347.781118 -152.253188)
		(end 348.136718 -152.253188)
		(stroke
			(width 0.2)
			(type default)
		)
		(layer "In1.Cu")
	)
	(gr_arc
		(start 347.781118 -151.486108)
		(mid 347.635638 -151.546368)
		(end 347.575378 -151.691848)
		(stroke
			(width 0.2)
			(type default)
		)
		(layer "In1.Cu")
	)
	(gr_line
		(start 347.781118 -150.221188)
		(end 348.136718 -150.221188)
		(stroke
			(width 0.2)
			(type default)
		)
		(layer "In1.Cu")
	)
	(gr_arc
		(start 347.781118 -149.454108)
		(mid 347.635638 -149.514368)
		(end 347.575378 -149.659848)
		(stroke
			(width 0.2)
			(type default)
		)
		(layer "In1.Cu")
	)
	(gr_line
		(start 347.781118 -149.078188)
		(end 348.136718 -149.078188)
		(stroke
			(width 0.2)
			(type default)
		)
		(layer "In1.Cu")
	)
	(gr_arc
		(start 347.781118 -148.311108)
		(mid 347.635638 -148.371368)
		(end 347.575378 -148.516848)
		(stroke
			(width 0.2)
			(type default)
		)
		(layer "In1.Cu")
	)
	(gr_arc
		(start 348.136718 -155.682188)
		(mid 348.282198 -155.621928)
		(end 348.342458 -155.476448)
		(stroke
			(width 0.2)
			(type default)
		)
		(layer "In1.Cu")
	)
	(gr_line
		(start 348.136718 -154.915108)
		(end 347.781118 -154.915108)
		(stroke
			(width 0.2)
			(type default)
		)
		(layer "In1.Cu")
	)
	(gr_arc
		(start 348.136718 -154.539188)
		(mid 348.282198 -154.478928)
		(end 348.342458 -154.333448)
		(stroke
			(width 0.2)
			(type default)
		)
		(layer "In1.Cu")
	)
	(gr_line
		(start 348.136718 -153.772108)
		(end 347.781118 -153.772108)
		(stroke
			(width 0.2)
			(type default)
		)
		(layer "In1.Cu")
	)
	(gr_arc
		(start 348.136718 -153.396188)
		(mid 348.282198 -153.335928)
		(end 348.342458 -153.190448)
		(stroke
			(width 0.2)
			(type default)
		)
		(layer "In1.Cu")
	)
	(gr_line
		(start 348.136718 -152.629108)
		(end 347.781118 -152.629108)
		(stroke
			(width 0.2)
			(type default)
		)
		(layer "In1.Cu")
	)
	(gr_arc
		(start 348.136718 -152.253188)
		(mid 348.282198 -152.192928)
		(end 348.342458 -152.047448)
		(stroke
			(width 0.2)
			(type default)
		)
		(layer "In1.Cu")
	)
	(gr_line
		(start 348.136718 -151.486108)
		(end 347.781118 -151.486108)
		(stroke
			(width 0.2)
			(type default)
		)
		(layer "In1.Cu")
	)
	(gr_arc
		(start 348.136718 -150.221188)
		(mid 348.282198 -150.160928)
		(end 348.342458 -150.015448)
		(stroke
			(width 0.2)
			(type default)
		)
		(layer "In1.Cu")
	)
	(gr_line
		(start 348.136718 -149.454108)
		(end 347.781118 -149.454108)
		(stroke
			(width 0.2)
			(type default)
		)
		(layer "In1.Cu")
	)
	(gr_arc
		(start 348.136718 -149.078188)
		(mid 348.282198 -149.017928)
		(end 348.342458 -148.872448)
		(stroke
			(width 0.2)
			(type default)
		)
		(layer "In1.Cu")
	)
	(gr_line
		(start 348.136718 -148.311108)
		(end 347.781118 -148.311108)
		(stroke
			(width 0.2)
			(type default)
		)
		(layer "In1.Cu")
	)
	(gr_line
		(start 348.342458 -155.476448)
		(end 348.342458 -155.120848)
		(stroke
			(width 0.2)
			(type default)
		)
		(layer "In1.Cu")
	)
	(gr_arc
		(start 348.342458 -155.120848)
		(mid 348.282198 -154.975368)
		(end 348.136718 -154.915108)
		(stroke
			(width 0.2)
			(type default)
		)
		(layer "In1.Cu")
	)
	(gr_line
		(start 348.342458 -154.333448)
		(end 348.342458 -153.977848)
		(stroke
			(width 0.2)
			(type default)
		)
		(layer "In1.Cu")
	)
	(gr_arc
		(start 348.342458 -153.977848)
		(mid 348.282198 -153.832368)
		(end 348.136718 -153.772108)
		(stroke
			(width 0.2)
			(type default)
		)
		(layer "In1.Cu")
	)
	(gr_line
		(start 348.342458 -153.190448)
		(end 348.342458 -152.834848)
		(stroke
			(width 0.2)
			(type default)
		)
		(layer "In1.Cu")
	)
	(gr_arc
		(start 348.342458 -152.834848)
		(mid 348.282198 -152.689368)
		(end 348.136718 -152.629108)
		(stroke
			(width 0.2)
			(type default)
		)
		(layer "In1.Cu")
	)
	(gr_line
		(start 348.342458 -152.047448)
		(end 348.342458 -151.691848)
		(stroke
			(width 0.2)
			(type default)
		)
		(layer "In1.Cu")
	)
	(gr_arc
		(start 348.342458 -151.691848)
		(mid 348.282198 -151.546368)
		(end 348.136718 -151.486108)
		(stroke
			(width 0.2)
			(type default)
		)
		(layer "In1.Cu")
	)
	(gr_line
		(start 348.342458 -150.015448)
		(end 348.342458 -149.659848)
		(stroke
			(width 0.2)
			(type default)
		)
		(layer "In1.Cu")
	)
	(gr_arc
		(start 348.342458 -149.659848)
		(mid 348.282198 -149.514368)
		(end 348.136718 -149.454108)
		(stroke
			(width 0.2)
			(type default)
		)
		(layer "In1.Cu")
	)
	(gr_line
		(start 348.342458 -148.872448)
		(end 348.342458 -148.516848)
		(stroke
			(width 0.2)
			(type default)
		)
		(layer "In1.Cu")
	)
	(gr_arc
		(start 348.342458 -148.516848)
		(mid 348.282198 -148.371368)
		(end 348.136718 -148.311108)
		(stroke
			(width 0.2)
			(type default)
		)
		(layer "In1.Cu")
	)
	(gr_arc
		(start 348.438978 -155.476448)
		(mid 348.499238 -155.621928)
		(end 348.644718 -155.682188)
		(stroke
			(width 0.2)
			(type default)
		)
		(layer "In1.Cu")
	)
	(gr_line
		(start 348.438978 -155.120848)
		(end 348.438978 -155.476448)
		(stroke
			(width 0.2)
			(type default)
		)
		(layer "In1.Cu")
	)
	(gr_arc
		(start 348.438978 -154.333448)
		(mid 348.499238 -154.478928)
		(end 348.644718 -154.539188)
		(stroke
			(width 0.2)
			(type default)
		)
		(layer "In1.Cu")
	)
	(gr_line
		(start 348.438978 -153.977848)
		(end 348.438978 -154.333448)
		(stroke
			(width 0.2)
			(type default)
		)
		(layer "In1.Cu")
	)
	(gr_arc
		(start 348.438978 -153.190448)
		(mid 348.499238 -153.335928)
		(end 348.644718 -153.396188)
		(stroke
			(width 0.2)
			(type default)
		)
		(layer "In1.Cu")
	)
	(gr_line
		(start 348.438978 -152.834848)
		(end 348.438978 -153.190448)
		(stroke
			(width 0.2)
			(type default)
		)
		(layer "In1.Cu")
	)
	(gr_arc
		(start 348.438978 -152.047448)
		(mid 348.499238 -152.192928)
		(end 348.644718 -152.253188)
		(stroke
			(width 0.2)
			(type default)
		)
		(layer "In1.Cu")
	)
	(gr_line
		(start 348.438978 -151.691848)
		(end 348.438978 -152.047448)
		(stroke
			(width 0.2)
			(type default)
		)
		(layer "In1.Cu")
	)
	(gr_arc
		(start 348.438978 -150.015448)
		(mid 348.499238 -150.160928)
		(end 348.644718 -150.221188)
		(stroke
			(width 0.2)
			(type default)
		)
		(layer "In1.Cu")
	)
	(gr_line
		(start 348.438978 -149.659848)
		(end 348.438978 -150.015448)
		(stroke
			(width 0.2)
			(type default)
		)
		(layer "In1.Cu")
	)
	(gr_arc
		(start 348.438978 -148.872448)
		(mid 348.499238 -149.017928)
		(end 348.644718 -149.078188)
		(stroke
			(width 0.2)
			(type default)
		)
		(layer "In1.Cu")
	)
	(gr_line
		(start 348.438978 -148.516848)
		(end 348.438978 -148.872448)
		(stroke
			(width 0.2)
			(type default)
		)
		(layer "In1.Cu")
	)
	(gr_line
		(start 348.644718 -155.682188)
		(end 349.000318 -155.682188)
		(stroke
			(width 0.2)
			(type default)
		)
		(layer "In1.Cu")
	)
	(gr_arc
		(start 348.644718 -154.915108)
		(mid 348.499238 -154.975368)
		(end 348.438978 -155.120848)
		(stroke
			(width 0.2)
			(type default)
		)
		(layer "In1.Cu")
	)
	(gr_line
		(start 348.644718 -154.539188)
		(end 349.000318 -154.539188)
		(stroke
			(width 0.2)
			(type default)
		)
		(layer "In1.Cu")
	)
	(gr_arc
		(start 348.644718 -153.772108)
		(mid 348.499238 -153.832368)
		(end 348.438978 -153.977848)
		(stroke
			(width 0.2)
			(type default)
		)
		(layer "In1.Cu")
	)
	(gr_line
		(start 348.644718 -153.396188)
		(end 349.000318 -153.396188)
		(stroke
			(width 0.2)
			(type default)
		)
		(layer "In1.Cu")
	)
	(gr_arc
		(start 348.644718 -152.629108)
		(mid 348.499238 -152.689368)
		(end 348.438978 -152.834848)
		(stroke
			(width 0.2)
			(type default)
		)
		(layer "In1.Cu")
	)
	(gr_line
		(start 348.644718 -152.253188)
		(end 349.000318 -152.253188)
		(stroke
			(width 0.2)
			(type default)
		)
		(layer "In1.Cu")
	)
	(gr_arc
		(start 348.644718 -151.486108)
		(mid 348.499238 -151.546368)
		(end 348.438978 -151.691848)
		(stroke
			(width 0.2)
			(type default)
		)
		(layer "In1.Cu")
	)
	(gr_line
		(start 348.644718 -150.221188)
		(end 349.000318 -150.221188)
		(stroke
			(width 0.2)
			(type default)
		)
		(layer "In1.Cu")
	)
	(gr_arc
		(start 348.644718 -149.454108)
		(mid 348.499238 -149.514368)
		(end 348.438978 -149.659848)
		(stroke
			(width 0.2)
			(type default)
		)
		(layer "In1.Cu")
	)
	(gr_line
		(start 348.644718 -149.078188)
		(end 349.000318 -149.078188)
		(stroke
			(width 0.2)
			(type default)
		)
		(layer "In1.Cu")
	)
	(gr_arc
		(start 348.644718 -148.311108)
		(mid 348.499238 -148.371368)
		(end 348.438978 -148.516848)
		(stroke
			(width 0.2)
			(type default)
		)
		(layer "In1.Cu")
	)
	(gr_arc
		(start 349.000318 -155.682188)
		(mid 349.145798 -155.621928)
		(end 349.206058 -155.476448)
		(stroke
			(width 0.2)
			(type default)
		)
		(layer "In1.Cu")
	)
	(gr_line
		(start 349.000318 -154.915108)
		(end 348.644718 -154.915108)
		(stroke
			(width 0.2)
			(type default)
		)
		(layer "In1.Cu")
	)
	(gr_arc
		(start 349.000318 -154.539188)
		(mid 349.145798 -154.478928)
		(end 349.206058 -154.333448)
		(stroke
			(width 0.2)
			(type default)
		)
		(layer "In1.Cu")
	)
	(gr_line
		(start 349.000318 -153.772108)
		(end 348.644718 -153.772108)
		(stroke
			(width 0.2)
			(type default)
		)
		(layer "In1.Cu")
	)
	(gr_arc
		(start 349.000318 -153.396188)
		(mid 349.145798 -153.335928)
		(end 349.206058 -153.190448)
		(stroke
			(width 0.2)
			(type default)
		)
		(layer "In1.Cu")
	)
	(gr_line
		(start 349.000318 -152.629108)
		(end 348.644718 -152.629108)
		(stroke
			(width 0.2)
			(type default)
		)
		(layer "In1.Cu")
	)
	(gr_arc
		(start 349.000318 -152.253188)
		(mid 349.145798 -152.192928)
		(end 349.206058 -152.047448)
		(stroke
			(width 0.2)
			(type default)
		)
		(layer "In1.Cu")
	)
	(gr_line
		(start 349.000318 -151.486108)
		(end 348.644718 -151.486108)
		(stroke
			(width 0.2)
			(type default)
		)
		(layer "In1.Cu")
	)
	(gr_arc
		(start 349.000318 -150.221188)
		(mid 349.145798 -150.160928)
		(end 349.206058 -150.015448)
		(stroke
			(width 0.2)
			(type default)
		)
		(layer "In1.Cu")
	)
	(gr_line
		(start 349.000318 -149.454108)
		(end 348.644718 -149.454108)
		(stroke
			(width 0.2)
			(type default)
		)
		(layer "In1.Cu")
	)
	(gr_arc
		(start 349.000318 -149.078188)
		(mid 349.145798 -149.017928)
		(end 349.206058 -148.872448)
		(stroke
			(width 0.2)
			(type default)
		)
		(layer "In1.Cu")
	)
	(gr_line
		(start 349.000318 -148.311108)
		(end 348.644718 -148.311108)
		(stroke
			(width 0.2)
			(type default)
		)
		(layer "In1.Cu")
	)
	(gr_line
		(start 349.206058 -155.476448)
		(end 349.206058 -155.120848)
		(stroke
			(width 0.2)
			(type default)
		)
		(layer "In1.Cu")
	)
	(gr_arc
		(start 349.206058 -155.120848)
		(mid 349.145798 -154.975368)
		(end 349.000318 -154.915108)
		(stroke
			(width 0.2)
			(type default)
		)
		(layer "In1.Cu")
	)
	(gr_line
		(start 349.206058 -154.333448)
		(end 349.206058 -153.977848)
		(stroke
			(width 0.2)
			(type default)
		)
		(layer "In1.Cu")
	)
	(gr_arc
		(start 349.206058 -153.977848)
		(mid 349.145798 -153.832368)
		(end 349.000318 -153.772108)
		(stroke
			(width 0.2)
			(type default)
		)
		(layer "In1.Cu")
	)
	(gr_line
		(start 349.206058 -153.190448)
		(end 349.206058 -152.834848)
		(stroke
			(width 0.2)
			(type default)
		)
		(layer "In1.Cu")
	)
	(gr_arc
		(start 349.206058 -152.834848)
		(mid 349.145798 -152.689368)
		(end 349.000318 -152.629108)
		(stroke
			(width 0.2)
			(type default)
		)
		(layer "In1.Cu")
	)
	(gr_line
		(start 349.206058 -152.047448)
		(end 349.206058 -151.691848)
		(stroke
			(width 0.2)
			(type default)
		)
		(layer "In1.Cu")
	)
	(gr_arc
		(start 349.206058 -151.691848)
		(mid 349.145798 -151.546368)
		(end 349.000318 -151.486108)
		(stroke
			(width 0.2)
			(type default)
		)
		(layer "In1.Cu")
	)
	(gr_line
		(start 349.206058 -150.015448)
		(end 349.206058 -149.659848)
		(stroke
			(width 0.2)
			(type default)
		)
		(layer "In1.Cu")
	)
	(gr_arc
		(start 349.206058 -149.659848)
		(mid 349.145798 -149.514368)
		(end 349.000318 -149.454108)
		(stroke
			(width 0.2)
			(type default)
		)
		(layer "In1.Cu")
	)
	(gr_line
		(start 349.206058 -148.872448)
		(end 349.206058 -148.516848)
		(stroke
			(width 0.2)
			(type default)
		)
		(layer "In1.Cu")
	)
	(gr_arc
		(start 349.206058 -148.516848)
		(mid 349.145798 -148.371368)
		(end 349.000318 -148.311108)
		(stroke
			(width 0.2)
			(type default)
		)
		(layer "In1.Cu")
	)
	(gr_arc
		(start 349.652844 -155.154884)
		(mid 350.010857 -155.513278)
		(end 350.369124 -155.155138)
		(stroke
			(width 0.2)
			(type default)
		)
		(layer "In1.Cu")
	)
	(gr_line
		(start 349.652844 -154.275028)
		(end 349.652844 -155.154884)
		(stroke
			(width 0.2)
			(type default)
		)
		(layer "In1.Cu")
	)
	(gr_line
		(start 350.369124 -155.155138)
		(end 350.369124 -154.275028)
		(stroke
			(width 0.2)
			(type default)
		)
		(layer "In1.Cu")
	)
	(gr_arc
		(start 350.369124 -154.275028)
		(mid 350.010984 -153.916888)
		(end 349.652844 -154.275028)
		(stroke
			(width 0.2)
			(type default)
		)
		(layer "In1.Cu")
	)
	(gr_arc
		(start 350.39681 -152.916636)
		(mid 350.754823 -153.27503)
		(end 351.11309 -152.91689)
		(stroke
			(width 0.2)
			(type default)
		)
		(layer "In1.Cu")
	)
	(gr_line
		(start 350.39681 -151.97201)
		(end 350.39681 -152.916636)
		(stroke
			(width 0.2)
			(type default)
		)
		(layer "In1.Cu")
	)
	(gr_line
		(start 350.60001 -251.000006)
		(end 256.15011 -251.000006)
		(stroke
			(width 1.524)
			(type default)
		)
		(layer "In1.Cu")
	)
	(gr_arc
		(start 350.60001 -251.000006)
		(mid 354.135536 -249.53554)
		(end 355.6 -246.000016)
		(stroke
			(width 1.524)
			(type default)
		)
		(layer "In1.Cu")
	)
	(gr_line
		(start 350.87941 -147.98167)
		(end 351.824036 -147.98167)
		(stroke
			(width 0.2)
			(type default)
		)
		(layer "In1.Cu")
	)
	(gr_arc
		(start 350.87941 -147.26539)
		(mid 350.52127 -147.62353)
		(end 350.87941 -147.98167)
		(stroke
			(width 0.2)
			(type default)
		)
		(layer "In1.Cu")
	)
	(gr_line
		(start 351.11309 -152.91689)
		(end 351.11309 -151.97201)
		(stroke
			(width 0.2)
			(type default)
		)
		(layer "In1.Cu")
	)
	(gr_arc
		(start 351.11309 -151.97201)
		(mid 350.75495 -151.61387)
		(end 350.39681 -151.97201)
		(stroke
			(width 0.2)
			(type default)
		)
		(layer "In1.Cu")
	)
	(gr_arc
		(start 351.824036 -147.98167)
		(mid 352.18243 -147.623657)
		(end 351.82429 -147.26539)
		(stroke
			(width 0.2)
			(type default)
		)
		(layer "In1.Cu")
	)
	(gr_line
		(start 351.82429 -147.26539)
		(end 350.87941 -147.26539)
		(stroke
			(width 0.2)
			(type default)
		)
		(layer "In1.Cu")
	)
	(gr_arc
		(start 355.6 -0.999998)
		(mid 355.307107 -0.292893)
		(end 354.600002 0)
		(stroke
			(width 1.524)
			(type default)
		)
		(layer "In1.Cu")
	)
	(gr_line
		(start 355.6 -0.999998)
		(end 355.6 -246.000016)
		(stroke
			(width 1.524)
			(type default)
		)
		(layer "In1.Cu")
	)
	(gr_line
		(start 76.157074 -36.659312)
		(end 76.163678 -36.66617)
		(stroke
			(width 0.0508)
			(type default)
		)
		(layer "In2.Cu")
	)
	(gr_arc
		(start 76.410566 -37.2618)
		(mid 76.346365 -36.939428)
		(end 76.163678 -36.66617)
		(stroke
			(width 0.0508)
			(type default)
		)
		(layer "In2.Cu")
	)
	(gr_arc
		(start 76.7588 -36.9824)
		(mid 76.745485 -37.002328)
		(end 76.740766 -37.025834)
		(stroke
			(width 0.0508)
			(type default)
		)
		(layer "In2.Cu")
	)
	(gr_line
		(start 76.7588 -36.9824)
		(end 77.045058 -36.696142)
		(stroke
			(width 0.0508)
			(type default)
		)
		(layer "In2.Cu")
	)
	(gr_arc
		(start 77.133958 -36.659312)
		(mid 77.085843 -36.668883)
		(end 77.045058 -36.696142)
		(stroke
			(width 0.0508)
			(type default)
		)
		(layer "In2.Cu")
	)
	(gr_line
		(start 77.686408 -41.6052)
		(end 77.92339 -41.842436)
		(stroke
			(width 0.0508)
			(type default)
		)
		(layer "In2.Cu")
	)
	(gr_arc
		(start 78.1304 -42.3418)
		(mid 78.076561 -42.071529)
		(end 77.92339 -41.842436)
		(stroke
			(width 0.0508)
			(type default)
		)
		(layer "In2.Cu")
	)
	(gr_arc
		(start 78.663292 -41.6052)
		(mid 78.513242 -41.829765)
		(end 78.4606 -42.094658)
		(stroke
			(width 0.0508)
			(type default)
		)
		(layer "In2.Cu")
	)
	(gr_line
		(start 79.604108 -39.624)
		(end 79.776828 -39.796974)
		(stroke
			(width 0.0508)
			(type default)
		)
		(layer "In2.Cu")
	)
	(gr_line
		(start 79.915766 -45.139356)
		(end 79.915766 -45.682916)
		(stroke
			(width 0.0508)
			(type default)
		)
		(layer "In2.Cu")
	)
	(gr_line
		(start 79.915766 -43.625516)
		(end 79.915766 -44.169076)
		(stroke
			(width 0.0508)
			(type default)
		)
		(layer "In2.Cu")
	)
	(gr_line
		(start 79.915766 -42.111676)
		(end 79.915766 -42.655236)
		(stroke
			(width 0.0508)
			(type default)
		)
		(layer "In2.Cu")
	)
	(gr_arc
		(start 79.915766 -40.132)
		(mid 79.879617 -39.95067)
		(end 79.776828 -39.796974)
		(stroke
			(width 0.0508)
			(type default)
		)
		(layer "In2.Cu")
	)
	(gr_arc
		(start 80.245966 -44.806616)
		(mid 80.275205 -44.933277)
		(end 80.358996 -45.032676)
		(stroke
			(width 0.0508)
			(type default)
		)
		(layer "In2.Cu")
	)
	(gr_arc
		(start 80.245966 -43.292776)
		(mid 80.275205 -43.419437)
		(end 80.358996 -43.518836)
		(stroke
			(width 0.0508)
			(type default)
		)
		(layer "In2.Cu")
	)
	(gr_arc
		(start 80.245966 -41.778936)
		(mid 80.275205 -41.905597)
		(end 80.358996 -42.004996)
		(stroke
			(width 0.0508)
			(type default)
		)
		(layer "In2.Cu")
	)
	(gr_arc
		(start 80.358996 -45.789596)
		(mid 80.275159 -45.888972)
		(end 80.245966 -46.015656)
		(stroke
			(width 0.0508)
			(type default)
		)
		(layer "In2.Cu")
	)
	(gr_arc
		(start 80.358996 -45.789596)
		(mid 80.442767 -45.690198)
		(end 80.472026 -45.563536)
		(stroke
			(width 0.0508)
			(type default)
		)
		(layer "In2.Cu")
	)
	(gr_arc
		(start 80.358996 -44.275756)
		(mid 80.275159 -44.375132)
		(end 80.245966 -44.501816)
		(stroke
			(width 0.0508)
			(type default)
		)
		(layer "In2.Cu")
	)
	(gr_arc
		(start 80.358996 -44.275756)
		(mid 80.442788 -44.176362)
		(end 80.472026 -44.049696)
		(stroke
			(width 0.0508)
			(type default)
		)
		(layer "In2.Cu")
	)
	(gr_arc
		(start 80.358996 -42.761916)
		(mid 80.275159 -42.861292)
		(end 80.245966 -42.987976)
		(stroke
			(width 0.0508)
			(type default)
		)
		(layer "In2.Cu")
	)
	(gr_arc
		(start 80.358996 -42.761916)
		(mid 80.442774 -42.66252)
		(end 80.472026 -42.535856)
		(stroke
			(width 0.0508)
			(type default)
		)
		(layer "In2.Cu")
	)
	(gr_arc
		(start 80.368394 -39.836852)
		(mid 80.27783 -39.972252)
		(end 80.245966 -40.132)
		(stroke
			(width 0.0508)
			(type default)
		)
		(layer "In2.Cu")
	)
	(gr_line
		(start 80.368394 -39.836852)
		(end 80.580992 -39.624)
		(stroke
			(width 0.0508)
			(type default)
		)
		(layer "In2.Cu")
	)
	(gr_arc
		(start 80.472026 -45.258736)
		(mid 80.442829 -45.132046)
		(end 80.358996 -45.032676)
		(stroke
			(width 0.0508)
			(type default)
		)
		(layer "In2.Cu")
	)
	(gr_line
		(start 80.472026 -45.258736)
		(end 80.472026 -45.563536)
		(stroke
			(width 0.0508)
			(type default)
		)
		(layer "In2.Cu")
	)
	(gr_arc
		(start 80.472026 -43.744896)
		(mid 80.442851 -43.618188)
		(end 80.358996 -43.518836)
		(stroke
			(width 0.0508)
			(type default)
		)
		(layer "In2.Cu")
	)
	(gr_line
		(start 80.472026 -43.744896)
		(end 80.472026 -44.049696)
		(stroke
			(width 0.0508)
			(type default)
		)
		(layer "In2.Cu")
	)
	(gr_arc
		(start 80.472026 -42.231056)
		(mid 80.442837 -42.10436)
		(end 80.358996 -42.004996)
		(stroke
			(width 0.0508)
			(type default)
		)
		(layer "In2.Cu")
	)
	(gr_line
		(start 80.472026 -42.231056)
		(end 80.472026 -42.535856)
		(stroke
			(width 0.0508)
			(type default)
		)
		(layer "In2.Cu")
	)
	(gr_arc
		(start 82.02549 -48.769524)
		(mid 82.0586 -48.798355)
		(end 82.095848 -48.821594)
		(stroke
			(width 0.0508)
			(type default)
		)
		(layer "In2.Cu")
	)
	(gr_line
		(start 82.02676 -49.238408)
		(end 82.411316 -49.622964)
		(stroke
			(width 0.0508)
			(type default)
		)
		(layer "In2.Cu")
	)
	(gr_arc
		(start 82.095848 -48.821594)
		(mid 82.178337 -48.849007)
		(end 82.265266 -48.849534)
		(stroke
			(width 0.0508)
			(type default)
		)
		(layer "In2.Cu")
	)
	(gr_arc
		(start 82.505042 -48.92929)
		(mid 82.394787 -48.860444)
		(end 82.265266 -48.849534)
		(stroke
			(width 0.0508)
			(type default)
		)
		(layer "In2.Cu")
	)
	(gr_line
		(start 82.505042 -48.92929)
		(end 82.720688 -49.144936)
		(stroke
			(width 0.0508)
			(type default)
		)
		(layer "In2.Cu")
	)
	(gr_line
		(start 82.614516 -38.153594)
		(end 82.754978 -38.168326)
		(stroke
			(width 0.0508)
			(type default)
		)
		(layer "In2.Cu")
	)
	(gr_line
		(start 82.724752 -38.550342)
		(end 82.911188 -38.736778)
		(stroke
			(width 0.0508)
			(type default)
		)
		(layer "In2.Cu")
	)
	(gr_arc
		(start 82.754978 -38.168326)
		(mid 82.781464 -38.165095)
		(end 82.804 -38.1508)
		(stroke
			(width 0.0508)
			(type default)
		)
		(layer "In2.Cu")
	)
	(gr_arc
		(start 82.800444 -49.384712)
		(mid 82.789505 -49.255204)
		(end 82.720688 -49.144936)
		(stroke
			(width 0.0508)
			(type default)
		)
		(layer "In2.Cu")
	)
	(gr_arc
		(start 82.800444 -49.384712)
		(mid 82.811487 -49.514269)
		(end 82.880454 -49.624488)
		(stroke
			(width 0.0508)
			(type default)
		)
		(layer "In2.Cu")
	)
	(gr_arc
		(start 82.804 -38.1508)
		(mid 82.883346 -38.03205)
		(end 82.911188 -37.891974)
		(stroke
			(width 0.0508)
			(type default)
		)
		(layer "In2.Cu")
	)
	(gr_arc
		(start 82.868008 -40.84828)
		(mid 82.994711 -40.8191)
		(end 83.094068 -40.73525)
		(stroke
			(width 0.0508)
			(type default)
		)
		(layer "In2.Cu")
	)
	(gr_line
		(start 82.911188 -37.831776)
		(end 82.911188 -37.891974)
		(stroke
			(width 0.0508)
			(type default)
		)
		(layer "In2.Cu")
	)
	(gr_arc
		(start 83.0961 -49.840134)
		(mid 83.206236 -49.90893)
		(end 83.335622 -49.91989)
		(stroke
			(width 0.0508)
			(type default)
		)
		(layer "In2.Cu")
	)
	(gr_line
		(start 83.097624 -50.309272)
		(end 83.481672 -50.69332)
		(stroke
			(width 0.0508)
			(type default)
		)
		(layer "In2.Cu")
	)
	(gr_line
		(start 83.200748 -41.17848)
		(end 83.744308 -41.17848)
		(stroke
			(width 0.0508)
			(type default)
		)
		(layer "In2.Cu")
	)
	(gr_arc
		(start 83.320128 -40.62222)
		(mid 83.193467 -40.651459)
		(end 83.094068 -40.73525)
		(stroke
			(width 0.0508)
			(type default)
		)
		(layer "In2.Cu")
	)
	(gr_line
		(start 83.320128 -40.62222)
		(end 83.624928 -40.62222)
		(stroke
			(width 0.0508)
			(type default)
		)
		(layer "In2.Cu")
	)
	(gr_arc
		(start 83.575398 -49.9999)
		(mid 83.465173 -49.930928)
		(end 83.335622 -49.91989)
		(stroke
			(width 0.0508)
			(type default)
		)
		(layer "In2.Cu")
	)
	(gr_line
		(start 83.575398 -49.9999)
		(end 83.791044 -50.215292)
		(stroke
			(width 0.0508)
			(type default)
		)
		(layer "In2.Cu")
	)
	(gr_arc
		(start 83.850988 -40.73525)
		(mid 83.751612 -40.651413)
		(end 83.624928 -40.62222)
		(stroke
			(width 0.0508)
			(type default)
		)
		(layer "In2.Cu")
	)
	(gr_arc
		(start 83.850988 -40.73525)
		(mid 83.950381 -40.81904)
		(end 84.077048 -40.84828)
		(stroke
			(width 0.0508)
			(type default)
		)
		(layer "In2.Cu")
	)
	(gr_arc
		(start 83.871054 -50.455068)
		(mid 83.859998 -50.325515)
		(end 83.791044 -50.215292)
		(stroke
			(width 0.0508)
			(type default)
		)
		(layer "In2.Cu")
	)
	(gr_arc
		(start 83.871054 -50.455068)
		(mid 83.881971 -50.58459)
		(end 83.95081 -50.694844)
		(stroke
			(width 0.0508)
			(type default)
		)
		(layer "In2.Cu")
	)
	(gr_arc
		(start 84.166456 -50.91049)
		(mid 84.276686 -50.979424)
		(end 84.406232 -50.9905)
		(stroke
			(width 0.0508)
			(type default)
		)
		(layer "In2.Cu")
	)
	(gr_line
		(start 84.16798 -51.379628)
		(end 84.552282 -51.76393)
		(stroke
			(width 0.0508)
			(type default)
		)
		(layer "In2.Cu")
	)
	(gr_arc
		(start 84.646008 -51.070256)
		(mid 84.535755 -51.001408)
		(end 84.406232 -50.9905)
		(stroke
			(width 0.0508)
			(type default)
		)
		(layer "In2.Cu")
	)
	(gr_line
		(start 84.646008 -51.070256)
		(end 84.8614 -51.285902)
		(stroke
			(width 0.0508)
			(type default)
		)
		(layer "In2.Cu")
	)
	(gr_arc
		(start 84.94141 -51.525678)
		(mid 84.930384 -51.396123)
		(end 84.8614 -51.285902)
		(stroke
			(width 0.0508)
			(type default)
		)
		(layer "In2.Cu")
	)
	(gr_arc
		(start 84.94141 -51.525678)
		(mid 84.95246 -51.655223)
		(end 85.02142 -51.765454)
		(stroke
			(width 0.0508)
			(type default)
		)
		(layer "In2.Cu")
	)
	(gr_line
		(start 85.249766 -45.443394)
		(end 85.249766 -45.986954)
		(stroke
			(width 0.0508)
			(type default)
		)
		(layer "In2.Cu")
	)
	(gr_line
		(start 85.249766 -43.929554)
		(end 85.249766 -44.473114)
		(stroke
			(width 0.0508)
			(type default)
		)
		(layer "In2.Cu")
	)
	(gr_arc
		(start 85.579966 -45.110654)
		(mid 85.609166 -45.237339)
		(end 85.692996 -45.336714)
		(stroke
			(width 0.0508)
			(type default)
		)
		(layer "In2.Cu")
	)
	(gr_arc
		(start 85.579966 -43.596814)
		(mid 85.609151 -43.723511)
		(end 85.692996 -43.822874)
		(stroke
			(width 0.0508)
			(type default)
		)
		(layer "In2.Cu")
	)
	(gr_arc
		(start 85.692996 -46.093634)
		(mid 85.609202 -46.193028)
		(end 85.579966 -46.319694)
		(stroke
			(width 0.0508)
			(type default)
		)
		(layer "In2.Cu")
	)
	(gr_arc
		(start 85.692996 -46.093634)
		(mid 85.776833 -45.994258)
		(end 85.806026 -45.867574)
		(stroke
			(width 0.0508)
			(type default)
		)
		(layer "In2.Cu")
	)
	(gr_arc
		(start 85.692996 -44.579794)
		(mid 85.609224 -44.679192)
		(end 85.579966 -44.805854)
		(stroke
			(width 0.0508)
			(type default)
		)
		(layer "In2.Cu")
	)
	(gr_arc
		(start 85.692996 -44.579794)
		(mid 85.776833 -44.480418)
		(end 85.806026 -44.353734)
		(stroke
			(width 0.0508)
			(type default)
		)
		(layer "In2.Cu")
	)
	(gr_arc
		(start 85.806026 -45.562774)
		(mid 85.776787 -45.436113)
		(end 85.692996 -45.336714)
		(stroke
			(width 0.0508)
			(type default)
		)
		(layer "In2.Cu")
	)
	(gr_line
		(start 85.806026 -45.562774)
		(end 85.806026 -45.867574)
		(stroke
			(width 0.0508)
			(type default)
		)
		(layer "In2.Cu")
	)
	(gr_arc
		(start 85.806026 -44.048934)
		(mid 85.776787 -43.922273)
		(end 85.692996 -43.822874)
		(stroke
			(width 0.0508)
			(type default)
		)
		(layer "In2.Cu")
	)
	(gr_line
		(start 85.806026 -44.048934)
		(end 85.806026 -44.353734)
		(stroke
			(width 0.0508)
			(type default)
		)
		(layer "In2.Cu")
	)
	(gr_arc
		(start 86.143338 -55.808372)
		(mid 86.253593 -55.877208)
		(end 86.383114 -55.888128)
		(stroke
			(width 0.0508)
			(type default)
		)
		(layer "In2.Cu")
	)
	(gr_line
		(start 86.144862 -56.277256)
		(end 86.529418 -56.661812)
		(stroke
			(width 0.0508)
			(type default)
		)
		(layer "In2.Cu")
	)
	(gr_arc
		(start 86.62289 -55.968138)
		(mid 86.512667 -55.89916)
		(end 86.383114 -55.888128)
		(stroke
			(width 0.0508)
			(type default)
		)
		(layer "In2.Cu")
	)
	(gr_line
		(start 86.62289 -55.968138)
		(end 86.838282 -56.183784)
		(stroke
			(width 0.0508)
			(type default)
		)
		(layer "In2.Cu")
	)
	(gr_arc
		(start 86.918292 -56.42356)
		(mid 86.907258 -56.29401)
		(end 86.838282 -56.183784)
		(stroke
			(width 0.0508)
			(type default)
		)
		(layer "In2.Cu")
	)
	(gr_arc
		(start 86.918292 -56.42356)
		(mid 86.929342 -56.553105)
		(end 86.998302 -56.663336)
		(stroke
			(width 0.0508)
			(type default)
		)
		(layer "In2.Cu")
	)
	(gr_arc
		(start 87.213694 -56.878728)
		(mid 87.323924 -56.947662)
		(end 87.45347 -56.958738)
		(stroke
			(width 0.0508)
			(type default)
		)
		(layer "In2.Cu")
	)
	(gr_line
		(start 87.215218 -57.347612)
		(end 87.599774 -57.732168)
		(stroke
			(width 0.0508)
			(type default)
		)
		(layer "In2.Cu")
	)
	(gr_line
		(start 87.544402 -51.199796)
		(end 88.34501 -52.000404)
		(stroke
			(width 0.0508)
			(type default)
		)
		(layer "In2.Cu")
	)
	(gr_arc
		(start 87.693246 -57.038494)
		(mid 87.582991 -56.969645)
		(end 87.45347 -56.958738)
		(stroke
			(width 0.0508)
			(type default)
		)
		(layer "In2.Cu")
	)
	(gr_line
		(start 87.693246 -57.038494)
		(end 87.908892 -57.25414)
		(stroke
			(width 0.0508)
			(type default)
		)
		(layer "In2.Cu")
	)
	(gr_arc
		(start 87.750904 -50.938938)
		(mid 87.861126 -51.007925)
		(end 87.99068 -51.018948)
		(stroke
			(width 0.0508)
			(type default)
		)
		(layer "In2.Cu")
	)
	(gr_arc
		(start 87.988648 -57.493916)
		(mid 87.977711 -57.364407)
		(end 87.908892 -57.25414)
		(stroke
			(width 0.0508)
			(type default)
		)
		(layer "In2.Cu")
	)
	(gr_arc
		(start 87.988648 -57.493916)
		(mid 87.999691 -57.623473)
		(end 88.068658 -57.733692)
		(stroke
			(width 0.0508)
			(type default)
		)
		(layer "In2.Cu")
	)
	(gr_arc
		(start 88.230456 -51.098704)
		(mid 88.120201 -51.029868)
		(end 87.99068 -51.018948)
		(stroke
			(width 0.0508)
			(type default)
		)
		(layer "In2.Cu")
	)
	(gr_line
		(start 88.230456 -51.098704)
		(end 88.446102 -51.31435)
		(stroke
			(width 0.0508)
			(type default)
		)
		(layer "In2.Cu")
	)
	(gr_arc
		(start 88.28405 -57.949084)
		(mid 88.394269 -58.018081)
		(end 88.523826 -58.029094)
		(stroke
			(width 0.0508)
			(type default)
		)
		(layer "In2.Cu")
	)
	(gr_line
		(start 88.285574 -58.417968)
		(end 88.67013 -58.802524)
		(stroke
			(width 0.0508)
			(type default)
		)
		(layer "In2.Cu")
	)
	(gr_arc
		(start 88.525858 -51.554126)
		(mid 88.514941 -51.424604)
		(end 88.446102 -51.31435)
		(stroke
			(width 0.0508)
			(type default)
		)
		(layer "In2.Cu")
	)
	(gr_arc
		(start 88.525858 -51.554126)
		(mid 88.536912 -51.68368)
		(end 88.605868 -51.793902)
		(stroke
			(width 0.0508)
			(type default)
		)
		(layer "In2.Cu")
	)
	(gr_line
		(start 88.614758 -52.270152)
		(end 89.415366 -53.07076)
		(stroke
			(width 0.0508)
			(type default)
		)
		(layer "In2.Cu")
	)
	(gr_arc
		(start 88.763602 -58.109104)
		(mid 88.653377 -58.040129)
		(end 88.523826 -58.029094)
		(stroke
			(width 0.0508)
			(type default)
		)
		(layer "In2.Cu")
	)
	(gr_line
		(start 88.763602 -58.109104)
		(end 88.979248 -58.324496)
		(stroke
			(width 0.0508)
			(type default)
		)
		(layer "In2.Cu")
	)
	(gr_arc
		(start 88.82126 -52.009294)
		(mid 88.931486 -52.078244)
		(end 89.061036 -52.089304)
		(stroke
			(width 0.0508)
			(type default)
		)
		(layer "In2.Cu")
	)
	(gr_arc
		(start 89.059258 -58.564272)
		(mid 89.048203 -58.434718)
		(end 88.979248 -58.324496)
		(stroke
			(width 0.0508)
			(type default)
		)
		(layer "In2.Cu")
	)
	(gr_arc
		(start 89.059258 -58.564272)
		(mid 89.070175 -58.693794)
		(end 89.139014 -58.804048)
		(stroke
			(width 0.0508)
			(type default)
		)
		(layer "In2.Cu")
	)
	(gr_arc
		(start 89.300812 -52.169314)
		(mid 89.190593 -52.100317)
		(end 89.061036 -52.089304)
		(stroke
			(width 0.0508)
			(type default)
		)
		(layer "In2.Cu")
	)
	(gr_line
		(start 89.300812 -52.169314)
		(end 89.516458 -52.384706)
		(stroke
			(width 0.0508)
			(type default)
		)
		(layer "In2.Cu")
	)
	(gr_arc
		(start 89.596468 -52.624482)
		(mid 89.585425 -52.494925)
		(end 89.516458 -52.384706)
		(stroke
			(width 0.0508)
			(type default)
		)
		(layer "In2.Cu")
	)
	(gr_arc
		(start 89.596468 -52.624482)
		(mid 89.607404 -52.753991)
		(end 89.676224 -52.864258)
		(stroke
			(width 0.0508)
			(type default)
		)
		(layer "In2.Cu")
	)
	(gr_arc
		(start 89.720166 -56.4642)
		(mid 89.830421 -56.533036)
		(end 89.959942 -56.543956)
		(stroke
			(width 0.0508)
			(type default)
		)
		(layer "In2.Cu")
	)
	(gr_line
		(start 89.72169 -56.933084)
		(end 90.106246 -57.31764)
		(stroke
			(width 0.0508)
			(type default)
		)
		(layer "In2.Cu")
	)
	(gr_arc
		(start 90.199718 -56.623966)
		(mid 90.089494 -56.55501)
		(end 89.959942 -56.543956)
		(stroke
			(width 0.0508)
			(type default)
		)
		(layer "In2.Cu")
	)
	(gr_line
		(start 90.199718 -56.623966)
		(end 90.41511 -56.839612)
		(stroke
			(width 0.0508)
			(type default)
		)
		(layer "In2.Cu")
	)
	(gr_arc
		(start 90.49512 -57.079388)
		(mid 90.484099 -56.94983)
		(end 90.41511 -56.839612)
		(stroke
			(width 0.0508)
			(type default)
		)
		(layer "In2.Cu")
	)
	(gr_arc
		(start 90.49512 -57.079388)
		(mid 90.50617 -57.208933)
		(end 90.57513 -57.319164)
		(stroke
			(width 0.0508)
			(type default)
		)
		(layer "In2.Cu")
	)
	(gr_line
		(start 90.668856 -54.32425)
		(end 91.469464 -55.124858)
		(stroke
			(width 0.0508)
			(type default)
		)
		(layer "In2.Cu")
	)
	(gr_arc
		(start 90.687652 -60.352686)
		(mid 90.797907 -60.421522)
		(end 90.927428 -60.432442)
		(stroke
			(width 0.0508)
			(type default)
		)
		(layer "In2.Cu")
	)
	(gr_line
		(start 90.689176 -60.82157)
		(end 91.073732 -61.206126)
		(stroke
			(width 0.0508)
			(type default)
		)
		(layer "In2.Cu")
	)
	(gr_arc
		(start 90.790522 -57.534556)
		(mid 90.900752 -57.60349)
		(end 91.030298 -57.614566)
		(stroke
			(width 0.0508)
			(type default)
		)
		(layer "In2.Cu")
	)
	(gr_line
		(start 90.792046 -58.00344)
		(end 91.176602 -58.387996)
		(stroke
			(width 0.0508)
			(type default)
		)
		(layer "In2.Cu")
	)
	(gr_arc
		(start 90.875612 -54.063646)
		(mid 90.985756 -54.132397)
		(end 91.115134 -54.143402)
		(stroke
			(width 0.0508)
			(type default)
		)
		(layer "In2.Cu")
	)
	(gr_arc
		(start 91.167204 -60.512452)
		(mid 91.056979 -60.443505)
		(end 90.927428 -60.432442)
		(stroke
			(width 0.0508)
			(type default)
		)
		(layer "In2.Cu")
	)
	(gr_line
		(start 91.167204 -60.512452)
		(end 91.382596 -60.728098)
		(stroke
			(width 0.0508)
			(type default)
		)
		(layer "In2.Cu")
	)
	(gr_arc
		(start 91.270074 -57.694322)
		(mid 91.159819 -57.625496)
		(end 91.030298 -57.614566)
		(stroke
			(width 0.0508)
			(type default)
		)
		(layer "In2.Cu")
	)
	(gr_line
		(start 91.270074 -57.694322)
		(end 91.48572 -57.909968)
		(stroke
			(width 0.0508)
			(type default)
		)
		(layer "In2.Cu")
	)
	(gr_arc
		(start 91.35491 -54.223412)
		(mid 91.244691 -54.154415)
		(end 91.115134 -54.143402)
		(stroke
			(width 0.0508)
			(type default)
		)
		(layer "In2.Cu")
	)
	(gr_line
		(start 91.35491 -54.223412)
		(end 91.570556 -54.438804)
		(stroke
			(width 0.0508)
			(type default)
		)
		(layer "In2.Cu")
	)
	(gr_arc
		(start 91.462606 -60.967874)
		(mid 91.451578 -60.83832)
		(end 91.382596 -60.728098)
		(stroke
			(width 0.0508)
			(type default)
		)
		(layer "In2.Cu")
	)
	(gr_arc
		(start 91.462606 -60.967874)
		(mid 91.473656 -61.097419)
		(end 91.542616 -61.20765)
		(stroke
			(width 0.0508)
			(type default)
		)
		(layer "In2.Cu")
	)
	(gr_arc
		(start 91.565476 -58.149744)
		(mid 91.554551 -58.020226)
		(end 91.48572 -57.909968)
		(stroke
			(width 0.0508)
			(type default)
		)
		(layer "In2.Cu")
	)
	(gr_arc
		(start 91.565476 -58.149744)
		(mid 91.576519 -58.279301)
		(end 91.645486 -58.38952)
		(stroke
			(width 0.0508)
			(type default)
		)
		(layer "In2.Cu")
	)
	(gr_arc
		(start 91.650566 -54.67858)
		(mid 91.639523 -54.549023)
		(end 91.570556 -54.438804)
		(stroke
			(width 0.0508)
			(type default)
		)
		(layer "In2.Cu")
	)
	(gr_arc
		(start 91.650566 -54.67858)
		(mid 91.661502 -54.80809)
		(end 91.730322 -54.918356)
		(stroke
			(width 0.0508)
			(type default)
		)
		(layer "In2.Cu")
	)
	(gr_line
		(start 91.739466 -55.39486)
		(end 92.540074 -56.195468)
		(stroke
			(width 0.0508)
			(type default)
		)
		(layer "In2.Cu")
	)
	(gr_arc
		(start 91.758008 -61.423042)
		(mid 91.868238 -61.491976)
		(end 91.997784 -61.503052)
		(stroke
			(width 0.0508)
			(type default)
		)
		(layer "In2.Cu")
	)
	(gr_line
		(start 91.759532 -61.891926)
		(end 92.144088 -62.276482)
		(stroke
			(width 0.0508)
			(type default)
		)
		(layer "In2.Cu")
	)
	(gr_arc
		(start 91.860878 -58.604912)
		(mid 91.971097 -58.673909)
		(end 92.100654 -58.684922)
		(stroke
			(width 0.0508)
			(type default)
		)
		(layer "In2.Cu")
	)
	(gr_line
		(start 91.862402 -59.073796)
		(end 92.246958 -59.458352)
		(stroke
			(width 0.0508)
			(type default)
		)
		(layer "In2.Cu")
	)
	(gr_arc
		(start 91.945968 -55.134002)
		(mid 92.05619 -55.202971)
		(end 92.185744 -55.214012)
		(stroke
			(width 0.0508)
			(type default)
		)
		(layer "In2.Cu")
	)
	(gr_arc
		(start 92.23756 -61.582808)
		(mid 92.127306 -61.51395)
		(end 91.997784 -61.503052)
		(stroke
			(width 0.0508)
			(type default)
		)
		(layer "In2.Cu")
	)
	(gr_line
		(start 92.23756 -61.582808)
		(end 92.453206 -61.798454)
		(stroke
			(width 0.0508)
			(type default)
		)
		(layer "In2.Cu")
	)
	(gr_arc
		(start 92.34043 -58.764932)
		(mid 92.230203 -58.695963)
		(end 92.100654 -58.684922)
		(stroke
			(width 0.0508)
			(type default)
		)
		(layer "In2.Cu")
	)
	(gr_line
		(start 92.34043 -58.764932)
		(end 92.556076 -58.980324)
		(stroke
			(width 0.0508)
			(type default)
		)
		(layer "In2.Cu")
	)
	(gr_arc
		(start 92.42552 -55.293768)
		(mid 92.315265 -55.224932)
		(end 92.185744 -55.214012)
		(stroke
			(width 0.0508)
			(type default)
		)
		(layer "In2.Cu")
	)
	(gr_line
		(start 92.42552 -55.293768)
		(end 92.640912 -55.509414)
		(stroke
			(width 0.0508)
			(type default)
		)
		(layer "In2.Cu")
	)
	(gr_arc
		(start 92.532962 -62.03823)
		(mid 92.522031 -61.908716)
		(end 92.453206 -61.798454)
		(stroke
			(width 0.0508)
			(type default)
		)
		(layer "In2.Cu")
	)
	(gr_arc
		(start 92.532962 -62.03823)
		(mid 92.544005 -62.167787)
		(end 92.612972 -62.278006)
		(stroke
			(width 0.0508)
			(type default)
		)
		(layer "In2.Cu")
	)
	(gr_arc
		(start 92.636086 -59.2201)
		(mid 92.625002 -59.090563)
		(end 92.556076 -58.980324)
		(stroke
			(width 0.0508)
			(type default)
		)
		(layer "In2.Cu")
	)
	(gr_arc
		(start 92.636086 -59.2201)
		(mid 92.647003 -59.349622)
		(end 92.715842 -59.459876)
		(stroke
			(width 0.0508)
			(type default)
		)
		(layer "In2.Cu")
	)
	(gr_arc
		(start 92.720922 -55.74919)
		(mid 92.709872 -55.619645)
		(end 92.640912 -55.509414)
		(stroke
			(width 0.0508)
			(type default)
		)
		(layer "In2.Cu")
	)
	(gr_arc
		(start 92.720922 -55.74919)
		(mid 92.731936 -55.878752)
		(end 92.800932 -55.988966)
		(stroke
			(width 0.0508)
			(type default)
		)
		(layer "In2.Cu")
	)
	(gr_line
		(start 92.809568 -56.465216)
		(end 93.611192 -57.267094)
		(stroke
			(width 0.0508)
			(type default)
		)
		(layer "In2.Cu")
	)
	(gr_arc
		(start 92.828364 -62.493398)
		(mid 92.938583 -62.562395)
		(end 93.06814 -62.573408)
		(stroke
			(width 0.0508)
			(type default)
		)
		(layer "In2.Cu")
	)
	(gr_line
		(start 92.829888 -62.962282)
		(end 93.214444 -63.346838)
		(stroke
			(width 0.0508)
			(type default)
		)
		(layer "In2.Cu")
	)
	(gr_arc
		(start 93.016324 -56.204358)
		(mid 93.126552 -56.273307)
		(end 93.2561 -56.284368)
		(stroke
			(width 0.0508)
			(type default)
		)
		(layer "In2.Cu")
	)
	(gr_arc
		(start 93.307916 -62.653418)
		(mid 93.197692 -62.584434)
		(end 93.06814 -62.573408)
		(stroke
			(width 0.0508)
			(type default)
		)
		(layer "In2.Cu")
	)
	(gr_line
		(start 93.307916 -62.653418)
		(end 93.523562 -62.86881)
		(stroke
			(width 0.0508)
			(type default)
		)
		(layer "In2.Cu")
	)
	(gr_arc
		(start 93.495876 -56.364378)
		(mid 93.385657 -56.295381)
		(end 93.2561 -56.284368)
		(stroke
			(width 0.0508)
			(type default)
		)
		(layer "In2.Cu")
	)
	(gr_line
		(start 93.495876 -56.364378)
		(end 93.711522 -56.57977)
		(stroke
			(width 0.0508)
			(type default)
		)
		(layer "In2.Cu")
	)
	(gr_arc
		(start 93.603572 -63.108586)
		(mid 93.592482 -62.979053)
		(end 93.523562 -62.86881)
		(stroke
			(width 0.0508)
			(type default)
		)
		(layer "In2.Cu")
	)
	(gr_arc
		(start 93.603572 -63.108586)
		(mid 93.614489 -63.238108)
		(end 93.683328 -63.348362)
		(stroke
			(width 0.0508)
			(type default)
		)
		(layer "In2.Cu")
	)
	(gr_arc
		(start 93.791278 -56.819546)
		(mid 93.780361 -56.690024)
		(end 93.711522 -56.57977)
		(stroke
			(width 0.0508)
			(type default)
		)
		(layer "In2.Cu")
	)
	(gr_arc
		(start 93.791278 -56.819546)
		(mid 93.802272 -56.94912)
		(end 93.871288 -57.059322)
		(stroke
			(width 0.0508)
			(type default)
		)
		(layer "In2.Cu")
	)
	(gr_arc
		(start 95.081852 -61.825886)
		(mid 95.192107 -61.894722)
		(end 95.321628 -61.905642)
		(stroke
			(width 0.0508)
			(type default)
		)
		(layer "In2.Cu")
	)
	(gr_line
		(start 95.08363 -62.29477)
		(end 95.467932 -62.679072)
		(stroke
			(width 0.0508)
			(type default)
		)
		(layer "In2.Cu")
	)
	(gr_line
		(start 95.497142 -59.15279)
		(end 96.29902 -59.954668)
		(stroke
			(width 0.0508)
			(type default)
		)
		(layer "In2.Cu")
	)
	(gr_arc
		(start 95.561404 -61.985652)
		(mid 95.451179 -61.916705)
		(end 95.321628 -61.905642)
		(stroke
			(width 0.0508)
			(type default)
		)
		(layer "In2.Cu")
	)
	(gr_line
		(start 95.561404 -61.985652)
		(end 95.776796 -62.201298)
		(stroke
			(width 0.0508)
			(type default)
		)
		(layer "In2.Cu")
	)
	(gr_arc
		(start 95.61068 -65.275714)
		(mid 95.720935 -65.34455)
		(end 95.850456 -65.35547)
		(stroke
			(width 0.0508)
			(type default)
		)
		(layer "In2.Cu")
	)
	(gr_line
		(start 95.612204 -65.744598)
		(end 95.99676 -66.129154)
		(stroke
			(width 0.0508)
			(type default)
		)
		(layer "In2.Cu")
	)
	(gr_arc
		(start 95.705168 -58.893202)
		(mid 95.815423 -58.962046)
		(end 95.944944 -58.972958)
		(stroke
			(width 0.0508)
			(type default)
		)
		(layer "In2.Cu")
	)
	(gr_arc
		(start 95.856806 -62.441074)
		(mid 95.845778 -62.31152)
		(end 95.776796 -62.201298)
		(stroke
			(width 0.0508)
			(type default)
		)
		(layer "In2.Cu")
	)
	(gr_arc
		(start 95.856806 -62.441074)
		(mid 95.867856 -62.570619)
		(end 95.936816 -62.68085)
		(stroke
			(width 0.0508)
			(type default)
		)
		(layer "In2.Cu")
	)
	(gr_arc
		(start 96.090232 -65.43548)
		(mid 95.980009 -65.366515)
		(end 95.850456 -65.35547)
		(stroke
			(width 0.0508)
			(type default)
		)
		(layer "In2.Cu")
	)
	(gr_line
		(start 96.090232 -65.43548)
		(end 96.305624 -65.651126)
		(stroke
			(width 0.0508)
			(type default)
		)
		(layer "In2.Cu")
	)
	(gr_arc
		(start 96.152208 -62.896242)
		(mid 96.262438 -62.965176)
		(end 96.391984 -62.976252)
		(stroke
			(width 0.0508)
			(type default)
		)
		(layer "In2.Cu")
	)
	(gr_line
		(start 96.153986 -63.365126)
		(end 96.538288 -63.749428)
		(stroke
			(width 0.0508)
			(type default)
		)
		(layer "In2.Cu")
	)
	(gr_arc
		(start 96.18472 -59.052968)
		(mid 96.07449 -58.984034)
		(end 95.944944 -58.972958)
		(stroke
			(width 0.0508)
			(type default)
		)
		(layer "In2.Cu")
	)
	(gr_line
		(start 96.18472 -59.052968)
		(end 96.400112 -59.268614)
		(stroke
			(width 0.0508)
			(type default)
		)
		(layer "In2.Cu")
	)
	(gr_arc
		(start 96.385634 -65.890902)
		(mid 96.374619 -65.76134)
		(end 96.305624 -65.651126)
		(stroke
			(width 0.0508)
			(type default)
		)
		(layer "In2.Cu")
	)
	(gr_arc
		(start 96.385634 -65.890902)
		(mid 96.396684 -66.020447)
		(end 96.465644 -66.130678)
		(stroke
			(width 0.0508)
			(type default)
		)
		(layer "In2.Cu")
	)
	(gr_arc
		(start 96.480122 -59.50839)
		(mid 96.469079 -59.378833)
		(end 96.400112 -59.268614)
		(stroke
			(width 0.0508)
			(type default)
		)
		(layer "In2.Cu")
	)
	(gr_arc
		(start 96.480122 -59.50839)
		(mid 96.49106 -59.637899)
		(end 96.559878 -59.748166)
		(stroke
			(width 0.0508)
			(type default)
		)
		(layer "In2.Cu")
	)
	(gr_line
		(start 96.567498 -60.2234)
		(end 97.371408 -61.02731)
		(stroke
			(width 0.0508)
			(type default)
		)
		(layer "In2.Cu")
	)
	(gr_arc
		(start 96.63176 -63.056008)
		(mid 96.521506 -62.98715)
		(end 96.391984 -62.976252)
		(stroke
			(width 0.0508)
			(type default)
		)
		(layer "In2.Cu")
	)
	(gr_line
		(start 96.63176 -63.056008)
		(end 96.847406 -63.271654)
		(stroke
			(width 0.0508)
			(type default)
		)
		(layer "In2.Cu")
	)
	(gr_arc
		(start 96.681036 -66.34607)
		(mid 96.791266 -66.415004)
		(end 96.920812 -66.42608)
		(stroke
			(width 0.0508)
			(type default)
		)
		(layer "In2.Cu")
	)
	(gr_line
		(start 96.68256 -66.814954)
		(end 97.067116 -67.19951)
		(stroke
			(width 0.0508)
			(type default)
		)
		(layer "In2.Cu")
	)
	(gr_arc
		(start 96.775524 -59.963558)
		(mid 96.885752 -60.032507)
		(end 97.0153 -60.043568)
		(stroke
			(width 0.0508)
			(type default)
		)
		(layer "In2.Cu")
	)
	(gr_arc
		(start 96.927162 -63.51143)
		(mid 96.916231 -63.381916)
		(end 96.847406 -63.271654)
		(stroke
			(width 0.0508)
			(type default)
		)
		(layer "In2.Cu")
	)
	(gr_arc
		(start 96.927162 -63.51143)
		(mid 96.938205 -63.640987)
		(end 97.007172 -63.751206)
		(stroke
			(width 0.0508)
			(type default)
		)
		(layer "In2.Cu")
	)
	(gr_arc
		(start 97.160588 -66.505836)
		(mid 97.050334 -66.437001)
		(end 96.920812 -66.42608)
		(stroke
			(width 0.0508)
			(type default)
		)
		(layer "In2.Cu")
	)
	(gr_line
		(start 97.160588 -66.505836)
		(end 97.376234 -66.721482)
		(stroke
			(width 0.0508)
			(type default)
		)
		(layer "In2.Cu")
	)
	(gr_arc
		(start 97.222564 -63.966598)
		(mid 97.332783 -64.035595)
		(end 97.46234 -64.046608)
		(stroke
			(width 0.0508)
			(type default)
		)
		(layer "In2.Cu")
	)
	(gr_line
		(start 97.224342 -64.435482)
		(end 97.608644 -64.819784)
		(stroke
			(width 0.0508)
			(type default)
		)
		(layer "In2.Cu")
	)
	(gr_arc
		(start 97.255076 -60.123578)
		(mid 97.144857 -60.054581)
		(end 97.0153 -60.043568)
		(stroke
			(width 0.0508)
			(type default)
		)
		(layer "In2.Cu")
	)
	(gr_line
		(start 97.255076 -60.123578)
		(end 97.470468 -60.33897)
		(stroke
			(width 0.0508)
			(type default)
		)
		(layer "In2.Cu")
	)
	(gr_arc
		(start 97.45599 -66.961258)
		(mid 97.445072 -66.831736)
		(end 97.376234 -66.721482)
		(stroke
			(width 0.0508)
			(type default)
		)
		(layer "In2.Cu")
	)
	(gr_arc
		(start 97.45599 -66.961258)
		(mid 97.467033 -67.090815)
		(end 97.536 -67.201034)
		(stroke
			(width 0.0508)
			(type default)
		)
		(layer "In2.Cu")
	)
	(gr_arc
		(start 97.550478 -60.578746)
		(mid 97.539428 -60.449201)
		(end 97.470468 -60.33897)
		(stroke
			(width 0.0508)
			(type default)
		)
		(layer "In2.Cu")
	)
	(gr_arc
		(start 97.550478 -60.578746)
		(mid 97.561472 -60.70832)
		(end 97.630488 -60.818522)
		(stroke
			(width 0.0508)
			(type default)
		)
		(layer "In2.Cu")
	)
	(gr_line
		(start 97.638362 -61.294264)
		(end 98.231706 -61.887608)
		(stroke
			(width 0.0508)
			(type default)
		)
		(layer "In2.Cu")
	)
	(gr_arc
		(start 97.702116 -64.126618)
		(mid 97.591892 -64.057634)
		(end 97.46234 -64.046608)
		(stroke
			(width 0.0508)
			(type default)
		)
		(layer "In2.Cu")
	)
	(gr_line
		(start 97.702116 -64.126618)
		(end 97.917762 -64.34201)
		(stroke
			(width 0.0508)
			(type default)
		)
		(layer "In2.Cu")
	)
	(gr_arc
		(start 97.751392 -67.416426)
		(mid 97.861611 -67.485423)
		(end 97.991168 -67.496436)
		(stroke
			(width 0.0508)
			(type default)
		)
		(layer "In2.Cu")
	)
	(gr_line
		(start 97.752916 -67.88531)
		(end 98.137472 -68.269866)
		(stroke
			(width 0.0508)
			(type default)
		)
		(layer "In2.Cu")
	)
	(gr_arc
		(start 97.84588 -61.034168)
		(mid 97.956134 -61.103015)
		(end 98.085656 -61.113924)
		(stroke
			(width 0.0508)
			(type default)
		)
		(layer "In2.Cu")
	)
	(gr_arc
		(start 97.997772 -64.581786)
		(mid 97.986682 -64.452253)
		(end 97.917762 -64.34201)
		(stroke
			(width 0.0508)
			(type default)
		)
		(layer "In2.Cu")
	)
	(gr_arc
		(start 97.997772 -64.581786)
		(mid 98.008519 -64.710796)
		(end 98.076766 -64.8208)
		(stroke
			(width 0.0508)
			(type default)
		)
		(layer "In2.Cu")
	)
	(gr_arc
		(start 98.076766 -64.8208)
		(mid 98.077147 -64.821181)
		(end 98.077528 -64.821562)
		(stroke
			(width 0.0508)
			(type default)
		)
		(layer "In2.Cu")
	)
	(gr_arc
		(start 98.230944 -67.576446)
		(mid 98.120715 -67.507509)
		(end 97.991168 -67.496436)
		(stroke
			(width 0.0508)
			(type default)
		)
		(layer "In2.Cu")
	)
	(gr_line
		(start 98.230944 -67.576446)
		(end 98.44659 -67.791838)
		(stroke
			(width 0.0508)
			(type default)
		)
		(layer "In2.Cu")
	)
	(gr_arc
		(start 98.325432 -61.193934)
		(mid 98.215202 -61.125)
		(end 98.085656 -61.113924)
		(stroke
			(width 0.0508)
			(type default)
		)
		(layer "In2.Cu")
	)
	(gr_line
		(start 98.325432 -61.193934)
		(end 98.541078 -61.40958)
		(stroke
			(width 0.0508)
			(type default)
		)
		(layer "In2.Cu")
	)
	(gr_arc
		(start 98.5266 -68.031614)
		(mid 98.51552 -67.902077)
		(end 98.44659 -67.791838)
		(stroke
			(width 0.0508)
			(type default)
		)
		(layer "In2.Cu")
	)
	(gr_arc
		(start 98.5266 -68.031614)
		(mid 98.537517 -68.161136)
		(end 98.606356 -68.27139)
		(stroke
			(width 0.0508)
			(type default)
		)
		(layer "In2.Cu")
	)
	(gr_arc
		(start 98.620834 -61.649356)
		(mid 98.609917 -61.519834)
		(end 98.541078 -61.40958)
		(stroke
			(width 0.0508)
			(type default)
		)
		(layer "In2.Cu")
	)
	(gr_arc
		(start 99.595178 -69.260212)
		(mid 99.705314 -69.329008)
		(end 99.8347 -69.339968)
		(stroke
			(width 0.0508)
			(type default)
		)
		(layer "In2.Cu")
	)
	(gr_line
		(start 99.596702 -69.729096)
		(end 99.981004 -70.113398)
		(stroke
			(width 0.0508)
			(type default)
		)
		(layer "In2.Cu")
	)
	(gr_arc
		(start 100.074476 -69.419978)
		(mid 99.96425 -69.35102)
		(end 99.8347 -69.339968)
		(stroke
			(width 0.0508)
			(type default)
		)
		(layer "In2.Cu")
	)
	(gr_line
		(start 100.074476 -69.419978)
		(end 100.290122 -69.63537)
		(stroke
			(width 0.0508)
			(type default)
		)
		(layer "In2.Cu")
	)
	(gr_arc
		(start 100.370132 -69.875146)
		(mid 100.359066 -69.7456)
		(end 100.290122 -69.63537)
		(stroke
			(width 0.0508)
			(type default)
		)
		(layer "In2.Cu")
	)
	(gr_arc
		(start 100.370132 -69.875146)
		(mid 100.380599 -70.003303)
		(end 100.447856 -70.11289)
		(stroke
			(width 0.0508)
			(type default)
		)
		(layer "In2.Cu")
	)
	(gr_arc
		(start 100.447856 -70.11289)
		(mid 100.448869 -70.113909)
		(end 100.449888 -70.114922)
		(stroke
			(width 0.0508)
			(type default)
		)
		(layer "In2.Cu")
	)
	(gr_arc
		(start 100.665534 -70.330568)
		(mid 100.775764 -70.399502)
		(end 100.90531 -70.410578)
		(stroke
			(width 0.0508)
			(type default)
		)
		(layer "In2.Cu")
	)
	(gr_line
		(start 100.667058 -70.799452)
		(end 101.051614 -71.184008)
		(stroke
			(width 0.0508)
			(type default)
		)
		(layer "In2.Cu")
	)
	(gr_arc
		(start 101.145086 -70.490334)
		(mid 101.034832 -70.4215)
		(end 100.90531 -70.410578)
		(stroke
			(width 0.0508)
			(type default)
		)
		(layer "In2.Cu")
	)
	(gr_line
		(start 101.145086 -70.490334)
		(end 101.360478 -70.70598)
		(stroke
			(width 0.0508)
			(type default)
		)
		(layer "In2.Cu")
	)
	(gr_arc
		(start 101.440488 -70.945756)
		(mid 101.429453 -70.816207)
		(end 101.360478 -70.70598)
		(stroke
			(width 0.0508)
			(type default)
		)
		(layer "In2.Cu")
	)
	(gr_arc
		(start 101.440488 -70.945756)
		(mid 101.451538 -71.075301)
		(end 101.520498 -71.185532)
		(stroke
			(width 0.0508)
			(type default)
		)
		(layer "In2.Cu")
	)
	(gr_arc
		(start 105.34904 -65.58407)
		(mid 105.459269 -65.653009)
		(end 105.588816 -65.66408)
		(stroke
			(width 0.0508)
			(type default)
		)
		(layer "In2.Cu")
	)
	(gr_line
		(start 105.350818 -66.052954)
		(end 105.73512 -66.437256)
		(stroke
			(width 0.0508)
			(type default)
		)
		(layer "In2.Cu")
	)
	(gr_arc
		(start 105.828592 -65.74409)
		(mid 105.718373 -65.675093)
		(end 105.588816 -65.66408)
		(stroke
			(width 0.0508)
			(type default)
		)
		(layer "In2.Cu")
	)
	(gr_line
		(start 105.828592 -65.74409)
		(end 106.044238 -65.959482)
		(stroke
			(width 0.0508)
			(type default)
		)
		(layer "In2.Cu")
	)
	(gr_arc
		(start 106.124248 -66.199258)
		(mid 106.113205 -66.069701)
		(end 106.044238 -65.959482)
		(stroke
			(width 0.0508)
			(type default)
		)
		(layer "In2.Cu")
	)
	(gr_arc
		(start 106.124248 -66.199258)
		(mid 106.135174 -66.328774)
		(end 106.204004 -66.439034)
		(stroke
			(width 0.0508)
			(type default)
		)
		(layer "In2.Cu")
	)
	(gr_arc
		(start 106.41965 -66.65468)
		(mid 106.529903 -66.723537)
		(end 106.659426 -66.734436)
		(stroke
			(width 0.0508)
			(type default)
		)
		(layer "In2.Cu")
	)
	(gr_line
		(start 106.421428 -67.123564)
		(end 106.80573 -67.507866)
		(stroke
			(width 0.0508)
			(type default)
		)
		(layer "In2.Cu")
	)
	(gr_arc
		(start 106.899202 -66.814446)
		(mid 106.788972 -66.745512)
		(end 106.659426 -66.734436)
		(stroke
			(width 0.0508)
			(type default)
		)
		(layer "In2.Cu")
	)
	(gr_line
		(start 106.899202 -66.814446)
		(end 107.114594 -67.030092)
		(stroke
			(width 0.0508)
			(type default)
		)
		(layer "In2.Cu")
	)
	(gr_arc
		(start 107.194604 -67.269868)
		(mid 107.183554 -67.140323)
		(end 107.114594 -67.030092)
		(stroke
			(width 0.0508)
			(type default)
		)
		(layer "In2.Cu")
	)
	(gr_arc
		(start 107.194604 -67.269868)
		(mid 107.205608 -67.399436)
		(end 107.274614 -67.509644)
		(stroke
			(width 0.0508)
			(type default)
		)
		(layer "In2.Cu")
	)
	(gr_arc
		(start 110.05185 -68.834)
		(mid 110.178542 -68.804807)
		(end 110.27791 -68.72097)
		(stroke
			(width 0.0508)
			(type default)
		)
		(layer "In2.Cu")
	)
	(gr_line
		(start 110.38459 -69.1642)
		(end 110.92815 -69.1642)
		(stroke
			(width 0.0508)
			(type default)
		)
		(layer "In2.Cu")
	)
	(gr_arc
		(start 110.50397 -68.60794)
		(mid 110.377309 -68.637179)
		(end 110.27791 -68.72097)
		(stroke
			(width 0.0508)
			(type default)
		)
		(layer "In2.Cu")
	)
	(gr_line
		(start 110.50397 -68.60794)
		(end 110.80877 -68.60794)
		(stroke
			(width 0.0508)
			(type default)
		)
		(layer "In2.Cu")
	)
	(gr_arc
		(start 111.03483 -68.72097)
		(mid 110.935454 -68.637133)
		(end 110.80877 -68.60794)
		(stroke
			(width 0.0508)
			(type default)
		)
		(layer "In2.Cu")
	)
	(gr_arc
		(start 111.03483 -68.72097)
		(mid 111.13422 -68.804775)
		(end 111.26089 -68.834)
		(stroke
			(width 0.0508)
			(type default)
		)
		(layer "In2.Cu")
	)
	(gr_arc
		(start 111.56569 -68.834)
		(mid 111.69237 -68.804792)
		(end 111.79175 -68.72097)
		(stroke
			(width 0.0508)
			(type default)
		)
		(layer "In2.Cu")
	)
	(gr_line
		(start 111.89843 -69.1642)
		(end 112.44199 -69.1642)
		(stroke
			(width 0.0508)
			(type default)
		)
		(layer "In2.Cu")
	)
	(gr_arc
		(start 112.01781 -68.60794)
		(mid 111.891149 -68.637179)
		(end 111.79175 -68.72097)
		(stroke
			(width 0.0508)
			(type default)
		)
		(layer "In2.Cu")
	)
	(gr_line
		(start 112.01781 -68.60794)
		(end 112.32261 -68.60794)
		(stroke
			(width 0.0508)
			(type default)
		)
		(layer "In2.Cu")
	)
	(gr_arc
		(start 112.54867 -68.72097)
		(mid 112.449294 -68.637133)
		(end 112.32261 -68.60794)
		(stroke
			(width 0.0508)
			(type default)
		)
		(layer "In2.Cu")
	)
	(gr_arc
		(start 112.54867 -68.72097)
		(mid 112.648063 -68.804761)
		(end 112.77473 -68.834)
		(stroke
			(width 0.0508)
			(type default)
		)
		(layer "In2.Cu")
	)
	(gr_arc
		(start 122.92457 -80.9244)
		(mid 122.811983 -80.849228)
		(end 122.679206 -80.8228)
		(stroke
			(width 0.0508)
			(type default)
		)
		(layer "In2.Cu")
	)
	(gr_line
		(start 123.011946 -80.4926)
		(end 123.449842 -80.4926)
		(stroke
			(width 0.0508)
			(type default)
		)
		(layer "In2.Cu")
	)
	(gr_arc
		(start 123.593352 -80.552036)
		(mid 123.527509 -80.508039)
		(end 123.449842 -80.4926)
		(stroke
			(width 0.0508)
			(type default)
		)
		(layer "In2.Cu")
	)
	(gr_line
		(start 123.593352 -80.552036)
		(end 123.793758 -80.751934)
		(stroke
			(width 0.0508)
			(type default)
		)
		(layer "In2.Cu")
	)
	(gr_arc
		(start 123.853448 -80.895698)
		(mid 123.83793 -80.817868)
		(end 123.793758 -80.751934)
		(stroke
			(width 0.0508)
			(type default)
		)
		(layer "In2.Cu")
	)
	(gr_line
		(start 123.853448 -80.895698)
		(end 123.853448 -80.925924)
		(stroke
			(width 0.0508)
			(type default)
		)
		(layer "In2.Cu")
	)
	(gr_line
		(start 124.779278 -80.053434)
		(end 124.779278 -80.251808)
		(stroke
			(width 0.0508)
			(type default)
		)
		(layer "In2.Cu")
	)
	(gr_line
		(start 125.146054 -79.808324)
		(end 125.471682 -80.133952)
		(stroke
			(width 0.0508)
			(type default)
		)
		(layer "In2.Cu")
	)
	(gr_arc
		(start 125.471682 -80.133952)
		(mid 125.602203 -80.221163)
		(end 125.756162 -80.251808)
		(stroke
			(width 0.0508)
			(type default)
		)
		(layer "In2.Cu")
	)
	(gr_line
		(start 127.154178 -79.8068)
		(end 127.318262 -79.64297)
		(stroke
			(width 0.0508)
			(type default)
		)
		(layer "In2.Cu")
	)
	(gr_arc
		(start 127.318262 -79.64297)
		(mid 127.431462 -79.473393)
		(end 127.47117 -79.2734)
		(stroke
			(width 0.0508)
			(type default)
		)
		(layer "In2.Cu")
	)
	(gr_line
		(start 127.47117 -76.438506)
		(end 127.47117 -76.982066)
		(stroke
			(width 0.0508)
			(type default)
		)
		(layer "In2.Cu")
	)
	(gr_arc
		(start 127.80137 -79.2734)
		(mid 127.838802 -79.461582)
		(end 127.945388 -79.621126)
		(stroke
			(width 0.0508)
			(type default)
		)
		(layer "In2.Cu")
	)
	(gr_arc
		(start 127.80137 -76.105766)
		(mid 127.830609 -76.232427)
		(end 127.9144 -76.331826)
		(stroke
			(width 0.0508)
			(type default)
		)
		(layer "In2.Cu")
	)
	(gr_arc
		(start 127.9144 -77.088746)
		(mid 127.830563 -77.188122)
		(end 127.80137 -77.314806)
		(stroke
			(width 0.0508)
			(type default)
		)
		(layer "In2.Cu")
	)
	(gr_arc
		(start 127.9144 -77.088746)
		(mid 127.998188 -76.989351)
		(end 128.02743 -76.862686)
		(stroke
			(width 0.0508)
			(type default)
		)
		(layer "In2.Cu")
	)
	(gr_line
		(start 127.945388 -79.621126)
		(end 128.131062 -79.8068)
		(stroke
			(width 0.0508)
			(type default)
		)
		(layer "In2.Cu")
	)
	(gr_arc
		(start 128.02743 -76.557886)
		(mid 127.998245 -76.43119)
		(end 127.9144 -76.331826)
		(stroke
			(width 0.0508)
			(type default)
		)
		(layer "In2.Cu")
	)
	(gr_line
		(start 128.02743 -76.557886)
		(end 128.02743 -76.862686)
		(stroke
			(width 0.0508)
			(type default)
		)
		(layer "In2.Cu")
	)
	(gr_line
		(start 129.159 -81.28)
		(end 129.300478 -81.138268)
		(stroke
			(width 0.0508)
			(type default)
		)
		(layer "In2.Cu")
	)
	(gr_arc
		(start 129.300478 -81.138268)
		(mid 129.412845 -80.970238)
		(end 129.45237 -80.772)
		(stroke
			(width 0.0508)
			(type default)
		)
		(layer "In2.Cu")
	)
	(gr_arc
		(start 129.78257 -80.772)
		(mid 129.827111 -80.99618)
		(end 129.95402 -81.186274)
		(stroke
			(width 0.0508)
			(type default)
		)
		(layer "In2.Cu")
	)
	(gr_line
		(start 129.95402 -81.186274)
		(end 130.048 -81.28)
		(stroke
			(width 0.0508)
			(type default)
		)
		(layer "In2.Cu")
	)
	(gr_line
		(start 276.7076 -51.16703)
		(end 276.7076 -51.58359)
		(stroke
			(width 0.0635)
			(type default)
		)
		(layer "In2.Cu")
	)
	(gr_line
		(start 276.7076 -49.80559)
		(end 276.7076 -50.22215)
		(stroke
			(width 0.0635)
			(type default)
		)
		(layer "In2.Cu")
	)
	(gr_line
		(start 276.7076 -48.44415)
		(end 276.7076 -48.86071)
		(stroke
			(width 0.0635)
			(type default)
		)
		(layer "In2.Cu")
	)
	(gr_line
		(start 276.7076 -44.975272)
		(end 276.7076 -45.391832)
		(stroke
			(width 0.0635)
			(type default)
		)
		(layer "In2.Cu")
	)
	(gr_line
		(start 276.7076 -43.613832)
		(end 276.7076 -44.030392)
		(stroke
			(width 0.0635)
			(type default)
		)
		(layer "In2.Cu")
	)
	(gr_line
		(start 276.7076 -40.837866)
		(end 276.7076 -41.254426)
		(stroke
			(width 0.0635)
			(type default)
		)
		(layer "In2.Cu")
	)
	(gr_line
		(start 276.867112 -32.131)
		(end 276.87397 -32.138112)
		(stroke
			(width 0.0635)
			(type default)
		)
		(layer "In2.Cu")
	)
	(gr_arc
		(start 276.987 -50.88509)
		(mid 277.008064 -50.968226)
		(end 277.06193 -51.03495)
		(stroke
			(width 0.0635)
			(type default)
		)
		(layer "In2.Cu")
	)
	(gr_arc
		(start 276.987 -49.52365)
		(mid 277.008064 -49.606786)
		(end 277.06193 -49.67351)
		(stroke
			(width 0.0635)
			(type default)
		)
		(layer "In2.Cu")
	)
	(gr_arc
		(start 276.987 -48.16221)
		(mid 277.008064 -48.245346)
		(end 277.06193 -48.31207)
		(stroke
			(width 0.0635)
			(type default)
		)
		(layer "In2.Cu")
	)
	(gr_arc
		(start 276.987 -44.693332)
		(mid 277.008064 -44.776468)
		(end 277.06193 -44.843192)
		(stroke
			(width 0.0635)
			(type default)
		)
		(layer "In2.Cu")
	)
	(gr_arc
		(start 276.987 -43.331892)
		(mid 277.008064 -43.415028)
		(end 277.06193 -43.481752)
		(stroke
			(width 0.0635)
			(type default)
		)
		(layer "In2.Cu")
	)
	(gr_arc
		(start 276.987 -40.555926)
		(mid 277.008083 -40.639041)
		(end 277.06193 -40.705786)
		(stroke
			(width 0.0635)
			(type default)
		)
		(layer "In2.Cu")
	)
	(gr_arc
		(start 277.06193 -51.71567)
		(mid 277.008041 -51.782394)
		(end 276.987 -51.86553)
		(stroke
			(width 0.0635)
			(type default)
		)
		(layer "In2.Cu")
	)
	(gr_arc
		(start 277.06193 -51.71567)
		(mid 277.1158 -51.648943)
		(end 277.13686 -51.56581)
		(stroke
			(width 0.0635)
			(type default)
		)
		(layer "In2.Cu")
	)
	(gr_arc
		(start 277.06193 -50.35423)
		(mid 277.008041 -50.420954)
		(end 276.987 -50.50409)
		(stroke
			(width 0.0635)
			(type default)
		)
		(layer "In2.Cu")
	)
	(gr_arc
		(start 277.06193 -50.35423)
		(mid 277.11582 -50.287508)
		(end 277.13686 -50.20437)
		(stroke
			(width 0.0635)
			(type default)
		)
		(layer "In2.Cu")
	)
	(gr_arc
		(start 277.06193 -48.99279)
		(mid 277.008041 -49.059514)
		(end 276.987 -49.14265)
		(stroke
			(width 0.0635)
			(type default)
		)
		(layer "In2.Cu")
	)
	(gr_arc
		(start 277.06193 -48.99279)
		(mid 277.115806 -48.926065)
		(end 277.13686 -48.84293)
		(stroke
			(width 0.0635)
			(type default)
		)
		(layer "In2.Cu")
	)
	(gr_arc
		(start 277.06193 -45.523912)
		(mid 277.008106 -45.590657)
		(end 276.987 -45.673772)
		(stroke
			(width 0.0635)
			(type default)
		)
		(layer "In2.Cu")
	)
	(gr_arc
		(start 277.06193 -45.523912)
		(mid 277.115814 -45.457188)
		(end 277.13686 -45.374052)
		(stroke
			(width 0.0635)
			(type default)
		)
		(layer "In2.Cu")
	)
	(gr_arc
		(start 277.06193 -44.162472)
		(mid 277.008106 -44.229217)
		(end 276.987 -44.312332)
		(stroke
			(width 0.0635)
			(type default)
		)
		(layer "In2.Cu")
	)
	(gr_arc
		(start 277.06193 -44.162472)
		(mid 277.1158 -44.095745)
		(end 277.13686 -44.012612)
		(stroke
			(width 0.0635)
			(type default)
		)
		(layer "In2.Cu")
	)
	(gr_arc
		(start 277.06193 -41.386506)
		(mid 277.008106 -41.453251)
		(end 276.987 -41.536366)
		(stroke
			(width 0.0635)
			(type default)
		)
		(layer "In2.Cu")
	)
	(gr_arc
		(start 277.06193 -41.386506)
		(mid 277.115768 -41.319764)
		(end 277.13686 -41.236646)
		(stroke
			(width 0.0635)
			(type default)
		)
		(layer "In2.Cu")
	)
	(gr_arc
		(start 277.13686 -51.18481)
		(mid 277.11583 -51.10166)
		(end 277.06193 -51.03495)
		(stroke
			(width 0.0635)
			(type default)
		)
		(layer "In2.Cu")
	)
	(gr_line
		(start 277.13686 -51.18481)
		(end 277.13686 -51.56581)
		(stroke
			(width 0.0635)
			(type default)
		)
		(layer "In2.Cu")
	)
	(gr_arc
		(start 277.13686 -49.82337)
		(mid 277.115816 -49.74023)
		(end 277.06193 -49.67351)
		(stroke
			(width 0.0635)
			(type default)
		)
		(layer "In2.Cu")
	)
	(gr_line
		(start 277.13686 -49.82337)
		(end 277.13686 -50.20437)
		(stroke
			(width 0.0635)
			(type default)
		)
		(layer "In2.Cu")
	)
	(gr_arc
		(start 277.13686 -48.46193)
		(mid 277.115803 -48.378801)
		(end 277.06193 -48.31207)
		(stroke
			(width 0.0635)
			(type default)
		)
		(layer "In2.Cu")
	)
	(gr_line
		(start 277.13686 -48.46193)
		(end 277.13686 -48.84293)
		(stroke
			(width 0.0635)
			(type default)
		)
		(layer "In2.Cu")
	)
	(gr_arc
		(start 277.13686 -44.993052)
		(mid 277.115763 -44.909936)
		(end 277.06193 -44.843192)
		(stroke
			(width 0.0635)
			(type default)
		)
		(layer "In2.Cu")
	)
	(gr_line
		(start 277.13686 -44.993052)
		(end 277.13686 -45.374052)
		(stroke
			(width 0.0635)
			(type default)
		)
		(layer "In2.Cu")
	)
	(gr_arc
		(start 277.13686 -43.631612)
		(mid 277.11575 -43.548506)
		(end 277.06193 -43.481752)
		(stroke
			(width 0.0635)
			(type default)
		)
		(layer "In2.Cu")
	)
	(gr_line
		(start 277.13686 -43.631612)
		(end 277.13686 -44.012612)
		(stroke
			(width 0.0635)
			(type default)
		)
		(layer "In2.Cu")
	)
	(gr_arc
		(start 277.13686 -40.855646)
		(mid 277.115761 -40.772532)
		(end 277.06193 -40.705786)
		(stroke
			(width 0.0635)
			(type default)
		)
		(layer "In2.Cu")
	)
	(gr_line
		(start 277.13686 -40.855646)
		(end 277.13686 -41.236646)
		(stroke
			(width 0.0635)
			(type default)
		)
		(layer "In2.Cu")
	)
	(gr_arc
		(start 277.218394 -32.9692)
		(mid 277.128847 -32.519394)
		(end 276.87397 -32.138112)
		(stroke
			(width 0.0635)
			(type default)
		)
		(layer "In2.Cu")
	)
	(gr_arc
		(start 277.842218 -32.138112)
		(mid 277.587354 -32.519403)
		(end 277.497794 -32.9692)
		(stroke
			(width 0.0635)
			(type default)
		)
		(layer "In2.Cu")
	)
	(gr_line
		(start 277.842218 -32.138112)
		(end 277.849076 -32.131)
		(stroke
			(width 0.0635)
			(type default)
		)
		(layer "In2.Cu")
	)
	(gr_line
		(start 293.497 -114.492532)
		(end 293.811198 -114.178334)
		(stroke
			(width 0.0635)
			(type default)
		)
		(layer "In2.Cu")
	)
	(gr_line
		(start 293.497 -113.510568)
		(end 293.811198 -113.824766)
		(stroke
			(width 0.0635)
			(type default)
		)
		(layer "In2.Cu")
	)
	(gr_arc
		(start 293.811198 -113.824766)
		(mid 293.852345 -113.852211)
		(end 293.90086 -113.86185)
		(stroke
			(width 0.0635)
			(type default)
		)
		(layer "In2.Cu")
	)
	(gr_arc
		(start 293.90086 -114.14125)
		(mid 293.852342 -114.150883)
		(end 293.811198 -114.178334)
		(stroke
			(width 0.0635)
			(type default)
		)
		(layer "In2.Cu")
	)
	(gr_line
		(start 0 -246.000016)
		(end 0 -81.009998)
		(stroke
			(width 1.524)
			(type default)
		)
		(layer "In3.Cu")
	)
	(gr_arc
		(start 0 -246.000016)
		(mid 1.464462 -249.535545)
		(end 4.99999 -251.000006)
		(stroke
			(width 1.524)
			(type default)
		)
		(layer "In3.Cu")
	)
	(gr_arc
		(start 2.999994 -78.010004)
		(mid 0.878678 -78.888682)
		(end 0 -81.009998)
		(stroke
			(width 1.524)
			(type default)
		)
		(layer "In3.Cu")
	)
	(gr_line
		(start 2.999994 -78.010004)
		(end 25.500076 -78.010004)
		(stroke
			(width 1.524)
			(type default)
		)
		(layer "In3.Cu")
	)
	(gr_line
		(start 11.14552 -98.876866)
		(end 12.059666 -98.878644)
		(stroke
			(width 0.2)
			(type default)
		)
		(layer "In3.Cu")
	)
	(gr_arc
		(start 11.147044 -98.109786)
		(mid 10.762742 -98.492564)
		(end 11.14552 -98.876866)
		(stroke
			(width 0.2)
			(type default)
		)
		(layer "In3.Cu")
	)
	(gr_arc
		(start 12.059666 -98.878644)
		(mid 12.444222 -98.495993)
		(end 12.061444 -98.111564)
		(stroke
			(width 0.2)
			(type default)
		)
		(layer "In3.Cu")
	)
	(gr_line
		(start 12.061444 -98.111564)
		(end 11.147044 -98.109786)
		(stroke
			(width 0.2)
			(type default)
		)
		(layer "In3.Cu")
	)
	(gr_line
		(start 13.487654 -98.852736)
		(end 14.4272 -98.903536)
		(stroke
			(width 0.2)
			(type default)
		)
		(layer "In3.Cu")
	)
	(gr_arc
		(start 13.52931 -98.086672)
		(mid 13.12545 -98.448876)
		(end 13.487654 -98.852736)
		(stroke
			(width 0.2)
			(type default)
		)
		(layer "In3.Cu")
	)
	(gr_line
		(start 14.4272 -98.903536)
		(end 14.427454 -98.903536)
		(stroke
			(width 0.2)
			(type default)
		)
		(layer "In3.Cu")
	)
	(gr_arc
		(start 14.427454 -98.903536)
		(mid 14.831314 -98.541332)
		(end 14.46911 -98.137472)
		(stroke
			(width 0.2)
			(type default)
		)
		(layer "In3.Cu")
	)
	(gr_line
		(start 14.46911 -98.137472)
		(end 13.52931 -98.086672)
		(stroke
			(width 0.2)
			(type default)
		)
		(layer "In3.Cu")
	)
	(gr_line
		(start 15.936468 -98.88093)
		(end 16.876268 -98.90633)
		(stroke
			(width 0.2)
			(type default)
		)
		(layer "In3.Cu")
	)
	(gr_line
		(start 15.936468 -98.87839)
		(end 15.936468 -98.88093)
		(stroke
			(width 0.2)
			(type default)
		)
		(layer "In3.Cu")
	)
	(gr_arc
		(start 15.957296 -98.111818)
		(mid 15.563596 -98.48469)
		(end 15.936468 -98.87839)
		(stroke
			(width 0.2)
			(type default)
		)
		(layer "In3.Cu")
	)
	(gr_line
		(start 15.957296 -98.109532)
		(end 15.957296 -98.111818)
		(stroke
			(width 0.2)
			(type default)
		)
		(layer "In3.Cu")
	)
	(gr_line
		(start 15.95755 -98.109278)
		(end 15.957296 -98.109532)
		(stroke
			(width 0.2)
			(type default)
		)
		(layer "In3.Cu")
	)
	(gr_line
		(start 16.876268 -98.90633)
		(end 16.876268 -98.90379)
		(stroke
			(width 0.2)
			(type default)
		)
		(layer "In3.Cu")
	)
	(gr_arc
		(start 16.876268 -98.90379)
		(mid 17.269968 -98.530918)
		(end 16.897096 -98.137218)
		(stroke
			(width 0.2)
			(type default)
		)
		(layer "In3.Cu")
	)
	(gr_line
		(start 16.897096 -98.137218)
		(end 16.897096 -98.134678)
		(stroke
			(width 0.2)
			(type default)
		)
		(layer "In3.Cu")
	)
	(gr_line
		(start 16.897096 -98.134678)
		(end 15.95755 -98.109278)
		(stroke
			(width 0.2)
			(type default)
		)
		(layer "In3.Cu")
	)
	(gr_line
		(start 18.258282 -98.929444)
		(end 19.325082 -98.929444)
		(stroke
			(width 0.2)
			(type default)
		)
		(layer "In3.Cu")
	)
	(gr_arc
		(start 18.258536 -98.162364)
		(mid 17.874742 -98.545777)
		(end 18.258282 -98.929444)
		(stroke
			(width 0.2)
			(type default)
		)
		(layer "In3.Cu")
	)
	(gr_arc
		(start 19.325082 -98.929444)
		(mid 19.708622 -98.545904)
		(end 19.325082 -98.162364)
		(stroke
			(width 0.2)
			(type default)
		)
		(layer "In3.Cu")
	)
	(gr_line
		(start 19.325082 -98.162364)
		(end 18.258536 -98.162364)
		(stroke
			(width 0.2)
			(type default)
		)
		(layer "In3.Cu")
	)
	(gr_arc
		(start 25.500076 -78.010004)
		(mid 26.914287 -77.424219)
		(end 27.500072 -76.010008)
		(stroke
			(width 1.524)
			(type default)
		)
		(layer "In3.Cu")
	)
	(gr_line
		(start 26.34996 -251.000006)
		(end 4.99999 -251.000006)
		(stroke
			(width 1.524)
			(type default)
		)
		(layer "In3.Cu")
	)
	(gr_line
		(start 27.349958 -258.59994)
		(end 27.349958 -252.000004)
		(stroke
			(width 1.524)
			(type default)
		)
		(layer "In3.Cu")
	)
	(gr_arc
		(start 27.349958 -252.000004)
		(mid 27.057065 -251.292899)
		(end 26.34996 -251.000006)
		(stroke
			(width 1.524)
			(type default)
		)
		(layer "In3.Cu")
	)
	(gr_line
		(start 27.500072 -76.010008)
		(end 27.500072 -60.01004)
		(stroke
			(width 1.524)
			(type default)
		)
		(layer "In3.Cu")
	)
	(gr_arc
		(start 29.500068 -58.010044)
		(mid 28.085859 -58.59583)
		(end 27.500072 -60.01004)
		(stroke
			(width 1.524)
			(type default)
		)
		(layer "In3.Cu")
	)
	(gr_line
		(start 29.500068 -58.010044)
		(end 60.950094 -58.010044)
		(stroke
			(width 1.524)
			(type default)
		)
		(layer "In3.Cu")
	)
	(gr_line
		(start 32.334454 -90.479626)
		(end 33.311338 -90.479626)
		(stroke
			(width 0.2)
			(type default)
		)
		(layer "In3.Cu")
	)
	(gr_arc
		(start 32.334708 -89.712546)
		(mid 31.950914 -90.095959)
		(end 32.334454 -90.479626)
		(stroke
			(width 0.2)
			(type default)
		)
		(layer "In3.Cu")
	)
	(gr_arc
		(start 33.311338 -90.479626)
		(mid 33.694878 -90.096086)
		(end 33.311338 -89.712546)
		(stroke
			(width 0.2)
			(type default)
		)
		(layer "In3.Cu")
	)
	(gr_line
		(start 33.311338 -89.712546)
		(end 32.334708 -89.712546)
		(stroke
			(width 0.2)
			(type default)
		)
		(layer "In3.Cu")
	)
	(gr_line
		(start 34.550096 -258.59994)
		(end 27.349958 -258.59994)
		(stroke
			(width 5.08)
			(type default)
		)
		(layer "In3.Cu")
	)
	(gr_line
		(start 34.550096 -252.549914)
		(end 34.550096 -258.59994)
		(stroke
			(width 1.524)
			(type default)
		)
		(layer "In3.Cu")
	)
	(gr_line
		(start 35.382454 -90.479626)
		(end 36.359084 -90.479626)
		(stroke
			(width 0.2)
			(type default)
		)
		(layer "In3.Cu")
	)
	(gr_arc
		(start 35.382454 -89.712546)
		(mid 34.998914 -90.096086)
		(end 35.382454 -90.479626)
		(stroke
			(width 0.2)
			(type default)
		)
		(layer "In3.Cu")
	)
	(gr_arc
		(start 36.359084 -90.479626)
		(mid 36.742878 -90.096213)
		(end 36.359338 -89.712546)
		(stroke
			(width 0.2)
			(type default)
		)
		(layer "In3.Cu")
	)
	(gr_line
		(start 36.359338 -89.712546)
		(end 35.382454 -89.712546)
		(stroke
			(width 0.2)
			(type default)
		)
		(layer "In3.Cu")
	)
	(gr_line
		(start 36.450016 -258.59994)
		(end 36.450016 -252.549914)
		(stroke
			(width 1.524)
			(type default)
		)
		(layer "In3.Cu")
	)
	(gr_arc
		(start 36.450016 -252.549914)
		(mid 35.500056 -251.599954)
		(end 34.550096 -252.549914)
		(stroke
			(width 1.524)
			(type default)
		)
		(layer "In3.Cu")
	)
	(gr_line
		(start 38.1 -147.447)
		(end 58.42 -167.767)
		(stroke
			(width 0.381)
			(type default)
		)
		(layer "In3.Cu")
	)
	(gr_line
		(start 38.1 -101.854)
		(end 38.1 -147.447)
		(stroke
			(width 0.381)
			(type default)
		)
		(layer "In3.Cu")
	)
	(gr_line
		(start 38.430454 -90.479626)
		(end 39.407084 -90.479626)
		(stroke
			(width 0.2)
			(type default)
		)
		(layer "In3.Cu")
	)
	(gr_arc
		(start 38.430454 -89.712546)
		(mid 38.046914 -90.096086)
		(end 38.430454 -90.479626)
		(stroke
			(width 0.2)
			(type default)
		)
		(layer "In3.Cu")
	)
	(gr_arc
		(start 39.208456 -83.046824)
		(mid 39.591869 -83.430618)
		(end 39.975536 -83.047078)
		(stroke
			(width 0.2)
			(type default)
		)
		(layer "In3.Cu")
	)
	(gr_line
		(start 39.208456 -82.070194)
		(end 39.208456 -83.046824)
		(stroke
			(width 0.2)
			(type default)
		)
		(layer "In3.Cu")
	)
	(gr_arc
		(start 39.208456 -80.722978)
		(mid 39.591996 -81.106518)
		(end 39.975536 -80.722978)
		(stroke
			(width 0.2)
			(type default)
		)
		(layer "In3.Cu")
	)
	(gr_line
		(start 39.208456 -79.746094)
		(end 39.208456 -80.722978)
		(stroke
			(width 0.2)
			(type default)
		)
		(layer "In3.Cu")
	)
	(gr_arc
		(start 39.407084 -90.479626)
		(mid 39.790878 -90.096213)
		(end 39.407338 -89.712546)
		(stroke
			(width 0.2)
			(type default)
		)
		(layer "In3.Cu")
	)
	(gr_line
		(start 39.407338 -89.712546)
		(end 38.430454 -89.712546)
		(stroke
			(width 0.2)
			(type default)
		)
		(layer "In3.Cu")
	)
	(gr_line
		(start 39.975536 -83.047078)
		(end 39.975536 -82.070194)
		(stroke
			(width 0.2)
			(type default)
		)
		(layer "In3.Cu")
	)
	(gr_arc
		(start 39.975536 -82.070194)
		(mid 39.591996 -81.686654)
		(end 39.208456 -82.070194)
		(stroke
			(width 0.2)
			(type default)
		)
		(layer "In3.Cu")
	)
	(gr_line
		(start 39.975536 -80.722978)
		(end 39.975536 -79.746348)
		(stroke
			(width 0.2)
			(type default)
		)
		(layer "In3.Cu")
	)
	(gr_arc
		(start 39.975536 -79.746348)
		(mid 39.592123 -79.362554)
		(end 39.208456 -79.746094)
		(stroke
			(width 0.2)
			(type default)
		)
		(layer "In3.Cu")
	)
	(gr_line
		(start 41.351454 -90.479626)
		(end 42.328338 -90.479626)
		(stroke
			(width 0.2)
			(type default)
		)
		(layer "In3.Cu")
	)
	(gr_arc
		(start 41.351708 -89.712546)
		(mid 40.967914 -90.095959)
		(end 41.351454 -90.479626)
		(stroke
			(width 0.2)
			(type default)
		)
		(layer "In3.Cu")
	)
	(gr_line
		(start 41.693338 -83.873086)
		(end 42.670222 -83.873086)
		(stroke
			(width 0.2)
			(type default)
		)
		(layer "In3.Cu")
	)
	(gr_arc
		(start 41.693592 -83.106006)
		(mid 41.309798 -83.489419)
		(end 41.693338 -83.873086)
		(stroke
			(width 0.2)
			(type default)
		)
		(layer "In3.Cu")
	)
	(gr_line
		(start 42.111422 -75.138026)
		(end 43.088306 -75.138026)
		(stroke
			(width 0.2)
			(type default)
		)
		(layer "In3.Cu")
	)
	(gr_arc
		(start 42.111676 -74.370946)
		(mid 41.727882 -74.754359)
		(end 42.111422 -75.138026)
		(stroke
			(width 0.2)
			(type default)
		)
		(layer "In3.Cu")
	)
	(gr_arc
		(start 42.328338 -90.479626)
		(mid 42.711878 -90.096086)
		(end 42.328338 -89.712546)
		(stroke
			(width 0.2)
			(type default)
		)
		(layer "In3.Cu")
	)
	(gr_line
		(start 42.328338 -89.712546)
		(end 41.351708 -89.712546)
		(stroke
			(width 0.2)
			(type default)
		)
		(layer "In3.Cu")
	)
	(gr_arc
		(start 42.670222 -83.873086)
		(mid 43.053762 -83.489546)
		(end 42.670222 -83.106006)
		(stroke
			(width 0.2)
			(type default)
		)
		(layer "In3.Cu")
	)
	(gr_line
		(start 42.670222 -83.106006)
		(end 41.693592 -83.106006)
		(stroke
			(width 0.2)
			(type default)
		)
		(layer "In3.Cu")
	)
	(gr_arc
		(start 43.088306 -75.138026)
		(mid 43.471846 -74.754486)
		(end 43.088306 -74.370946)
		(stroke
			(width 0.2)
			(type default)
		)
		(layer "In3.Cu")
	)
	(gr_line
		(start 43.088306 -74.370946)
		(end 42.111676 -74.370946)
		(stroke
			(width 0.2)
			(type default)
		)
		(layer "In3.Cu")
	)
	(gr_line
		(start 44.511468 -75.290426)
		(end 45.488098 -75.290426)
		(stroke
			(width 0.2)
			(type default)
		)
		(layer "In3.Cu")
	)
	(gr_arc
		(start 44.511468 -74.523346)
		(mid 44.127928 -74.906886)
		(end 44.511468 -75.290426)
		(stroke
			(width 0.2)
			(type default)
		)
		(layer "In3.Cu")
	)
	(gr_line
		(start 44.647104 -83.885786)
		(end 45.623734 -83.885786)
		(stroke
			(width 0.2)
			(type default)
		)
		(layer "In3.Cu")
	)
	(gr_arc
		(start 44.647104 -83.118706)
		(mid 44.263564 -83.502246)
		(end 44.647104 -83.885786)
		(stroke
			(width 0.2)
			(type default)
		)
		(layer "In3.Cu")
	)
	(gr_arc
		(start 45.488098 -75.290426)
		(mid 45.871892 -74.907013)
		(end 45.488352 -74.523346)
		(stroke
			(width 0.2)
			(type default)
		)
		(layer "In3.Cu")
	)
	(gr_line
		(start 45.488352 -74.523346)
		(end 44.511468 -74.523346)
		(stroke
			(width 0.2)
			(type default)
		)
		(layer "In3.Cu")
	)
	(gr_arc
		(start 45.623734 -83.885786)
		(mid 46.007528 -83.502373)
		(end 45.623988 -83.118706)
		(stroke
			(width 0.2)
			(type default)
		)
		(layer "In3.Cu")
	)
	(gr_line
		(start 45.623988 -83.118706)
		(end 44.647104 -83.118706)
		(stroke
			(width 0.2)
			(type default)
		)
		(layer "In3.Cu")
	)
	(gr_line
		(start 47.649892 -258.59994)
		(end 36.450016 -258.59994)
		(stroke
			(width 5.08)
			(type default)
		)
		(layer "In3.Cu")
	)
	(gr_line
		(start 47.649892 -252.000004)
		(end 47.649892 -258.59994)
		(stroke
			(width 1.524)
			(type default)
		)
		(layer "In3.Cu")
	)
	(gr_arc
		(start 48.606456 -87.746078)
		(mid 48.989996 -88.129618)
		(end 49.373536 -87.746078)
		(stroke
			(width 0.2)
			(type default)
		)
		(layer "In3.Cu")
	)
	(gr_line
		(start 48.606456 -86.769194)
		(end 48.606456 -87.746078)
		(stroke
			(width 0.2)
			(type default)
		)
		(layer "In3.Cu")
	)
	(gr_arc
		(start 48.606456 -84.913724)
		(mid 48.989869 -85.297518)
		(end 49.373536 -84.913978)
		(stroke
			(width 0.2)
			(type default)
		)
		(layer "In3.Cu")
	)
	(gr_line
		(start 48.606456 -83.937094)
		(end 48.606456 -84.913724)
		(stroke
			(width 0.2)
			(type default)
		)
		(layer "In3.Cu")
	)
	(gr_arc
		(start 48.64989 -251.000006)
		(mid 47.942785 -251.292899)
		(end 47.649892 -252.000004)
		(stroke
			(width 1.524)
			(type default)
		)
		(layer "In3.Cu")
	)
	(gr_line
		(start 49.373536 -87.746078)
		(end 49.373536 -86.769448)
		(stroke
			(width 0.2)
			(type default)
		)
		(layer "In3.Cu")
	)
	(gr_arc
		(start 49.373536 -86.769448)
		(mid 48.990123 -86.385654)
		(end 48.606456 -86.769194)
		(stroke
			(width 0.2)
			(type default)
		)
		(layer "In3.Cu")
	)
	(gr_line
		(start 49.373536 -84.913978)
		(end 49.373536 -83.937094)
		(stroke
			(width 0.2)
			(type default)
		)
		(layer "In3.Cu")
	)
	(gr_arc
		(start 49.373536 -83.937094)
		(mid 48.989996 -83.553554)
		(end 48.606456 -83.937094)
		(stroke
			(width 0.2)
			(type default)
		)
		(layer "In3.Cu")
	)
	(gr_line
		(start 50.911506 -75.290426)
		(end 51.888136 -75.290426)
		(stroke
			(width 0.2)
			(type default)
		)
		(layer "In3.Cu")
	)
	(gr_arc
		(start 50.911506 -74.523346)
		(mid 50.527966 -74.906886)
		(end 50.911506 -75.290426)
		(stroke
			(width 0.2)
			(type default)
		)
		(layer "In3.Cu")
	)
	(gr_arc
		(start 51.888136 -75.290426)
		(mid 52.27193 -74.907013)
		(end 51.88839 -74.523346)
		(stroke
			(width 0.2)
			(type default)
		)
		(layer "In3.Cu")
	)
	(gr_line
		(start 51.88839 -74.523346)
		(end 50.911506 -74.523346)
		(stroke
			(width 0.2)
			(type default)
		)
		(layer "In3.Cu")
	)
	(gr_line
		(start 52.959 -143.637)
		(end 61.976 -152.654)
		(stroke
			(width 0.381)
			(type default)
		)
		(layer "In3.Cu")
	)
	(gr_line
		(start 52.959 -111.379)
		(end 52.959 -143.637)
		(stroke
			(width 0.381)
			(type default)
		)
		(layer "In3.Cu")
	)
	(gr_line
		(start 53.311298 -75.290426)
		(end 54.287928 -75.290426)
		(stroke
			(width 0.2)
			(type default)
		)
		(layer "In3.Cu")
	)
	(gr_arc
		(start 53.311298 -74.523346)
		(mid 52.927758 -74.906886)
		(end 53.311298 -75.290426)
		(stroke
			(width 0.2)
			(type default)
		)
		(layer "In3.Cu")
	)
	(gr_arc
		(start 54.287928 -75.290426)
		(mid 54.671722 -74.907013)
		(end 54.288182 -74.523346)
		(stroke
			(width 0.2)
			(type default)
		)
		(layer "In3.Cu")
	)
	(gr_line
		(start 54.288182 -74.523346)
		(end 53.311298 -74.523346)
		(stroke
			(width 0.2)
			(type default)
		)
		(layer "In3.Cu")
	)
	(gr_line
		(start 56.515 -140.716)
		(end 56.515 -112.395)
		(stroke
			(width 0.381)
			(type default)
		)
		(layer "In3.Cu")
	)
	(gr_line
		(start 56.515 -112.395)
		(end 74.93 -93.98)
		(stroke
			(width 0.381)
			(type default)
		)
		(layer "In3.Cu")
	)
	(gr_line
		(start 58.42 -167.767)
		(end 95.504 -167.767)
		(stroke
			(width 0.381)
			(type default)
		)
		(layer "In3.Cu")
	)
	(gr_line
		(start 58.801 -81.153)
		(end 38.1 -101.854)
		(stroke
			(width 0.381)
			(type default)
		)
		(layer "In3.Cu")
	)
	(gr_line
		(start 58.801 -57.785)
		(end 58.801 -81.153)
		(stroke
			(width 0.381)
			(type default)
		)
		(layer "In3.Cu")
	)
	(gr_arc
		(start 60.950094 -58.010044)
		(mid 61.657199 -57.717151)
		(end 61.950092 -57.010046)
		(stroke
			(width 1.524)
			(type default)
		)
		(layer "In3.Cu")
	)
	(gr_line
		(start 61.950092 -57.010046)
		(end 61.950092 -17.999964)
		(stroke
			(width 1.524)
			(type default)
		)
		(layer "In3.Cu")
	)
	(gr_arc
		(start 62.95009 -16.999966)
		(mid 62.242978 -17.29286)
		(end 61.950092 -17.999964)
		(stroke
			(width 1.524)
			(type default)
		)
		(layer "In3.Cu")
	)
	(gr_line
		(start 62.95009 -16.999966)
		(end 73.449942 -16.999966)
		(stroke
			(width 1.524)
			(type default)
		)
		(layer "In3.Cu")
	)
	(gr_line
		(start 62.992 -147.193)
		(end 56.515 -140.716)
		(stroke
			(width 0.381)
			(type default)
		)
		(layer "In3.Cu")
	)
	(gr_line
		(start 66.34988 -251.000006)
		(end 48.64989 -251.000006)
		(stroke
			(width 1.524)
			(type default)
		)
		(layer "In3.Cu")
	)
	(gr_line
		(start 67.349878 -258.59994)
		(end 67.349878 -252.000004)
		(stroke
			(width 1.524)
			(type default)
		)
		(layer "In3.Cu")
	)
	(gr_arc
		(start 67.349878 -252.000004)
		(mid 67.056985 -251.292899)
		(end 66.34988 -251.000006)
		(stroke
			(width 1.524)
			(type default)
		)
		(layer "In3.Cu")
	)
	(gr_line
		(start 71.501 -92.837)
		(end 52.959 -111.379)
		(stroke
			(width 0.381)
			(type default)
		)
		(layer "In3.Cu")
	)
	(gr_line
		(start 71.501 -79.248)
		(end 71.501 -92.837)
		(stroke
			(width 0.381)
			(type default)
		)
		(layer "In3.Cu")
	)
	(gr_line
		(start 72.263 -78.486)
		(end 71.501 -79.248)
		(stroke
			(width 0.381)
			(type default)
		)
		(layer "In3.Cu")
	)
	(gr_arc
		(start 73.449942 -16.999966)
		(mid 74.157047 -16.707073)
		(end 74.44994 -15.999968)
		(stroke
			(width 1.524)
			(type default)
		)
		(layer "In3.Cu")
	)
	(gr_line
		(start 74.295 -78.486)
		(end 74.93 -77.851)
		(stroke
			(width 0.381)
			(type default)
		)
		(layer "In3.Cu")
	)
	(gr_line
		(start 74.44994 -15.999968)
		(end 74.44994 -0.999998)
		(stroke
			(width 1.524)
			(type default)
		)
		(layer "In3.Cu")
	)
	(gr_line
		(start 74.44994 -1.29794)
		(end 75.311 -2.159)
		(stroke
			(width 0.381)
			(type default)
		)
		(layer "In3.Cu")
	)
	(gr_line
		(start 74.44994 -0.999998)
		(end 74.44994 -1.29794)
		(stroke
			(width 0.381)
			(type default)
		)
		(layer "In3.Cu")
	)
	(gr_line
		(start 74.803 -78.994)
		(end 74.295 -78.486)
		(stroke
			(width 0.381)
			(type default)
		)
		(layer "In3.Cu")
	)
	(gr_line
		(start 74.93 -93.98)
		(end 74.93 -78.486)
		(stroke
			(width 0.381)
			(type default)
		)
		(layer "In3.Cu")
	)
	(gr_line
		(start 74.93 -78.486)
		(end 72.263 -78.486)
		(stroke
			(width 0.381)
			(type default)
		)
		(layer "In3.Cu")
	)
	(gr_line
		(start 74.93 -36.703)
		(end 74.93 -78.486)
		(stroke
			(width 0.381)
			(type default)
		)
		(layer "In3.Cu")
	)
	(gr_line
		(start 75.311 -2.159)
		(end 74.676 -2.794)
		(stroke
			(width 0.381)
			(type default)
		)
		(layer "In3.Cu")
	)
	(gr_arc
		(start 75.449938 0)
		(mid 74.742807 -0.292879)
		(end 74.44994 -0.999998)
		(stroke
			(width 1.524)
			(type default)
		)
		(layer "In3.Cu")
	)
	(gr_line
		(start 75.449938 0)
		(end 281.485086 0)
		(stroke
			(width 1.524)
			(type default)
		)
		(layer "In3.Cu")
	)
	(gr_line
		(start 76.157074 -37.042852)
		(end 77.133958 -37.042852)
		(stroke
			(width 0.2)
			(type default)
		)
		(layer "In3.Cu")
	)
	(gr_arc
		(start 76.157328 -36.275772)
		(mid 75.773534 -36.659185)
		(end 76.157074 -37.042852)
		(stroke
			(width 0.2)
			(type default)
		)
		(layer "In3.Cu")
	)
	(gr_arc
		(start 77.133958 -37.042852)
		(mid 77.517498 -36.659312)
		(end 77.133958 -36.275772)
		(stroke
			(width 0.2)
			(type default)
		)
		(layer "In3.Cu")
	)
	(gr_line
		(start 77.133958 -36.275772)
		(end 76.157328 -36.275772)
		(stroke
			(width 0.2)
			(type default)
		)
		(layer "In3.Cu")
	)
	(gr_line
		(start 77.686408 -41.98874)
		(end 78.663038 -41.98874)
		(stroke
			(width 0.2)
			(type default)
		)
		(layer "In3.Cu")
	)
	(gr_arc
		(start 77.686408 -41.22166)
		(mid 77.302868 -41.6052)
		(end 77.686408 -41.98874)
		(stroke
			(width 0.2)
			(type default)
		)
		(layer "In3.Cu")
	)
	(gr_arc
		(start 78.663038 -41.98874)
		(mid 79.046832 -41.605327)
		(end 78.663292 -41.22166)
		(stroke
			(width 0.2)
			(type default)
		)
		(layer "In3.Cu")
	)
	(gr_line
		(start 78.663292 -41.22166)
		(end 77.686408 -41.22166)
		(stroke
			(width 0.2)
			(type default)
		)
		(layer "In3.Cu")
	)
	(gr_line
		(start 79.375 -32.258)
		(end 74.93 -36.703)
		(stroke
			(width 0.381)
			(type default)
		)
		(layer "In3.Cu")
	)
	(gr_line
		(start 79.375 -32.258)
		(end 79.883 -31.75)
		(stroke
			(width 0.381)
			(type default)
		)
		(layer "In3.Cu")
	)
	(gr_line
		(start 79.604108 -40.00754)
		(end 80.580738 -40.00754)
		(stroke
			(width 0.2)
			(type default)
		)
		(layer "In3.Cu")
	)
	(gr_arc
		(start 79.604108 -39.24046)
		(mid 79.220568 -39.624)
		(end 79.604108 -40.00754)
		(stroke
			(width 0.2)
			(type default)
		)
		(layer "In3.Cu")
	)
	(gr_line
		(start 79.883 -32.258)
		(end 79.883 -31.75)
		(stroke
			(width 0.381)
			(type default)
		)
		(layer "In3.Cu")
	)
	(gr_line
		(start 79.883 -31.75)
		(end 79.883 -16.637)
		(stroke
			(width 0.381)
			(type default)
		)
		(layer "In3.Cu")
	)
	(gr_line
		(start 79.883 -31.75)
		(end 80.391 -32.258)
		(stroke
			(width 0.381)
			(type default)
		)
		(layer "In3.Cu")
	)
	(gr_line
		(start 79.883 -16.637)
		(end 80.391 -16.129)
		(stroke
			(width 0.381)
			(type default)
		)
		(layer "In3.Cu")
	)
	(gr_line
		(start 80.391 -32.258)
		(end 79.883 -32.258)
		(stroke
			(width 0.381)
			(type default)
		)
		(layer "In3.Cu")
	)
	(gr_line
		(start 80.391 -16.129)
		(end 81.661 -16.129)
		(stroke
			(width 0.381)
			(type default)
		)
		(layer "In3.Cu")
	)
	(gr_arc
		(start 80.580738 -40.00754)
		(mid 80.964532 -39.624127)
		(end 80.580992 -39.24046)
		(stroke
			(width 0.2)
			(type default)
		)
		(layer "In3.Cu")
	)
	(gr_line
		(start 80.580992 -39.24046)
		(end 79.604108 -39.24046)
		(stroke
			(width 0.2)
			(type default)
		)
		(layer "In3.Cu")
	)
	(gr_arc
		(start 80.84566 -37.312092)
		(mid 81.2292 -37.695632)
		(end 81.61274 -37.312092)
		(stroke
			(width 0.2)
			(type default)
		)
		(layer "In3.Cu")
	)
	(gr_line
		(start 80.84566 -36.335208)
		(end 80.84566 -37.312092)
		(stroke
			(width 0.2)
			(type default)
		)
		(layer "In3.Cu")
	)
	(gr_line
		(start 81.61274 -37.312092)
		(end 81.61274 -36.335462)
		(stroke
			(width 0.2)
			(type default)
		)
		(layer "In3.Cu")
	)
	(gr_arc
		(start 81.61274 -36.335462)
		(mid 81.229327 -35.951668)
		(end 80.84566 -36.335208)
		(stroke
			(width 0.2)
			(type default)
		)
		(layer "In3.Cu")
	)
	(gr_line
		(start 81.661 -16.129)
		(end 82.423 -15.367)
		(stroke
			(width 0.381)
			(type default)
		)
		(layer "In3.Cu")
	)
	(gr_line
		(start 81.788 -32.258)
		(end 81.915 -32.131)
		(stroke
			(width 0.381)
			(type default)
		)
		(layer "In3.Cu")
	)
	(gr_line
		(start 81.8896 -31.75)
		(end 81.3562 -32.2834)
		(stroke
			(width 0.381)
			(type default)
		)
		(layer "In3.Cu")
	)
	(gr_line
		(start 81.915 -32.131)
		(end 81.915 -31.75)
		(stroke
			(width 0.381)
			(type default)
		)
		(layer "In3.Cu")
	)
	(gr_line
		(start 81.915 -31.75)
		(end 81.8896 -31.75)
		(stroke
			(width 0.381)
			(type default)
		)
		(layer "In3.Cu")
	)
	(gr_line
		(start 81.915 -31.75)
		(end 81.915 -29.718)
		(stroke
			(width 0.381)
			(type default)
		)
		(layer "In3.Cu")
	)
	(gr_line
		(start 81.915 -29.718)
		(end 82.677 -28.956)
		(stroke
			(width 0.381)
			(type default)
		)
		(layer "In3.Cu")
	)
	(gr_line
		(start 82.296 -32.258)
		(end 79.375 -32.258)
		(stroke
			(width 0.381)
			(type default)
		)
		(layer "In3.Cu")
	)
	(gr_line
		(start 82.423 -32.258)
		(end 81.915 -31.75)
		(stroke
			(width 0.381)
			(type default)
		)
		(layer "In3.Cu")
	)
	(gr_line
		(start 82.423 -15.367)
		(end 82.423 -7.366)
		(stroke
			(width 0.381)
			(type default)
		)
		(layer "In3.Cu")
	)
	(gr_line
		(start 82.423 -7.366)
		(end 82.931 -6.858)
		(stroke
			(width 0.381)
			(type default)
		)
		(layer "In3.Cu")
	)
	(gr_line
		(start 82.423 -2.159)
		(end 83.185 -2.159)
		(stroke
			(width 0.381)
			(type default)
		)
		(layer "In3.Cu")
	)
	(gr_arc
		(start 82.527648 -38.736524)
		(mid 82.911061 -39.120318)
		(end 83.294728 -38.736778)
		(stroke
			(width 0.2)
			(type default)
		)
		(layer "In3.Cu")
	)
	(gr_line
		(start 82.527648 -37.831776)
		(end 82.527648 -38.736524)
		(stroke
			(width 0.2)
			(type default)
		)
		(layer "In3.Cu")
	)
	(gr_line
		(start 82.677 -28.956)
		(end 93.345 -28.956)
		(stroke
			(width 0.381)
			(type default)
		)
		(layer "In3.Cu")
	)
	(gr_arc
		(start 82.69986 -35.523678)
		(mid 83.0834 -35.907218)
		(end 83.46694 -35.523678)
		(stroke
			(width 0.2)
			(type default)
		)
		(layer "In3.Cu")
	)
	(gr_line
		(start 82.69986 -34.618676)
		(end 82.69986 -35.523678)
		(stroke
			(width 0.2)
			(type default)
		)
		(layer "In3.Cu")
	)
	(gr_line
		(start 82.931 -6.858)
		(end 82.931 -2.159)
		(stroke
			(width 0.381)
			(type default)
		)
		(layer "In3.Cu")
	)
	(gr_line
		(start 82.931 -2.667)
		(end 82.423 -2.159)
		(stroke
			(width 0.381)
			(type default)
		)
		(layer "In3.Cu")
	)
	(gr_line
		(start 82.931 -2.159)
		(end 83.439 -2.159)
		(stroke
			(width 0.381)
			(type default)
		)
		(layer "In3.Cu")
	)
	(gr_line
		(start 83.185 -84.328)
		(end 84.074 -85.217)
		(stroke
			(width 0.381)
			(type default)
		)
		(layer "In3.Cu")
	)
	(gr_line
		(start 83.185 -76.962)
		(end 83.185 -84.328)
		(stroke
			(width 0.381)
			(type default)
		)
		(layer "In3.Cu")
	)
	(gr_line
		(start 83.294728 -38.736778)
		(end 83.294728 -37.831776)
		(stroke
			(width 0.2)
			(type default)
		)
		(layer "In3.Cu")
	)
	(gr_arc
		(start 83.294728 -37.831776)
		(mid 82.911188 -37.448236)
		(end 82.527648 -37.831776)
		(stroke
			(width 0.2)
			(type default)
		)
		(layer "In3.Cu")
	)
	(gr_line
		(start 83.439 -2.159)
		(end 82.931 -2.667)
		(stroke
			(width 0.381)
			(type default)
		)
		(layer "In3.Cu")
	)
	(gr_line
		(start 83.46694 -35.523678)
		(end 83.46694 -34.61893)
		(stroke
			(width 0.2)
			(type default)
		)
		(layer "In3.Cu")
	)
	(gr_arc
		(start 83.46694 -34.61893)
		(mid 83.083527 -34.235136)
		(end 82.69986 -34.618676)
		(stroke
			(width 0.2)
			(type default)
		)
		(layer "In3.Cu")
	)
	(gr_line
		(start 83.69554 -37.754306)
		(end 83.723734 -38.770306)
		(stroke
			(width 0.2)
			(type default)
		)
		(layer "In3.Cu")
	)
	(gr_line
		(start 83.69808 -37.754306)
		(end 83.69554 -37.754306)
		(stroke
			(width 0.2)
			(type default)
		)
		(layer "In3.Cu")
	)
	(gr_line
		(start 83.723734 -38.770306)
		(end 83.723988 -38.77056)
		(stroke
			(width 0.2)
			(type default)
		)
		(layer "In3.Cu")
	)
	(gr_line
		(start 83.723988 -38.77056)
		(end 83.726274 -38.77056)
		(stroke
			(width 0.2)
			(type default)
		)
		(layer "In3.Cu")
	)
	(gr_arc
		(start 83.726274 -38.77056)
		(mid 84.094066 -39.11854)
		(end 84.442046 -38.750748)
		(stroke
			(width 0.2)
			(type default)
		)
		(layer "In3.Cu")
	)
	(gr_line
		(start 83.947 -76.2)
		(end 83.185 -76.962)
		(stroke
			(width 0.381)
			(type default)
		)
		(layer "In3.Cu")
	)
	(gr_line
		(start 84.074 -85.217)
		(end 108.204 -85.217)
		(stroke
			(width 0.381)
			(type default)
		)
		(layer "In3.Cu")
	)
	(gr_arc
		(start 84.413852 -37.734494)
		(mid 84.04606 -37.386514)
		(end 83.69808 -37.754306)
		(stroke
			(width 0.2)
			(type default)
		)
		(layer "In3.Cu")
	)
	(gr_line
		(start 84.416392 -37.734494)
		(end 84.413852 -37.734494)
		(stroke
			(width 0.2)
			(type default)
		)
		(layer "In3.Cu")
	)
	(gr_line
		(start 84.442046 -38.750748)
		(end 84.444586 -38.750748)
		(stroke
			(width 0.2)
			(type default)
		)
		(layer "In3.Cu")
	)
	(gr_line
		(start 84.444586 -38.750748)
		(end 84.416392 -37.734494)
		(stroke
			(width 0.2)
			(type default)
		)
		(layer "In3.Cu")
	)
	(gr_arc
		(start 84.60486 -33.789874)
		(mid 84.9884 -34.173414)
		(end 85.37194 -33.789874)
		(stroke
			(width 0.2)
			(type default)
		)
		(layer "In3.Cu")
	)
	(gr_line
		(start 84.60486 -32.884872)
		(end 84.60486 -33.789874)
		(stroke
			(width 0.2)
			(type default)
		)
		(layer "In3.Cu")
	)
	(gr_line
		(start 85.37194 -33.789874)
		(end 85.37194 -32.885126)
		(stroke
			(width 0.2)
			(type default)
		)
		(layer "In3.Cu")
	)
	(gr_arc
		(start 85.37194 -32.885126)
		(mid 84.988527 -32.501332)
		(end 84.60486 -32.884872)
		(stroke
			(width 0.2)
			(type default)
		)
		(layer "In3.Cu")
	)
	(gr_line
		(start 85.598 -32.258)
		(end 82.423 -32.258)
		(stroke
			(width 0.381)
			(type default)
		)
		(layer "In3.Cu")
	)
	(gr_line
		(start 85.725 -2.159)
		(end 86.233 -2.667)
		(stroke
			(width 0.381)
			(type default)
		)
		(layer "In3.Cu")
	)
	(gr_line
		(start 86.106 -43.434)
		(end 86.106 -32.766)
		(stroke
			(width 0.381)
			(type default)
		)
		(layer "In3.Cu")
	)
	(gr_line
		(start 86.106 -32.766)
		(end 85.598 -32.258)
		(stroke
			(width 0.381)
			(type default)
		)
		(layer "In3.Cu")
	)
	(gr_line
		(start 86.233 -2.667)
		(end 86.36 -2.667)
		(stroke
			(width 0.381)
			(type default)
		)
		(layer "In3.Cu")
	)
	(gr_line
		(start 86.36 -12.065)
		(end 87.249 -12.954)
		(stroke
			(width 0.381)
			(type default)
		)
		(layer "In3.Cu")
	)
	(gr_line
		(start 86.36 -2.667)
		(end 86.868 -2.159)
		(stroke
			(width 0.381)
			(type default)
		)
		(layer "In3.Cu")
	)
	(gr_line
		(start 86.36 -2.159)
		(end 86.36 -12.065)
		(stroke
			(width 0.381)
			(type default)
		)
		(layer "In3.Cu")
	)
	(gr_line
		(start 87.249 -12.954)
		(end 99.441 -12.954)
		(stroke
			(width 0.381)
			(type default)
		)
		(layer "In3.Cu")
	)
	(gr_line
		(start 87.249 -2.159)
		(end 74.803 -2.159)
		(stroke
			(width 0.381)
			(type default)
		)
		(layer "In3.Cu")
	)
	(gr_line
		(start 90.043 -47.371)
		(end 86.106 -43.434)
		(stroke
			(width 0.381)
			(type default)
		)
		(layer "In3.Cu")
	)
	(gr_line
		(start 91.313 -13.081)
		(end 91.821 -13.589)
		(stroke
			(width 0.381)
			(type default)
		)
		(layer "In3.Cu")
	)
	(gr_line
		(start 91.821 -20.955)
		(end 91.821 -13.081)
		(stroke
			(width 0.381)
			(type default)
		)
		(layer "In3.Cu")
	)
	(gr_line
		(start 91.821 -13.589)
		(end 92.329 -13.081)
		(stroke
			(width 0.381)
			(type default)
		)
		(layer "In3.Cu")
	)
	(gr_line
		(start 92.71 -28.956)
		(end 93.218 -29.464)
		(stroke
			(width 0.381)
			(type default)
		)
		(layer "In3.Cu")
	)
	(gr_line
		(start 92.744798 -39.75354)
		(end 93.55582 -39.755318)
		(stroke
			(width 0.2)
			(type default)
		)
		(layer "In3.Cu")
	)
	(gr_line
		(start 92.746576 -42.154856)
		(end 93.550994 -42.16273)
		(stroke
			(width 0.2)
			(type default)
		)
		(layer "In3.Cu")
	)
	(gr_arc
		(start 92.746576 -39.03726)
		(mid 92.387674 -39.394511)
		(end 92.744798 -39.75354)
		(stroke
			(width 0.2)
			(type default)
		)
		(layer "In3.Cu")
	)
	(gr_arc
		(start 92.753942 -41.438576)
		(mid 92.392247 -41.793033)
		(end 92.746576 -42.154856)
		(stroke
			(width 0.2)
			(type default)
		)
		(layer "In3.Cu")
	)
	(gr_line
		(start 93.182694 -40.206422)
		(end 93.196664 -41.001696)
		(stroke
			(width 0.2)
			(type default)
		)
		(layer "In3.Cu")
	)
	(gr_line
		(start 93.19133 -35.40887)
		(end 93.193616 -36.197032)
		(stroke
			(width 0.2)
			(type default)
		)
		(layer "In3.Cu")
	)
	(gr_arc
		(start 93.192346 -43.387772)
		(mid 93.547565 -43.748961)
		(end 93.908626 -43.393614)
		(stroke
			(width 0.2)
			(type default)
		)
		(layer "In3.Cu")
	)
	(gr_arc
		(start 93.193616 -36.197032)
		(mid 93.552645 -36.55441)
		(end 93.909896 -36.195254)
		(stroke
			(width 0.2)
			(type default)
		)
		(layer "In3.Cu")
	)
	(gr_arc
		(start 93.196664 -41.001696)
		(mid 93.561027 -41.353738)
		(end 93.912944 -40.98925)
		(stroke
			(width 0.2)
			(type default)
		)
		(layer "In3.Cu")
	)
	(gr_arc
		(start 93.197426 -38.596316)
		(mid 93.555058 -38.954964)
		(end 93.913706 -38.597332)
		(stroke
			(width 0.2)
			(type default)
		)
		(layer "In3.Cu")
	)
	(gr_line
		(start 93.198442 -37.80155)
		(end 93.197426 -38.596316)
		(stroke
			(width 0.2)
			(type default)
		)
		(layer "In3.Cu")
	)
	(gr_line
		(start 93.198696 -42.59453)
		(end 93.192346 -43.387772)
		(stroke
			(width 0.2)
			(type default)
		)
		(layer "In3.Cu")
	)
	(gr_line
		(start 93.218 -28.448)
		(end 92.71 -28.956)
		(stroke
			(width 0.381)
			(type default)
		)
		(layer "In3.Cu")
	)
	(gr_line
		(start 93.345 -37.465)
		(end 93.98 -38.1)
		(stroke
			(width 0.381)
			(type default)
		)
		(layer "In3.Cu")
	)
	(gr_line
		(start 93.345 -28.956)
		(end 93.345 -37.465)
		(stroke
			(width 0.381)
			(type default)
		)
		(layer "In3.Cu")
	)
	(gr_line
		(start 93.345 -28.956)
		(end 93.345 -22.479)
		(stroke
			(width 0.381)
			(type default)
		)
		(layer "In3.Cu")
	)
	(gr_line
		(start 93.345 -22.479)
		(end 91.821 -20.955)
		(stroke
			(width 0.381)
			(type default)
		)
		(layer "In3.Cu")
	)
	(gr_arc
		(start 93.544644 -34.248344)
		(mid 93.189297 -34.609151)
		(end 93.549978 -34.964624)
		(stroke
			(width 0.2)
			(type default)
		)
		(layer "In3.Cu")
	)
	(gr_line
		(start 93.549978 -34.964624)
		(end 94.352618 -34.958274)
		(stroke
			(width 0.2)
			(type default)
		)
		(layer "In3.Cu")
	)
	(gr_arc
		(start 93.550232 -36.64458)
		(mid 93.193616 -37.004244)
		(end 93.55328 -37.36086)
		(stroke
			(width 0.2)
			(type default)
		)
		(layer "In3.Cu")
	)
	(gr_arc
		(start 93.550994 -42.16273)
		(mid 93.91269 -41.808146)
		(end 93.558106 -41.44645)
		(stroke
			(width 0.2)
			(type default)
		)
		(layer "In3.Cu")
	)
	(gr_line
		(start 93.55328 -37.36086)
		(end 94.360492 -37.357558)
		(stroke
			(width 0.2)
			(type default)
		)
		(layer "In3.Cu")
	)
	(gr_arc
		(start 93.55582 -39.755318)
		(mid 93.914722 -39.39794)
		(end 93.557344 -39.039038)
		(stroke
			(width 0.2)
			(type default)
		)
		(layer "In3.Cu")
	)
	(gr_line
		(start 93.557344 -39.039038)
		(end 92.746576 -39.03726)
		(stroke
			(width 0.2)
			(type default)
		)
		(layer "In3.Cu")
	)
	(gr_line
		(start 93.558106 -41.44645)
		(end 92.753942 -41.438576)
		(stroke
			(width 0.2)
			(type default)
		)
		(layer "In3.Cu")
	)
	(gr_arc
		(start 93.898974 -40.193722)
		(mid 93.534484 -39.841932)
		(end 93.182694 -40.206422)
		(stroke
			(width 0.2)
			(type default)
		)
		(layer "In3.Cu")
	)
	(gr_line
		(start 93.90761 -35.407854)
		(end 93.90761 -35.406838)
		(stroke
			(width 0.2)
			(type default)
		)
		(layer "In3.Cu")
	)
	(gr_arc
		(start 93.90761 -35.406838)
		(mid 93.548454 -35.049714)
		(end 93.19133 -35.40887)
		(stroke
			(width 0.2)
			(type default)
		)
		(layer "In3.Cu")
	)
	(gr_line
		(start 93.908626 -43.393614)
		(end 93.914976 -42.600118)
		(stroke
			(width 0.2)
			(type default)
		)
		(layer "In3.Cu")
	)
	(gr_line
		(start 93.909896 -36.195254)
		(end 93.90761 -35.407854)
		(stroke
			(width 0.2)
			(type default)
		)
		(layer "In3.Cu")
	)
	(gr_line
		(start 93.912944 -40.98925)
		(end 93.898974 -40.193722)
		(stroke
			(width 0.2)
			(type default)
		)
		(layer "In3.Cu")
	)
	(gr_line
		(start 93.913706 -38.597332)
		(end 93.913706 -38.596824)
		(stroke
			(width 0.2)
			(type default)
		)
		(layer "In3.Cu")
	)
	(gr_line
		(start 93.913706 -38.596824)
		(end 93.914722 -37.80282)
		(stroke
			(width 0.2)
			(type default)
		)
		(layer "In3.Cu")
	)
	(gr_arc
		(start 93.914722 -37.80282)
		(mid 93.557217 -37.444172)
		(end 93.198442 -37.80155)
		(stroke
			(width 0.2)
			(type default)
		)
		(layer "In3.Cu")
	)
	(gr_arc
		(start 93.914976 -42.600118)
		(mid 93.55963 -42.239184)
		(end 93.198696 -42.59453)
		(stroke
			(width 0.2)
			(type default)
		)
		(layer "In3.Cu")
	)
	(gr_line
		(start 93.98 -38.1)
		(end 96.393 -38.1)
		(stroke
			(width 0.381)
			(type default)
		)
		(layer "In3.Cu")
	)
	(gr_line
		(start 94.34703 -34.241994)
		(end 93.544644 -34.248344)
		(stroke
			(width 0.2)
			(type default)
		)
		(layer "In3.Cu")
	)
	(gr_arc
		(start 94.352618 -34.958274)
		(mid 94.707964 -34.59734)
		(end 94.34703 -34.241994)
		(stroke
			(width 0.2)
			(type default)
		)
		(layer "In3.Cu")
	)
	(gr_line
		(start 94.357698 -36.641278)
		(end 93.550232 -36.64458)
		(stroke
			(width 0.2)
			(type default)
		)
		(layer "In3.Cu")
	)
	(gr_arc
		(start 94.360492 -37.357558)
		(mid 94.717362 -36.998021)
		(end 94.357698 -36.641278)
		(stroke
			(width 0.2)
			(type default)
		)
		(layer "In3.Cu")
	)
	(gr_line
		(start 94.79026 -35.405822)
		(end 94.792038 -36.200588)
		(stroke
			(width 0.2)
			(type default)
		)
		(layer "In3.Cu")
	)
	(gr_arc
		(start 94.792038 -36.200588)
		(mid 95.150813 -36.55822)
		(end 95.508318 -36.199318)
		(stroke
			(width 0.2)
			(type default)
		)
		(layer "In3.Cu")
	)
	(gr_line
		(start 95.504 -167.767)
		(end 96.647 -167.767)
		(stroke
			(width 0.4064)
			(type default)
		)
		(layer "In3.Cu")
	)
	(gr_line
		(start 95.50654 -35.40506)
		(end 95.50654 -35.404298)
		(stroke
			(width 0.2)
			(type default)
		)
		(layer "In3.Cu")
	)
	(gr_arc
		(start 95.50654 -35.404298)
		(mid 95.147638 -35.04692)
		(end 94.79026 -35.405822)
		(stroke
			(width 0.2)
			(type default)
		)
		(layer "In3.Cu")
	)
	(gr_line
		(start 95.508318 -36.199318)
		(end 95.50654 -35.40506)
		(stroke
			(width 0.2)
			(type default)
		)
		(layer "In3.Cu")
	)
	(gr_line
		(start 95.59036 -35.408362)
		(end 95.592138 -36.200588)
		(stroke
			(width 0.2)
			(type default)
		)
		(layer "In3.Cu")
	)
	(gr_arc
		(start 95.592138 -36.200588)
		(mid 95.950913 -36.55822)
		(end 96.308418 -36.199318)
		(stroke
			(width 0.2)
			(type default)
		)
		(layer "In3.Cu")
	)
	(gr_line
		(start 96.30664 -35.4076)
		(end 96.30664 -35.406838)
		(stroke
			(width 0.2)
			(type default)
		)
		(layer "In3.Cu")
	)
	(gr_arc
		(start 96.30664 -35.406838)
		(mid 95.947738 -35.04946)
		(end 95.59036 -35.408362)
		(stroke
			(width 0.2)
			(type default)
		)
		(layer "In3.Cu")
	)
	(gr_line
		(start 96.308418 -36.199318)
		(end 96.30664 -35.4076)
		(stroke
			(width 0.2)
			(type default)
		)
		(layer "In3.Cu")
	)
	(gr_line
		(start 96.393 -38.1)
		(end 97.536 -39.243)
		(stroke
			(width 0.381)
			(type default)
		)
		(layer "In3.Cu")
	)
	(gr_line
		(start 96.647 -167.767)
		(end 97.663 -166.751)
		(stroke
			(width 0.4064)
			(type default)
		)
		(layer "In3.Cu")
	)
	(gr_line
		(start 96.9518 -47.3964)
		(end 96.9518 -47.3202)
		(stroke
			(width 0.381)
			(type default)
		)
		(layer "In3.Cu")
	)
	(gr_line
		(start 96.9518 -47.3202)
		(end 97.4852 -46.7868)
		(stroke
			(width 0.381)
			(type default)
		)
		(layer "In3.Cu")
	)
	(gr_line
		(start 97.028 -152.654)
		(end 97.536 -153.162)
		(stroke
			(width 0.381)
			(type default)
		)
		(layer "In3.Cu")
	)
	(gr_line
		(start 97.182686 -35.404552)
		(end 97.192084 -36.204144)
		(stroke
			(width 0.2)
			(type default)
		)
		(layer "In3.Cu")
	)
	(gr_arc
		(start 97.192084 -36.204144)
		(mid 97.554415 -36.558219)
		(end 97.908364 -36.195762)
		(stroke
			(width 0.2)
			(type default)
		)
		(layer "In3.Cu")
	)
	(gr_line
		(start 97.536 -153.162)
		(end 97.79 -153.162)
		(stroke
			(width 0.381)
			(type default)
		)
		(layer "In3.Cu")
	)
	(gr_line
		(start 97.536 -50.038)
		(end 98.171 -50.673)
		(stroke
			(width 0.381)
			(type default)
		)
		(layer "In3.Cu")
	)
	(gr_line
		(start 97.536 -47.9806)
		(end 96.9518 -47.3964)
		(stroke
			(width 0.381)
			(type default)
		)
		(layer "In3.Cu")
	)
	(gr_line
		(start 97.536 -47.371)
		(end 90.043 -47.371)
		(stroke
			(width 0.381)
			(type default)
		)
		(layer "In3.Cu")
	)
	(gr_line
		(start 97.536 -40.767)
		(end 98.044 -40.259)
		(stroke
			(width 0.381)
			(type default)
		)
		(layer "In3.Cu")
	)
	(gr_line
		(start 97.536 -39.243)
		(end 97.536 -50.038)
		(stroke
			(width 0.381)
			(type default)
		)
		(layer "In3.Cu")
	)
	(gr_line
		(start 97.663 -166.751)
		(end 97.663 -152.654)
		(stroke
			(width 0.381)
			(type default)
		)
		(layer "In3.Cu")
	)
	(gr_line
		(start 97.663 -152.654)
		(end 61.976 -152.654)
		(stroke
			(width 0.381)
			(type default)
		)
		(layer "In3.Cu")
	)
	(gr_line
		(start 97.663 -152.654)
		(end 137.033 -152.654)
		(stroke
			(width 0.381)
			(type default)
		)
		(layer "In3.Cu")
	)
	(gr_line
		(start 97.79 -153.162)
		(end 98.298 -152.654)
		(stroke
			(width 0.381)
			(type default)
		)
		(layer "In3.Cu")
	)
	(gr_arc
		(start 97.898966 -35.395916)
		(mid 97.536508 -35.042094)
		(end 97.182686 -35.404552)
		(stroke
			(width 0.2)
			(type default)
		)
		(layer "In3.Cu")
	)
	(gr_line
		(start 97.908364 -36.195762)
		(end 97.898966 -35.395916)
		(stroke
			(width 0.2)
			(type default)
		)
		(layer "In3.Cu")
	)
	(gr_line
		(start 97.983802 -35.405314)
		(end 97.992184 -36.203636)
		(stroke
			(width 0.2)
			(type default)
		)
		(layer "In3.Cu")
	)
	(gr_arc
		(start 97.992184 -36.203636)
		(mid 98.354007 -36.558219)
		(end 98.708464 -36.19627)
		(stroke
			(width 0.2)
			(type default)
		)
		(layer "In3.Cu")
	)
	(gr_line
		(start 98.044 -40.259)
		(end 97.536 -39.751)
		(stroke
			(width 0.381)
			(type default)
		)
		(layer "In3.Cu")
	)
	(gr_line
		(start 98.171 -50.673)
		(end 101.6 -50.673)
		(stroke
			(width 0.381)
			(type default)
		)
		(layer "In3.Cu")
	)
	(gr_arc
		(start 98.700082 -35.397694)
		(mid 98.338132 -35.043364)
		(end 97.983802 -35.405314)
		(stroke
			(width 0.2)
			(type default)
		)
		(layer "In3.Cu")
	)
	(gr_line
		(start 98.708464 -36.19627)
		(end 98.700082 -35.397694)
		(stroke
			(width 0.2)
			(type default)
		)
		(layer "In3.Cu")
	)
	(gr_line
		(start 99.441 -12.954)
		(end 106.934 -20.447)
		(stroke
			(width 0.381)
			(type default)
		)
		(layer "In3.Cu")
	)
	(gr_arc
		(start 99.59213 -36.199318)
		(mid 99.949635 -36.55822)
		(end 100.30841 -36.200588)
		(stroke
			(width 0.2)
			(type default)
		)
		(layer "In3.Cu")
	)
	(gr_line
		(start 99.5934 -35.391852)
		(end 99.59213 -36.199318)
		(stroke
			(width 0.2)
			(type default)
		)
		(layer "In3.Cu")
	)
	(gr_line
		(start 100.30841 -36.200588)
		(end 100.30841 -36.20008)
		(stroke
			(width 0.2)
			(type default)
		)
		(layer "In3.Cu")
	)
	(gr_line
		(start 100.30841 -36.20008)
		(end 100.30968 -35.392868)
		(stroke
			(width 0.2)
			(type default)
		)
		(layer "In3.Cu")
	)
	(gr_arc
		(start 100.30968 -35.392868)
		(mid 99.952048 -35.03422)
		(end 99.5934 -35.391852)
		(stroke
			(width 0.2)
			(type default)
		)
		(layer "In3.Cu")
	)
	(gr_arc
		(start 100.39223 -36.196524)
		(mid 100.746941 -36.558221)
		(end 101.10851 -36.203382)
		(stroke
			(width 0.2)
			(type default)
		)
		(layer "In3.Cu")
	)
	(gr_line
		(start 100.399342 -35.394646)
		(end 100.39223 -36.196524)
		(stroke
			(width 0.2)
			(type default)
		)
		(layer "In3.Cu")
	)
	(gr_line
		(start 101.10851 -36.203382)
		(end 101.115622 -35.40125)
		(stroke
			(width 0.2)
			(type default)
		)
		(layer "In3.Cu")
	)
	(gr_arc
		(start 101.115622 -35.40125)
		(mid 100.760784 -35.039808)
		(end 100.399342 -35.394646)
		(stroke
			(width 0.2)
			(type default)
		)
		(layer "In3.Cu")
	)
	(gr_line
		(start 101.6 -50.673)
		(end 111.76 -50.673)
		(stroke
			(width 0.381)
			(type default)
		)
		(layer "In3.Cu")
	)
	(gr_line
		(start 101.991922 -35.400234)
		(end 101.992176 -36.199826)
		(stroke
			(width 0.2)
			(type default)
		)
		(layer "In3.Cu")
	)
	(gr_arc
		(start 101.992176 -36.199826)
		(mid 102.350316 -36.55822)
		(end 102.708456 -36.199826)
		(stroke
			(width 0.2)
			(type default)
		)
		(layer "In3.Cu")
	)
	(gr_line
		(start 102.708202 -35.75812)
		(end 102.708202 -35.39998)
		(stroke
			(width 0.2)
			(type default)
		)
		(layer "In3.Cu")
	)
	(gr_arc
		(start 102.708202 -35.39998)
		(mid 102.349935 -35.04184)
		(end 101.991922 -35.400234)
		(stroke
			(width 0.2)
			(type default)
		)
		(layer "In3.Cu")
	)
	(gr_line
		(start 102.708456 -36.199826)
		(end 102.708202 -35.75812)
		(stroke
			(width 0.2)
			(type default)
		)
		(layer "In3.Cu")
	)
	(gr_arc
		(start 102.792022 -36.199826)
		(mid 103.150035 -36.55822)
		(end 103.508302 -36.20008)
		(stroke
			(width 0.2)
			(type default)
		)
		(layer "In3.Cu")
	)
	(gr_line
		(start 102.792022 -35.400234)
		(end 102.792022 -36.199826)
		(stroke
			(width 0.2)
			(type default)
		)
		(layer "In3.Cu")
	)
	(gr_line
		(start 103.508302 -36.20008)
		(end 103.508302 -35.400234)
		(stroke
			(width 0.2)
			(type default)
		)
		(layer "In3.Cu")
	)
	(gr_arc
		(start 103.508302 -35.400234)
		(mid 103.150162 -35.042094)
		(end 102.792022 -35.400234)
		(stroke
			(width 0.2)
			(type default)
		)
		(layer "In3.Cu")
	)
	(gr_line
		(start 103.886 -40.259)
		(end 97.536 -40.259)
		(stroke
			(width 0.381)
			(type default)
		)
		(layer "In3.Cu")
	)
	(gr_line
		(start 106.426 -114.046)
		(end 106.426 -109.347)
		(stroke
			(width 0.381)
			(type default)
		)
		(layer "In3.Cu")
	)
	(gr_line
		(start 106.426 -109.347)
		(end 107.442 -108.331)
		(stroke
			(width 0.381)
			(type default)
		)
		(layer "In3.Cu")
	)
	(gr_arc
		(start 106.491532 -103.850186)
		(mid 106.849672 -104.208326)
		(end 107.207812 -103.850186)
		(stroke
			(width 0.2)
			(type default)
		)
		(layer "In3.Cu")
	)
	(gr_line
		(start 106.491532 -102.850188)
		(end 106.491532 -103.850186)
		(stroke
			(width 0.2)
			(type default)
		)
		(layer "In3.Cu")
	)
	(gr_line
		(start 106.807 -114.427)
		(end 106.426 -114.046)
		(stroke
			(width 0.381)
			(type default)
		)
		(layer "In3.Cu")
	)
	(gr_line
		(start 106.934 -37.211)
		(end 103.886 -40.259)
		(stroke
			(width 0.381)
			(type default)
		)
		(layer "In3.Cu")
	)
	(gr_line
		(start 106.934 -20.447)
		(end 106.934 -37.211)
		(stroke
			(width 0.381)
			(type default)
		)
		(layer "In3.Cu")
	)
	(gr_line
		(start 107.207812 -103.850186)
		(end 107.207812 -102.850442)
		(stroke
			(width 0.2)
			(type default)
		)
		(layer "In3.Cu")
	)
	(gr_arc
		(start 107.207812 -102.850442)
		(mid 106.849799 -102.492048)
		(end 106.491532 -102.850188)
		(stroke
			(width 0.2)
			(type default)
		)
		(layer "In3.Cu")
	)
	(gr_line
		(start 107.442 -108.331)
		(end 107.442 -104.775)
		(stroke
			(width 0.381)
			(type default)
		)
		(layer "In3.Cu")
	)
	(gr_line
		(start 107.442 -104.775)
		(end 107.696 -104.521)
		(stroke
			(width 0.381)
			(type default)
		)
		(layer "In3.Cu")
	)
	(gr_arc
		(start 107.49153 -103.850186)
		(mid 107.84967 -104.208326)
		(end 108.20781 -103.850186)
		(stroke
			(width 0.2)
			(type default)
		)
		(layer "In3.Cu")
	)
	(gr_line
		(start 107.49153 -102.850188)
		(end 107.49153 -103.850186)
		(stroke
			(width 0.2)
			(type default)
		)
		(layer "In3.Cu")
	)
	(gr_line
		(start 107.696 -104.521)
		(end 107.696 -101.6)
		(stroke
			(width 0.381)
			(type default)
		)
		(layer "In3.Cu")
	)
	(gr_line
		(start 107.696 -101.6)
		(end 108.077 -101.219)
		(stroke
			(width 0.381)
			(type default)
		)
		(layer "In3.Cu")
	)
	(gr_line
		(start 108.077 -101.219)
		(end 117.729 -101.219)
		(stroke
			(width 0.381)
			(type default)
		)
		(layer "In3.Cu")
	)
	(gr_line
		(start 108.204 -85.217)
		(end 111.76 -88.773)
		(stroke
			(width 0.381)
			(type default)
		)
		(layer "In3.Cu")
	)
	(gr_line
		(start 108.20781 -103.850186)
		(end 108.20781 -102.850442)
		(stroke
			(width 0.2)
			(type default)
		)
		(layer "In3.Cu")
	)
	(gr_arc
		(start 108.20781 -102.850442)
		(mid 107.849797 -102.492048)
		(end 107.49153 -102.850188)
		(stroke
			(width 0.2)
			(type default)
		)
		(layer "In3.Cu")
	)
	(gr_arc
		(start 108.491528 -103.849932)
		(mid 108.849541 -104.208326)
		(end 109.207808 -103.850186)
		(stroke
			(width 0.2)
			(type default)
		)
		(layer "In3.Cu")
	)
	(gr_line
		(start 108.491528 -102.850188)
		(end 108.491528 -103.849932)
		(stroke
			(width 0.2)
			(type default)
		)
		(layer "In3.Cu")
	)
	(gr_line
		(start 109.207808 -103.850186)
		(end 109.207808 -102.850188)
		(stroke
			(width 0.2)
			(type default)
		)
		(layer "In3.Cu")
	)
	(gr_arc
		(start 109.207808 -102.850188)
		(mid 108.849668 -102.492048)
		(end 108.491528 -102.850188)
		(stroke
			(width 0.2)
			(type default)
		)
		(layer "In3.Cu")
	)
	(gr_arc
		(start 109.491526 -103.849932)
		(mid 109.849539 -104.208326)
		(end 110.207806 -103.850186)
		(stroke
			(width 0.2)
			(type default)
		)
		(layer "In3.Cu")
	)
	(gr_line
		(start 109.491526 -102.850188)
		(end 109.491526 -103.849932)
		(stroke
			(width 0.2)
			(type default)
		)
		(layer "In3.Cu")
	)
	(gr_line
		(start 110.207806 -103.850186)
		(end 110.207806 -102.850188)
		(stroke
			(width 0.2)
			(type default)
		)
		(layer "In3.Cu")
	)
	(gr_arc
		(start 110.207806 -102.850188)
		(mid 109.849666 -102.492048)
		(end 109.491526 -102.850188)
		(stroke
			(width 0.2)
			(type default)
		)
		(layer "In3.Cu")
	)
	(gr_arc
		(start 110.491524 -103.850186)
		(mid 110.849664 -104.208326)
		(end 111.207804 -103.850186)
		(stroke
			(width 0.2)
			(type default)
		)
		(layer "In3.Cu")
	)
	(gr_line
		(start 110.491524 -102.850188)
		(end 110.491524 -103.850186)
		(stroke
			(width 0.2)
			(type default)
		)
		(layer "In3.Cu")
	)
	(gr_line
		(start 111.207804 -103.850186)
		(end 111.207804 -102.850442)
		(stroke
			(width 0.2)
			(type default)
		)
		(layer "In3.Cu")
	)
	(gr_arc
		(start 111.207804 -102.850442)
		(mid 110.849791 -102.492048)
		(end 110.491524 -102.850188)
		(stroke
			(width 0.2)
			(type default)
		)
		(layer "In3.Cu")
	)
	(gr_arc
		(start 111.491522 -103.849932)
		(mid 111.849535 -104.208326)
		(end 112.207802 -103.850186)
		(stroke
			(width 0.2)
			(type default)
		)
		(layer "In3.Cu")
	)
	(gr_line
		(start 111.491522 -102.850188)
		(end 111.491522 -103.849932)
		(stroke
			(width 0.2)
			(type default)
		)
		(layer "In3.Cu")
	)
	(gr_line
		(start 111.76 -88.773)
		(end 112.522 -88.773)
		(stroke
			(width 0.381)
			(type default)
		)
		(layer "In3.Cu")
	)
	(gr_line
		(start 111.76 -50.673)
		(end 120.65 -41.783)
		(stroke
			(width 0.381)
			(type default)
		)
		(layer "In3.Cu")
	)
	(gr_line
		(start 112.207802 -103.850186)
		(end 112.207802 -102.850188)
		(stroke
			(width 0.2)
			(type default)
		)
		(layer "In3.Cu")
	)
	(gr_arc
		(start 112.207802 -102.850188)
		(mid 111.849662 -102.492048)
		(end 111.491522 -102.850188)
		(stroke
			(width 0.2)
			(type default)
		)
		(layer "In3.Cu")
	)
	(gr_arc
		(start 112.49152 -103.850186)
		(mid 112.84966 -104.208326)
		(end 113.2078 -103.850186)
		(stroke
			(width 0.2)
			(type default)
		)
		(layer "In3.Cu")
	)
	(gr_line
		(start 112.49152 -102.850188)
		(end 112.49152 -103.850186)
		(stroke
			(width 0.2)
			(type default)
		)
		(layer "In3.Cu")
	)
	(gr_line
		(start 112.522 -88.773)
		(end 116.459 -88.773)
		(stroke
			(width 0.381)
			(type default)
		)
		(layer "In3.Cu")
	)
	(gr_line
		(start 112.776 -76.2)
		(end 83.947 -76.2)
		(stroke
			(width 0.381)
			(type default)
		)
		(layer "In3.Cu")
	)
	(gr_line
		(start 113.2078 -103.850186)
		(end 113.2078 -102.850442)
		(stroke
			(width 0.2)
			(type default)
		)
		(layer "In3.Cu")
	)
	(gr_arc
		(start 113.2078 -102.850442)
		(mid 112.849787 -102.492048)
		(end 112.49152 -102.850188)
		(stroke
			(width 0.2)
			(type default)
		)
		(layer "In3.Cu")
	)
	(gr_arc
		(start 113.491518 -103.849932)
		(mid 113.849531 -104.208326)
		(end 114.207798 -103.850186)
		(stroke
			(width 0.2)
			(type default)
		)
		(layer "In3.Cu")
	)
	(gr_line
		(start 113.491518 -102.850188)
		(end 113.491518 -103.849932)
		(stroke
			(width 0.2)
			(type default)
		)
		(layer "In3.Cu")
	)
	(gr_line
		(start 114.207798 -103.850186)
		(end 114.207798 -102.850188)
		(stroke
			(width 0.2)
			(type default)
		)
		(layer "In3.Cu")
	)
	(gr_arc
		(start 114.207798 -102.850188)
		(mid 113.849658 -102.492048)
		(end 113.491518 -102.850188)
		(stroke
			(width 0.2)
			(type default)
		)
		(layer "In3.Cu")
	)
	(gr_arc
		(start 114.506502 -103.830882)
		(mid 114.864642 -104.189022)
		(end 115.222782 -103.830882)
		(stroke
			(width 0.2)
			(type default)
		)
		(layer "In3.Cu")
	)
	(gr_line
		(start 114.506502 -102.840282)
		(end 114.506502 -103.830882)
		(stroke
			(width 0.2)
			(type default)
		)
		(layer "In3.Cu")
	)
	(gr_line
		(start 114.554 -2.159)
		(end 87.249 -2.159)
		(stroke
			(width 0.381)
			(type default)
		)
		(layer "In3.Cu")
	)
	(gr_line
		(start 115.222782 -103.830882)
		(end 115.222782 -102.840536)
		(stroke
			(width 0.2)
			(type default)
		)
		(layer "In3.Cu")
	)
	(gr_arc
		(start 115.222782 -102.840536)
		(mid 114.864769 -102.482142)
		(end 114.506502 -102.840282)
		(stroke
			(width 0.2)
			(type default)
		)
		(layer "In3.Cu")
	)
	(gr_arc
		(start 115.522502 -103.830882)
		(mid 115.880642 -104.189022)
		(end 116.238782 -103.830882)
		(stroke
			(width 0.2)
			(type default)
		)
		(layer "In3.Cu")
	)
	(gr_line
		(start 115.522502 -102.840282)
		(end 115.522502 -103.830882)
		(stroke
			(width 0.2)
			(type default)
		)
		(layer "In3.Cu")
	)
	(gr_line
		(start 116.238782 -103.830882)
		(end 116.238782 -102.840536)
		(stroke
			(width 0.2)
			(type default)
		)
		(layer "In3.Cu")
	)
	(gr_arc
		(start 116.238782 -102.840536)
		(mid 115.880769 -102.482142)
		(end 115.522502 -102.840282)
		(stroke
			(width 0.2)
			(type default)
		)
		(layer "In3.Cu")
	)
	(gr_line
		(start 116.459 -88.773)
		(end 117.094 -88.138)
		(stroke
			(width 0.381)
			(type default)
		)
		(layer "In3.Cu")
	)
	(gr_line
		(start 117.094 -88.138)
		(end 117.094 -80.518)
		(stroke
			(width 0.381)
			(type default)
		)
		(layer "In3.Cu")
	)
	(gr_line
		(start 117.094 -80.518)
		(end 112.776 -76.2)
		(stroke
			(width 0.381)
			(type default)
		)
		(layer "In3.Cu")
	)
	(gr_arc
		(start 117.492018 -103.849932)
		(mid 117.850031 -104.208326)
		(end 118.208298 -103.850186)
		(stroke
			(width 0.2)
			(type default)
		)
		(layer "In3.Cu")
	)
	(gr_line
		(start 117.492018 -102.850188)
		(end 117.492018 -103.849932)
		(stroke
			(width 0.2)
			(type default)
		)
		(layer "In3.Cu")
	)
	(gr_line
		(start 117.729 -101.219)
		(end 118.999 -99.949)
		(stroke
			(width 0.381)
			(type default)
		)
		(layer "In3.Cu")
	)
	(gr_line
		(start 118.208298 -103.850186)
		(end 118.208298 -102.850188)
		(stroke
			(width 0.2)
			(type default)
		)
		(layer "In3.Cu")
	)
	(gr_arc
		(start 118.208298 -102.850188)
		(mid 117.850158 -102.492048)
		(end 117.492018 -102.850188)
		(stroke
			(width 0.2)
			(type default)
		)
		(layer "In3.Cu")
	)
	(gr_arc
		(start 118.492016 -103.849932)
		(mid 118.850029 -104.208326)
		(end 119.208296 -103.850186)
		(stroke
			(width 0.2)
			(type default)
		)
		(layer "In3.Cu")
	)
	(gr_line
		(start 118.492016 -102.850188)
		(end 118.492016 -103.849932)
		(stroke
			(width 0.2)
			(type default)
		)
		(layer "In3.Cu")
	)
	(gr_line
		(start 118.999 -99.949)
		(end 118.999 -98.171)
		(stroke
			(width 0.381)
			(type default)
		)
		(layer "In3.Cu")
	)
	(gr_line
		(start 118.999 -98.171)
		(end 121.031 -96.139)
		(stroke
			(width 0.381)
			(type default)
		)
		(layer "In3.Cu")
	)
	(gr_line
		(start 119.208296 -103.850186)
		(end 119.208296 -102.850188)
		(stroke
			(width 0.2)
			(type default)
		)
		(layer "In3.Cu")
	)
	(gr_arc
		(start 119.208296 -102.850188)
		(mid 118.850156 -102.492048)
		(end 118.492016 -102.850188)
		(stroke
			(width 0.2)
			(type default)
		)
		(layer "In3.Cu")
	)
	(gr_line
		(start 120.65 -41.783)
		(end 120.65 -8.255)
		(stroke
			(width 0.381)
			(type default)
		)
		(layer "In3.Cu")
	)
	(gr_line
		(start 120.65 -8.255)
		(end 114.554 -2.159)
		(stroke
			(width 0.381)
			(type default)
		)
		(layer "In3.Cu")
	)
	(gr_line
		(start 121.031 -96.139)
		(end 121.031 -82.042)
		(stroke
			(width 0.381)
			(type default)
		)
		(layer "In3.Cu")
	)
	(gr_line
		(start 121.031 -82.042)
		(end 121.412 -81.661)
		(stroke
			(width 0.381)
			(type default)
		)
		(layer "In3.Cu")
	)
	(gr_line
		(start 121.412 -81.661)
		(end 124.841 -81.661)
		(stroke
			(width 0.381)
			(type default)
		)
		(layer "In3.Cu")
	)
	(gr_line
		(start 122.492008 -91.849956)
		(end 122.492262 -92.827348)
		(stroke
			(width 0.2)
			(type default)
		)
		(layer "In3.Cu")
	)
	(gr_arc
		(start 122.492262 -92.827348)
		(mid 122.850402 -93.185742)
		(end 123.208542 -92.827348)
		(stroke
			(width 0.2)
			(type default)
		)
		(layer "In3.Cu")
	)
	(gr_arc
		(start 122.829574 -84.492084)
		(mid 122.492516 -84.87029)
		(end 122.870722 -85.207348)
		(stroke
			(width 0.2)
			(type default)
		)
		(layer "In3.Cu")
	)
	(gr_line
		(start 122.848116 -94.186502)
		(end 123.843542 -94.206822)
		(stroke
			(width 0.2)
			(type default)
		)
		(layer "In3.Cu")
	)
	(gr_line
		(start 122.850148 -91.207844)
		(end 123.850146 -91.207844)
		(stroke
			(width 0.2)
			(type default)
		)
		(layer "In3.Cu")
	)
	(gr_line
		(start 122.850148 -90.207846)
		(end 123.850146 -90.207846)
		(stroke
			(width 0.2)
			(type default)
		)
		(layer "In3.Cu")
	)
	(gr_line
		(start 122.850148 -84.207858)
		(end 123.849892 -84.207858)
		(stroke
			(width 0.2)
			(type default)
		)
		(layer "In3.Cu")
	)
	(gr_arc
		(start 122.850148 -83.491578)
		(mid 122.492008 -83.849718)
		(end 122.850148 -84.207858)
		(stroke
			(width 0.2)
			(type default)
		)
		(layer "In3.Cu")
	)
	(gr_line
		(start 122.850148 -83.20786)
		(end 123.850146 -83.20786)
		(stroke
			(width 0.2)
			(type default)
		)
		(layer "In3.Cu")
	)
	(gr_arc
		(start 122.850402 -90.491564)
		(mid 122.492008 -90.849577)
		(end 122.850148 -91.207844)
		(stroke
			(width 0.2)
			(type default)
		)
		(layer "In3.Cu")
	)
	(gr_arc
		(start 122.850402 -89.491566)
		(mid 122.492008 -89.849579)
		(end 122.850148 -90.207846)
		(stroke
			(width 0.2)
			(type default)
		)
		(layer "In3.Cu")
	)
	(gr_arc
		(start 122.850402 -82.49158)
		(mid 122.492008 -82.849593)
		(end 122.850148 -83.20786)
		(stroke
			(width 0.2)
			(type default)
		)
		(layer "In3.Cu")
	)
	(gr_arc
		(start 122.862848 -93.470222)
		(mid 122.497342 -93.820996)
		(end 122.848116 -94.186502)
		(stroke
			(width 0.2)
			(type default)
		)
		(layer "In3.Cu")
	)
	(gr_line
		(start 122.870722 -85.207348)
		(end 123.84532 -85.151214)
		(stroke
			(width 0.2)
			(type default)
		)
		(layer "In3.Cu")
	)
	(gr_line
		(start 122.924062 -81.28254)
		(end 123.831858 -81.308956)
		(stroke
			(width 0.2)
			(type default)
		)
		(layer "In3.Cu")
	)
	(gr_arc
		(start 122.92457 -81.430114)
		(mid 122.578114 -81.79943)
		(end 122.94743 -82.145886)
		(stroke
			(width 0.2)
			(type default)
		)
		(layer "In3.Cu")
	)
	(gr_line
		(start 122.92457 -81.427828)
		(end 122.92457 -81.430114)
		(stroke
			(width 0.2)
			(type default)
		)
		(layer "In3.Cu")
	)
	(gr_line
		(start 122.924824 -81.427574)
		(end 122.92457 -81.427828)
		(stroke
			(width 0.2)
			(type default)
		)
		(layer "In3.Cu")
	)
	(gr_arc
		(start 122.925332 -80.56626)
		(mid 122.566684 -80.923765)
		(end 122.924062 -81.28254)
		(stroke
			(width 0.2)
			(type default)
		)
		(layer "In3.Cu")
	)
	(gr_line
		(start 122.94743 -82.148426)
		(end 123.7488 -82.123026)
		(stroke
			(width 0.2)
			(type default)
		)
		(layer "In3.Cu")
	)
	(gr_line
		(start 122.94743 -82.145886)
		(end 122.94743 -82.148426)
		(stroke
			(width 0.2)
			(type default)
		)
		(layer "In3.Cu")
	)
	(gr_line
		(start 123.208288 -91.849956)
		(end 123.208288 -91.849702)
		(stroke
			(width 0.2)
			(type default)
		)
		(layer "In3.Cu")
	)
	(gr_arc
		(start 123.208288 -91.849702)
		(mid 122.850021 -91.491562)
		(end 122.492008 -91.849956)
		(stroke
			(width 0.2)
			(type default)
		)
		(layer "In3.Cu")
	)
	(gr_line
		(start 123.208542 -92.827348)
		(end 123.208288 -91.849956)
		(stroke
			(width 0.2)
			(type default)
		)
		(layer "In3.Cu")
	)
	(gr_line
		(start 123.317 -147.193)
		(end 62.992 -147.193)
		(stroke
			(width 0.381)
			(type default)
		)
		(layer "In3.Cu")
	)
	(gr_line
		(start 123.72594 -81.404714)
		(end 123.72594 -81.402174)
		(stroke
			(width 0.2)
			(type default)
		)
		(layer "In3.Cu")
	)
	(gr_line
		(start 123.72594 -81.402174)
		(end 122.924824 -81.427574)
		(stroke
			(width 0.2)
			(type default)
		)
		(layer "In3.Cu")
	)
	(gr_line
		(start 123.7488 -82.123026)
		(end 123.7488 -82.12074)
		(stroke
			(width 0.2)
			(type default)
		)
		(layer "In3.Cu")
	)
	(gr_line
		(start 123.7488 -82.12074)
		(end 123.7488 -82.120486)
		(stroke
			(width 0.2)
			(type default)
		)
		(layer "In3.Cu")
	)
	(gr_arc
		(start 123.7488 -82.120486)
		(mid 124.095256 -81.75117)
		(end 123.72594 -81.404714)
		(stroke
			(width 0.2)
			(type default)
		)
		(layer "In3.Cu")
	)
	(gr_line
		(start 123.804426 -84.43595)
		(end 122.829574 -84.492084)
		(stroke
			(width 0.2)
			(type default)
		)
		(layer "In3.Cu")
	)
	(gr_arc
		(start 123.831858 -81.308956)
		(mid 123.842395 -81.309356)
		(end 123.85294 -81.309464)
		(stroke
			(width 0.2)
			(type default)
		)
		(layer "In3.Cu")
	)
	(gr_line
		(start 123.833128 -80.542892)
		(end 122.925332 -80.56626)
		(stroke
			(width 0.2)
			(type default)
		)
		(layer "In3.Cu")
	)
	(gr_arc
		(start 123.843542 -94.206822)
		(mid 124.209305 -93.856175)
		(end 123.858528 -93.490542)
		(stroke
			(width 0.2)
			(type default)
		)
		(layer "In3.Cu")
	)
	(gr_arc
		(start 123.84532 -85.151214)
		(mid 124.182625 -84.773135)
		(end 123.804426 -84.43595)
		(stroke
			(width 0.2)
			(type default)
		)
		(layer "In3.Cu")
	)
	(gr_arc
		(start 123.849892 -84.207858)
		(mid 124.208286 -83.849845)
		(end 123.850146 -83.491578)
		(stroke
			(width 0.2)
			(type default)
		)
		(layer "In3.Cu")
	)
	(gr_arc
		(start 123.850146 -91.207844)
		(mid 124.208286 -90.849704)
		(end 123.850146 -90.491564)
		(stroke
			(width 0.2)
			(type default)
		)
		(layer "In3.Cu")
	)
	(gr_line
		(start 123.850146 -90.491564)
		(end 122.850402 -90.491564)
		(stroke
			(width 0.2)
			(type default)
		)
		(layer "In3.Cu")
	)
	(gr_arc
		(start 123.850146 -90.207846)
		(mid 124.208286 -89.849706)
		(end 123.850146 -89.491566)
		(stroke
			(width 0.2)
			(type default)
		)
		(layer "In3.Cu")
	)
	(gr_line
		(start 123.850146 -89.491566)
		(end 122.850402 -89.491566)
		(stroke
			(width 0.2)
			(type default)
		)
		(layer "In3.Cu")
	)
	(gr_line
		(start 123.850146 -83.491578)
		(end 122.850148 -83.491578)
		(stroke
			(width 0.2)
			(type default)
		)
		(layer "In3.Cu")
	)
	(gr_arc
		(start 123.850146 -83.20786)
		(mid 124.208286 -82.84972)
		(end 123.850146 -82.49158)
		(stroke
			(width 0.2)
			(type default)
		)
		(layer "In3.Cu")
	)
	(gr_line
		(start 123.850146 -82.49158)
		(end 122.850402 -82.49158)
		(stroke
			(width 0.2)
			(type default)
		)
		(layer "In3.Cu")
	)
	(gr_arc
		(start 123.85294 -81.309464)
		(mid 124.236988 -80.926432)
		(end 123.853956 -80.542384)
		(stroke
			(width 0.2)
			(type default)
		)
		(layer "In3.Cu")
	)
	(gr_arc
		(start 123.853956 -80.542384)
		(mid 123.843539 -80.542498)
		(end 123.833128 -80.542892)
		(stroke
			(width 0.2)
			(type default)
		)
		(layer "In3.Cu")
	)
	(gr_line
		(start 123.858528 -93.490542)
		(end 122.862848 -93.470222)
		(stroke
			(width 0.2)
			(type default)
		)
		(layer "In3.Cu")
	)
	(gr_line
		(start 124.779278 -80.635348)
		(end 125.756162 -80.635348)
		(stroke
			(width 0.2)
			(type default)
		)
		(layer "In3.Cu")
	)
	(gr_arc
		(start 124.779532 -79.868268)
		(mid 124.395738 -80.251681)
		(end 124.779278 -80.635348)
		(stroke
			(width 0.2)
			(type default)
		)
		(layer "In3.Cu")
	)
	(gr_line
		(start 124.841 -81.661)
		(end 125.476 -81.026)
		(stroke
			(width 0.381)
			(type default)
		)
		(layer "In3.Cu")
	)
	(gr_line
		(start 125.476 -81.026)
		(end 127.508 -81.026)
		(stroke
			(width 0.381)
			(type default)
		)
		(layer "In3.Cu")
	)
	(gr_arc
		(start 125.756162 -80.635348)
		(mid 126.139702 -80.251808)
		(end 125.756162 -79.868268)
		(stroke
			(width 0.2)
			(type default)
		)
		(layer "In3.Cu")
	)
	(gr_line
		(start 125.756162 -79.868268)
		(end 124.779532 -79.868268)
		(stroke
			(width 0.2)
			(type default)
		)
		(layer "In3.Cu")
	)
	(gr_line
		(start 127.154178 -80.19034)
		(end 128.130808 -80.19034)
		(stroke
			(width 0.2)
			(type default)
		)
		(layer "In3.Cu")
	)
	(gr_arc
		(start 127.154178 -79.42326)
		(mid 126.770638 -79.8068)
		(end 127.154178 -80.19034)
		(stroke
			(width 0.2)
			(type default)
		)
		(layer "In3.Cu")
	)
	(gr_line
		(start 127.508 -81.026)
		(end 131.953 -85.471)
		(stroke
			(width 0.381)
			(type default)
		)
		(layer "In3.Cu")
	)
	(gr_arc
		(start 128.130808 -80.19034)
		(mid 128.514602 -79.806927)
		(end 128.131062 -79.42326)
		(stroke
			(width 0.2)
			(type default)
		)
		(layer "In3.Cu")
	)
	(gr_line
		(start 128.131062 -79.42326)
		(end 127.154178 -79.42326)
		(stroke
			(width 0.2)
			(type default)
		)
		(layer "In3.Cu")
	)
	(gr_line
		(start 128.778 -141.732)
		(end 123.317 -147.193)
		(stroke
			(width 0.381)
			(type default)
		)
		(layer "In3.Cu")
	)
	(gr_line
		(start 128.778 -131.953)
		(end 128.778 -141.732)
		(stroke
			(width 0.381)
			(type default)
		)
		(layer "In3.Cu")
	)
	(gr_line
		(start 129.159 -81.66354)
		(end 130.047746 -81.66354)
		(stroke
			(width 0.2)
			(type default)
		)
		(layer "In3.Cu")
	)
	(gr_arc
		(start 129.159 -80.89646)
		(mid 128.77546 -81.28)
		(end 129.159 -81.66354)
		(stroke
			(width 0.2)
			(type default)
		)
		(layer "In3.Cu")
	)
	(gr_line
		(start 129.794 -130.937)
		(end 128.778 -131.953)
		(stroke
			(width 0.381)
			(type default)
		)
		(layer "In3.Cu")
	)
	(gr_arc
		(start 130.047746 -81.66354)
		(mid 130.43154 -81.280127)
		(end 130.048 -80.89646)
		(stroke
			(width 0.2)
			(type default)
		)
		(layer "In3.Cu")
	)
	(gr_line
		(start 130.048 -80.89646)
		(end 129.159 -80.89646)
		(stroke
			(width 0.2)
			(type default)
		)
		(layer "In3.Cu")
	)
	(gr_line
		(start 131.02844 -80.13954)
		(end 132.00507 -80.13954)
		(stroke
			(width 0.2)
			(type default)
		)
		(layer "In3.Cu")
	)
	(gr_arc
		(start 131.02844 -79.37246)
		(mid 130.6449 -79.756)
		(end 131.02844 -80.13954)
		(stroke
			(width 0.2)
			(type default)
		)
		(layer "In3.Cu")
	)
	(gr_arc
		(start 131.82346 -92.075)
		(mid 132.207 -92.45854)
		(end 132.59054 -92.075)
		(stroke
			(width 0.2)
			(type default)
		)
		(layer "In3.Cu")
	)
	(gr_line
		(start 131.82346 -91.169998)
		(end 131.82346 -92.075)
		(stroke
			(width 0.2)
			(type default)
		)
		(layer "In3.Cu")
	)
	(gr_arc
		(start 131.82346 -89.281)
		(mid 132.207 -89.66454)
		(end 132.59054 -89.281)
		(stroke
			(width 0.2)
			(type default)
		)
		(layer "In3.Cu")
	)
	(gr_line
		(start 131.82346 -88.375998)
		(end 131.82346 -89.281)
		(stroke
			(width 0.2)
			(type default)
		)
		(layer "In3.Cu")
	)
	(gr_line
		(start 131.953 -92.075)
		(end 134.493 -94.615)
		(stroke
			(width 0.381)
			(type default)
		)
		(layer "In3.Cu")
	)
	(gr_line
		(start 131.953 -85.471)
		(end 131.953 -92.075)
		(stroke
			(width 0.381)
			(type default)
		)
		(layer "In3.Cu")
	)
	(gr_arc
		(start 132.00507 -80.13954)
		(mid 132.388864 -79.756127)
		(end 132.005324 -79.37246)
		(stroke
			(width 0.2)
			(type default)
		)
		(layer "In3.Cu")
	)
	(gr_line
		(start 132.005324 -79.37246)
		(end 131.02844 -79.37246)
		(stroke
			(width 0.2)
			(type default)
		)
		(layer "In3.Cu")
	)
	(gr_line
		(start 132.59054 -92.075)
		(end 132.59054 -91.170252)
		(stroke
			(width 0.2)
			(type default)
		)
		(layer "In3.Cu")
	)
	(gr_arc
		(start 132.59054 -91.170252)
		(mid 132.207127 -90.786458)
		(end 131.82346 -91.169998)
		(stroke
			(width 0.2)
			(type default)
		)
		(layer "In3.Cu")
	)
	(gr_line
		(start 132.59054 -89.281)
		(end 132.59054 -88.376252)
		(stroke
			(width 0.2)
			(type default)
		)
		(layer "In3.Cu")
	)
	(gr_arc
		(start 132.59054 -88.376252)
		(mid 132.207127 -87.992458)
		(end 131.82346 -88.375998)
		(stroke
			(width 0.2)
			(type default)
		)
		(layer "In3.Cu")
	)
	(gr_line
		(start 132.930392 -81.500726)
		(end 133.858254 -81.500726)
		(stroke
			(width 0.2)
			(type default)
		)
		(layer "In3.Cu")
	)
	(gr_arc
		(start 132.930392 -80.733646)
		(mid 132.546852 -81.117186)
		(end 132.930392 -81.500726)
		(stroke
			(width 0.2)
			(type default)
		)
		(layer "In3.Cu")
	)
	(gr_arc
		(start 133.34746 -90.558874)
		(mid 133.730873 -90.942668)
		(end 134.11454 -90.559128)
		(stroke
			(width 0.2)
			(type default)
		)
		(layer "In3.Cu")
	)
	(gr_line
		(start 133.34746 -89.654126)
		(end 133.34746 -90.558874)
		(stroke
			(width 0.2)
			(type default)
		)
		(layer "In3.Cu")
	)
	(gr_arc
		(start 133.34746 -88.019128)
		(mid 133.731 -88.402668)
		(end 134.11454 -88.019128)
		(stroke
			(width 0.2)
			(type default)
		)
		(layer "In3.Cu")
	)
	(gr_line
		(start 133.34746 -87.114126)
		(end 133.34746 -88.019128)
		(stroke
			(width 0.2)
			(type default)
		)
		(layer "In3.Cu")
	)
	(gr_arc
		(start 133.858254 -81.500726)
		(mid 134.242048 -81.117313)
		(end 133.858508 -80.733646)
		(stroke
			(width 0.2)
			(type default)
		)
		(layer "In3.Cu")
	)
	(gr_line
		(start 133.858508 -80.733646)
		(end 132.930392 -80.733646)
		(stroke
			(width 0.2)
			(type default)
		)
		(layer "In3.Cu")
	)
	(gr_line
		(start 134.11454 -90.559128)
		(end 134.11454 -89.654126)
		(stroke
			(width 0.2)
			(type default)
		)
		(layer "In3.Cu")
	)
	(gr_arc
		(start 134.11454 -89.654126)
		(mid 133.731 -89.270586)
		(end 133.34746 -89.654126)
		(stroke
			(width 0.2)
			(type default)
		)
		(layer "In3.Cu")
	)
	(gr_line
		(start 134.11454 -88.019128)
		(end 134.11454 -87.11438)
		(stroke
			(width 0.2)
			(type default)
		)
		(layer "In3.Cu")
	)
	(gr_arc
		(start 134.11454 -87.11438)
		(mid 133.731127 -86.730586)
		(end 133.34746 -87.114126)
		(stroke
			(width 0.2)
			(type default)
		)
		(layer "In3.Cu")
	)
	(gr_line
		(start 134.493 -94.615)
		(end 150.114 -94.615)
		(stroke
			(width 0.381)
			(type default)
		)
		(layer "In3.Cu")
	)
	(gr_line
		(start 134.581392 -83.06054)
		(end 135.509508 -83.06054)
		(stroke
			(width 0.2)
			(type default)
		)
		(layer "In3.Cu")
	)
	(gr_arc
		(start 134.581646 -82.29346)
		(mid 134.197852 -82.676873)
		(end 134.581392 -83.06054)
		(stroke
			(width 0.2)
			(type default)
		)
		(layer "In3.Cu")
	)
	(gr_arc
		(start 135.509508 -83.06054)
		(mid 135.893048 -82.677)
		(end 135.509508 -82.29346)
		(stroke
			(width 0.2)
			(type default)
		)
		(layer "In3.Cu")
	)
	(gr_line
		(start 135.509508 -82.29346)
		(end 134.581646 -82.29346)
		(stroke
			(width 0.2)
			(type default)
		)
		(layer "In3.Cu")
	)
	(gr_line
		(start 135.87984 -81.91754)
		(end 136.807956 -81.91754)
		(stroke
			(width 0.2)
			(type default)
		)
		(layer "In3.Cu")
	)
	(gr_arc
		(start 135.880094 -81.15046)
		(mid 135.4963 -81.533873)
		(end 135.87984 -81.91754)
		(stroke
			(width 0.2)
			(type default)
		)
		(layer "In3.Cu")
	)
	(gr_arc
		(start 136.807956 -81.91754)
		(mid 137.191496 -81.534)
		(end 136.807956 -81.15046)
		(stroke
			(width 0.2)
			(type default)
		)
		(layer "In3.Cu")
	)
	(gr_line
		(start 136.807956 -81.15046)
		(end 135.880094 -81.15046)
		(stroke
			(width 0.2)
			(type default)
		)
		(layer "In3.Cu")
	)
	(gr_line
		(start 137.033 -152.654)
		(end 138.049 -151.638)
		(stroke
			(width 0.4064)
			(type default)
		)
		(layer "In3.Cu")
	)
	(gr_line
		(start 137.287 -130.937)
		(end 129.794 -130.937)
		(stroke
			(width 0.381)
			(type default)
		)
		(layer "In3.Cu")
	)
	(gr_line
		(start 138.049 -151.638)
		(end 138.049 -131.699)
		(stroke
			(width 0.4064)
			(type default)
		)
		(layer "In3.Cu")
	)
	(gr_line
		(start 138.049 -131.699)
		(end 137.287 -130.937)
		(stroke
			(width 0.381)
			(type default)
		)
		(layer "In3.Cu")
	)
	(gr_line
		(start 138.549888 -258.59994)
		(end 67.349878 -258.59994)
		(stroke
			(width 5.08)
			(type default)
		)
		(layer "In3.Cu")
	)
	(gr_line
		(start 138.549888 -252.549914)
		(end 138.549888 -258.59994)
		(stroke
			(width 1.524)
			(type default)
		)
		(layer "In3.Cu")
	)
	(gr_line
		(start 140.450062 -258.59994)
		(end 140.450062 -252.549914)
		(stroke
			(width 1.524)
			(type default)
		)
		(layer "In3.Cu")
	)
	(gr_arc
		(start 140.450062 -252.549914)
		(mid 139.500102 -251.599954)
		(end 138.549888 -252.549914)
		(stroke
			(width 1.524)
			(type default)
		)
		(layer "In3.Cu")
	)
	(gr_line
		(start 150.114 -114.427)
		(end 106.807 -114.427)
		(stroke
			(width 0.381)
			(type default)
		)
		(layer "In3.Cu")
	)
	(gr_line
		(start 150.114 -94.615)
		(end 151.003 -95.504)
		(stroke
			(width 0.381)
			(type default)
		)
		(layer "In3.Cu")
	)
	(gr_line
		(start 151.003 -113.538)
		(end 150.114 -114.427)
		(stroke
			(width 0.381)
			(type default)
		)
		(layer "In3.Cu")
	)
	(gr_line
		(start 151.003 -95.504)
		(end 151.003 -113.411)
		(stroke
			(width 0.381)
			(type default)
		)
		(layer "In3.Cu")
	)
	(gr_line
		(start 151.649938 -258.59994)
		(end 140.450062 -258.59994)
		(stroke
			(width 5.08)
			(type default)
		)
		(layer "In3.Cu")
	)
	(gr_line
		(start 151.649938 -252.000004)
		(end 151.649938 -258.59994)
		(stroke
			(width 1.524)
			(type default)
		)
		(layer "In3.Cu")
	)
	(gr_arc
		(start 152.649936 -251.000006)
		(mid 151.942831 -251.292899)
		(end 151.649938 -252.000004)
		(stroke
			(width 1.524)
			(type default)
		)
		(layer "In3.Cu")
	)
	(gr_line
		(start 155.946348 -77.40904)
		(end 156.928312 -77.40904)
		(stroke
			(width 0.2)
			(type default)
		)
		(layer "In3.Cu")
	)
	(gr_arc
		(start 155.946602 -76.64196)
		(mid 155.562808 -77.025373)
		(end 155.946348 -77.40904)
		(stroke
			(width 0.2)
			(type default)
		)
		(layer "In3.Cu")
	)
	(gr_arc
		(start 156.928312 -77.40904)
		(mid 157.311852 -77.0255)
		(end 156.928312 -76.64196)
		(stroke
			(width 0.2)
			(type default)
		)
		(layer "In3.Cu")
	)
	(gr_line
		(start 156.928312 -76.64196)
		(end 155.946602 -76.64196)
		(stroke
			(width 0.2)
			(type default)
		)
		(layer "In3.Cu")
	)
	(gr_line
		(start 159.946848 -77.40904)
		(end 160.928812 -77.40904)
		(stroke
			(width 0.2)
			(type default)
		)
		(layer "In3.Cu")
	)
	(gr_arc
		(start 159.947102 -76.64196)
		(mid 159.563308 -77.025373)
		(end 159.946848 -77.40904)
		(stroke
			(width 0.2)
			(type default)
		)
		(layer "In3.Cu")
	)
	(gr_arc
		(start 160.928812 -77.40904)
		(mid 161.312352 -77.0255)
		(end 160.928812 -76.64196)
		(stroke
			(width 0.2)
			(type default)
		)
		(layer "In3.Cu")
	)
	(gr_line
		(start 160.928812 -76.64196)
		(end 159.947102 -76.64196)
		(stroke
			(width 0.2)
			(type default)
		)
		(layer "In3.Cu")
	)
	(gr_line
		(start 163.946078 -77.40904)
		(end 164.928042 -77.40904)
		(stroke
			(width 0.2)
			(type default)
		)
		(layer "In3.Cu")
	)
	(gr_arc
		(start 163.946332 -76.64196)
		(mid 163.562538 -77.025373)
		(end 163.946078 -77.40904)
		(stroke
			(width 0.2)
			(type default)
		)
		(layer "In3.Cu")
	)
	(gr_arc
		(start 164.928042 -77.40904)
		(mid 165.311582 -77.0255)
		(end 164.928042 -76.64196)
		(stroke
			(width 0.2)
			(type default)
		)
		(layer "In3.Cu")
	)
	(gr_line
		(start 164.928042 -76.64196)
		(end 163.946332 -76.64196)
		(stroke
			(width 0.2)
			(type default)
		)
		(layer "In3.Cu")
	)
	(gr_line
		(start 167.946578 -77.40904)
		(end 168.928542 -77.40904)
		(stroke
			(width 0.2)
			(type default)
		)
		(layer "In3.Cu")
	)
	(gr_arc
		(start 167.946832 -76.64196)
		(mid 167.563038 -77.025373)
		(end 167.946578 -77.40904)
		(stroke
			(width 0.2)
			(type default)
		)
		(layer "In3.Cu")
	)
	(gr_arc
		(start 168.928542 -77.40904)
		(mid 169.312082 -77.0255)
		(end 168.928542 -76.64196)
		(stroke
			(width 0.2)
			(type default)
		)
		(layer "In3.Cu")
	)
	(gr_line
		(start 168.928542 -76.64196)
		(end 167.946832 -76.64196)
		(stroke
			(width 0.2)
			(type default)
		)
		(layer "In3.Cu")
	)
	(gr_line
		(start 181.150006 -251.000006)
		(end 152.649936 -251.000006)
		(stroke
			(width 1.524)
			(type default)
		)
		(layer "In3.Cu")
	)
	(gr_line
		(start 182.150004 -258.59994)
		(end 182.150004 -252.000004)
		(stroke
			(width 1.524)
			(type default)
		)
		(layer "In3.Cu")
	)
	(gr_arc
		(start 182.150004 -252.000004)
		(mid 181.857111 -251.292899)
		(end 181.150006 -251.000006)
		(stroke
			(width 1.524)
			(type default)
		)
		(layer "In3.Cu")
	)
	(gr_line
		(start 189.349888 -258.59994)
		(end 182.150004 -258.59994)
		(stroke
			(width 5.08)
			(type default)
		)
		(layer "In3.Cu")
	)
	(gr_line
		(start 189.349888 -252.549914)
		(end 189.349888 -258.59994)
		(stroke
			(width 1.524)
			(type default)
		)
		(layer "In3.Cu")
	)
	(gr_line
		(start 191.250062 -258.59994)
		(end 191.250062 -252.549914)
		(stroke
			(width 1.524)
			(type default)
		)
		(layer "In3.Cu")
	)
	(gr_arc
		(start 191.250062 -252.549914)
		(mid 190.300102 -251.599954)
		(end 189.349888 -252.549914)
		(stroke
			(width 1.524)
			(type default)
		)
		(layer "In3.Cu")
	)
	(gr_line
		(start 191.947038 -77.40904)
		(end 192.928748 -77.40904)
		(stroke
			(width 0.2)
			(type default)
		)
		(layer "In3.Cu")
	)
	(gr_arc
		(start 191.947038 -76.64196)
		(mid 191.563498 -77.0255)
		(end 191.947038 -77.40904)
		(stroke
			(width 0.2)
			(type default)
		)
		(layer "In3.Cu")
	)
	(gr_arc
		(start 192.928748 -77.40904)
		(mid 193.312542 -77.025627)
		(end 192.929002 -76.64196)
		(stroke
			(width 0.2)
			(type default)
		)
		(layer "In3.Cu")
	)
	(gr_line
		(start 192.929002 -76.64196)
		(end 191.947038 -76.64196)
		(stroke
			(width 0.2)
			(type default)
		)
		(layer "In3.Cu")
	)
	(gr_line
		(start 195.947538 -77.40904)
		(end 196.929502 -77.40904)
		(stroke
			(width 0.2)
			(type default)
		)
		(layer "In3.Cu")
	)
	(gr_arc
		(start 195.947792 -76.64196)
		(mid 195.563998 -77.025373)
		(end 195.947538 -77.40904)
		(stroke
			(width 0.2)
			(type default)
		)
		(layer "In3.Cu")
	)
	(gr_arc
		(start 196.929502 -77.40904)
		(mid 197.313042 -77.0255)
		(end 196.929502 -76.64196)
		(stroke
			(width 0.2)
			(type default)
		)
		(layer "In3.Cu")
	)
	(gr_line
		(start 196.929502 -76.64196)
		(end 195.947792 -76.64196)
		(stroke
			(width 0.2)
			(type default)
		)
		(layer "In3.Cu")
	)
	(gr_line
		(start 199.946768 -77.40904)
		(end 200.928478 -77.40904)
		(stroke
			(width 0.2)
			(type default)
		)
		(layer "In3.Cu")
	)
	(gr_arc
		(start 199.946768 -76.64196)
		(mid 199.563228 -77.0255)
		(end 199.946768 -77.40904)
		(stroke
			(width 0.2)
			(type default)
		)
		(layer "In3.Cu")
	)
	(gr_arc
		(start 200.928478 -77.40904)
		(mid 201.312272 -77.025627)
		(end 200.928732 -76.64196)
		(stroke
			(width 0.2)
			(type default)
		)
		(layer "In3.Cu")
	)
	(gr_line
		(start 200.928732 -76.64196)
		(end 199.946768 -76.64196)
		(stroke
			(width 0.2)
			(type default)
		)
		(layer "In3.Cu")
	)
	(gr_line
		(start 202.449938 -258.59994)
		(end 191.250062 -258.59994)
		(stroke
			(width 5.08)
			(type default)
		)
		(layer "In3.Cu")
	)
	(gr_line
		(start 202.449938 -252.000004)
		(end 202.449938 -258.59994)
		(stroke
			(width 1.524)
			(type default)
		)
		(layer "In3.Cu")
	)
	(gr_arc
		(start 203.449936 -251.000006)
		(mid 202.742831 -251.292899)
		(end 202.449938 -252.000004)
		(stroke
			(width 1.524)
			(type default)
		)
		(layer "In3.Cu")
	)
	(gr_line
		(start 203.947268 -77.40904)
		(end 204.929232 -77.40904)
		(stroke
			(width 0.2)
			(type default)
		)
		(layer "In3.Cu")
	)
	(gr_arc
		(start 203.947522 -76.64196)
		(mid 203.563728 -77.025373)
		(end 203.947268 -77.40904)
		(stroke
			(width 0.2)
			(type default)
		)
		(layer "In3.Cu")
	)
	(gr_arc
		(start 204.929232 -77.40904)
		(mid 205.312772 -77.0255)
		(end 204.929232 -76.64196)
		(stroke
			(width 0.2)
			(type default)
		)
		(layer "In3.Cu")
	)
	(gr_line
		(start 204.929232 -76.64196)
		(end 203.947522 -76.64196)
		(stroke
			(width 0.2)
			(type default)
		)
		(layer "In3.Cu")
	)
	(gr_line
		(start 209.677 -100.711)
		(end 209.677 -88.265)
		(stroke
			(width 0.381)
			(type default)
		)
		(layer "In3.Cu")
	)
	(gr_line
		(start 209.677 -88.265)
		(end 211.328 -86.614)
		(stroke
			(width 0.381)
			(type default)
		)
		(layer "In3.Cu")
	)
	(gr_line
		(start 211.328 -86.614)
		(end 219.329 -86.614)
		(stroke
			(width 0.381)
			(type default)
		)
		(layer "In3.Cu")
	)
	(gr_line
		(start 212.09 -103.124)
		(end 209.677 -100.711)
		(stroke
			(width 0.381)
			(type default)
		)
		(layer "In3.Cu")
	)
	(gr_line
		(start 216.916 -103.124)
		(end 212.09 -103.124)
		(stroke
			(width 0.381)
			(type default)
		)
		(layer "In3.Cu")
	)
	(gr_line
		(start 219.202 -86.614)
		(end 229.235 -86.614)
		(stroke
			(width 0.381)
			(type default)
		)
		(layer "In3.Cu")
	)
	(gr_line
		(start 219.71 -100.33)
		(end 216.916 -103.124)
		(stroke
			(width 0.381)
			(type default)
		)
		(layer "In3.Cu")
	)
	(gr_line
		(start 229.14991 -251.000006)
		(end 203.449936 -251.000006)
		(stroke
			(width 1.524)
			(type default)
		)
		(layer "In3.Cu")
	)
	(gr_arc
		(start 229.14991 -251.000006)
		(mid 232.685436 -249.53554)
		(end 234.1499 -246.000016)
		(stroke
			(width 1.524)
			(type default)
		)
		(layer "In3.Cu")
	)
	(gr_line
		(start 229.235 -86.614)
		(end 233.299 -82.55)
		(stroke
			(width 0.381)
			(type default)
		)
		(layer "In3.Cu")
	)
	(gr_line
		(start 233.299 -82.55)
		(end 233.299 -54.61)
		(stroke
			(width 0.381)
			(type default)
		)
		(layer "In3.Cu")
	)
	(gr_line
		(start 233.299 -54.61)
		(end 234.315 -53.594)
		(stroke
			(width 0.381)
			(type default)
		)
		(layer "In3.Cu")
	)
	(gr_line
		(start 234.1499 -197.000114)
		(end 234.1499 -246.000016)
		(stroke
			(width 1.524)
			(type default)
		)
		(layer "In3.Cu")
	)
	(gr_line
		(start 234.315 -53.594)
		(end 241.173 -53.594)
		(stroke
			(width 0.381)
			(type default)
		)
		(layer "In3.Cu")
	)
	(gr_arc
		(start 235.149898 -196.000116)
		(mid 234.442793 -196.293009)
		(end 234.1499 -197.000114)
		(stroke
			(width 1.524)
			(type default)
		)
		(layer "In3.Cu")
	)
	(gr_line
		(start 238.887 -168.275)
		(end 239.903 -169.291)
		(stroke
			(width 0.381)
			(type default)
		)
		(layer "In3.Cu")
	)
	(gr_line
		(start 238.887 -142.367)
		(end 238.887 -168.275)
		(stroke
			(width 0.381)
			(type default)
		)
		(layer "In3.Cu")
	)
	(gr_line
		(start 239.903 -169.291)
		(end 255.778 -169.291)
		(stroke
			(width 0.381)
			(type default)
		)
		(layer "In3.Cu")
	)
	(gr_line
		(start 240.03 -100.33)
		(end 219.71 -100.33)
		(stroke
			(width 0.381)
			(type default)
		)
		(layer "In3.Cu")
	)
	(gr_line
		(start 241.173 -53.594)
		(end 242.062 -54.483)
		(stroke
			(width 0.381)
			(type default)
		)
		(layer "In3.Cu")
	)
	(gr_line
		(start 242.062 -98.298)
		(end 240.03 -100.33)
		(stroke
			(width 0.381)
			(type default)
		)
		(layer "In3.Cu")
	)
	(gr_line
		(start 242.062 -54.483)
		(end 242.062 -98.298)
		(stroke
			(width 0.381)
			(type default)
		)
		(layer "In3.Cu")
	)
	(gr_line
		(start 250.150122 -196.000116)
		(end 235.149898 -196.000116)
		(stroke
			(width 1.524)
			(type default)
		)
		(layer "In3.Cu")
	)
	(gr_line
		(start 251.15012 -246.000016)
		(end 251.15012 -197.000114)
		(stroke
			(width 1.524)
			(type default)
		)
		(layer "In3.Cu")
	)
	(gr_arc
		(start 251.15012 -246.000016)
		(mid 252.614589 -249.535529)
		(end 256.15011 -251.000006)
		(stroke
			(width 1.524)
			(type default)
		)
		(layer "In3.Cu")
	)
	(gr_arc
		(start 251.15012 -197.000114)
		(mid 250.857227 -196.293009)
		(end 250.150122 -196.000116)
		(stroke
			(width 1.524)
			(type default)
		)
		(layer "In3.Cu")
	)
	(gr_line
		(start 255.27 -169.291)
		(end 255.905 -168.656)
		(stroke
			(width 0.381)
			(type default)
		)
		(layer "In3.Cu")
	)
	(gr_line
		(start 255.397 -125.857)
		(end 238.887 -142.367)
		(stroke
			(width 0.381)
			(type default)
		)
		(layer "In3.Cu")
	)
	(gr_line
		(start 255.905 -180.213)
		(end 255.905 -153.543)
		(stroke
			(width 0.381)
			(type default)
		)
		(layer "In3.Cu")
	)
	(gr_line
		(start 255.905 -169.926)
		(end 255.27 -169.291)
		(stroke
			(width 0.381)
			(type default)
		)
		(layer "In3.Cu")
	)
	(gr_line
		(start 255.905 -153.543)
		(end 264.287 -145.161)
		(stroke
			(width 0.381)
			(type default)
		)
		(layer "In3.Cu")
	)
	(gr_line
		(start 264.287 -145.161)
		(end 332.359 -145.161)
		(stroke
			(width 0.381)
			(type default)
		)
		(layer "In3.Cu")
	)
	(gr_line
		(start 266.573 -190.881)
		(end 255.905 -180.213)
		(stroke
			(width 0.381)
			(type default)
		)
		(layer "In3.Cu")
	)
	(gr_line
		(start 270.999966 -11.779758)
		(end 272.999962 -11.779758)
		(stroke
			(width 0.2)
			(type default)
		)
		(layer "In3.Cu")
	)
	(gr_arc
		(start 270.999966 -10.199878)
		(mid 270.210026 -10.989818)
		(end 270.999966 -11.779758)
		(stroke
			(width 0.2)
			(type default)
		)
		(layer "In3.Cu")
	)
	(gr_arc
		(start 272.999962 -11.779758)
		(mid 273.789902 -10.989818)
		(end 272.999962 -10.199878)
		(stroke
			(width 0.2)
			(type default)
		)
		(layer "In3.Cu")
	)
	(gr_line
		(start 272.999962 -10.199878)
		(end 270.999966 -10.199878)
		(stroke
			(width 0.2)
			(type default)
		)
		(layer "In3.Cu")
	)
	(gr_line
		(start 276.867112 -32.51454)
		(end 277.848822 -32.51454)
		(stroke
			(width 0.2)
			(type default)
		)
		(layer "In3.Cu")
	)
	(gr_arc
		(start 276.867112 -31.74746)
		(mid 276.483572 -32.131)
		(end 276.867112 -32.51454)
		(stroke
			(width 0.2)
			(type default)
		)
		(layer "In3.Cu")
	)
	(gr_arc
		(start 277.848822 -32.51454)
		(mid 278.232616 -32.131127)
		(end 277.849076 -31.74746)
		(stroke
			(width 0.2)
			(type default)
		)
		(layer "In3.Cu")
	)
	(gr_line
		(start 277.849076 -31.74746)
		(end 276.867112 -31.74746)
		(stroke
			(width 0.2)
			(type default)
		)
		(layer "In3.Cu")
	)
	(gr_arc
		(start 282.485084 -53.50002)
		(mid 282.777977 -54.207125)
		(end 283.485082 -54.500018)
		(stroke
			(width 1.524)
			(type default)
		)
		(layer "In3.Cu")
	)
	(gr_arc
		(start 282.485084 -0.999998)
		(mid 282.19219 -0.292899)
		(end 281.485086 0)
		(stroke
			(width 1.524)
			(type default)
		)
		(layer "In3.Cu")
	)
	(gr_line
		(start 282.485084 -0.999998)
		(end 282.485084 -53.50002)
		(stroke
			(width 1.524)
			(type default)
		)
		(layer "In3.Cu")
	)
	(gr_line
		(start 283.21 -190.881)
		(end 266.573 -190.881)
		(stroke
			(width 0.381)
			(type default)
		)
		(layer "In3.Cu")
	)
	(gr_line
		(start 283.485082 -54.500018)
		(end 303.485042 -54.500018)
		(stroke
			(width 1.524)
			(type default)
		)
		(layer "In3.Cu")
	)
	(gr_arc
		(start 284.552898 -184.91327)
		(mid 284.227506 -185.347232)
		(end 284.661356 -185.67273)
		(stroke
			(width 0.2)
			(type default)
		)
		(layer "In3.Cu")
	)
	(gr_line
		(start 284.661356 -185.67273)
		(end 285.550356 -185.54573)
		(stroke
			(width 0.2)
			(type default)
		)
		(layer "In3.Cu")
	)
	(gr_line
		(start 285.441644 -184.78627)
		(end 284.552898 -184.91327)
		(stroke
			(width 0.2)
			(type default)
		)
		(layer "In3.Cu")
	)
	(gr_arc
		(start 285.550356 -185.54573)
		(mid 285.87573 -185.111644)
		(end 285.441644 -184.78627)
		(stroke
			(width 0.2)
			(type default)
		)
		(layer "In3.Cu")
	)
	(gr_line
		(start 290.957 -125.857)
		(end 255.397 -125.857)
		(stroke
			(width 0.381)
			(type default)
		)
		(layer "In3.Cu")
	)
	(gr_line
		(start 291.846 -145.034)
		(end 291.846 -126.746)
		(stroke
			(width 0.381)
			(type default)
		)
		(layer "In3.Cu")
	)
	(gr_line
		(start 291.846 -144.526)
		(end 291.211 -145.161)
		(stroke
			(width 0.381)
			(type default)
		)
		(layer "In3.Cu")
	)
	(gr_line
		(start 291.846 -126.746)
		(end 290.957 -125.857)
		(stroke
			(width 0.381)
			(type default)
		)
		(layer "In3.Cu")
	)
	(gr_line
		(start 292.481 -145.161)
		(end 291.846 -144.526)
		(stroke
			(width 0.381)
			(type default)
		)
		(layer "In3.Cu")
	)
	(gr_arc
		(start 293.26586 -80.366616)
		(mid 293.649273 -80.75041)
		(end 294.03294 -80.36687)
		(stroke
			(width 0.2)
			(type default)
		)
		(layer "In3.Cu")
	)
	(gr_line
		(start 293.26586 -79.44993)
		(end 293.26586 -80.366616)
		(stroke
			(width 0.2)
			(type default)
		)
		(layer "In3.Cu")
	)
	(gr_line
		(start 294.03294 -80.36687)
		(end 294.03294 -79.44993)
		(stroke
			(width 0.2)
			(type default)
		)
		(layer "In3.Cu")
	)
	(gr_arc
		(start 294.03294 -79.44993)
		(mid 293.6494 -79.06639)
		(end 293.26586 -79.44993)
		(stroke
			(width 0.2)
			(type default)
		)
		(layer "In3.Cu")
	)
	(gr_arc
		(start 295.52646 -78.276196)
		(mid 295.909873 -78.65999)
		(end 296.29354 -78.27645)
		(stroke
			(width 0.2)
			(type default)
		)
		(layer "In3.Cu")
	)
	(gr_line
		(start 295.52646 -77.35951)
		(end 295.52646 -78.276196)
		(stroke
			(width 0.2)
			(type default)
		)
		(layer "In3.Cu")
	)
	(gr_line
		(start 296.29354 -78.27645)
		(end 296.29354 -77.35951)
		(stroke
			(width 0.2)
			(type default)
		)
		(layer "In3.Cu")
	)
	(gr_arc
		(start 296.29354 -77.35951)
		(mid 295.91 -76.97597)
		(end 295.52646 -77.35951)
		(stroke
			(width 0.2)
			(type default)
		)
		(layer "In3.Cu")
	)
	(gr_line
		(start 297.05681 -82.607404)
		(end 297.973496 -82.607404)
		(stroke
			(width 0.2)
			(type default)
		)
		(layer "In3.Cu")
	)
	(gr_arc
		(start 297.05681 -81.840324)
		(mid 296.67327 -82.223864)
		(end 297.05681 -82.607404)
		(stroke
			(width 0.2)
			(type default)
		)
		(layer "In3.Cu")
	)
	(gr_line
		(start 297.123358 -74.07529)
		(end 298.139104 -74.07529)
		(stroke
			(width 0.2)
			(type default)
		)
		(layer "In3.Cu")
	)
	(gr_arc
		(start 297.123358 -73.30821)
		(mid 296.739818 -73.69175)
		(end 297.123358 -74.07529)
		(stroke
			(width 0.2)
			(type default)
		)
		(layer "In3.Cu")
	)
	(gr_arc
		(start 297.973496 -82.607404)
		(mid 298.35729 -82.223991)
		(end 297.97375 -81.840324)
		(stroke
			(width 0.2)
			(type default)
		)
		(layer "In3.Cu")
	)
	(gr_line
		(start 297.97375 -81.840324)
		(end 297.05681 -81.840324)
		(stroke
			(width 0.2)
			(type default)
		)
		(layer "In3.Cu")
	)
	(gr_arc
		(start 298.139104 -74.07529)
		(mid 298.522898 -73.691877)
		(end 298.139358 -73.30821)
		(stroke
			(width 0.2)
			(type default)
		)
		(layer "In3.Cu")
	)
	(gr_line
		(start 298.139358 -73.30821)
		(end 297.123358 -73.30821)
		(stroke
			(width 0.2)
			(type default)
		)
		(layer "In3.Cu")
	)
	(gr_line
		(start 299.633132 -175.392334)
		(end 300.430438 -175.40351)
		(stroke
			(width 0.2)
			(type default)
		)
		(layer "In3.Cu")
	)
	(gr_arc
		(start 299.643546 -174.676054)
		(mid 299.280328 -175.028987)
		(end 299.633132 -175.392334)
		(stroke
			(width 0.2)
			(type default)
		)
		(layer "In3.Cu")
	)
	(gr_arc
		(start 300.430438 -175.40351)
		(mid 300.793658 -175.05045)
		(end 300.440598 -174.68723)
		(stroke
			(width 0.2)
			(type default)
		)
		(layer "In3.Cu")
	)
	(gr_line
		(start 300.440598 -174.68723)
		(end 299.643546 -174.676054)
		(stroke
			(width 0.2)
			(type default)
		)
		(layer "In3.Cu")
	)
	(gr_line
		(start 301.974758 -73.99274)
		(end 302.956722 -73.99274)
		(stroke
			(width 0.2)
			(type default)
		)
		(layer "In3.Cu")
	)
	(gr_arc
		(start 301.975012 -73.22566)
		(mid 301.591218 -73.609073)
		(end 301.974758 -73.99274)
		(stroke
			(width 0.2)
			(type default)
		)
		(layer "In3.Cu")
	)
	(gr_arc
		(start 302.214026 -173.36643)
		(mid 301.849028 -173.767496)
		(end 302.250094 -174.132494)
		(stroke
			(width 0.2)
			(type default)
		)
		(layer "In3.Cu")
	)
	(gr_line
		(start 302.214026 -173.364144)
		(end 302.214026 -173.36643)
		(stroke
			(width 0.2)
			(type default)
		)
		(layer "In3.Cu")
	)
	(gr_line
		(start 302.21428 -173.36389)
		(end 302.214026 -173.364144)
		(stroke
			(width 0.2)
			(type default)
		)
		(layer "In3.Cu")
	)
	(gr_line
		(start 302.250094 -174.135034)
		(end 303.024032 -174.098966)
		(stroke
			(width 0.2)
			(type default)
		)
		(layer "In3.Cu")
	)
	(gr_line
		(start 302.250094 -174.132494)
		(end 302.250094 -174.135034)
		(stroke
			(width 0.2)
			(type default)
		)
		(layer "In3.Cu")
	)
	(gr_arc
		(start 302.956722 -73.99274)
		(mid 303.340262 -73.6092)
		(end 302.956722 -73.22566)
		(stroke
			(width 0.2)
			(type default)
		)
		(layer "In3.Cu")
	)
	(gr_line
		(start 302.956722 -73.22566)
		(end 301.975012 -73.22566)
		(stroke
			(width 0.2)
			(type default)
		)
		(layer "In3.Cu")
	)
	(gr_line
		(start 302.987964 -173.330362)
		(end 302.987964 -173.327822)
		(stroke
			(width 0.2)
			(type default)
		)
		(layer "In3.Cu")
	)
	(gr_line
		(start 302.987964 -173.327822)
		(end 302.21428 -173.36389)
		(stroke
			(width 0.2)
			(type default)
		)
		(layer "In3.Cu")
	)
	(gr_line
		(start 303.024032 -174.098966)
		(end 303.024032 -174.096934)
		(stroke
			(width 0.2)
			(type default)
		)
		(layer "In3.Cu")
	)
	(gr_line
		(start 303.024032 -174.096934)
		(end 303.024032 -174.096426)
		(stroke
			(width 0.2)
			(type default)
		)
		(layer "In3.Cu")
	)
	(gr_arc
		(start 303.024032 -174.096426)
		(mid 303.38903 -173.69536)
		(end 302.987964 -173.330362)
		(stroke
			(width 0.2)
			(type default)
		)
		(layer "In3.Cu")
	)
	(gr_arc
		(start 303.485042 -54.500018)
		(mid 304.192147 -54.207125)
		(end 304.48504 -53.50002)
		(stroke
			(width 1.524)
			(type default)
		)
		(layer "In3.Cu")
	)
	(gr_line
		(start 303.80305 -87.908892)
		(end 304.719736 -87.908892)
		(stroke
			(width 0.2)
			(type default)
		)
		(layer "In3.Cu")
	)
	(gr_arc
		(start 303.80305 -87.141812)
		(mid 303.41951 -87.525352)
		(end 303.80305 -87.908892)
		(stroke
			(width 0.2)
			(type default)
		)
		(layer "In3.Cu")
	)
	(gr_line
		(start 304.48504 -53.50002)
		(end 304.48504 -45.500036)
		(stroke
			(width 1.524)
			(type default)
		)
		(layer "In3.Cu")
	)
	(gr_arc
		(start 304.719736 -87.908892)
		(mid 305.10353 -87.525479)
		(end 304.71999 -87.141812)
		(stroke
			(width 0.2)
			(type default)
		)
		(layer "In3.Cu")
	)
	(gr_line
		(start 304.71999 -87.141812)
		(end 303.80305 -87.141812)
		(stroke
			(width 0.2)
			(type default)
		)
		(layer "In3.Cu")
	)
	(gr_arc
		(start 305.485038 -44.500038)
		(mid 304.777921 -44.792919)
		(end 304.48504 -45.500036)
		(stroke
			(width 1.524)
			(type default)
		)
		(layer "In3.Cu")
	)
	(gr_arc
		(start 305.485038 -44.500038)
		(mid 306.192143 -44.207145)
		(end 306.485036 -43.50004)
		(stroke
			(width 1.524)
			(type default)
		)
		(layer "In3.Cu")
	)
	(gr_line
		(start 306.485036 -43.50004)
		(end 306.485036 -0.999998)
		(stroke
			(width 1.524)
			(type default)
		)
		(layer "In3.Cu")
	)
	(gr_arc
		(start 307.485034 0)
		(mid 306.777906 -0.29288)
		(end 306.485036 -0.999998)
		(stroke
			(width 1.524)
			(type default)
		)
		(layer "In3.Cu")
	)
	(gr_line
		(start 307.485034 0)
		(end 354.600002 0)
		(stroke
			(width 1.524)
			(type default)
		)
		(layer "In3.Cu")
	)
	(gr_arc
		(start 317.263018 -73.024746)
		(mid 317.671831 -73.43394)
		(end 318.080898 -73.025)
		(stroke
			(width 0.2)
			(type default)
		)
		(layer "In3.Cu")
	)
	(gr_line
		(start 317.263018 -72.009)
		(end 317.263018 -73.024746)
		(stroke
			(width 0.2)
			(type default)
		)
		(layer "In3.Cu")
	)
	(gr_arc
		(start 317.898018 -82.422746)
		(mid 318.306831 -82.83194)
		(end 318.715898 -82.423)
		(stroke
			(width 0.2)
			(type default)
		)
		(layer "In3.Cu")
	)
	(gr_line
		(start 317.898018 -81.407)
		(end 317.898018 -82.422746)
		(stroke
			(width 0.2)
			(type default)
		)
		(layer "In3.Cu")
	)
	(gr_line
		(start 317.971932 -79.440786)
		(end 317.972186 -79.44104)
		(stroke
			(width 0.2)
			(type default)
		)
		(layer "In3.Cu")
	)
	(gr_line
		(start 317.972186 -79.44104)
		(end 317.974218 -79.44104)
		(stroke
			(width 0.2)
			(type default)
		)
		(layer "In3.Cu")
	)
	(gr_arc
		(start 317.974218 -79.44104)
		(mid 318.372998 -79.86014)
		(end 318.792098 -79.46136)
		(stroke
			(width 0.2)
			(type default)
		)
		(layer "In3.Cu")
	)
	(gr_line
		(start 317.997332 -78.42504)
		(end 317.971932 -79.440786)
		(stroke
			(width 0.2)
			(type default)
		)
		(layer "In3.Cu")
	)
	(gr_line
		(start 317.999618 -78.42504)
		(end 317.997332 -78.42504)
		(stroke
			(width 0.2)
			(type default)
		)
		(layer "In3.Cu")
	)
	(gr_line
		(start 318.080898 -73.025)
		(end 318.080898 -72.009)
		(stroke
			(width 0.2)
			(type default)
		)
		(layer "In3.Cu")
	)
	(gr_arc
		(start 318.080898 -72.009)
		(mid 317.671958 -71.60006)
		(end 317.263018 -72.009)
		(stroke
			(width 0.2)
			(type default)
		)
		(layer "In3.Cu")
	)
	(gr_arc
		(start 318.372236 -69.197982)
		(mid 318.755776 -69.581522)
		(end 319.139316 -69.197982)
		(stroke
			(width 0.2)
			(type default)
		)
		(layer "In3.Cu")
	)
	(gr_line
		(start 318.372236 -68.216018)
		(end 318.372236 -69.197982)
		(stroke
			(width 0.2)
			(type default)
		)
		(layer "In3.Cu")
	)
	(gr_line
		(start 318.715898 -82.423)
		(end 318.715898 -81.407)
		(stroke
			(width 0.2)
			(type default)
		)
		(layer "In3.Cu")
	)
	(gr_arc
		(start 318.715898 -81.407)
		(mid 318.306958 -80.99806)
		(end 317.898018 -81.407)
		(stroke
			(width 0.2)
			(type default)
		)
		(layer "In3.Cu")
	)
	(gr_line
		(start 318.792098 -79.46136)
		(end 318.794384 -79.46136)
		(stroke
			(width 0.2)
			(type default)
		)
		(layer "In3.Cu")
	)
	(gr_line
		(start 318.794384 -79.46136)
		(end 318.819784 -78.44536)
		(stroke
			(width 0.2)
			(type default)
		)
		(layer "In3.Cu")
	)
	(gr_arc
		(start 318.817498 -78.44536)
		(mid 318.418718 -78.02626)
		(end 317.999618 -78.42504)
		(stroke
			(width 0.2)
			(type default)
		)
		(layer "In3.Cu")
	)
	(gr_line
		(start 318.819784 -78.44536)
		(end 318.817498 -78.44536)
		(stroke
			(width 0.2)
			(type default)
		)
		(layer "In3.Cu")
	)
	(gr_line
		(start 319.139316 -69.197982)
		(end 319.139316 -68.216272)
		(stroke
			(width 0.2)
			(type default)
		)
		(layer "In3.Cu")
	)
	(gr_arc
		(start 319.139316 -68.216272)
		(mid 318.755903 -67.832478)
		(end 318.372236 -68.216018)
		(stroke
			(width 0.2)
			(type default)
		)
		(layer "In3.Cu")
	)
	(gr_arc
		(start 319.777618 -76.191618)
		(mid 320.186431 -76.600812)
		(end 320.595498 -76.191872)
		(stroke
			(width 0.2)
			(type default)
		)
		(layer "In3.Cu")
	)
	(gr_line
		(start 319.777618 -75.209908)
		(end 319.777618 -76.191618)
		(stroke
			(width 0.2)
			(type default)
		)
		(layer "In3.Cu")
	)
	(gr_line
		(start 320.595498 -76.191872)
		(end 320.595498 -75.209908)
		(stroke
			(width 0.2)
			(type default)
		)
		(layer "In3.Cu")
	)
	(gr_arc
		(start 320.595498 -75.209908)
		(mid 320.186558 -74.800968)
		(end 319.777618 -75.209908)
		(stroke
			(width 0.2)
			(type default)
		)
		(layer "In3.Cu")
	)
	(gr_line
		(start 332.359 -145.161)
		(end 346.075 -158.877)
		(stroke
			(width 0.381)
			(type default)
		)
		(layer "In3.Cu")
	)
	(gr_line
		(start 336.296 -190.881)
		(end 283.21 -190.881)
		(stroke
			(width 0.381)
			(type default)
		)
		(layer "In3.Cu")
	)
	(gr_line
		(start 346.075 -181.102)
		(end 336.296 -190.881)
		(stroke
			(width 0.381)
			(type default)
		)
		(layer "In3.Cu")
	)
	(gr_line
		(start 346.075 -158.877)
		(end 346.075 -181.102)
		(stroke
			(width 0.381)
			(type default)
		)
		(layer "In3.Cu")
	)
	(gr_arc
		(start 349.652844 -155.154884)
		(mid 350.010857 -155.513278)
		(end 350.369124 -155.155138)
		(stroke
			(width 0.2)
			(type default)
		)
		(layer "In3.Cu")
	)
	(gr_line
		(start 349.652844 -154.275028)
		(end 349.652844 -155.154884)
		(stroke
			(width 0.2)
			(type default)
		)
		(layer "In3.Cu")
	)
	(gr_line
		(start 350.369124 -155.155138)
		(end 350.369124 -154.275028)
		(stroke
			(width 0.2)
			(type default)
		)
		(layer "In3.Cu")
	)
	(gr_arc
		(start 350.369124 -154.275028)
		(mid 350.010984 -153.916888)
		(end 349.652844 -154.275028)
		(stroke
			(width 0.2)
			(type default)
		)
		(layer "In3.Cu")
	)
	(gr_arc
		(start 350.39681 -152.916636)
		(mid 350.754823 -153.27503)
		(end 351.11309 -152.91689)
		(stroke
			(width 0.2)
			(type default)
		)
		(layer "In3.Cu")
	)
	(gr_line
		(start 350.39681 -151.97201)
		(end 350.39681 -152.916636)
		(stroke
			(width 0.2)
			(type default)
		)
		(layer "In3.Cu")
	)
	(gr_line
		(start 350.60001 -251.000006)
		(end 256.15011 -251.000006)
		(stroke
			(width 1.524)
			(type default)
		)
		(layer "In3.Cu")
	)
	(gr_arc
		(start 350.60001 -251.000006)
		(mid 354.135536 -249.53554)
		(end 355.6 -246.000016)
		(stroke
			(width 1.524)
			(type default)
		)
		(layer "In3.Cu")
	)
	(gr_line
		(start 350.87941 -147.98167)
		(end 351.824036 -147.98167)
		(stroke
			(width 0.2)
			(type default)
		)
		(layer "In3.Cu")
	)
	(gr_arc
		(start 350.87941 -147.26539)
		(mid 350.52127 -147.62353)
		(end 350.87941 -147.98167)
		(stroke
			(width 0.2)
			(type default)
		)
		(layer "In3.Cu")
	)
	(gr_line
		(start 351.11309 -152.91689)
		(end 351.11309 -151.97201)
		(stroke
			(width 0.2)
			(type default)
		)
		(layer "In3.Cu")
	)
	(gr_arc
		(start 351.11309 -151.97201)
		(mid 350.75495 -151.61387)
		(end 350.39681 -151.97201)
		(stroke
			(width 0.2)
			(type default)
		)
		(layer "In3.Cu")
	)
	(gr_arc
		(start 351.824036 -147.98167)
		(mid 352.18243 -147.623657)
		(end 351.82429 -147.26539)
		(stroke
			(width 0.2)
			(type default)
		)
		(layer "In3.Cu")
	)
	(gr_line
		(start 351.82429 -147.26539)
		(end 350.87941 -147.26539)
		(stroke
			(width 0.2)
			(type default)
		)
		(layer "In3.Cu")
	)
	(gr_arc
		(start 355.6 -0.999998)
		(mid 355.307107 -0.292893)
		(end 354.600002 0)
		(stroke
			(width 1.524)
			(type default)
		)
		(layer "In3.Cu")
	)
	(gr_line
		(start 355.6 -0.999998)
		(end 355.6 -246.000016)
		(stroke
			(width 1.524)
			(type default)
		)
		(layer "In3.Cu")
	)
	(gr_line
		(start 0 -246.000016)
		(end 0 -81.009998)
		(stroke
			(width 1.524)
			(type default)
		)
		(layer "In4.Cu")
	)
	(gr_arc
		(start 0 -246.000016)
		(mid 1.464462 -249.535545)
		(end 4.99999 -251.000006)
		(stroke
			(width 1.524)
			(type default)
		)
		(layer "In4.Cu")
	)
	(gr_arc
		(start 2.999994 -78.010004)
		(mid 0.878678 -78.888682)
		(end 0 -81.009998)
		(stroke
			(width 1.524)
			(type default)
		)
		(layer "In4.Cu")
	)
	(gr_line
		(start 2.999994 -78.010004)
		(end 25.500076 -78.010004)
		(stroke
			(width 1.524)
			(type default)
		)
		(layer "In4.Cu")
	)
	(gr_line
		(start 11.14552 -98.876866)
		(end 12.059666 -98.878644)
		(stroke
			(width 0.2)
			(type default)
		)
		(layer "In4.Cu")
	)
	(gr_arc
		(start 11.147044 -98.109786)
		(mid 10.762742 -98.492564)
		(end 11.14552 -98.876866)
		(stroke
			(width 0.2)
			(type default)
		)
		(layer "In4.Cu")
	)
	(gr_arc
		(start 12.059666 -98.878644)
		(mid 12.444222 -98.495993)
		(end 12.061444 -98.111564)
		(stroke
			(width 0.2)
			(type default)
		)
		(layer "In4.Cu")
	)
	(gr_line
		(start 12.061444 -98.111564)
		(end 11.147044 -98.109786)
		(stroke
			(width 0.2)
			(type default)
		)
		(layer "In4.Cu")
	)
	(gr_line
		(start 13.487654 -98.852736)
		(end 14.4272 -98.903536)
		(stroke
			(width 0.2)
			(type default)
		)
		(layer "In4.Cu")
	)
	(gr_arc
		(start 13.52931 -98.086672)
		(mid 13.12545 -98.448876)
		(end 13.487654 -98.852736)
		(stroke
			(width 0.2)
			(type default)
		)
		(layer "In4.Cu")
	)
	(gr_line
		(start 14.4272 -98.903536)
		(end 14.427454 -98.903536)
		(stroke
			(width 0.2)
			(type default)
		)
		(layer "In4.Cu")
	)
	(gr_arc
		(start 14.427454 -98.903536)
		(mid 14.831314 -98.541332)
		(end 14.46911 -98.137472)
		(stroke
			(width 0.2)
			(type default)
		)
		(layer "In4.Cu")
	)
	(gr_line
		(start 14.46911 -98.137472)
		(end 13.52931 -98.086672)
		(stroke
			(width 0.2)
			(type default)
		)
		(layer "In4.Cu")
	)
	(gr_line
		(start 15.936468 -98.88093)
		(end 16.876268 -98.90633)
		(stroke
			(width 0.2)
			(type default)
		)
		(layer "In4.Cu")
	)
	(gr_line
		(start 15.936468 -98.87839)
		(end 15.936468 -98.88093)
		(stroke
			(width 0.2)
			(type default)
		)
		(layer "In4.Cu")
	)
	(gr_arc
		(start 15.957296 -98.111818)
		(mid 15.563596 -98.48469)
		(end 15.936468 -98.87839)
		(stroke
			(width 0.2)
			(type default)
		)
		(layer "In4.Cu")
	)
	(gr_line
		(start 15.957296 -98.109532)
		(end 15.957296 -98.111818)
		(stroke
			(width 0.2)
			(type default)
		)
		(layer "In4.Cu")
	)
	(gr_line
		(start 15.95755 -98.109278)
		(end 15.957296 -98.109532)
		(stroke
			(width 0.2)
			(type default)
		)
		(layer "In4.Cu")
	)
	(gr_line
		(start 16.876268 -98.90633)
		(end 16.876268 -98.90379)
		(stroke
			(width 0.2)
			(type default)
		)
		(layer "In4.Cu")
	)
	(gr_arc
		(start 16.876268 -98.90379)
		(mid 17.269968 -98.530918)
		(end 16.897096 -98.137218)
		(stroke
			(width 0.2)
			(type default)
		)
		(layer "In4.Cu")
	)
	(gr_line
		(start 16.897096 -98.137218)
		(end 16.897096 -98.134678)
		(stroke
			(width 0.2)
			(type default)
		)
		(layer "In4.Cu")
	)
	(gr_line
		(start 16.897096 -98.134678)
		(end 15.95755 -98.109278)
		(stroke
			(width 0.2)
			(type default)
		)
		(layer "In4.Cu")
	)
	(gr_line
		(start 18.258282 -98.929444)
		(end 19.325082 -98.929444)
		(stroke
			(width 0.2)
			(type default)
		)
		(layer "In4.Cu")
	)
	(gr_arc
		(start 18.258536 -98.162364)
		(mid 17.874742 -98.545777)
		(end 18.258282 -98.929444)
		(stroke
			(width 0.2)
			(type default)
		)
		(layer "In4.Cu")
	)
	(gr_arc
		(start 19.325082 -98.929444)
		(mid 19.708622 -98.545904)
		(end 19.325082 -98.162364)
		(stroke
			(width 0.2)
			(type default)
		)
		(layer "In4.Cu")
	)
	(gr_line
		(start 19.325082 -98.162364)
		(end 18.258536 -98.162364)
		(stroke
			(width 0.2)
			(type default)
		)
		(layer "In4.Cu")
	)
	(gr_arc
		(start 25.500076 -78.010004)
		(mid 26.914287 -77.424219)
		(end 27.500072 -76.010008)
		(stroke
			(width 1.524)
			(type default)
		)
		(layer "In4.Cu")
	)
	(gr_line
		(start 26.34996 -251.000006)
		(end 4.99999 -251.000006)
		(stroke
			(width 1.524)
			(type default)
		)
		(layer "In4.Cu")
	)
	(gr_line
		(start 27.349958 -258.59994)
		(end 27.349958 -252.000004)
		(stroke
			(width 1.524)
			(type default)
		)
		(layer "In4.Cu")
	)
	(gr_arc
		(start 27.349958 -252.000004)
		(mid 27.057065 -251.292899)
		(end 26.34996 -251.000006)
		(stroke
			(width 1.524)
			(type default)
		)
		(layer "In4.Cu")
	)
	(gr_line
		(start 27.500072 -76.010008)
		(end 27.500072 -60.01004)
		(stroke
			(width 1.524)
			(type default)
		)
		(layer "In4.Cu")
	)
	(gr_line
		(start 29.464 -151.13)
		(end 29.464 -126.619)
		(stroke
			(width 0.381)
			(type default)
		)
		(layer "In4.Cu")
	)
	(gr_line
		(start 29.464 -126.619)
		(end 47.625 -108.458)
		(stroke
			(width 0.381)
			(type default)
		)
		(layer "In4.Cu")
	)
	(gr_arc
		(start 29.500068 -58.010044)
		(mid 28.085859 -58.59583)
		(end 27.500072 -60.01004)
		(stroke
			(width 1.524)
			(type default)
		)
		(layer "In4.Cu")
	)
	(gr_line
		(start 29.500068 -58.010044)
		(end 60.950094 -58.010044)
		(stroke
			(width 1.524)
			(type default)
		)
		(layer "In4.Cu")
	)
	(gr_line
		(start 31.115 -152.781)
		(end 29.464 -151.13)
		(stroke
			(width 0.381)
			(type default)
		)
		(layer "In4.Cu")
	)
	(gr_line
		(start 32.334454 -90.479626)
		(end 33.311338 -90.479626)
		(stroke
			(width 0.2)
			(type default)
		)
		(layer "In4.Cu")
	)
	(gr_arc
		(start 32.334708 -89.712546)
		(mid 31.950914 -90.095959)
		(end 32.334454 -90.479626)
		(stroke
			(width 0.2)
			(type default)
		)
		(layer "In4.Cu")
	)
	(gr_arc
		(start 33.311338 -90.479626)
		(mid 33.694878 -90.096086)
		(end 33.311338 -89.712546)
		(stroke
			(width 0.2)
			(type default)
		)
		(layer "In4.Cu")
	)
	(gr_line
		(start 33.311338 -89.712546)
		(end 32.334708 -89.712546)
		(stroke
			(width 0.2)
			(type default)
		)
		(layer "In4.Cu")
	)
	(gr_line
		(start 34.550096 -258.59994)
		(end 27.349958 -258.59994)
		(stroke
			(width 5.08)
			(type default)
		)
		(layer "In4.Cu")
	)
	(gr_line
		(start 34.550096 -252.549914)
		(end 34.550096 -258.59994)
		(stroke
			(width 1.524)
			(type default)
		)
		(layer "In4.Cu")
	)
	(gr_line
		(start 35.306 -152.781)
		(end 31.115 -152.781)
		(stroke
			(width 0.381)
			(type default)
		)
		(layer "In4.Cu")
	)
	(gr_line
		(start 35.306 -152.781)
		(end 61.214 -152.781)
		(stroke
			(width 0.381)
			(type default)
		)
		(layer "In4.Cu")
	)
	(gr_line
		(start 35.382454 -90.479626)
		(end 36.359084 -90.479626)
		(stroke
			(width 0.2)
			(type default)
		)
		(layer "In4.Cu")
	)
	(gr_arc
		(start 35.382454 -89.712546)
		(mid 34.998914 -90.096086)
		(end 35.382454 -90.479626)
		(stroke
			(width 0.2)
			(type default)
		)
		(layer "In4.Cu")
	)
	(gr_arc
		(start 36.359084 -90.479626)
		(mid 36.742878 -90.096213)
		(end 36.359338 -89.712546)
		(stroke
			(width 0.2)
			(type default)
		)
		(layer "In4.Cu")
	)
	(gr_line
		(start 36.359338 -89.712546)
		(end 35.382454 -89.712546)
		(stroke
			(width 0.2)
			(type default)
		)
		(layer "In4.Cu")
	)
	(gr_line
		(start 36.450016 -258.59994)
		(end 36.450016 -252.549914)
		(stroke
			(width 1.524)
			(type default)
		)
		(layer "In4.Cu")
	)
	(gr_arc
		(start 36.450016 -252.549914)
		(mid 35.500056 -251.599954)
		(end 34.550096 -252.549914)
		(stroke
			(width 1.524)
			(type default)
		)
		(layer "In4.Cu")
	)
	(gr_line
		(start 38.430454 -90.479626)
		(end 39.407084 -90.479626)
		(stroke
			(width 0.2)
			(type default)
		)
		(layer "In4.Cu")
	)
	(gr_arc
		(start 38.430454 -89.712546)
		(mid 38.046914 -90.096086)
		(end 38.430454 -90.479626)
		(stroke
			(width 0.2)
			(type default)
		)
		(layer "In4.Cu")
	)
	(gr_arc
		(start 39.208456 -83.046824)
		(mid 39.591869 -83.430618)
		(end 39.975536 -83.047078)
		(stroke
			(width 0.2)
			(type default)
		)
		(layer "In4.Cu")
	)
	(gr_line
		(start 39.208456 -82.070194)
		(end 39.208456 -83.046824)
		(stroke
			(width 0.2)
			(type default)
		)
		(layer "In4.Cu")
	)
	(gr_arc
		(start 39.208456 -80.722978)
		(mid 39.591996 -81.106518)
		(end 39.975536 -80.722978)
		(stroke
			(width 0.2)
			(type default)
		)
		(layer "In4.Cu")
	)
	(gr_line
		(start 39.208456 -79.746094)
		(end 39.208456 -80.722978)
		(stroke
			(width 0.2)
			(type default)
		)
		(layer "In4.Cu")
	)
	(gr_arc
		(start 39.407084 -90.479626)
		(mid 39.790878 -90.096213)
		(end 39.407338 -89.712546)
		(stroke
			(width 0.2)
			(type default)
		)
		(layer "In4.Cu")
	)
	(gr_line
		(start 39.407338 -89.712546)
		(end 38.430454 -89.712546)
		(stroke
			(width 0.2)
			(type default)
		)
		(layer "In4.Cu")
	)
	(gr_line
		(start 39.975536 -83.047078)
		(end 39.975536 -82.070194)
		(stroke
			(width 0.2)
			(type default)
		)
		(layer "In4.Cu")
	)
	(gr_arc
		(start 39.975536 -82.070194)
		(mid 39.591996 -81.686654)
		(end 39.208456 -82.070194)
		(stroke
			(width 0.2)
			(type default)
		)
		(layer "In4.Cu")
	)
	(gr_line
		(start 39.975536 -80.722978)
		(end 39.975536 -79.746348)
		(stroke
			(width 0.2)
			(type default)
		)
		(layer "In4.Cu")
	)
	(gr_arc
		(start 39.975536 -79.746348)
		(mid 39.592123 -79.362554)
		(end 39.208456 -79.746094)
		(stroke
			(width 0.2)
			(type default)
		)
		(layer "In4.Cu")
	)
	(gr_line
		(start 41.351454 -90.479626)
		(end 42.328338 -90.479626)
		(stroke
			(width 0.2)
			(type default)
		)
		(layer "In4.Cu")
	)
	(gr_arc
		(start 41.351708 -89.712546)
		(mid 40.967914 -90.095959)
		(end 41.351454 -90.479626)
		(stroke
			(width 0.2)
			(type default)
		)
		(layer "In4.Cu")
	)
	(gr_line
		(start 41.693338 -83.873086)
		(end 42.670222 -83.873086)
		(stroke
			(width 0.2)
			(type default)
		)
		(layer "In4.Cu")
	)
	(gr_arc
		(start 41.693592 -83.106006)
		(mid 41.309798 -83.489419)
		(end 41.693338 -83.873086)
		(stroke
			(width 0.2)
			(type default)
		)
		(layer "In4.Cu")
	)
	(gr_line
		(start 42.111422 -75.138026)
		(end 43.088306 -75.138026)
		(stroke
			(width 0.2)
			(type default)
		)
		(layer "In4.Cu")
	)
	(gr_arc
		(start 42.111676 -74.370946)
		(mid 41.727882 -74.754359)
		(end 42.111422 -75.138026)
		(stroke
			(width 0.2)
			(type default)
		)
		(layer "In4.Cu")
	)
	(gr_arc
		(start 42.328338 -90.479626)
		(mid 42.711878 -90.096086)
		(end 42.328338 -89.712546)
		(stroke
			(width 0.2)
			(type default)
		)
		(layer "In4.Cu")
	)
	(gr_line
		(start 42.328338 -89.712546)
		(end 41.351708 -89.712546)
		(stroke
			(width 0.2)
			(type default)
		)
		(layer "In4.Cu")
	)
	(gr_arc
		(start 42.670222 -83.873086)
		(mid 43.053762 -83.489546)
		(end 42.670222 -83.106006)
		(stroke
			(width 0.2)
			(type default)
		)
		(layer "In4.Cu")
	)
	(gr_line
		(start 42.670222 -83.106006)
		(end 41.693592 -83.106006)
		(stroke
			(width 0.2)
			(type default)
		)
		(layer "In4.Cu")
	)
	(gr_arc
		(start 43.088306 -75.138026)
		(mid 43.471846 -74.754486)
		(end 43.088306 -74.370946)
		(stroke
			(width 0.2)
			(type default)
		)
		(layer "In4.Cu")
	)
	(gr_line
		(start 43.088306 -74.370946)
		(end 42.111676 -74.370946)
		(stroke
			(width 0.2)
			(type default)
		)
		(layer "In4.Cu")
	)
	(gr_line
		(start 44.511468 -75.290426)
		(end 45.488098 -75.290426)
		(stroke
			(width 0.2)
			(type default)
		)
		(layer "In4.Cu")
	)
	(gr_arc
		(start 44.511468 -74.523346)
		(mid 44.127928 -74.906886)
		(end 44.511468 -75.290426)
		(stroke
			(width 0.2)
			(type default)
		)
		(layer "In4.Cu")
	)
	(gr_line
		(start 44.647104 -83.885786)
		(end 45.623734 -83.885786)
		(stroke
			(width 0.2)
			(type default)
		)
		(layer "In4.Cu")
	)
	(gr_arc
		(start 44.647104 -83.118706)
		(mid 44.263564 -83.502246)
		(end 44.647104 -83.885786)
		(stroke
			(width 0.2)
			(type default)
		)
		(layer "In4.Cu")
	)
	(gr_arc
		(start 45.488098 -75.290426)
		(mid 45.871892 -74.907013)
		(end 45.488352 -74.523346)
		(stroke
			(width 0.2)
			(type default)
		)
		(layer "In4.Cu")
	)
	(gr_line
		(start 45.488352 -74.523346)
		(end 44.511468 -74.523346)
		(stroke
			(width 0.2)
			(type default)
		)
		(layer "In4.Cu")
	)
	(gr_arc
		(start 45.623734 -83.885786)
		(mid 46.007528 -83.502373)
		(end 45.623988 -83.118706)
		(stroke
			(width 0.2)
			(type default)
		)
		(layer "In4.Cu")
	)
	(gr_line
		(start 45.623988 -83.118706)
		(end 44.647104 -83.118706)
		(stroke
			(width 0.2)
			(type default)
		)
		(layer "In4.Cu")
	)
	(gr_line
		(start 47.625 -108.458)
		(end 57.658 -108.458)
		(stroke
			(width 0.381)
			(type default)
		)
		(layer "In4.Cu")
	)
	(gr_line
		(start 47.649892 -258.59994)
		(end 36.450016 -258.59994)
		(stroke
			(width 5.08)
			(type default)
		)
		(layer "In4.Cu")
	)
	(gr_line
		(start 47.649892 -252.000004)
		(end 47.649892 -258.59994)
		(stroke
			(width 1.524)
			(type default)
		)
		(layer "In4.Cu")
	)
	(gr_arc
		(start 48.606456 -87.746078)
		(mid 48.989996 -88.129618)
		(end 49.373536 -87.746078)
		(stroke
			(width 0.2)
			(type default)
		)
		(layer "In4.Cu")
	)
	(gr_line
		(start 48.606456 -86.769194)
		(end 48.606456 -87.746078)
		(stroke
			(width 0.2)
			(type default)
		)
		(layer "In4.Cu")
	)
	(gr_arc
		(start 48.606456 -84.913724)
		(mid 48.989869 -85.297518)
		(end 49.373536 -84.913978)
		(stroke
			(width 0.2)
			(type default)
		)
		(layer "In4.Cu")
	)
	(gr_line
		(start 48.606456 -83.937094)
		(end 48.606456 -84.913724)
		(stroke
			(width 0.2)
			(type default)
		)
		(layer "In4.Cu")
	)
	(gr_arc
		(start 48.64989 -251.000006)
		(mid 47.942785 -251.292899)
		(end 47.649892 -252.000004)
		(stroke
			(width 1.524)
			(type default)
		)
		(layer "In4.Cu")
	)
	(gr_line
		(start 49.373536 -87.746078)
		(end 49.373536 -86.769448)
		(stroke
			(width 0.2)
			(type default)
		)
		(layer "In4.Cu")
	)
	(gr_arc
		(start 49.373536 -86.769448)
		(mid 48.990123 -86.385654)
		(end 48.606456 -86.769194)
		(stroke
			(width 0.2)
			(type default)
		)
		(layer "In4.Cu")
	)
	(gr_line
		(start 49.373536 -84.913978)
		(end 49.373536 -83.937094)
		(stroke
			(width 0.2)
			(type default)
		)
		(layer "In4.Cu")
	)
	(gr_arc
		(start 49.373536 -83.937094)
		(mid 48.989996 -83.553554)
		(end 48.606456 -83.937094)
		(stroke
			(width 0.2)
			(type default)
		)
		(layer "In4.Cu")
	)
	(gr_line
		(start 50.911506 -75.290426)
		(end 51.888136 -75.290426)
		(stroke
			(width 0.2)
			(type default)
		)
		(layer "In4.Cu")
	)
	(gr_arc
		(start 50.911506 -74.523346)
		(mid 50.527966 -74.906886)
		(end 50.911506 -75.290426)
		(stroke
			(width 0.2)
			(type default)
		)
		(layer "In4.Cu")
	)
	(gr_arc
		(start 51.888136 -75.290426)
		(mid 52.27193 -74.907013)
		(end 51.88839 -74.523346)
		(stroke
			(width 0.2)
			(type default)
		)
		(layer "In4.Cu")
	)
	(gr_line
		(start 51.88839 -74.523346)
		(end 50.911506 -74.523346)
		(stroke
			(width 0.2)
			(type default)
		)
		(layer "In4.Cu")
	)
	(gr_line
		(start 53.311298 -75.290426)
		(end 54.287928 -75.290426)
		(stroke
			(width 0.2)
			(type default)
		)
		(layer "In4.Cu")
	)
	(gr_arc
		(start 53.311298 -74.523346)
		(mid 52.927758 -74.906886)
		(end 53.311298 -75.290426)
		(stroke
			(width 0.2)
			(type default)
		)
		(layer "In4.Cu")
	)
	(gr_arc
		(start 54.287928 -75.290426)
		(mid 54.671722 -74.907013)
		(end 54.288182 -74.523346)
		(stroke
			(width 0.2)
			(type default)
		)
		(layer "In4.Cu")
	)
	(gr_line
		(start 54.288182 -74.523346)
		(end 53.311298 -74.523346)
		(stroke
			(width 0.2)
			(type default)
		)
		(layer "In4.Cu")
	)
	(gr_line
		(start 57.658 -108.458)
		(end 58.293 -107.823)
		(stroke
			(width 0.381)
			(type default)
		)
		(layer "In4.Cu")
	)
	(gr_line
		(start 58.293 -107.823)
		(end 58.293 -97.79)
		(stroke
			(width 0.381)
			(type default)
		)
		(layer "In4.Cu")
	)
	(gr_line
		(start 58.293 -97.79)
		(end 83.058 -73.025)
		(stroke
			(width 0.381)
			(type default)
		)
		(layer "In4.Cu")
	)
	(gr_arc
		(start 60.950094 -58.010044)
		(mid 61.657199 -57.717151)
		(end 61.950092 -57.010046)
		(stroke
			(width 1.524)
			(type default)
		)
		(layer "In4.Cu")
	)
	(gr_line
		(start 61.950092 -57.010046)
		(end 61.950092 -17.999964)
		(stroke
			(width 1.524)
			(type default)
		)
		(layer "In4.Cu")
	)
	(gr_arc
		(start 62.95009 -16.999966)
		(mid 62.242978 -17.29286)
		(end 61.950092 -17.999964)
		(stroke
			(width 1.524)
			(type default)
		)
		(layer "In4.Cu")
	)
	(gr_line
		(start 62.95009 -16.999966)
		(end 73.449942 -16.999966)
		(stroke
			(width 1.524)
			(type default)
		)
		(layer "In4.Cu")
	)
	(gr_line
		(start 66.34988 -251.000006)
		(end 48.64989 -251.000006)
		(stroke
			(width 1.524)
			(type default)
		)
		(layer "In4.Cu")
	)
	(gr_line
		(start 67.349878 -258.59994)
		(end 67.349878 -252.000004)
		(stroke
			(width 1.524)
			(type default)
		)
		(layer "In4.Cu")
	)
	(gr_arc
		(start 67.349878 -252.000004)
		(mid 67.056985 -251.292899)
		(end 66.34988 -251.000006)
		(stroke
			(width 1.524)
			(type default)
		)
		(layer "In4.Cu")
	)
	(gr_line
		(start 69.342 -152.781)
		(end 61.214 -152.781)
		(stroke
			(width 0.381)
			(type default)
		)
		(layer "In4.Cu")
	)
	(gr_arc
		(start 73.449942 -16.999966)
		(mid 74.157047 -16.707073)
		(end 74.44994 -15.999968)
		(stroke
			(width 1.524)
			(type default)
		)
		(layer "In4.Cu")
	)
	(gr_line
		(start 74.44994 -15.999968)
		(end 74.44994 -0.999998)
		(stroke
			(width 1.524)
			(type default)
		)
		(layer "In4.Cu")
	)
	(gr_arc
		(start 75.449938 0)
		(mid 74.742807 -0.292879)
		(end 74.44994 -0.999998)
		(stroke
			(width 1.524)
			(type default)
		)
		(layer "In4.Cu")
	)
	(gr_line
		(start 75.449938 0)
		(end 281.485086 0)
		(stroke
			(width 1.524)
			(type default)
		)
		(layer "In4.Cu")
	)
	(gr_line
		(start 76.157074 -37.042852)
		(end 77.133958 -37.042852)
		(stroke
			(width 0.2)
			(type default)
		)
		(layer "In4.Cu")
	)
	(gr_arc
		(start 76.157328 -36.275772)
		(mid 75.773534 -36.659185)
		(end 76.157074 -37.042852)
		(stroke
			(width 0.2)
			(type default)
		)
		(layer "In4.Cu")
	)
	(gr_arc
		(start 77.133958 -37.042852)
		(mid 77.517498 -36.659312)
		(end 77.133958 -36.275772)
		(stroke
			(width 0.2)
			(type default)
		)
		(layer "In4.Cu")
	)
	(gr_line
		(start 77.133958 -36.275772)
		(end 76.157328 -36.275772)
		(stroke
			(width 0.2)
			(type default)
		)
		(layer "In4.Cu")
	)
	(gr_line
		(start 77.686408 -41.98874)
		(end 78.663038 -41.98874)
		(stroke
			(width 0.2)
			(type default)
		)
		(layer "In4.Cu")
	)
	(gr_arc
		(start 77.686408 -41.22166)
		(mid 77.302868 -41.6052)
		(end 77.686408 -41.98874)
		(stroke
			(width 0.2)
			(type default)
		)
		(layer "In4.Cu")
	)
	(gr_arc
		(start 78.663038 -41.98874)
		(mid 79.046832 -41.605327)
		(end 78.663292 -41.22166)
		(stroke
			(width 0.2)
			(type default)
		)
		(layer "In4.Cu")
	)
	(gr_line
		(start 78.663292 -41.22166)
		(end 77.686408 -41.22166)
		(stroke
			(width 0.2)
			(type default)
		)
		(layer "In4.Cu")
	)
	(gr_line
		(start 79.604108 -40.00754)
		(end 80.580738 -40.00754)
		(stroke
			(width 0.2)
			(type default)
		)
		(layer "In4.Cu")
	)
	(gr_arc
		(start 79.604108 -39.24046)
		(mid 79.220568 -39.624)
		(end 79.604108 -40.00754)
		(stroke
			(width 0.2)
			(type default)
		)
		(layer "In4.Cu")
	)
	(gr_arc
		(start 80.580738 -40.00754)
		(mid 80.964532 -39.624127)
		(end 80.580992 -39.24046)
		(stroke
			(width 0.2)
			(type default)
		)
		(layer "In4.Cu")
	)
	(gr_line
		(start 80.580992 -39.24046)
		(end 79.604108 -39.24046)
		(stroke
			(width 0.2)
			(type default)
		)
		(layer "In4.Cu")
	)
	(gr_arc
		(start 80.84566 -37.312092)
		(mid 81.2292 -37.695632)
		(end 81.61274 -37.312092)
		(stroke
			(width 0.2)
			(type default)
		)
		(layer "In4.Cu")
	)
	(gr_line
		(start 80.84566 -36.335208)
		(end 80.84566 -37.312092)
		(stroke
			(width 0.2)
			(type default)
		)
		(layer "In4.Cu")
	)
	(gr_line
		(start 81.61274 -37.312092)
		(end 81.61274 -36.335462)
		(stroke
			(width 0.2)
			(type default)
		)
		(layer "In4.Cu")
	)
	(gr_arc
		(start 81.61274 -36.335462)
		(mid 81.229327 -35.951668)
		(end 80.84566 -36.335208)
		(stroke
			(width 0.2)
			(type default)
		)
		(layer "In4.Cu")
	)
	(gr_arc
		(start 82.527648 -38.736524)
		(mid 82.911061 -39.120318)
		(end 83.294728 -38.736778)
		(stroke
			(width 0.2)
			(type default)
		)
		(layer "In4.Cu")
	)
	(gr_line
		(start 82.527648 -37.831776)
		(end 82.527648 -38.736524)
		(stroke
			(width 0.2)
			(type default)
		)
		(layer "In4.Cu")
	)
	(gr_arc
		(start 82.69986 -35.523678)
		(mid 83.0834 -35.907218)
		(end 83.46694 -35.523678)
		(stroke
			(width 0.2)
			(type default)
		)
		(layer "In4.Cu")
	)
	(gr_line
		(start 82.69986 -34.618676)
		(end 82.69986 -35.523678)
		(stroke
			(width 0.2)
			(type default)
		)
		(layer "In4.Cu")
	)
	(gr_line
		(start 83.058 -73.025)
		(end 105.156 -73.025)
		(stroke
			(width 0.381)
			(type default)
		)
		(layer "In4.Cu")
	)
	(gr_line
		(start 83.294728 -38.736778)
		(end 83.294728 -37.831776)
		(stroke
			(width 0.2)
			(type default)
		)
		(layer "In4.Cu")
	)
	(gr_arc
		(start 83.294728 -37.831776)
		(mid 82.911188 -37.448236)
		(end 82.527648 -37.831776)
		(stroke
			(width 0.2)
			(type default)
		)
		(layer "In4.Cu")
	)
	(gr_line
		(start 83.46694 -35.523678)
		(end 83.46694 -34.61893)
		(stroke
			(width 0.2)
			(type default)
		)
		(layer "In4.Cu")
	)
	(gr_arc
		(start 83.46694 -34.61893)
		(mid 83.083527 -34.235136)
		(end 82.69986 -34.618676)
		(stroke
			(width 0.2)
			(type default)
		)
		(layer "In4.Cu")
	)
	(gr_line
		(start 83.69554 -37.754306)
		(end 83.723734 -38.770306)
		(stroke
			(width 0.2)
			(type default)
		)
		(layer "In4.Cu")
	)
	(gr_line
		(start 83.69808 -37.754306)
		(end 83.69554 -37.754306)
		(stroke
			(width 0.2)
			(type default)
		)
		(layer "In4.Cu")
	)
	(gr_line
		(start 83.723734 -38.770306)
		(end 83.723988 -38.77056)
		(stroke
			(width 0.2)
			(type default)
		)
		(layer "In4.Cu")
	)
	(gr_line
		(start 83.723988 -38.77056)
		(end 83.726274 -38.77056)
		(stroke
			(width 0.2)
			(type default)
		)
		(layer "In4.Cu")
	)
	(gr_arc
		(start 83.726274 -38.77056)
		(mid 84.094066 -39.11854)
		(end 84.442046 -38.750748)
		(stroke
			(width 0.2)
			(type default)
		)
		(layer "In4.Cu")
	)
	(gr_arc
		(start 84.413852 -37.734494)
		(mid 84.04606 -37.386514)
		(end 83.69808 -37.754306)
		(stroke
			(width 0.2)
			(type default)
		)
		(layer "In4.Cu")
	)
	(gr_line
		(start 84.416392 -37.734494)
		(end 84.413852 -37.734494)
		(stroke
			(width 0.2)
			(type default)
		)
		(layer "In4.Cu")
	)
	(gr_line
		(start 84.442046 -38.750748)
		(end 84.444586 -38.750748)
		(stroke
			(width 0.2)
			(type default)
		)
		(layer "In4.Cu")
	)
	(gr_line
		(start 84.444586 -38.750748)
		(end 84.416392 -37.734494)
		(stroke
			(width 0.2)
			(type default)
		)
		(layer "In4.Cu")
	)
	(gr_arc
		(start 84.60486 -33.789874)
		(mid 84.9884 -34.173414)
		(end 85.37194 -33.789874)
		(stroke
			(width 0.2)
			(type default)
		)
		(layer "In4.Cu")
	)
	(gr_line
		(start 84.60486 -32.884872)
		(end 84.60486 -33.789874)
		(stroke
			(width 0.2)
			(type default)
		)
		(layer "In4.Cu")
	)
	(gr_line
		(start 85.37194 -33.789874)
		(end 85.37194 -32.885126)
		(stroke
			(width 0.2)
			(type default)
		)
		(layer "In4.Cu")
	)
	(gr_arc
		(start 85.37194 -32.885126)
		(mid 84.988527 -32.501332)
		(end 84.60486 -32.884872)
		(stroke
			(width 0.2)
			(type default)
		)
		(layer "In4.Cu")
	)
	(gr_line
		(start 92.744798 -39.75354)
		(end 93.55582 -39.755318)
		(stroke
			(width 0.2)
			(type default)
		)
		(layer "In4.Cu")
	)
	(gr_line
		(start 92.746576 -42.154856)
		(end 93.550994 -42.16273)
		(stroke
			(width 0.2)
			(type default)
		)
		(layer "In4.Cu")
	)
	(gr_arc
		(start 92.746576 -39.03726)
		(mid 92.387674 -39.394511)
		(end 92.744798 -39.75354)
		(stroke
			(width 0.2)
			(type default)
		)
		(layer "In4.Cu")
	)
	(gr_arc
		(start 92.753942 -41.438576)
		(mid 92.392247 -41.793033)
		(end 92.746576 -42.154856)
		(stroke
			(width 0.2)
			(type default)
		)
		(layer "In4.Cu")
	)
	(gr_line
		(start 93.182694 -40.206422)
		(end 93.196664 -41.001696)
		(stroke
			(width 0.2)
			(type default)
		)
		(layer "In4.Cu")
	)
	(gr_line
		(start 93.19133 -35.40887)
		(end 93.193616 -36.197032)
		(stroke
			(width 0.2)
			(type default)
		)
		(layer "In4.Cu")
	)
	(gr_arc
		(start 93.192346 -43.387772)
		(mid 93.547565 -43.748961)
		(end 93.908626 -43.393614)
		(stroke
			(width 0.2)
			(type default)
		)
		(layer "In4.Cu")
	)
	(gr_arc
		(start 93.193616 -36.197032)
		(mid 93.552645 -36.55441)
		(end 93.909896 -36.195254)
		(stroke
			(width 0.2)
			(type default)
		)
		(layer "In4.Cu")
	)
	(gr_arc
		(start 93.196664 -41.001696)
		(mid 93.561027 -41.353738)
		(end 93.912944 -40.98925)
		(stroke
			(width 0.2)
			(type default)
		)
		(layer "In4.Cu")
	)
	(gr_arc
		(start 93.197426 -38.596316)
		(mid 93.555058 -38.954964)
		(end 93.913706 -38.597332)
		(stroke
			(width 0.2)
			(type default)
		)
		(layer "In4.Cu")
	)
	(gr_line
		(start 93.198442 -37.80155)
		(end 93.197426 -38.596316)
		(stroke
			(width 0.2)
			(type default)
		)
		(layer "In4.Cu")
	)
	(gr_line
		(start 93.198696 -42.59453)
		(end 93.192346 -43.387772)
		(stroke
			(width 0.2)
			(type default)
		)
		(layer "In4.Cu")
	)
	(gr_arc
		(start 93.544644 -34.248344)
		(mid 93.189297 -34.609151)
		(end 93.549978 -34.964624)
		(stroke
			(width 0.2)
			(type default)
		)
		(layer "In4.Cu")
	)
	(gr_line
		(start 93.549978 -34.964624)
		(end 94.352618 -34.958274)
		(stroke
			(width 0.2)
			(type default)
		)
		(layer "In4.Cu")
	)
	(gr_arc
		(start 93.550232 -36.64458)
		(mid 93.193616 -37.004244)
		(end 93.55328 -37.36086)
		(stroke
			(width 0.2)
			(type default)
		)
		(layer "In4.Cu")
	)
	(gr_arc
		(start 93.550994 -42.16273)
		(mid 93.91269 -41.808146)
		(end 93.558106 -41.44645)
		(stroke
			(width 0.2)
			(type default)
		)
		(layer "In4.Cu")
	)
	(gr_line
		(start 93.55328 -37.36086)
		(end 94.360492 -37.357558)
		(stroke
			(width 0.2)
			(type default)
		)
		(layer "In4.Cu")
	)
	(gr_arc
		(start 93.55582 -39.755318)
		(mid 93.914722 -39.39794)
		(end 93.557344 -39.039038)
		(stroke
			(width 0.2)
			(type default)
		)
		(layer "In4.Cu")
	)
	(gr_line
		(start 93.557344 -39.039038)
		(end 92.746576 -39.03726)
		(stroke
			(width 0.2)
			(type default)
		)
		(layer "In4.Cu")
	)
	(gr_line
		(start 93.558106 -41.44645)
		(end 92.753942 -41.438576)
		(stroke
			(width 0.2)
			(type default)
		)
		(layer "In4.Cu")
	)
	(gr_arc
		(start 93.898974 -40.193722)
		(mid 93.534484 -39.841932)
		(end 93.182694 -40.206422)
		(stroke
			(width 0.2)
			(type default)
		)
		(layer "In4.Cu")
	)
	(gr_line
		(start 93.90761 -35.407854)
		(end 93.90761 -35.406838)
		(stroke
			(width 0.2)
			(type default)
		)
		(layer "In4.Cu")
	)
	(gr_arc
		(start 93.90761 -35.406838)
		(mid 93.548454 -35.049714)
		(end 93.19133 -35.40887)
		(stroke
			(width 0.2)
			(type default)
		)
		(layer "In4.Cu")
	)
	(gr_line
		(start 93.908626 -43.393614)
		(end 93.914976 -42.600118)
		(stroke
			(width 0.2)
			(type default)
		)
		(layer "In4.Cu")
	)
	(gr_line
		(start 93.909896 -36.195254)
		(end 93.90761 -35.407854)
		(stroke
			(width 0.2)
			(type default)
		)
		(layer "In4.Cu")
	)
	(gr_line
		(start 93.912944 -40.98925)
		(end 93.898974 -40.193722)
		(stroke
			(width 0.2)
			(type default)
		)
		(layer "In4.Cu")
	)
	(gr_line
		(start 93.913706 -38.597332)
		(end 93.913706 -38.596824)
		(stroke
			(width 0.2)
			(type default)
		)
		(layer "In4.Cu")
	)
	(gr_line
		(start 93.913706 -38.596824)
		(end 93.914722 -37.80282)
		(stroke
			(width 0.2)
			(type default)
		)
		(layer "In4.Cu")
	)
	(gr_arc
		(start 93.914722 -37.80282)
		(mid 93.557217 -37.444172)
		(end 93.198442 -37.80155)
		(stroke
			(width 0.2)
			(type default)
		)
		(layer "In4.Cu")
	)
	(gr_arc
		(start 93.914976 -42.600118)
		(mid 93.55963 -42.239184)
		(end 93.198696 -42.59453)
		(stroke
			(width 0.2)
			(type default)
		)
		(layer "In4.Cu")
	)
	(gr_line
		(start 94.34703 -34.241994)
		(end 93.544644 -34.248344)
		(stroke
			(width 0.2)
			(type default)
		)
		(layer "In4.Cu")
	)
	(gr_arc
		(start 94.352618 -34.958274)
		(mid 94.707964 -34.59734)
		(end 94.34703 -34.241994)
		(stroke
			(width 0.2)
			(type default)
		)
		(layer "In4.Cu")
	)
	(gr_line
		(start 94.357698 -36.641278)
		(end 93.550232 -36.64458)
		(stroke
			(width 0.2)
			(type default)
		)
		(layer "In4.Cu")
	)
	(gr_arc
		(start 94.360492 -37.357558)
		(mid 94.717362 -36.998021)
		(end 94.357698 -36.641278)
		(stroke
			(width 0.2)
			(type default)
		)
		(layer "In4.Cu")
	)
	(gr_line
		(start 94.79026 -35.405822)
		(end 94.792038 -36.200588)
		(stroke
			(width 0.2)
			(type default)
		)
		(layer "In4.Cu")
	)
	(gr_arc
		(start 94.792038 -36.200588)
		(mid 95.150813 -36.55822)
		(end 95.508318 -36.199318)
		(stroke
			(width 0.2)
			(type default)
		)
		(layer "In4.Cu")
	)
	(gr_line
		(start 94.996 -37.084)
		(end 94.996 -29.083)
		(stroke
			(width 0.381)
			(type default)
		)
		(layer "In4.Cu")
	)
	(gr_line
		(start 94.996 -29.083)
		(end 107.315 -16.764)
		(stroke
			(width 0.381)
			(type default)
		)
		(layer "In4.Cu")
	)
	(gr_line
		(start 95.50654 -35.40506)
		(end 95.50654 -35.404298)
		(stroke
			(width 0.2)
			(type default)
		)
		(layer "In4.Cu")
	)
	(gr_arc
		(start 95.50654 -35.404298)
		(mid 95.147638 -35.04692)
		(end 94.79026 -35.405822)
		(stroke
			(width 0.2)
			(type default)
		)
		(layer "In4.Cu")
	)
	(gr_line
		(start 95.508318 -36.199318)
		(end 95.50654 -35.40506)
		(stroke
			(width 0.2)
			(type default)
		)
		(layer "In4.Cu")
	)
	(gr_line
		(start 95.59036 -35.408362)
		(end 95.592138 -36.200588)
		(stroke
			(width 0.2)
			(type default)
		)
		(layer "In4.Cu")
	)
	(gr_arc
		(start 95.592138 -36.200588)
		(mid 95.950913 -36.55822)
		(end 96.308418 -36.199318)
		(stroke
			(width 0.2)
			(type default)
		)
		(layer "In4.Cu")
	)
	(gr_line
		(start 95.885 -37.973)
		(end 94.996 -37.084)
		(stroke
			(width 0.381)
			(type default)
		)
		(layer "In4.Cu")
	)
	(gr_line
		(start 96.30664 -35.4076)
		(end 96.30664 -35.406838)
		(stroke
			(width 0.2)
			(type default)
		)
		(layer "In4.Cu")
	)
	(gr_arc
		(start 96.30664 -35.406838)
		(mid 95.947738 -35.04946)
		(end 95.59036 -35.408362)
		(stroke
			(width 0.2)
			(type default)
		)
		(layer "In4.Cu")
	)
	(gr_line
		(start 96.308418 -36.199318)
		(end 96.30664 -35.4076)
		(stroke
			(width 0.2)
			(type default)
		)
		(layer "In4.Cu")
	)
	(gr_line
		(start 97.182686 -35.404552)
		(end 97.192084 -36.204144)
		(stroke
			(width 0.2)
			(type default)
		)
		(layer "In4.Cu")
	)
	(gr_arc
		(start 97.192084 -36.204144)
		(mid 97.554415 -36.558219)
		(end 97.908364 -36.195762)
		(stroke
			(width 0.2)
			(type default)
		)
		(layer "In4.Cu")
	)
	(gr_arc
		(start 97.898966 -35.395916)
		(mid 97.536508 -35.042094)
		(end 97.182686 -35.404552)
		(stroke
			(width 0.2)
			(type default)
		)
		(layer "In4.Cu")
	)
	(gr_line
		(start 97.908364 -36.195762)
		(end 97.898966 -35.395916)
		(stroke
			(width 0.2)
			(type default)
		)
		(layer "In4.Cu")
	)
	(gr_line
		(start 97.983802 -35.405314)
		(end 97.992184 -36.203636)
		(stroke
			(width 0.2)
			(type default)
		)
		(layer "In4.Cu")
	)
	(gr_arc
		(start 97.992184 -36.203636)
		(mid 98.354007 -36.558219)
		(end 98.708464 -36.19627)
		(stroke
			(width 0.2)
			(type default)
		)
		(layer "In4.Cu")
	)
	(gr_arc
		(start 98.700082 -35.397694)
		(mid 98.338132 -35.043364)
		(end 97.983802 -35.405314)
		(stroke
			(width 0.2)
			(type default)
		)
		(layer "In4.Cu")
	)
	(gr_line
		(start 98.708464 -36.19627)
		(end 98.700082 -35.397694)
		(stroke
			(width 0.2)
			(type default)
		)
		(layer "In4.Cu")
	)
	(gr_arc
		(start 99.59213 -36.199318)
		(mid 99.949635 -36.55822)
		(end 100.30841 -36.200588)
		(stroke
			(width 0.2)
			(type default)
		)
		(layer "In4.Cu")
	)
	(gr_line
		(start 99.5934 -35.391852)
		(end 99.59213 -36.199318)
		(stroke
			(width 0.2)
			(type default)
		)
		(layer "In4.Cu")
	)
	(gr_line
		(start 100.30841 -36.200588)
		(end 100.30841 -36.20008)
		(stroke
			(width 0.2)
			(type default)
		)
		(layer "In4.Cu")
	)
	(gr_line
		(start 100.30841 -36.20008)
		(end 100.30968 -35.392868)
		(stroke
			(width 0.2)
			(type default)
		)
		(layer "In4.Cu")
	)
	(gr_arc
		(start 100.30968 -35.392868)
		(mid 99.952048 -35.03422)
		(end 99.5934 -35.391852)
		(stroke
			(width 0.2)
			(type default)
		)
		(layer "In4.Cu")
	)
	(gr_arc
		(start 100.39223 -36.196524)
		(mid 100.746941 -36.558221)
		(end 101.10851 -36.203382)
		(stroke
			(width 0.2)
			(type default)
		)
		(layer "In4.Cu")
	)
	(gr_line
		(start 100.399342 -35.394646)
		(end 100.39223 -36.196524)
		(stroke
			(width 0.2)
			(type default)
		)
		(layer "In4.Cu")
	)
	(gr_line
		(start 101.10851 -36.203382)
		(end 101.115622 -35.40125)
		(stroke
			(width 0.2)
			(type default)
		)
		(layer "In4.Cu")
	)
	(gr_arc
		(start 101.115622 -35.40125)
		(mid 100.760784 -35.039808)
		(end 100.399342 -35.394646)
		(stroke
			(width 0.2)
			(type default)
		)
		(layer "In4.Cu")
	)
	(gr_line
		(start 101.991922 -35.400234)
		(end 101.992176 -36.199826)
		(stroke
			(width 0.2)
			(type default)
		)
		(layer "In4.Cu")
	)
	(gr_arc
		(start 101.992176 -36.199826)
		(mid 102.350316 -36.55822)
		(end 102.708456 -36.199826)
		(stroke
			(width 0.2)
			(type default)
		)
		(layer "In4.Cu")
	)
	(gr_circle
		(center 102.350062 -5.999988)
		(end 103.025702 -5.999988)
		(stroke
			(width 0.2)
			(type default)
		)
		(fill no)
		(layer "In4.Cu")
	)
	(gr_line
		(start 102.708202 -35.75812)
		(end 102.708202 -35.39998)
		(stroke
			(width 0.2)
			(type default)
		)
		(layer "In4.Cu")
	)
	(gr_arc
		(start 102.708202 -35.39998)
		(mid 102.349935 -35.04184)
		(end 101.991922 -35.400234)
		(stroke
			(width 0.2)
			(type default)
		)
		(layer "In4.Cu")
	)
	(gr_line
		(start 102.708456 -36.199826)
		(end 102.708202 -35.75812)
		(stroke
			(width 0.2)
			(type default)
		)
		(layer "In4.Cu")
	)
	(gr_arc
		(start 102.792022 -36.199826)
		(mid 103.150035 -36.55822)
		(end 103.508302 -36.20008)
		(stroke
			(width 0.2)
			(type default)
		)
		(layer "In4.Cu")
	)
	(gr_line
		(start 102.792022 -35.400234)
		(end 102.792022 -36.199826)
		(stroke
			(width 0.2)
			(type default)
		)
		(layer "In4.Cu")
	)
	(gr_line
		(start 103.508302 -36.20008)
		(end 103.508302 -35.400234)
		(stroke
			(width 0.2)
			(type default)
		)
		(layer "In4.Cu")
	)
	(gr_arc
		(start 103.508302 -35.400234)
		(mid 103.150162 -35.042094)
		(end 102.792022 -35.400234)
		(stroke
			(width 0.2)
			(type default)
		)
		(layer "In4.Cu")
	)
	(gr_line
		(start 104.013 -37.973)
		(end 95.885 -37.973)
		(stroke
			(width 0.381)
			(type default)
		)
		(layer "In4.Cu")
	)
	(gr_line
		(start 104.013 -37.973)
		(end 105.029 -37.973)
		(stroke
			(width 0.381)
			(type default)
		)
		(layer "In4.Cu")
	)
	(gr_line
		(start 104.521 -37.973)
		(end 104.521 -37.465)
		(stroke
			(width 0.381)
			(type default)
		)
		(layer "In4.Cu")
	)
	(gr_line
		(start 104.521 -37.465)
		(end 104.013 -37.973)
		(stroke
			(width 0.381)
			(type default)
		)
		(layer "In4.Cu")
	)
	(gr_line
		(start 104.521 -37.465)
		(end 113.157 -46.101)
		(stroke
			(width 0.381)
			(type default)
		)
		(layer "In4.Cu")
	)
	(gr_line
		(start 104.521 -35.433)
		(end 104.521 -37.465)
		(stroke
			(width 0.381)
			(type default)
		)
		(layer "In4.Cu")
	)
	(gr_circle
		(center 104.950006 -5.999988)
		(end 105.625646 -5.999988)
		(stroke
			(width 0.2)
			(type default)
		)
		(fill no)
		(layer "In4.Cu")
	)
	(gr_line
		(start 105.156 -73.025)
		(end 106.172 -74.041)
		(stroke
			(width 0.381)
			(type default)
		)
		(layer "In4.Cu")
	)
	(gr_line
		(start 105.791 -116.332)
		(end 69.342 -152.781)
		(stroke
			(width 0.381)
			(type default)
		)
		(layer "In4.Cu")
	)
	(gr_line
		(start 105.791 -102.616)
		(end 105.791 -116.332)
		(stroke
			(width 0.381)
			(type default)
		)
		(layer "In4.Cu")
	)
	(gr_line
		(start 106.172 -74.041)
		(end 115.57 -74.041)
		(stroke
			(width 0.381)
			(type default)
		)
		(layer "In4.Cu")
	)
	(gr_arc
		(start 106.491532 -103.850186)
		(mid 106.849672 -104.208326)
		(end 107.207812 -103.850186)
		(stroke
			(width 0.2)
			(type default)
		)
		(layer "In4.Cu")
	)
	(gr_line
		(start 106.491532 -102.850188)
		(end 106.491532 -103.850186)
		(stroke
			(width 0.2)
			(type default)
		)
		(layer "In4.Cu")
	)
	(gr_line
		(start 107.207812 -103.850186)
		(end 107.207812 -102.850442)
		(stroke
			(width 0.2)
			(type default)
		)
		(layer "In4.Cu")
	)
	(gr_arc
		(start 107.207812 -102.850442)
		(mid 106.849799 -102.492048)
		(end 106.491532 -102.850188)
		(stroke
			(width 0.2)
			(type default)
		)
		(layer "In4.Cu")
	)
	(gr_line
		(start 107.315 -16.764)
		(end 139.446 -16.764)
		(stroke
			(width 0.381)
			(type default)
		)
		(layer "In4.Cu")
	)
	(gr_arc
		(start 107.49153 -103.850186)
		(mid 107.84967 -104.208326)
		(end 108.20781 -103.850186)
		(stroke
			(width 0.2)
			(type default)
		)
		(layer "In4.Cu")
	)
	(gr_line
		(start 107.49153 -102.850188)
		(end 107.49153 -103.850186)
		(stroke
			(width 0.2)
			(type default)
		)
		(layer "In4.Cu")
	)
	(gr_circle
		(center 107.54995 -5.999988)
		(end 108.22559 -5.999988)
		(stroke
			(width 0.2)
			(type default)
		)
		(fill no)
		(layer "In4.Cu")
	)
	(gr_line
		(start 108.20781 -103.850186)
		(end 108.20781 -102.850442)
		(stroke
			(width 0.2)
			(type default)
		)
		(layer "In4.Cu")
	)
	(gr_arc
		(start 108.20781 -102.850442)
		(mid 107.849797 -102.492048)
		(end 107.49153 -102.850188)
		(stroke
			(width 0.2)
			(type default)
		)
		(layer "In4.Cu")
	)
	(gr_arc
		(start 108.491528 -103.849932)
		(mid 108.849541 -104.208326)
		(end 109.207808 -103.850186)
		(stroke
			(width 0.2)
			(type default)
		)
		(layer "In4.Cu")
	)
	(gr_line
		(start 108.491528 -102.850188)
		(end 108.491528 -103.849932)
		(stroke
			(width 0.2)
			(type default)
		)
		(layer "In4.Cu")
	)
	(gr_line
		(start 109.207808 -103.850186)
		(end 109.207808 -102.850188)
		(stroke
			(width 0.2)
			(type default)
		)
		(layer "In4.Cu")
	)
	(gr_arc
		(start 109.207808 -102.850188)
		(mid 108.849668 -102.492048)
		(end 108.491528 -102.850188)
		(stroke
			(width 0.2)
			(type default)
		)
		(layer "In4.Cu")
	)
	(gr_arc
		(start 109.491526 -103.849932)
		(mid 109.849539 -104.208326)
		(end 110.207806 -103.850186)
		(stroke
			(width 0.2)
			(type default)
		)
		(layer "In4.Cu")
	)
	(gr_line
		(start 109.491526 -102.850188)
		(end 109.491526 -103.849932)
		(stroke
			(width 0.2)
			(type default)
		)
		(layer "In4.Cu")
	)
	(gr_line
		(start 110.207806 -103.850186)
		(end 110.207806 -102.850188)
		(stroke
			(width 0.2)
			(type default)
		)
		(layer "In4.Cu")
	)
	(gr_arc
		(start 110.207806 -102.850188)
		(mid 109.849666 -102.492048)
		(end 109.491526 -102.850188)
		(stroke
			(width 0.2)
			(type default)
		)
		(layer "In4.Cu")
	)
	(gr_line
		(start 110.49 -97.917)
		(end 105.791 -102.616)
		(stroke
			(width 0.381)
			(type default)
		)
		(layer "In4.Cu")
	)
	(gr_line
		(start 110.49 -91.059)
		(end 110.49 -97.917)
		(stroke
			(width 0.381)
			(type default)
		)
		(layer "In4.Cu")
	)
	(gr_arc
		(start 110.491524 -103.850186)
		(mid 110.849664 -104.208326)
		(end 111.207804 -103.850186)
		(stroke
			(width 0.2)
			(type default)
		)
		(layer "In4.Cu")
	)
	(gr_line
		(start 110.491524 -102.850188)
		(end 110.491524 -103.850186)
		(stroke
			(width 0.2)
			(type default)
		)
		(layer "In4.Cu")
	)
	(gr_line
		(start 110.617 -29.337)
		(end 104.521 -35.433)
		(stroke
			(width 0.381)
			(type default)
		)
		(layer "In4.Cu")
	)
	(gr_line
		(start 111.207804 -103.850186)
		(end 111.207804 -102.850442)
		(stroke
			(width 0.2)
			(type default)
		)
		(layer "In4.Cu")
	)
	(gr_arc
		(start 111.207804 -102.850442)
		(mid 110.849791 -102.492048)
		(end 110.491524 -102.850188)
		(stroke
			(width 0.2)
			(type default)
		)
		(layer "In4.Cu")
	)
	(gr_arc
		(start 111.491522 -103.849932)
		(mid 111.849535 -104.208326)
		(end 112.207802 -103.850186)
		(stroke
			(width 0.2)
			(type default)
		)
		(layer "In4.Cu")
	)
	(gr_line
		(start 111.491522 -102.850188)
		(end 111.491522 -103.849932)
		(stroke
			(width 0.2)
			(type default)
		)
		(layer "In4.Cu")
	)
	(gr_line
		(start 112.207802 -103.850186)
		(end 112.207802 -102.850188)
		(stroke
			(width 0.2)
			(type default)
		)
		(layer "In4.Cu")
	)
	(gr_arc
		(start 112.207802 -102.850188)
		(mid 111.849662 -102.492048)
		(end 111.491522 -102.850188)
		(stroke
			(width 0.2)
			(type default)
		)
		(layer "In4.Cu")
	)
	(gr_arc
		(start 112.49152 -103.850186)
		(mid 112.84966 -104.208326)
		(end 113.2078 -103.850186)
		(stroke
			(width 0.2)
			(type default)
		)
		(layer "In4.Cu")
	)
	(gr_line
		(start 112.49152 -102.850188)
		(end 112.49152 -103.850186)
		(stroke
			(width 0.2)
			(type default)
		)
		(layer "In4.Cu")
	)
	(gr_line
		(start 112.776 -88.773)
		(end 110.49 -91.059)
		(stroke
			(width 0.381)
			(type default)
		)
		(layer "In4.Cu")
	)
	(gr_line
		(start 113.157 -46.101)
		(end 113.665 -46.101)
		(stroke
			(width 0.381)
			(type default)
		)
		(layer "In4.Cu")
	)
	(gr_line
		(start 113.2078 -103.850186)
		(end 113.2078 -102.850442)
		(stroke
			(width 0.2)
			(type default)
		)
		(layer "In4.Cu")
	)
	(gr_arc
		(start 113.2078 -102.850442)
		(mid 112.849787 -102.492048)
		(end 112.49152 -102.850188)
		(stroke
			(width 0.2)
			(type default)
		)
		(layer "In4.Cu")
	)
	(gr_arc
		(start 113.491518 -103.849932)
		(mid 113.849531 -104.208326)
		(end 114.207798 -103.850186)
		(stroke
			(width 0.2)
			(type default)
		)
		(layer "In4.Cu")
	)
	(gr_line
		(start 113.491518 -102.850188)
		(end 113.491518 -103.849932)
		(stroke
			(width 0.2)
			(type default)
		)
		(layer "In4.Cu")
	)
	(gr_line
		(start 113.665 -46.101)
		(end 119.634 -46.101)
		(stroke
			(width 0.381)
			(type default)
		)
		(layer "In4.Cu")
	)
	(gr_line
		(start 114.207798 -103.850186)
		(end 114.207798 -102.850188)
		(stroke
			(width 0.2)
			(type default)
		)
		(layer "In4.Cu")
	)
	(gr_arc
		(start 114.207798 -102.850188)
		(mid 113.849658 -102.492048)
		(end 113.491518 -102.850188)
		(stroke
			(width 0.2)
			(type default)
		)
		(layer "In4.Cu")
	)
	(gr_arc
		(start 114.506502 -103.830882)
		(mid 114.864642 -104.189022)
		(end 115.222782 -103.830882)
		(stroke
			(width 0.2)
			(type default)
		)
		(layer "In4.Cu")
	)
	(gr_line
		(start 114.506502 -102.840282)
		(end 114.506502 -103.830882)
		(stroke
			(width 0.2)
			(type default)
		)
		(layer "In4.Cu")
	)
	(gr_line
		(start 115.222782 -103.830882)
		(end 115.222782 -102.840536)
		(stroke
			(width 0.2)
			(type default)
		)
		(layer "In4.Cu")
	)
	(gr_arc
		(start 115.222782 -102.840536)
		(mid 114.864769 -102.482142)
		(end 114.506502 -102.840282)
		(stroke
			(width 0.2)
			(type default)
		)
		(layer "In4.Cu")
	)
	(gr_arc
		(start 115.522502 -103.830882)
		(mid 115.880642 -104.189022)
		(end 116.238782 -103.830882)
		(stroke
			(width 0.2)
			(type default)
		)
		(layer "In4.Cu")
	)
	(gr_line
		(start 115.522502 -102.840282)
		(end 115.522502 -103.830882)
		(stroke
			(width 0.2)
			(type default)
		)
		(layer "In4.Cu")
	)
	(gr_line
		(start 115.57 -74.041)
		(end 120.015 -78.486)
		(stroke
			(width 0.381)
			(type default)
		)
		(layer "In4.Cu")
	)
	(gr_line
		(start 116.238782 -103.830882)
		(end 116.238782 -102.840536)
		(stroke
			(width 0.2)
			(type default)
		)
		(layer "In4.Cu")
	)
	(gr_arc
		(start 116.238782 -102.840536)
		(mid 115.880769 -102.482142)
		(end 115.522502 -102.840282)
		(stroke
			(width 0.2)
			(type default)
		)
		(layer "In4.Cu")
	)
	(gr_arc
		(start 117.492018 -103.849932)
		(mid 117.850031 -104.208326)
		(end 118.208298 -103.850186)
		(stroke
			(width 0.2)
			(type default)
		)
		(layer "In4.Cu")
	)
	(gr_line
		(start 117.492018 -102.850188)
		(end 117.492018 -103.849932)
		(stroke
			(width 0.2)
			(type default)
		)
		(layer "In4.Cu")
	)
	(gr_line
		(start 118.208298 -103.850186)
		(end 118.208298 -102.850188)
		(stroke
			(width 0.2)
			(type default)
		)
		(layer "In4.Cu")
	)
	(gr_arc
		(start 118.208298 -102.850188)
		(mid 117.850158 -102.492048)
		(end 117.492018 -102.850188)
		(stroke
			(width 0.2)
			(type default)
		)
		(layer "In4.Cu")
	)
	(gr_arc
		(start 118.492016 -103.849932)
		(mid 118.850029 -104.208326)
		(end 119.208296 -103.850186)
		(stroke
			(width 0.2)
			(type default)
		)
		(layer "In4.Cu")
	)
	(gr_line
		(start 118.492016 -102.850188)
		(end 118.492016 -103.849932)
		(stroke
			(width 0.2)
			(type default)
		)
		(layer "In4.Cu")
	)
	(gr_line
		(start 118.618 -88.773)
		(end 112.776 -88.773)
		(stroke
			(width 0.381)
			(type default)
		)
		(layer "In4.Cu")
	)
	(gr_line
		(start 119.208296 -103.850186)
		(end 119.208296 -102.850188)
		(stroke
			(width 0.2)
			(type default)
		)
		(layer "In4.Cu")
	)
	(gr_arc
		(start 119.208296 -102.850188)
		(mid 118.850156 -102.492048)
		(end 118.492016 -102.850188)
		(stroke
			(width 0.2)
			(type default)
		)
		(layer "In4.Cu")
	)
	(gr_line
		(start 119.634 -46.101)
		(end 123.19 -42.545)
		(stroke
			(width 0.381)
			(type default)
		)
		(layer "In4.Cu")
	)
	(gr_line
		(start 120.015 -87.376)
		(end 118.618 -88.773)
		(stroke
			(width 0.381)
			(type default)
		)
		(layer "In4.Cu")
	)
	(gr_line
		(start 120.015 -78.486)
		(end 120.015 -87.376)
		(stroke
			(width 0.381)
			(type default)
		)
		(layer "In4.Cu")
	)
	(gr_line
		(start 121.666 -29.337)
		(end 110.617 -29.337)
		(stroke
			(width 0.381)
			(type default)
		)
		(layer "In4.Cu")
	)
	(gr_line
		(start 122.492008 -91.849956)
		(end 122.492262 -92.827348)
		(stroke
			(width 0.2)
			(type default)
		)
		(layer "In4.Cu")
	)
	(gr_arc
		(start 122.492262 -92.827348)
		(mid 122.850402 -93.185742)
		(end 123.208542 -92.827348)
		(stroke
			(width 0.2)
			(type default)
		)
		(layer "In4.Cu")
	)
	(gr_arc
		(start 122.829574 -84.492084)
		(mid 122.492516 -84.87029)
		(end 122.870722 -85.207348)
		(stroke
			(width 0.2)
			(type default)
		)
		(layer "In4.Cu")
	)
	(gr_line
		(start 122.848116 -94.186502)
		(end 123.843542 -94.206822)
		(stroke
			(width 0.2)
			(type default)
		)
		(layer "In4.Cu")
	)
	(gr_line
		(start 122.850148 -91.207844)
		(end 123.850146 -91.207844)
		(stroke
			(width 0.2)
			(type default)
		)
		(layer "In4.Cu")
	)
	(gr_line
		(start 122.850148 -90.207846)
		(end 123.850146 -90.207846)
		(stroke
			(width 0.2)
			(type default)
		)
		(layer "In4.Cu")
	)
	(gr_line
		(start 122.850148 -84.207858)
		(end 123.849892 -84.207858)
		(stroke
			(width 0.2)
			(type default)
		)
		(layer "In4.Cu")
	)
	(gr_arc
		(start 122.850148 -83.491578)
		(mid 122.492008 -83.849718)
		(end 122.850148 -84.207858)
		(stroke
			(width 0.2)
			(type default)
		)
		(layer "In4.Cu")
	)
	(gr_line
		(start 122.850148 -83.20786)
		(end 123.850146 -83.20786)
		(stroke
			(width 0.2)
			(type default)
		)
		(layer "In4.Cu")
	)
	(gr_arc
		(start 122.850402 -90.491564)
		(mid 122.492008 -90.849577)
		(end 122.850148 -91.207844)
		(stroke
			(width 0.2)
			(type default)
		)
		(layer "In4.Cu")
	)
	(gr_arc
		(start 122.850402 -89.491566)
		(mid 122.492008 -89.849579)
		(end 122.850148 -90.207846)
		(stroke
			(width 0.2)
			(type default)
		)
		(layer "In4.Cu")
	)
	(gr_arc
		(start 122.850402 -82.49158)
		(mid 122.492008 -82.849593)
		(end 122.850148 -83.20786)
		(stroke
			(width 0.2)
			(type default)
		)
		(layer "In4.Cu")
	)
	(gr_arc
		(start 122.862848 -93.470222)
		(mid 122.497342 -93.820996)
		(end 122.848116 -94.186502)
		(stroke
			(width 0.2)
			(type default)
		)
		(layer "In4.Cu")
	)
	(gr_line
		(start 122.870722 -85.207348)
		(end 123.84532 -85.151214)
		(stroke
			(width 0.2)
			(type default)
		)
		(layer "In4.Cu")
	)
	(gr_line
		(start 122.924062 -81.28254)
		(end 123.831858 -81.308956)
		(stroke
			(width 0.2)
			(type default)
		)
		(layer "In4.Cu")
	)
	(gr_arc
		(start 122.92457 -81.430114)
		(mid 122.578114 -81.79943)
		(end 122.94743 -82.145886)
		(stroke
			(width 0.2)
			(type default)
		)
		(layer "In4.Cu")
	)
	(gr_line
		(start 122.92457 -81.427828)
		(end 122.92457 -81.430114)
		(stroke
			(width 0.2)
			(type default)
		)
		(layer "In4.Cu")
	)
	(gr_line
		(start 122.924824 -81.427574)
		(end 122.92457 -81.427828)
		(stroke
			(width 0.2)
			(type default)
		)
		(layer "In4.Cu")
	)
	(gr_arc
		(start 122.925332 -80.56626)
		(mid 122.566684 -80.923765)
		(end 122.924062 -81.28254)
		(stroke
			(width 0.2)
			(type default)
		)
		(layer "In4.Cu")
	)
	(gr_line
		(start 122.94743 -82.148426)
		(end 123.7488 -82.123026)
		(stroke
			(width 0.2)
			(type default)
		)
		(layer "In4.Cu")
	)
	(gr_line
		(start 122.94743 -82.145886)
		(end 122.94743 -82.148426)
		(stroke
			(width 0.2)
			(type default)
		)
		(layer "In4.Cu")
	)
	(gr_line
		(start 123.19 -42.545)
		(end 123.19 -29.337)
		(stroke
			(width 0.381)
			(type default)
		)
		(layer "In4.Cu")
	)
	(gr_line
		(start 123.19 -29.972)
		(end 122.555 -29.337)
		(stroke
			(width 0.381)
			(type default)
		)
		(layer "In4.Cu")
	)
	(gr_line
		(start 123.19 -29.972)
		(end 123.825 -29.337)
		(stroke
			(width 0.381)
			(type default)
		)
		(layer "In4.Cu")
	)
	(gr_line
		(start 123.208288 -91.849956)
		(end 123.208288 -91.849702)
		(stroke
			(width 0.2)
			(type default)
		)
		(layer "In4.Cu")
	)
	(gr_arc
		(start 123.208288 -91.849702)
		(mid 122.850021 -91.491562)
		(end 122.492008 -91.849956)
		(stroke
			(width 0.2)
			(type default)
		)
		(layer "In4.Cu")
	)
	(gr_line
		(start 123.208542 -92.827348)
		(end 123.208288 -91.849956)
		(stroke
			(width 0.2)
			(type default)
		)
		(layer "In4.Cu")
	)
	(gr_line
		(start 123.72594 -81.404714)
		(end 123.72594 -81.402174)
		(stroke
			(width 0.2)
			(type default)
		)
		(layer "In4.Cu")
	)
	(gr_line
		(start 123.72594 -81.402174)
		(end 122.924824 -81.427574)
		(stroke
			(width 0.2)
			(type default)
		)
		(layer "In4.Cu")
	)
	(gr_line
		(start 123.7488 -82.123026)
		(end 123.7488 -82.12074)
		(stroke
			(width 0.2)
			(type default)
		)
		(layer "In4.Cu")
	)
	(gr_line
		(start 123.7488 -82.12074)
		(end 123.7488 -82.120486)
		(stroke
			(width 0.2)
			(type default)
		)
		(layer "In4.Cu")
	)
	(gr_arc
		(start 123.7488 -82.120486)
		(mid 124.095256 -81.75117)
		(end 123.72594 -81.404714)
		(stroke
			(width 0.2)
			(type default)
		)
		(layer "In4.Cu")
	)
	(gr_line
		(start 123.804426 -84.43595)
		(end 122.829574 -84.492084)
		(stroke
			(width 0.2)
			(type default)
		)
		(layer "In4.Cu")
	)
	(gr_arc
		(start 123.831858 -81.308956)
		(mid 123.842395 -81.309356)
		(end 123.85294 -81.309464)
		(stroke
			(width 0.2)
			(type default)
		)
		(layer "In4.Cu")
	)
	(gr_line
		(start 123.833128 -80.542892)
		(end 122.925332 -80.56626)
		(stroke
			(width 0.2)
			(type default)
		)
		(layer "In4.Cu")
	)
	(gr_arc
		(start 123.843542 -94.206822)
		(mid 124.209305 -93.856175)
		(end 123.858528 -93.490542)
		(stroke
			(width 0.2)
			(type default)
		)
		(layer "In4.Cu")
	)
	(gr_arc
		(start 123.84532 -85.151214)
		(mid 124.182625 -84.773135)
		(end 123.804426 -84.43595)
		(stroke
			(width 0.2)
			(type default)
		)
		(layer "In4.Cu")
	)
	(gr_arc
		(start 123.849892 -84.207858)
		(mid 124.208286 -83.849845)
		(end 123.850146 -83.491578)
		(stroke
			(width 0.2)
			(type default)
		)
		(layer "In4.Cu")
	)
	(gr_arc
		(start 123.850146 -91.207844)
		(mid 124.208286 -90.849704)
		(end 123.850146 -90.491564)
		(stroke
			(width 0.2)
			(type default)
		)
		(layer "In4.Cu")
	)
	(gr_line
		(start 123.850146 -90.491564)
		(end 122.850402 -90.491564)
		(stroke
			(width 0.2)
			(type default)
		)
		(layer "In4.Cu")
	)
	(gr_arc
		(start 123.850146 -90.207846)
		(mid 124.208286 -89.849706)
		(end 123.850146 -89.491566)
		(stroke
			(width 0.2)
			(type default)
		)
		(layer "In4.Cu")
	)
	(gr_line
		(start 123.850146 -89.491566)
		(end 122.850402 -89.491566)
		(stroke
			(width 0.2)
			(type default)
		)
		(layer "In4.Cu")
	)
	(gr_line
		(start 123.850146 -83.491578)
		(end 122.850148 -83.491578)
		(stroke
			(width 0.2)
			(type default)
		)
		(layer "In4.Cu")
	)
	(gr_arc
		(start 123.850146 -83.20786)
		(mid 124.208286 -82.84972)
		(end 123.850146 -82.49158)
		(stroke
			(width 0.2)
			(type default)
		)
		(layer "In4.Cu")
	)
	(gr_line
		(start 123.850146 -82.49158)
		(end 122.850402 -82.49158)
		(stroke
			(width 0.2)
			(type default)
		)
		(layer "In4.Cu")
	)
	(gr_arc
		(start 123.85294 -81.309464)
		(mid 124.236988 -80.926432)
		(end 123.853956 -80.542384)
		(stroke
			(width 0.2)
			(type default)
		)
		(layer "In4.Cu")
	)
	(gr_arc
		(start 123.853956 -80.542384)
		(mid 123.843539 -80.542498)
		(end 123.833128 -80.542892)
		(stroke
			(width 0.2)
			(type default)
		)
		(layer "In4.Cu")
	)
	(gr_line
		(start 123.858528 -93.490542)
		(end 122.862848 -93.470222)
		(stroke
			(width 0.2)
			(type default)
		)
		(layer "In4.Cu")
	)
	(gr_line
		(start 124.779278 -80.635348)
		(end 125.756162 -80.635348)
		(stroke
			(width 0.2)
			(type default)
		)
		(layer "In4.Cu")
	)
	(gr_arc
		(start 124.779532 -79.868268)
		(mid 124.395738 -80.251681)
		(end 124.779278 -80.635348)
		(stroke
			(width 0.2)
			(type default)
		)
		(layer "In4.Cu")
	)
	(gr_arc
		(start 125.756162 -80.635348)
		(mid 126.139702 -80.251808)
		(end 125.756162 -79.868268)
		(stroke
			(width 0.2)
			(type default)
		)
		(layer "In4.Cu")
	)
	(gr_line
		(start 125.756162 -79.868268)
		(end 124.779532 -79.868268)
		(stroke
			(width 0.2)
			(type default)
		)
		(layer "In4.Cu")
	)
	(gr_line
		(start 127.154178 -80.19034)
		(end 128.130808 -80.19034)
		(stroke
			(width 0.2)
			(type default)
		)
		(layer "In4.Cu")
	)
	(gr_arc
		(start 127.154178 -79.42326)
		(mid 126.770638 -79.8068)
		(end 127.154178 -80.19034)
		(stroke
			(width 0.2)
			(type default)
		)
		(layer "In4.Cu")
	)
	(gr_arc
		(start 128.130808 -80.19034)
		(mid 128.514602 -79.806927)
		(end 128.131062 -79.42326)
		(stroke
			(width 0.2)
			(type default)
		)
		(layer "In4.Cu")
	)
	(gr_line
		(start 128.131062 -79.42326)
		(end 127.154178 -79.42326)
		(stroke
			(width 0.2)
			(type default)
		)
		(layer "In4.Cu")
	)
	(gr_line
		(start 129.159 -81.66354)
		(end 130.047746 -81.66354)
		(stroke
			(width 0.2)
			(type default)
		)
		(layer "In4.Cu")
	)
	(gr_arc
		(start 129.159 -80.89646)
		(mid 128.77546 -81.28)
		(end 129.159 -81.66354)
		(stroke
			(width 0.2)
			(type default)
		)
		(layer "In4.Cu")
	)
	(gr_arc
		(start 130.047746 -81.66354)
		(mid 130.43154 -81.280127)
		(end 130.048 -80.89646)
		(stroke
			(width 0.2)
			(type default)
		)
		(layer "In4.Cu")
	)
	(gr_line
		(start 130.048 -80.89646)
		(end 129.159 -80.89646)
		(stroke
			(width 0.2)
			(type default)
		)
		(layer "In4.Cu")
	)
	(gr_line
		(start 131.02844 -80.13954)
		(end 132.00507 -80.13954)
		(stroke
			(width 0.2)
			(type default)
		)
		(layer "In4.Cu")
	)
	(gr_arc
		(start 131.02844 -79.37246)
		(mid 130.6449 -79.756)
		(end 131.02844 -80.13954)
		(stroke
			(width 0.2)
			(type default)
		)
		(layer "In4.Cu")
	)
	(gr_arc
		(start 131.82346 -92.075)
		(mid 132.207 -92.45854)
		(end 132.59054 -92.075)
		(stroke
			(width 0.2)
			(type default)
		)
		(layer "In4.Cu")
	)
	(gr_line
		(start 131.82346 -91.169998)
		(end 131.82346 -92.075)
		(stroke
			(width 0.2)
			(type default)
		)
		(layer "In4.Cu")
	)
	(gr_arc
		(start 131.82346 -89.281)
		(mid 132.207 -89.66454)
		(end 132.59054 -89.281)
		(stroke
			(width 0.2)
			(type default)
		)
		(layer "In4.Cu")
	)
	(gr_line
		(start 131.82346 -88.375998)
		(end 131.82346 -89.281)
		(stroke
			(width 0.2)
			(type default)
		)
		(layer "In4.Cu")
	)
	(gr_arc
		(start 132.00507 -80.13954)
		(mid 132.388864 -79.756127)
		(end 132.005324 -79.37246)
		(stroke
			(width 0.2)
			(type default)
		)
		(layer "In4.Cu")
	)
	(gr_line
		(start 132.005324 -79.37246)
		(end 131.02844 -79.37246)
		(stroke
			(width 0.2)
			(type default)
		)
		(layer "In4.Cu")
	)
	(gr_line
		(start 132.59054 -92.075)
		(end 132.59054 -91.170252)
		(stroke
			(width 0.2)
			(type default)
		)
		(layer "In4.Cu")
	)
	(gr_arc
		(start 132.59054 -91.170252)
		(mid 132.207127 -90.786458)
		(end 131.82346 -91.169998)
		(stroke
			(width 0.2)
			(type default)
		)
		(layer "In4.Cu")
	)
	(gr_line
		(start 132.59054 -89.281)
		(end 132.59054 -88.376252)
		(stroke
			(width 0.2)
			(type default)
		)
		(layer "In4.Cu")
	)
	(gr_arc
		(start 132.59054 -88.376252)
		(mid 132.207127 -87.992458)
		(end 131.82346 -88.375998)
		(stroke
			(width 0.2)
			(type default)
		)
		(layer "In4.Cu")
	)
	(gr_line
		(start 132.930392 -81.500726)
		(end 133.858254 -81.500726)
		(stroke
			(width 0.2)
			(type default)
		)
		(layer "In4.Cu")
	)
	(gr_arc
		(start 132.930392 -80.733646)
		(mid 132.546852 -81.117186)
		(end 132.930392 -81.500726)
		(stroke
			(width 0.2)
			(type default)
		)
		(layer "In4.Cu")
	)
	(gr_arc
		(start 133.34746 -90.558874)
		(mid 133.730873 -90.942668)
		(end 134.11454 -90.559128)
		(stroke
			(width 0.2)
			(type default)
		)
		(layer "In4.Cu")
	)
	(gr_line
		(start 133.34746 -89.654126)
		(end 133.34746 -90.558874)
		(stroke
			(width 0.2)
			(type default)
		)
		(layer "In4.Cu")
	)
	(gr_arc
		(start 133.34746 -88.019128)
		(mid 133.731 -88.402668)
		(end 134.11454 -88.019128)
		(stroke
			(width 0.2)
			(type default)
		)
		(layer "In4.Cu")
	)
	(gr_line
		(start 133.34746 -87.114126)
		(end 133.34746 -88.019128)
		(stroke
			(width 0.2)
			(type default)
		)
		(layer "In4.Cu")
	)
	(gr_arc
		(start 133.858254 -81.500726)
		(mid 134.242048 -81.117313)
		(end 133.858508 -80.733646)
		(stroke
			(width 0.2)
			(type default)
		)
		(layer "In4.Cu")
	)
	(gr_line
		(start 133.858508 -80.733646)
		(end 132.930392 -80.733646)
		(stroke
			(width 0.2)
			(type default)
		)
		(layer "In4.Cu")
	)
	(gr_line
		(start 134.11454 -90.559128)
		(end 134.11454 -89.654126)
		(stroke
			(width 0.2)
			(type default)
		)
		(layer "In4.Cu")
	)
	(gr_arc
		(start 134.11454 -89.654126)
		(mid 133.731 -89.270586)
		(end 133.34746 -89.654126)
		(stroke
			(width 0.2)
			(type default)
		)
		(layer "In4.Cu")
	)
	(gr_line
		(start 134.11454 -88.019128)
		(end 134.11454 -87.11438)
		(stroke
			(width 0.2)
			(type default)
		)
		(layer "In4.Cu")
	)
	(gr_arc
		(start 134.11454 -87.11438)
		(mid 133.731127 -86.730586)
		(end 133.34746 -87.114126)
		(stroke
			(width 0.2)
			(type default)
		)
		(layer "In4.Cu")
	)
	(gr_line
		(start 134.581392 -83.06054)
		(end 135.509508 -83.06054)
		(stroke
			(width 0.2)
			(type default)
		)
		(layer "In4.Cu")
	)
	(gr_arc
		(start 134.581646 -82.29346)
		(mid 134.197852 -82.676873)
		(end 134.581392 -83.06054)
		(stroke
			(width 0.2)
			(type default)
		)
		(layer "In4.Cu")
	)
	(gr_arc
		(start 135.509508 -83.06054)
		(mid 135.893048 -82.677)
		(end 135.509508 -82.29346)
		(stroke
			(width 0.2)
			(type default)
		)
		(layer "In4.Cu")
	)
	(gr_line
		(start 135.509508 -82.29346)
		(end 134.581646 -82.29346)
		(stroke
			(width 0.2)
			(type default)
		)
		(layer "In4.Cu")
	)
	(gr_line
		(start 135.87984 -81.91754)
		(end 136.807956 -81.91754)
		(stroke
			(width 0.2)
			(type default)
		)
		(layer "In4.Cu")
	)
	(gr_arc
		(start 135.880094 -81.15046)
		(mid 135.4963 -81.533873)
		(end 135.87984 -81.91754)
		(stroke
			(width 0.2)
			(type default)
		)
		(layer "In4.Cu")
	)
	(gr_line
		(start 136.017 -29.337)
		(end 121.666 -29.337)
		(stroke
			(width 0.381)
			(type default)
		)
		(layer "In4.Cu")
	)
	(gr_arc
		(start 136.807956 -81.91754)
		(mid 137.191496 -81.534)
		(end 136.807956 -81.15046)
		(stroke
			(width 0.2)
			(type default)
		)
		(layer "In4.Cu")
	)
	(gr_line
		(start 136.807956 -81.15046)
		(end 135.880094 -81.15046)
		(stroke
			(width 0.2)
			(type default)
		)
		(layer "In4.Cu")
	)
	(gr_line
		(start 138.549888 -258.59994)
		(end 67.349878 -258.59994)
		(stroke
			(width 5.08)
			(type default)
		)
		(layer "In4.Cu")
	)
	(gr_line
		(start 138.549888 -252.549914)
		(end 138.549888 -258.59994)
		(stroke
			(width 1.524)
			(type default)
		)
		(layer "In4.Cu")
	)
	(gr_line
		(start 139.446 -16.764)
		(end 175.895 -53.213)
		(stroke
			(width 0.381)
			(type default)
		)
		(layer "In4.Cu")
	)
	(gr_line
		(start 140.450062 -258.59994)
		(end 140.450062 -252.549914)
		(stroke
			(width 1.524)
			(type default)
		)
		(layer "In4.Cu")
	)
	(gr_arc
		(start 140.450062 -252.549914)
		(mid 139.500102 -251.599954)
		(end 138.549888 -252.549914)
		(stroke
			(width 1.524)
			(type default)
		)
		(layer "In4.Cu")
	)
	(gr_line
		(start 151.649938 -258.59994)
		(end 140.450062 -258.59994)
		(stroke
			(width 5.08)
			(type default)
		)
		(layer "In4.Cu")
	)
	(gr_line
		(start 151.649938 -252.000004)
		(end 151.649938 -258.59994)
		(stroke
			(width 1.524)
			(type default)
		)
		(layer "In4.Cu")
	)
	(gr_arc
		(start 152.649936 -251.000006)
		(mid 151.942831 -251.292899)
		(end 151.649938 -252.000004)
		(stroke
			(width 1.524)
			(type default)
		)
		(layer "In4.Cu")
	)
	(gr_line
		(start 155.946348 -77.40904)
		(end 156.928312 -77.40904)
		(stroke
			(width 0.2)
			(type default)
		)
		(layer "In4.Cu")
	)
	(gr_arc
		(start 155.946602 -76.64196)
		(mid 155.562808 -77.025373)
		(end 155.946348 -77.40904)
		(stroke
			(width 0.2)
			(type default)
		)
		(layer "In4.Cu")
	)
	(gr_arc
		(start 156.928312 -77.40904)
		(mid 157.311852 -77.0255)
		(end 156.928312 -76.64196)
		(stroke
			(width 0.2)
			(type default)
		)
		(layer "In4.Cu")
	)
	(gr_line
		(start 156.928312 -76.64196)
		(end 155.946602 -76.64196)
		(stroke
			(width 0.2)
			(type default)
		)
		(layer "In4.Cu")
	)
	(gr_line
		(start 159.946848 -77.40904)
		(end 160.928812 -77.40904)
		(stroke
			(width 0.2)
			(type default)
		)
		(layer "In4.Cu")
	)
	(gr_arc
		(start 159.947102 -76.64196)
		(mid 159.563308 -77.025373)
		(end 159.946848 -77.40904)
		(stroke
			(width 0.2)
			(type default)
		)
		(layer "In4.Cu")
	)
	(gr_arc
		(start 160.928812 -77.40904)
		(mid 161.312352 -77.0255)
		(end 160.928812 -76.64196)
		(stroke
			(width 0.2)
			(type default)
		)
		(layer "In4.Cu")
	)
	(gr_line
		(start 160.928812 -76.64196)
		(end 159.947102 -76.64196)
		(stroke
			(width 0.2)
			(type default)
		)
		(layer "In4.Cu")
	)
	(gr_line
		(start 163.946078 -77.40904)
		(end 164.928042 -77.40904)
		(stroke
			(width 0.2)
			(type default)
		)
		(layer "In4.Cu")
	)
	(gr_arc
		(start 163.946332 -76.64196)
		(mid 163.562538 -77.025373)
		(end 163.946078 -77.40904)
		(stroke
			(width 0.2)
			(type default)
		)
		(layer "In4.Cu")
	)
	(gr_arc
		(start 164.928042 -77.40904)
		(mid 165.311582 -77.0255)
		(end 164.928042 -76.64196)
		(stroke
			(width 0.2)
			(type default)
		)
		(layer "In4.Cu")
	)
	(gr_line
		(start 164.928042 -76.64196)
		(end 163.946332 -76.64196)
		(stroke
			(width 0.2)
			(type default)
		)
		(layer "In4.Cu")
	)
	(gr_line
		(start 167.946578 -77.40904)
		(end 168.928542 -77.40904)
		(stroke
			(width 0.2)
			(type default)
		)
		(layer "In4.Cu")
	)
	(gr_arc
		(start 167.946832 -76.64196)
		(mid 167.563038 -77.025373)
		(end 167.946578 -77.40904)
		(stroke
			(width 0.2)
			(type default)
		)
		(layer "In4.Cu")
	)
	(gr_arc
		(start 168.928542 -77.40904)
		(mid 169.312082 -77.0255)
		(end 168.928542 -76.64196)
		(stroke
			(width 0.2)
			(type default)
		)
		(layer "In4.Cu")
	)
	(gr_line
		(start 168.928542 -76.64196)
		(end 167.946832 -76.64196)
		(stroke
			(width 0.2)
			(type default)
		)
		(layer "In4.Cu")
	)
	(gr_line
		(start 170.053 -63.246)
		(end 136.017 -29.337)
		(stroke
			(width 0.381)
			(type default)
		)
		(layer "In4.Cu")
	)
	(gr_line
		(start 175.895 -53.213)
		(end 240.665 -53.213)
		(stroke
			(width 0.381)
			(type default)
		)
		(layer "In4.Cu")
	)
	(gr_line
		(start 181.150006 -251.000006)
		(end 152.649936 -251.000006)
		(stroke
			(width 1.524)
			(type default)
		)
		(layer "In4.Cu")
	)
	(gr_line
		(start 182.150004 -258.59994)
		(end 182.150004 -252.000004)
		(stroke
			(width 1.524)
			(type default)
		)
		(layer "In4.Cu")
	)
	(gr_arc
		(start 182.150004 -252.000004)
		(mid 181.857111 -251.292899)
		(end 181.150006 -251.000006)
		(stroke
			(width 1.524)
			(type default)
		)
		(layer "In4.Cu")
	)
	(gr_line
		(start 189.349888 -258.59994)
		(end 182.150004 -258.59994)
		(stroke
			(width 5.08)
			(type default)
		)
		(layer "In4.Cu")
	)
	(gr_line
		(start 189.349888 -252.549914)
		(end 189.349888 -258.59994)
		(stroke
			(width 1.524)
			(type default)
		)
		(layer "In4.Cu")
	)
	(gr_line
		(start 191.250062 -258.59994)
		(end 191.250062 -252.549914)
		(stroke
			(width 1.524)
			(type default)
		)
		(layer "In4.Cu")
	)
	(gr_arc
		(start 191.250062 -252.549914)
		(mid 190.300102 -251.599954)
		(end 189.349888 -252.549914)
		(stroke
			(width 1.524)
			(type default)
		)
		(layer "In4.Cu")
	)
	(gr_line
		(start 191.947038 -77.40904)
		(end 192.928748 -77.40904)
		(stroke
			(width 0.2)
			(type default)
		)
		(layer "In4.Cu")
	)
	(gr_arc
		(start 191.947038 -76.64196)
		(mid 191.563498 -77.0255)
		(end 191.947038 -77.40904)
		(stroke
			(width 0.2)
			(type default)
		)
		(layer "In4.Cu")
	)
	(gr_arc
		(start 192.928748 -77.40904)
		(mid 193.312542 -77.025627)
		(end 192.929002 -76.64196)
		(stroke
			(width 0.2)
			(type default)
		)
		(layer "In4.Cu")
	)
	(gr_line
		(start 192.929002 -76.64196)
		(end 191.947038 -76.64196)
		(stroke
			(width 0.2)
			(type default)
		)
		(layer "In4.Cu")
	)
	(gr_line
		(start 195.947538 -77.40904)
		(end 196.929502 -77.40904)
		(stroke
			(width 0.2)
			(type default)
		)
		(layer "In4.Cu")
	)
	(gr_arc
		(start 195.947792 -76.64196)
		(mid 195.563998 -77.025373)
		(end 195.947538 -77.40904)
		(stroke
			(width 0.2)
			(type default)
		)
		(layer "In4.Cu")
	)
	(gr_arc
		(start 196.929502 -77.40904)
		(mid 197.313042 -77.0255)
		(end 196.929502 -76.64196)
		(stroke
			(width 0.2)
			(type default)
		)
		(layer "In4.Cu")
	)
	(gr_line
		(start 196.929502 -76.64196)
		(end 195.947792 -76.64196)
		(stroke
			(width 0.2)
			(type default)
		)
		(layer "In4.Cu")
	)
	(gr_line
		(start 199.946768 -77.40904)
		(end 200.928478 -77.40904)
		(stroke
			(width 0.2)
			(type default)
		)
		(layer "In4.Cu")
	)
	(gr_arc
		(start 199.946768 -76.64196)
		(mid 199.563228 -77.0255)
		(end 199.946768 -77.40904)
		(stroke
			(width 0.2)
			(type default)
		)
		(layer "In4.Cu")
	)
	(gr_arc
		(start 200.928478 -77.40904)
		(mid 201.312272 -77.025627)
		(end 200.928732 -76.64196)
		(stroke
			(width 0.2)
			(type default)
		)
		(layer "In4.Cu")
	)
	(gr_line
		(start 200.928732 -76.64196)
		(end 199.946768 -76.64196)
		(stroke
			(width 0.2)
			(type default)
		)
		(layer "In4.Cu")
	)
	(gr_line
		(start 202.449938 -258.59994)
		(end 191.250062 -258.59994)
		(stroke
			(width 5.08)
			(type default)
		)
		(layer "In4.Cu")
	)
	(gr_line
		(start 202.449938 -252.000004)
		(end 202.449938 -258.59994)
		(stroke
			(width 1.524)
			(type default)
		)
		(layer "In4.Cu")
	)
	(gr_arc
		(start 203.449936 -251.000006)
		(mid 202.742831 -251.292899)
		(end 202.449938 -252.000004)
		(stroke
			(width 1.524)
			(type default)
		)
		(layer "In4.Cu")
	)
	(gr_line
		(start 203.947268 -77.40904)
		(end 204.929232 -77.40904)
		(stroke
			(width 0.2)
			(type default)
		)
		(layer "In4.Cu")
	)
	(gr_arc
		(start 203.947522 -76.64196)
		(mid 203.563728 -77.025373)
		(end 203.947268 -77.40904)
		(stroke
			(width 0.2)
			(type default)
		)
		(layer "In4.Cu")
	)
	(gr_arc
		(start 204.929232 -77.40904)
		(mid 205.312772 -77.0255)
		(end 204.929232 -76.64196)
		(stroke
			(width 0.2)
			(type default)
		)
		(layer "In4.Cu")
	)
	(gr_line
		(start 204.929232 -76.64196)
		(end 203.947522 -76.64196)
		(stroke
			(width 0.2)
			(type default)
		)
		(layer "In4.Cu")
	)
	(gr_line
		(start 229.14991 -251.000006)
		(end 203.449936 -251.000006)
		(stroke
			(width 1.524)
			(type default)
		)
		(layer "In4.Cu")
	)
	(gr_arc
		(start 229.14991 -251.000006)
		(mid 232.685436 -249.53554)
		(end 234.1499 -246.000016)
		(stroke
			(width 1.524)
			(type default)
		)
		(layer "In4.Cu")
	)
	(gr_line
		(start 234.1499 -197.000114)
		(end 234.1499 -246.000016)
		(stroke
			(width 1.524)
			(type default)
		)
		(layer "In4.Cu")
	)
	(gr_arc
		(start 235.149898 -196.000116)
		(mid 234.442793 -196.293009)
		(end 234.1499 -197.000114)
		(stroke
			(width 1.524)
			(type default)
		)
		(layer "In4.Cu")
	)
	(gr_line
		(start 240.538 -63.246)
		(end 170.053 -63.246)
		(stroke
			(width 0.381)
			(type default)
		)
		(layer "In4.Cu")
	)
	(gr_line
		(start 240.665 -53.213)
		(end 242.062 -54.61)
		(stroke
			(width 0.381)
			(type default)
		)
		(layer "In4.Cu")
	)
	(gr_line
		(start 242.062 -61.722)
		(end 240.538 -63.246)
		(stroke
			(width 0.381)
			(type default)
		)
		(layer "In4.Cu")
	)
	(gr_line
		(start 242.062 -54.61)
		(end 242.062 -61.722)
		(stroke
			(width 0.381)
			(type default)
		)
		(layer "In4.Cu")
	)
	(gr_line
		(start 250.150122 -196.000116)
		(end 235.149898 -196.000116)
		(stroke
			(width 1.524)
			(type default)
		)
		(layer "In4.Cu")
	)
	(gr_line
		(start 251.15012 -246.000016)
		(end 251.15012 -197.000114)
		(stroke
			(width 1.524)
			(type default)
		)
		(layer "In4.Cu")
	)
	(gr_arc
		(start 251.15012 -246.000016)
		(mid 252.614589 -249.535529)
		(end 256.15011 -251.000006)
		(stroke
			(width 1.524)
			(type default)
		)
		(layer "In4.Cu")
	)
	(gr_arc
		(start 251.15012 -197.000114)
		(mid 250.857227 -196.293009)
		(end 250.150122 -196.000116)
		(stroke
			(width 1.524)
			(type default)
		)
		(layer "In4.Cu")
	)
	(gr_line
		(start 266.573 -48.006)
		(end 266.573 -47.117)
		(stroke
			(width 0.381)
			(type default)
		)
		(layer "In4.Cu")
	)
	(gr_line
		(start 266.573 -47.117)
		(end 267.716 -45.974)
		(stroke
			(width 0.381)
			(type default)
		)
		(layer "In4.Cu")
	)
	(gr_line
		(start 267.208 -48.641)
		(end 266.573 -48.006)
		(stroke
			(width 0.381)
			(type default)
		)
		(layer "In4.Cu")
	)
	(gr_line
		(start 267.716 -45.974)
		(end 276.225 -45.974)
		(stroke
			(width 0.381)
			(type default)
		)
		(layer "In4.Cu")
	)
	(gr_line
		(start 268.986 -48.641)
		(end 267.208 -48.641)
		(stroke
			(width 0.381)
			(type default)
		)
		(layer "In4.Cu")
	)
	(gr_line
		(start 270.51 -53.467)
		(end 270.51 -50.165)
		(stroke
			(width 0.381)
			(type default)
		)
		(layer "In4.Cu")
	)
	(gr_line
		(start 270.51 -50.165)
		(end 268.986 -48.641)
		(stroke
			(width 0.381)
			(type default)
		)
		(layer "In4.Cu")
	)
	(gr_line
		(start 270.999966 -11.779758)
		(end 272.999962 -11.779758)
		(stroke
			(width 0.2)
			(type default)
		)
		(layer "In4.Cu")
	)
	(gr_arc
		(start 270.999966 -10.199878)
		(mid 270.210026 -10.989818)
		(end 270.999966 -11.779758)
		(stroke
			(width 0.2)
			(type default)
		)
		(layer "In4.Cu")
	)
	(gr_arc
		(start 272.999962 -11.779758)
		(mid 273.789902 -10.989818)
		(end 272.999962 -10.199878)
		(stroke
			(width 0.2)
			(type default)
		)
		(layer "In4.Cu")
	)
	(gr_line
		(start 272.999962 -10.199878)
		(end 270.999966 -10.199878)
		(stroke
			(width 0.2)
			(type default)
		)
		(layer "In4.Cu")
	)
	(gr_line
		(start 276.225 -45.974)
		(end 278.765 -48.514)
		(stroke
			(width 0.381)
			(type default)
		)
		(layer "In4.Cu")
	)
	(gr_line
		(start 276.867112 -32.51454)
		(end 277.848822 -32.51454)
		(stroke
			(width 0.2)
			(type default)
		)
		(layer "In4.Cu")
	)
	(gr_arc
		(start 276.867112 -31.74746)
		(mid 276.483572 -32.131)
		(end 276.867112 -32.51454)
		(stroke
			(width 0.2)
			(type default)
		)
		(layer "In4.Cu")
	)
	(gr_arc
		(start 277.848822 -32.51454)
		(mid 278.232616 -32.131127)
		(end 277.849076 -31.74746)
		(stroke
			(width 0.2)
			(type default)
		)
		(layer "In4.Cu")
	)
	(gr_line
		(start 277.849076 -31.74746)
		(end 276.867112 -31.74746)
		(stroke
			(width 0.2)
			(type default)
		)
		(layer "In4.Cu")
	)
	(gr_line
		(start 278.13 -61.087)
		(end 270.51 -53.467)
		(stroke
			(width 0.381)
			(type default)
		)
		(layer "In4.Cu")
	)
	(gr_line
		(start 278.765 -48.514)
		(end 282.702 -48.514)
		(stroke
			(width 0.381)
			(type default)
		)
		(layer "In4.Cu")
	)
	(gr_arc
		(start 282.485084 -53.50002)
		(mid 282.777977 -54.207125)
		(end 283.485082 -54.500018)
		(stroke
			(width 1.524)
			(type default)
		)
		(layer "In4.Cu")
	)
	(gr_arc
		(start 282.485084 -0.999998)
		(mid 282.19219 -0.292899)
		(end 281.485086 0)
		(stroke
			(width 1.524)
			(type default)
		)
		(layer "In4.Cu")
	)
	(gr_line
		(start 282.485084 -0.999998)
		(end 282.485084 -53.50002)
		(stroke
			(width 1.524)
			(type default)
		)
		(layer "In4.Cu")
	)
	(gr_line
		(start 283.485082 -54.500018)
		(end 303.485042 -54.500018)
		(stroke
			(width 1.524)
			(type default)
		)
		(layer "In4.Cu")
	)
	(gr_arc
		(start 284.552898 -184.91327)
		(mid 284.227506 -185.347232)
		(end 284.661356 -185.67273)
		(stroke
			(width 0.2)
			(type default)
		)
		(layer "In4.Cu")
	)
	(gr_line
		(start 284.661356 -185.67273)
		(end 285.550356 -185.54573)
		(stroke
			(width 0.2)
			(type default)
		)
		(layer "In4.Cu")
	)
	(gr_line
		(start 285.441644 -184.78627)
		(end 284.552898 -184.91327)
		(stroke
			(width 0.2)
			(type default)
		)
		(layer "In4.Cu")
	)
	(gr_arc
		(start 285.550356 -185.54573)
		(mid 285.87573 -185.111644)
		(end 285.441644 -184.78627)
		(stroke
			(width 0.2)
			(type default)
		)
		(layer "In4.Cu")
	)
	(gr_arc
		(start 293.26586 -80.366616)
		(mid 293.649273 -80.75041)
		(end 294.03294 -80.36687)
		(stroke
			(width 0.2)
			(type default)
		)
		(layer "In4.Cu")
	)
	(gr_line
		(start 293.26586 -79.44993)
		(end 293.26586 -80.366616)
		(stroke
			(width 0.2)
			(type default)
		)
		(layer "In4.Cu")
	)
	(gr_line
		(start 294.03294 -80.36687)
		(end 294.03294 -79.44993)
		(stroke
			(width 0.2)
			(type default)
		)
		(layer "In4.Cu")
	)
	(gr_arc
		(start 294.03294 -79.44993)
		(mid 293.6494 -79.06639)
		(end 293.26586 -79.44993)
		(stroke
			(width 0.2)
			(type default)
		)
		(layer "In4.Cu")
	)
	(gr_arc
		(start 295.52646 -78.276196)
		(mid 295.909873 -78.65999)
		(end 296.29354 -78.27645)
		(stroke
			(width 0.2)
			(type default)
		)
		(layer "In4.Cu")
	)
	(gr_line
		(start 295.52646 -77.35951)
		(end 295.52646 -78.276196)
		(stroke
			(width 0.2)
			(type default)
		)
		(layer "In4.Cu")
	)
	(gr_line
		(start 296.29354 -78.27645)
		(end 296.29354 -77.35951)
		(stroke
			(width 0.2)
			(type default)
		)
		(layer "In4.Cu")
	)
	(gr_arc
		(start 296.29354 -77.35951)
		(mid 295.91 -76.97597)
		(end 295.52646 -77.35951)
		(stroke
			(width 0.2)
			(type default)
		)
		(layer "In4.Cu")
	)
	(gr_line
		(start 297.05681 -82.607404)
		(end 297.973496 -82.607404)
		(stroke
			(width 0.2)
			(type default)
		)
		(layer "In4.Cu")
	)
	(gr_arc
		(start 297.05681 -81.840324)
		(mid 296.67327 -82.223864)
		(end 297.05681 -82.607404)
		(stroke
			(width 0.2)
			(type default)
		)
		(layer "In4.Cu")
	)
	(gr_line
		(start 297.123358 -74.07529)
		(end 298.139104 -74.07529)
		(stroke
			(width 0.2)
			(type default)
		)
		(layer "In4.Cu")
	)
	(gr_arc
		(start 297.123358 -73.30821)
		(mid 296.739818 -73.69175)
		(end 297.123358 -74.07529)
		(stroke
			(width 0.2)
			(type default)
		)
		(layer "In4.Cu")
	)
	(gr_arc
		(start 297.973496 -82.607404)
		(mid 298.35729 -82.223991)
		(end 297.97375 -81.840324)
		(stroke
			(width 0.2)
			(type default)
		)
		(layer "In4.Cu")
	)
	(gr_line
		(start 297.97375 -81.840324)
		(end 297.05681 -81.840324)
		(stroke
			(width 0.2)
			(type default)
		)
		(layer "In4.Cu")
	)
	(gr_arc
		(start 298.139104 -74.07529)
		(mid 298.522898 -73.691877)
		(end 298.139358 -73.30821)
		(stroke
			(width 0.2)
			(type default)
		)
		(layer "In4.Cu")
	)
	(gr_line
		(start 298.139358 -73.30821)
		(end 297.123358 -73.30821)
		(stroke
			(width 0.2)
			(type default)
		)
		(layer "In4.Cu")
	)
	(gr_line
		(start 299.633132 -175.392334)
		(end 300.430438 -175.40351)
		(stroke
			(width 0.2)
			(type default)
		)
		(layer "In4.Cu")
	)
	(gr_arc
		(start 299.643546 -174.676054)
		(mid 299.280328 -175.028987)
		(end 299.633132 -175.392334)
		(stroke
			(width 0.2)
			(type default)
		)
		(layer "In4.Cu")
	)
	(gr_arc
		(start 300.430438 -175.40351)
		(mid 300.793658 -175.05045)
		(end 300.440598 -174.68723)
		(stroke
			(width 0.2)
			(type default)
		)
		(layer "In4.Cu")
	)
	(gr_line
		(start 300.440598 -174.68723)
		(end 299.643546 -174.676054)
		(stroke
			(width 0.2)
			(type default)
		)
		(layer "In4.Cu")
	)
	(gr_line
		(start 301.974758 -73.99274)
		(end 302.956722 -73.99274)
		(stroke
			(width 0.2)
			(type default)
		)
		(layer "In4.Cu")
	)
	(gr_arc
		(start 301.975012 -73.22566)
		(mid 301.591218 -73.609073)
		(end 301.974758 -73.99274)
		(stroke
			(width 0.2)
			(type default)
		)
		(layer "In4.Cu")
	)
	(gr_arc
		(start 302.214026 -173.36643)
		(mid 301.849028 -173.767496)
		(end 302.250094 -174.132494)
		(stroke
			(width 0.2)
			(type default)
		)
		(layer "In4.Cu")
	)
	(gr_line
		(start 302.214026 -173.364144)
		(end 302.214026 -173.36643)
		(stroke
			(width 0.2)
			(type default)
		)
		(layer "In4.Cu")
	)
	(gr_line
		(start 302.21428 -173.36389)
		(end 302.214026 -173.364144)
		(stroke
			(width 0.2)
			(type default)
		)
		(layer "In4.Cu")
	)
	(gr_line
		(start 302.250094 -174.135034)
		(end 303.024032 -174.098966)
		(stroke
			(width 0.2)
			(type default)
		)
		(layer "In4.Cu")
	)
	(gr_line
		(start 302.250094 -174.132494)
		(end 302.250094 -174.135034)
		(stroke
			(width 0.2)
			(type default)
		)
		(layer "In4.Cu")
	)
	(gr_arc
		(start 302.956722 -73.99274)
		(mid 303.340262 -73.6092)
		(end 302.956722 -73.22566)
		(stroke
			(width 0.2)
			(type default)
		)
		(layer "In4.Cu")
	)
	(gr_line
		(start 302.956722 -73.22566)
		(end 301.975012 -73.22566)
		(stroke
			(width 0.2)
			(type default)
		)
		(layer "In4.Cu")
	)
	(gr_line
		(start 302.987964 -173.330362)
		(end 302.987964 -173.327822)
		(stroke
			(width 0.2)
			(type default)
		)
		(layer "In4.Cu")
	)
	(gr_line
		(start 302.987964 -173.327822)
		(end 302.21428 -173.36389)
		(stroke
			(width 0.2)
			(type default)
		)
		(layer "In4.Cu")
	)
	(gr_line
		(start 303.024032 -174.098966)
		(end 303.024032 -174.096934)
		(stroke
			(width 0.2)
			(type default)
		)
		(layer "In4.Cu")
	)
	(gr_line
		(start 303.024032 -174.096934)
		(end 303.024032 -174.096426)
		(stroke
			(width 0.2)
			(type default)
		)
		(layer "In4.Cu")
	)
	(gr_arc
		(start 303.024032 -174.096426)
		(mid 303.38903 -173.69536)
		(end 302.987964 -173.330362)
		(stroke
			(width 0.2)
			(type default)
		)
		(layer "In4.Cu")
	)
	(gr_arc
		(start 303.485042 -54.500018)
		(mid 304.192147 -54.207125)
		(end 304.48504 -53.50002)
		(stroke
			(width 1.524)
			(type default)
		)
		(layer "In4.Cu")
	)
	(gr_line
		(start 303.80305 -87.908892)
		(end 304.719736 -87.908892)
		(stroke
			(width 0.2)
			(type default)
		)
		(layer "In4.Cu")
	)
	(gr_arc
		(start 303.80305 -87.141812)
		(mid 303.41951 -87.525352)
		(end 303.80305 -87.908892)
		(stroke
			(width 0.2)
			(type default)
		)
		(layer "In4.Cu")
	)
	(gr_line
		(start 304.48504 -53.50002)
		(end 304.48504 -45.500036)
		(stroke
			(width 1.524)
			(type default)
		)
		(layer "In4.Cu")
	)
	(gr_line
		(start 304.673 -47.625)
		(end 308.102 -47.625)
		(stroke
			(width 0.381)
			(type default)
		)
		(layer "In4.Cu")
	)
	(gr_arc
		(start 304.719736 -87.908892)
		(mid 305.10353 -87.525479)
		(end 304.71999 -87.141812)
		(stroke
			(width 0.2)
			(type default)
		)
		(layer "In4.Cu")
	)
	(gr_line
		(start 304.71999 -87.141812)
		(end 303.80305 -87.141812)
		(stroke
			(width 0.2)
			(type default)
		)
		(layer "In4.Cu")
	)
	(gr_arc
		(start 305.485038 -44.500038)
		(mid 304.777921 -44.792919)
		(end 304.48504 -45.500036)
		(stroke
			(width 1.524)
			(type default)
		)
		(layer "In4.Cu")
	)
	(gr_arc
		(start 305.485038 -44.500038)
		(mid 306.192143 -44.207145)
		(end 306.485036 -43.50004)
		(stroke
			(width 1.524)
			(type default)
		)
		(layer "In4.Cu")
	)
	(gr_line
		(start 306.485036 -43.50004)
		(end 306.485036 -0.999998)
		(stroke
			(width 1.524)
			(type default)
		)
		(layer "In4.Cu")
	)
	(gr_arc
		(start 307.485034 0)
		(mid 306.777906 -0.29288)
		(end 306.485036 -0.999998)
		(stroke
			(width 1.524)
			(type default)
		)
		(layer "In4.Cu")
	)
	(gr_line
		(start 307.485034 0)
		(end 354.600002 0)
		(stroke
			(width 1.524)
			(type default)
		)
		(layer "In4.Cu")
	)
	(gr_line
		(start 308.102 -47.625)
		(end 311.277 -50.8)
		(stroke
			(width 0.381)
			(type default)
		)
		(layer "In4.Cu")
	)
	(gr_line
		(start 309.245 -61.087)
		(end 278.13 -61.087)
		(stroke
			(width 0.381)
			(type default)
		)
		(layer "In4.Cu")
	)
	(gr_line
		(start 311.277 -59.055)
		(end 309.245 -61.087)
		(stroke
			(width 0.381)
			(type default)
		)
		(layer "In4.Cu")
	)
	(gr_line
		(start 311.277 -50.8)
		(end 311.277 -59.055)
		(stroke
			(width 0.381)
			(type default)
		)
		(layer "In4.Cu")
	)
	(gr_arc
		(start 317.263018 -73.024746)
		(mid 317.671831 -73.43394)
		(end 318.080898 -73.025)
		(stroke
			(width 0.2)
			(type default)
		)
		(layer "In4.Cu")
	)
	(gr_line
		(start 317.263018 -72.009)
		(end 317.263018 -73.024746)
		(stroke
			(width 0.2)
			(type default)
		)
		(layer "In4.Cu")
	)
	(gr_arc
		(start 317.898018 -82.422746)
		(mid 318.306831 -82.83194)
		(end 318.715898 -82.423)
		(stroke
			(width 0.2)
			(type default)
		)
		(layer "In4.Cu")
	)
	(gr_line
		(start 317.898018 -81.407)
		(end 317.898018 -82.422746)
		(stroke
			(width 0.2)
			(type default)
		)
		(layer "In4.Cu")
	)
	(gr_line
		(start 317.971932 -79.440786)
		(end 317.972186 -79.44104)
		(stroke
			(width 0.2)
			(type default)
		)
		(layer "In4.Cu")
	)
	(gr_line
		(start 317.972186 -79.44104)
		(end 317.974218 -79.44104)
		(stroke
			(width 0.2)
			(type default)
		)
		(layer "In4.Cu")
	)
	(gr_arc
		(start 317.974218 -79.44104)
		(mid 318.372998 -79.86014)
		(end 318.792098 -79.46136)
		(stroke
			(width 0.2)
			(type default)
		)
		(layer "In4.Cu")
	)
	(gr_line
		(start 317.997332 -78.42504)
		(end 317.971932 -79.440786)
		(stroke
			(width 0.2)
			(type default)
		)
		(layer "In4.Cu")
	)
	(gr_line
		(start 317.999618 -78.42504)
		(end 317.997332 -78.42504)
		(stroke
			(width 0.2)
			(type default)
		)
		(layer "In4.Cu")
	)
	(gr_line
		(start 318.080898 -73.025)
		(end 318.080898 -72.009)
		(stroke
			(width 0.2)
			(type default)
		)
		(layer "In4.Cu")
	)
	(gr_arc
		(start 318.080898 -72.009)
		(mid 317.671958 -71.60006)
		(end 317.263018 -72.009)
		(stroke
			(width 0.2)
			(type default)
		)
		(layer "In4.Cu")
	)
	(gr_arc
		(start 318.372236 -69.197982)
		(mid 318.755776 -69.581522)
		(end 319.139316 -69.197982)
		(stroke
			(width 0.2)
			(type default)
		)
		(layer "In4.Cu")
	)
	(gr_line
		(start 318.372236 -68.216018)
		(end 318.372236 -69.197982)
		(stroke
			(width 0.2)
			(type default)
		)
		(layer "In4.Cu")
	)
	(gr_line
		(start 318.715898 -82.423)
		(end 318.715898 -81.407)
		(stroke
			(width 0.2)
			(type default)
		)
		(layer "In4.Cu")
	)
	(gr_arc
		(start 318.715898 -81.407)
		(mid 318.306958 -80.99806)
		(end 317.898018 -81.407)
		(stroke
			(width 0.2)
			(type default)
		)
		(layer "In4.Cu")
	)
	(gr_line
		(start 318.792098 -79.46136)
		(end 318.794384 -79.46136)
		(stroke
			(width 0.2)
			(type default)
		)
		(layer "In4.Cu")
	)
	(gr_line
		(start 318.794384 -79.46136)
		(end 318.819784 -78.44536)
		(stroke
			(width 0.2)
			(type default)
		)
		(layer "In4.Cu")
	)
	(gr_arc
		(start 318.817498 -78.44536)
		(mid 318.418718 -78.02626)
		(end 317.999618 -78.42504)
		(stroke
			(width 0.2)
			(type default)
		)
		(layer "In4.Cu")
	)
	(gr_line
		(start 318.819784 -78.44536)
		(end 318.817498 -78.44536)
		(stroke
			(width 0.2)
			(type default)
		)
		(layer "In4.Cu")
	)
	(gr_line
		(start 319.139316 -69.197982)
		(end 319.139316 -68.216272)
		(stroke
			(width 0.2)
			(type default)
		)
		(layer "In4.Cu")
	)
	(gr_arc
		(start 319.139316 -68.216272)
		(mid 318.755903 -67.832478)
		(end 318.372236 -68.216018)
		(stroke
			(width 0.2)
			(type default)
		)
		(layer "In4.Cu")
	)
	(gr_arc
		(start 319.777618 -76.191618)
		(mid 320.186431 -76.600812)
		(end 320.595498 -76.191872)
		(stroke
			(width 0.2)
			(type default)
		)
		(layer "In4.Cu")
	)
	(gr_line
		(start 319.777618 -75.209908)
		(end 319.777618 -76.191618)
		(stroke
			(width 0.2)
			(type default)
		)
		(layer "In4.Cu")
	)
	(gr_line
		(start 320.595498 -76.191872)
		(end 320.595498 -75.209908)
		(stroke
			(width 0.2)
			(type default)
		)
		(layer "In4.Cu")
	)
	(gr_arc
		(start 320.595498 -75.209908)
		(mid 320.186558 -74.800968)
		(end 319.777618 -75.209908)
		(stroke
			(width 0.2)
			(type default)
		)
		(layer "In4.Cu")
	)
	(gr_line
		(start 335.153 -94.869)
		(end 335.153 -85.979)
		(stroke
			(width 0.381)
			(type default)
		)
		(layer "In4.Cu")
	)
	(gr_line
		(start 335.153 -85.979)
		(end 335.661 -85.471)
		(stroke
			(width 0.381)
			(type default)
		)
		(layer "In4.Cu")
	)
	(gr_line
		(start 335.661 -85.471)
		(end 340.233 -85.471)
		(stroke
			(width 0.381)
			(type default)
		)
		(layer "In4.Cu")
	)
	(gr_line
		(start 335.788 -95.504)
		(end 335.153 -94.869)
		(stroke
			(width 0.381)
			(type default)
		)
		(layer "In4.Cu")
	)
	(gr_line
		(start 337.058 -95.504)
		(end 335.788 -95.504)
		(stroke
			(width 0.381)
			(type default)
		)
		(layer "In4.Cu")
	)
	(gr_line
		(start 340.233 -85.471)
		(end 340.995 -86.233)
		(stroke
			(width 0.381)
			(type default)
		)
		(layer "In4.Cu")
	)
	(gr_line
		(start 340.36 -95.504)
		(end 337.058 -95.504)
		(stroke
			(width 0.381)
			(type default)
		)
		(layer "In4.Cu")
	)
	(gr_line
		(start 340.995 -94.869)
		(end 340.36 -95.504)
		(stroke
			(width 0.381)
			(type default)
		)
		(layer "In4.Cu")
	)
	(gr_line
		(start 340.995 -86.233)
		(end 340.995 -94.869)
		(stroke
			(width 0.381)
			(type default)
		)
		(layer "In4.Cu")
	)
	(gr_arc
		(start 349.652844 -155.154884)
		(mid 350.010857 -155.513278)
		(end 350.369124 -155.155138)
		(stroke
			(width 0.2)
			(type default)
		)
		(layer "In4.Cu")
	)
	(gr_line
		(start 349.652844 -154.275028)
		(end 349.652844 -155.154884)
		(stroke
			(width 0.2)
			(type default)
		)
		(layer "In4.Cu")
	)
	(gr_line
		(start 350.369124 -155.155138)
		(end 350.369124 -154.275028)
		(stroke
			(width 0.2)
			(type default)
		)
		(layer "In4.Cu")
	)
	(gr_arc
		(start 350.369124 -154.275028)
		(mid 350.010984 -153.916888)
		(end 349.652844 -154.275028)
		(stroke
			(width 0.2)
			(type default)
		)
		(layer "In4.Cu")
	)
	(gr_arc
		(start 350.39681 -152.916636)
		(mid 350.754823 -153.27503)
		(end 351.11309 -152.91689)
		(stroke
			(width 0.2)
			(type default)
		)
		(layer "In4.Cu")
	)
	(gr_line
		(start 350.39681 -151.97201)
		(end 350.39681 -152.916636)
		(stroke
			(width 0.2)
			(type default)
		)
		(layer "In4.Cu")
	)
	(gr_line
		(start 350.60001 -251.000006)
		(end 256.15011 -251.000006)
		(stroke
			(width 1.524)
			(type default)
		)
		(layer "In4.Cu")
	)
	(gr_arc
		(start 350.60001 -251.000006)
		(mid 354.135536 -249.53554)
		(end 355.6 -246.000016)
		(stroke
			(width 1.524)
			(type default)
		)
		(layer "In4.Cu")
	)
	(gr_line
		(start 350.87941 -147.98167)
		(end 351.824036 -147.98167)
		(stroke
			(width 0.2)
			(type default)
		)
		(layer "In4.Cu")
	)
	(gr_arc
		(start 350.87941 -147.26539)
		(mid 350.52127 -147.62353)
		(end 350.87941 -147.98167)
		(stroke
			(width 0.2)
			(type default)
		)
		(layer "In4.Cu")
	)
	(gr_line
		(start 351.11309 -152.91689)
		(end 351.11309 -151.97201)
		(stroke
			(width 0.2)
			(type default)
		)
		(layer "In4.Cu")
	)
	(gr_arc
		(start 351.11309 -151.97201)
		(mid 350.75495 -151.61387)
		(end 350.39681 -151.97201)
		(stroke
			(width 0.2)
			(type default)
		)
		(layer "In4.Cu")
	)
	(gr_arc
		(start 351.824036 -147.98167)
		(mid 352.18243 -147.623657)
		(end 351.82429 -147.26539)
		(stroke
			(width 0.2)
			(type default)
		)
		(layer "In4.Cu")
	)
	(gr_line
		(start 351.82429 -147.26539)
		(end 350.87941 -147.26539)
		(stroke
			(width 0.2)
			(type default)
		)
		(layer "In4.Cu")
	)
	(gr_arc
		(start 355.6 -0.999998)
		(mid 355.307107 -0.292893)
		(end 354.600002 0)
		(stroke
			(width 1.524)
			(type default)
		)
		(layer "In4.Cu")
	)
	(gr_line
		(start 355.6 -0.999998)
		(end 355.6 -246.000016)
		(stroke
			(width 1.524)
			(type default)
		)
		(layer "In4.Cu")
	)
	(gr_line
		(start 12.8778 -148.241004)
		(end 12.8778 -148.784564)
		(stroke
			(width 0.0508)
			(type default)
		)
		(layer "In5.Cu")
	)
	(gr_line
		(start 12.8778 -146.727164)
		(end 12.8778 -147.270724)
		(stroke
			(width 0.0508)
			(type default)
		)
		(layer "In5.Cu")
	)
	(gr_line
		(start 12.8778 -142.865094)
		(end 12.8778 -143.408654)
		(stroke
			(width 0.0508)
			(type default)
		)
		(layer "In5.Cu")
	)
	(gr_line
		(start 12.8778 -141.351254)
		(end 12.8778 -141.894814)
		(stroke
			(width 0.0508)
			(type default)
		)
		(layer "In5.Cu")
	)
	(gr_line
		(start 12.8778 -137.597388)
		(end 12.8778 -138.140948)
		(stroke
			(width 0.0508)
			(type default)
		)
		(layer "In5.Cu")
	)
	(gr_line
		(start 12.8778 -136.083548)
		(end 12.8778 -136.627108)
		(stroke
			(width 0.0508)
			(type default)
		)
		(layer "In5.Cu")
	)
	(gr_line
		(start 12.8778 -134.569708)
		(end 12.8778 -135.113268)
		(stroke
			(width 0.0508)
			(type default)
		)
		(layer "In5.Cu")
	)
	(gr_arc
		(start 13.208 -147.908264)
		(mid 13.237239 -148.034925)
		(end 13.32103 -148.134324)
		(stroke
			(width 0.0508)
			(type default)
		)
		(layer "In5.Cu")
	)
	(gr_arc
		(start 13.208 -146.394424)
		(mid 13.237239 -146.521085)
		(end 13.32103 -146.620484)
		(stroke
			(width 0.0508)
			(type default)
		)
		(layer "In5.Cu")
	)
	(gr_arc
		(start 13.208 -142.532354)
		(mid 13.237239 -142.659015)
		(end 13.32103 -142.758414)
		(stroke
			(width 0.0508)
			(type default)
		)
		(layer "In5.Cu")
	)
	(gr_arc
		(start 13.208 -141.018514)
		(mid 13.237239 -141.145175)
		(end 13.32103 -141.244574)
		(stroke
			(width 0.0508)
			(type default)
		)
		(layer "In5.Cu")
	)
	(gr_arc
		(start 13.208 -137.264648)
		(mid 13.237239 -137.391309)
		(end 13.32103 -137.490708)
		(stroke
			(width 0.0508)
			(type default)
		)
		(layer "In5.Cu")
	)
	(gr_arc
		(start 13.208 -135.750808)
		(mid 13.237239 -135.877469)
		(end 13.32103 -135.976868)
		(stroke
			(width 0.0508)
			(type default)
		)
		(layer "In5.Cu")
	)
	(gr_arc
		(start 13.208 -134.236968)
		(mid 13.237239 -134.363629)
		(end 13.32103 -134.463028)
		(stroke
			(width 0.0508)
			(type default)
		)
		(layer "In5.Cu")
	)
	(gr_arc
		(start 13.32103 -148.891244)
		(mid 13.237193 -148.99062)
		(end 13.208 -149.117304)
		(stroke
			(width 0.0508)
			(type default)
		)
		(layer "In5.Cu")
	)
	(gr_arc
		(start 13.32103 -148.891244)
		(mid 13.404837 -148.791856)
		(end 13.43406 -148.665184)
		(stroke
			(width 0.0508)
			(type default)
		)
		(layer "In5.Cu")
	)
	(gr_arc
		(start 13.32103 -147.377404)
		(mid 13.237193 -147.47678)
		(end 13.208 -147.603464)
		(stroke
			(width 0.0508)
			(type default)
		)
		(layer "In5.Cu")
	)
	(gr_arc
		(start 13.32103 -147.377404)
		(mid 13.404823 -147.278013)
		(end 13.43406 -147.151344)
		(stroke
			(width 0.0508)
			(type default)
		)
		(layer "In5.Cu")
	)
	(gr_arc
		(start 13.32103 -143.515334)
		(mid 13.237193 -143.61471)
		(end 13.208 -143.741394)
		(stroke
			(width 0.0508)
			(type default)
		)
		(layer "In5.Cu")
	)
	(gr_arc
		(start 13.32103 -143.515334)
		(mid 13.404834 -143.415945)
		(end 13.43406 -143.289274)
		(stroke
			(width 0.0508)
			(type default)
		)
		(layer "In5.Cu")
	)
	(gr_arc
		(start 13.32103 -142.001494)
		(mid 13.237193 -142.10087)
		(end 13.208 -142.227554)
		(stroke
			(width 0.0508)
			(type default)
		)
		(layer "In5.Cu")
	)
	(gr_arc
		(start 13.32103 -142.001494)
		(mid 13.404819 -141.902102)
		(end 13.43406 -141.775434)
		(stroke
			(width 0.0508)
			(type default)
		)
		(layer "In5.Cu")
	)
	(gr_arc
		(start 13.32103 -138.247628)
		(mid 13.237193 -138.347004)
		(end 13.208 -138.473688)
		(stroke
			(width 0.0508)
			(type default)
		)
		(layer "In5.Cu")
	)
	(gr_arc
		(start 13.32103 -138.247628)
		(mid 13.404832 -138.148238)
		(end 13.43406 -138.021568)
		(stroke
			(width 0.0508)
			(type default)
		)
		(layer "In5.Cu")
	)
	(gr_arc
		(start 13.32103 -136.733788)
		(mid 13.237193 -136.833164)
		(end 13.208 -136.959848)
		(stroke
			(width 0.0508)
			(type default)
		)
		(layer "In5.Cu")
	)
	(gr_arc
		(start 13.32103 -136.733788)
		(mid 13.404817 -136.634396)
		(end 13.43406 -136.507728)
		(stroke
			(width 0.0508)
			(type default)
		)
		(layer "In5.Cu")
	)
	(gr_arc
		(start 13.32103 -135.219948)
		(mid 13.237193 -135.319324)
		(end 13.208 -135.446008)
		(stroke
			(width 0.0508)
			(type default)
		)
		(layer "In5.Cu")
	)
	(gr_arc
		(start 13.32103 -135.219948)
		(mid 13.404839 -135.12056)
		(end 13.43406 -134.993888)
		(stroke
			(width 0.0508)
			(type default)
		)
		(layer "In5.Cu")
	)
	(gr_arc
		(start 13.43406 -148.360384)
		(mid 13.404876 -148.233686)
		(end 13.32103 -148.134324)
		(stroke
			(width 0.0508)
			(type default)
		)
		(layer "In5.Cu")
	)
	(gr_line
		(start 13.43406 -148.360384)
		(end 13.43406 -148.665184)
		(stroke
			(width 0.0508)
			(type default)
		)
		(layer "In5.Cu")
	)
	(gr_arc
		(start 13.43406 -146.846544)
		(mid 13.404861 -146.719857)
		(end 13.32103 -146.620484)
		(stroke
			(width 0.0508)
			(type default)
		)
		(layer "In5.Cu")
	)
	(gr_line
		(start 13.43406 -146.846544)
		(end 13.43406 -147.151344)
		(stroke
			(width 0.0508)
			(type default)
		)
		(layer "In5.Cu")
	)
	(gr_arc
		(start 13.43406 -142.984474)
		(mid 13.404872 -142.857778)
		(end 13.32103 -142.758414)
		(stroke
			(width 0.0508)
			(type default)
		)
		(layer "In5.Cu")
	)
	(gr_line
		(start 13.43406 -142.984474)
		(end 13.43406 -143.289274)
		(stroke
			(width 0.0508)
			(type default)
		)
		(layer "In5.Cu")
	)
	(gr_arc
		(start 13.43406 -141.470634)
		(mid 13.404858 -141.34395)
		(end 13.32103 -141.244574)
		(stroke
			(width 0.0508)
			(type default)
		)
		(layer "In5.Cu")
	)
	(gr_line
		(start 13.43406 -141.470634)
		(end 13.43406 -141.775434)
		(stroke
			(width 0.0508)
			(type default)
		)
		(layer "In5.Cu")
	)
	(gr_arc
		(start 13.43406 -137.716768)
		(mid 13.40487 -137.590074)
		(end 13.32103 -137.490708)
		(stroke
			(width 0.0508)
			(type default)
		)
		(layer "In5.Cu")
	)
	(gr_line
		(start 13.43406 -137.716768)
		(end 13.43406 -138.021568)
		(stroke
			(width 0.0508)
			(type default)
		)
		(layer "In5.Cu")
	)
	(gr_arc
		(start 13.43406 -136.202928)
		(mid 13.404856 -136.076246)
		(end 13.32103 -135.976868)
		(stroke
			(width 0.0508)
			(type default)
		)
		(layer "In5.Cu")
	)
	(gr_line
		(start 13.43406 -136.202928)
		(end 13.43406 -136.507728)
		(stroke
			(width 0.0508)
			(type default)
		)
		(layer "In5.Cu")
	)
	(gr_arc
		(start 13.43406 -134.689088)
		(mid 13.404878 -134.562388)
		(end 13.32103 -134.463028)
		(stroke
			(width 0.0508)
			(type default)
		)
		(layer "In5.Cu")
	)
	(gr_line
		(start 13.43406 -134.689088)
		(end 13.43406 -134.993888)
		(stroke
			(width 0.0508)
			(type default)
		)
		(layer "In5.Cu")
	)
	(gr_arc
		(start 15.33398 -121.61266)
		(mid 15.402816 -121.502405)
		(end 15.413736 -121.372884)
		(stroke
			(width 0.0508)
			(type default)
		)
		(layer "In5.Cu")
	)
	(gr_arc
		(start 15.493746 -121.133108)
		(mid 15.424765 -121.243331)
		(end 15.413736 -121.372884)
		(stroke
			(width 0.0508)
			(type default)
		)
		(layer "In5.Cu")
	)
	(gr_line
		(start 15.493746 -121.133108)
		(end 15.709392 -120.917716)
		(stroke
			(width 0.0508)
			(type default)
		)
		(layer "In5.Cu")
	)
	(gr_line
		(start 15.802864 -121.611136)
		(end 16.18742 -121.22658)
		(stroke
			(width 0.0508)
			(type default)
		)
		(layer "In5.Cu")
	)
	(gr_arc
		(start 15.949168 -120.837706)
		(mid 15.819616 -120.848736)
		(end 15.709392 -120.917716)
		(stroke
			(width 0.0508)
			(type default)
		)
		(layer "In5.Cu")
	)
	(gr_arc
		(start 15.949168 -120.837706)
		(mid 16.078713 -120.826656)
		(end 16.188944 -120.757696)
		(stroke
			(width 0.0508)
			(type default)
		)
		(layer "In5.Cu")
	)
	(gr_arc
		(start 16.404336 -120.542304)
		(mid 16.47327 -120.432074)
		(end 16.484346 -120.302528)
		(stroke
			(width 0.0508)
			(type default)
		)
		(layer "In5.Cu")
	)
	(gr_arc
		(start 16.564102 -120.062752)
		(mid 16.495251 -120.173006)
		(end 16.484346 -120.302528)
		(stroke
			(width 0.0508)
			(type default)
		)
		(layer "In5.Cu")
	)
	(gr_line
		(start 16.564102 -120.062752)
		(end 16.779748 -119.847106)
		(stroke
			(width 0.0508)
			(type default)
		)
		(layer "In5.Cu")
	)
	(gr_arc
		(start 16.692118 -156.483558)
		(mid 16.802348 -156.552492)
		(end 16.931894 -156.563568)
		(stroke
			(width 0.0508)
			(type default)
		)
		(layer "In5.Cu")
	)
	(gr_line
		(start 16.693642 -156.952442)
		(end 17.078198 -157.336998)
		(stroke
			(width 0.0508)
			(type default)
		)
		(layer "In5.Cu")
	)
	(gr_line
		(start 16.87322 -120.54078)
		(end 17.257776 -120.156224)
		(stroke
			(width 0.0508)
			(type default)
		)
		(layer "In5.Cu")
	)
	(gr_arc
		(start 17.019524 -119.76735)
		(mid 16.890012 -119.778283)
		(end 16.779748 -119.847106)
		(stroke
			(width 0.0508)
			(type default)
		)
		(layer "In5.Cu")
	)
	(gr_arc
		(start 17.019524 -119.76735)
		(mid 17.149081 -119.756307)
		(end 17.2593 -119.68734)
		(stroke
			(width 0.0508)
			(type default)
		)
		(layer "In5.Cu")
	)
	(gr_arc
		(start 17.17167 -156.643324)
		(mid 17.061415 -156.574499)
		(end 16.931894 -156.563568)
		(stroke
			(width 0.0508)
			(type default)
		)
		(layer "In5.Cu")
	)
	(gr_line
		(start 17.17167 -156.643324)
		(end 17.387316 -156.85897)
		(stroke
			(width 0.0508)
			(type default)
		)
		(layer "In5.Cu")
	)
	(gr_arc
		(start 17.467072 -157.098746)
		(mid 17.456148 -156.969228)
		(end 17.387316 -156.85897)
		(stroke
			(width 0.0508)
			(type default)
		)
		(layer "In5.Cu")
	)
	(gr_arc
		(start 17.467072 -157.098746)
		(mid 17.478115 -157.228303)
		(end 17.547082 -157.338522)
		(stroke
			(width 0.0508)
			(type default)
		)
		(layer "In5.Cu")
	)
	(gr_arc
		(start 17.474692 -119.471948)
		(mid 17.543689 -119.361729)
		(end 17.554702 -119.232172)
		(stroke
			(width 0.0508)
			(type default)
		)
		(layer "In5.Cu")
	)
	(gr_arc
		(start 17.634712 -118.992396)
		(mid 17.565734 -119.10262)
		(end 17.554702 -119.232172)
		(stroke
			(width 0.0508)
			(type default)
		)
		(layer "In5.Cu")
	)
	(gr_line
		(start 17.634712 -118.992396)
		(end 17.850104 -118.77675)
		(stroke
			(width 0.0508)
			(type default)
		)
		(layer "In5.Cu")
	)
	(gr_arc
		(start 17.762474 -157.553914)
		(mid 17.872693 -157.622911)
		(end 18.00225 -157.633924)
		(stroke
			(width 0.0508)
			(type default)
		)
		(layer "In5.Cu")
	)
	(gr_line
		(start 17.763998 -158.022798)
		(end 18.148554 -158.407354)
		(stroke
			(width 0.0508)
			(type default)
		)
		(layer "In5.Cu")
	)
	(gr_line
		(start 17.943576 -119.470424)
		(end 18.328132 -119.085868)
		(stroke
			(width 0.0508)
			(type default)
		)
		(layer "In5.Cu")
	)
	(gr_arc
		(start 18.08988 -118.69674)
		(mid 17.960349 -118.707832)
		(end 17.850104 -118.77675)
		(stroke
			(width 0.0508)
			(type default)
		)
		(layer "In5.Cu")
	)
	(gr_arc
		(start 18.08988 -118.69674)
		(mid 18.219402 -118.685823)
		(end 18.329656 -118.616984)
		(stroke
			(width 0.0508)
			(type default)
		)
		(layer "In5.Cu")
	)
	(gr_arc
		(start 18.242026 -157.713934)
		(mid 18.131799 -157.644967)
		(end 18.00225 -157.633924)
		(stroke
			(width 0.0508)
			(type default)
		)
		(layer "In5.Cu")
	)
	(gr_line
		(start 18.242026 -157.713934)
		(end 18.457672 -157.929326)
		(stroke
			(width 0.0508)
			(type default)
		)
		(layer "In5.Cu")
	)
	(gr_arc
		(start 18.43532 -161.83356)
		(mid 18.545575 -161.902396)
		(end 18.675096 -161.913316)
		(stroke
			(width 0.0508)
			(type default)
		)
		(layer "In5.Cu")
	)
	(gr_line
		(start 18.436844 -162.302444)
		(end 18.821146 -162.686746)
		(stroke
			(width 0.0508)
			(type default)
		)
		(layer "In5.Cu")
	)
	(gr_arc
		(start 18.537682 -158.169102)
		(mid 18.526599 -158.039564)
		(end 18.457672 -157.929326)
		(stroke
			(width 0.0508)
			(type default)
		)
		(layer "In5.Cu")
	)
	(gr_arc
		(start 18.537682 -158.169102)
		(mid 18.548599 -158.298624)
		(end 18.617438 -158.408878)
		(stroke
			(width 0.0508)
			(type default)
		)
		(layer "In5.Cu")
	)
	(gr_arc
		(start 18.914872 -161.993326)
		(mid 18.804648 -161.924358)
		(end 18.675096 -161.913316)
		(stroke
			(width 0.0508)
			(type default)
		)
		(layer "In5.Cu")
	)
	(gr_line
		(start 18.914872 -161.993326)
		(end 19.130264 -162.208718)
		(stroke
			(width 0.0508)
			(type default)
		)
		(layer "In5.Cu")
	)
	(gr_arc
		(start 19.210274 -162.448494)
		(mid 19.199188 -162.318959)
		(end 19.130264 -162.208718)
		(stroke
			(width 0.0508)
			(type default)
		)
		(layer "In5.Cu")
	)
	(gr_arc
		(start 19.210274 -162.448494)
		(mid 19.221191 -162.578016)
		(end 19.29003 -162.68827)
		(stroke
			(width 0.0508)
			(type default)
		)
		(layer "In5.Cu")
	)
	(gr_arc
		(start 19.505676 -162.903916)
		(mid 19.615906 -162.97285)
		(end 19.745452 -162.983926)
		(stroke
			(width 0.0508)
			(type default)
		)
		(layer "In5.Cu")
	)
	(gr_line
		(start 19.5072 -163.3728)
		(end 19.891756 -163.757356)
		(stroke
			(width 0.0508)
			(type default)
		)
		(layer "In5.Cu")
	)
	(gr_arc
		(start 19.985228 -163.063682)
		(mid 19.874972 -162.994844)
		(end 19.745452 -162.983926)
		(stroke
			(width 0.0508)
			(type default)
		)
		(layer "In5.Cu")
	)
	(gr_line
		(start 19.985228 -163.063682)
		(end 20.20062 -163.279328)
		(stroke
			(width 0.0508)
			(type default)
		)
		(layer "In5.Cu")
	)
	(gr_arc
		(start 20.28063 -163.519104)
		(mid 20.269615 -163.389542)
		(end 20.20062 -163.279328)
		(stroke
			(width 0.0508)
			(type default)
		)
		(layer "In5.Cu")
	)
	(gr_arc
		(start 20.28063 -163.519104)
		(mid 20.291673 -163.648661)
		(end 20.36064 -163.75888)
		(stroke
			(width 0.0508)
			(type default)
		)
		(layer "In5.Cu")
	)
	(gr_arc
		(start 20.576032 -163.974272)
		(mid 20.686251 -164.043269)
		(end 20.815808 -164.054282)
		(stroke
			(width 0.0508)
			(type default)
		)
		(layer "In5.Cu")
	)
	(gr_line
		(start 20.577556 -164.443156)
		(end 20.962112 -164.827712)
		(stroke
			(width 0.0508)
			(type default)
		)
		(layer "In5.Cu")
	)
	(gr_arc
		(start 20.606258 -160.397698)
		(mid 20.716477 -160.466695)
		(end 20.846034 -160.477708)
		(stroke
			(width 0.0508)
			(type default)
		)
		(layer "In5.Cu")
	)
	(gr_line
		(start 20.607782 -160.866582)
		(end 20.992338 -161.251138)
		(stroke
			(width 0.0508)
			(type default)
		)
		(layer "In5.Cu")
	)
	(gr_arc
		(start 21.055584 -164.134292)
		(mid 20.945358 -164.065327)
		(end 20.815808 -164.054282)
		(stroke
			(width 0.0508)
			(type default)
		)
		(layer "In5.Cu")
	)
	(gr_line
		(start 21.055584 -164.134292)
		(end 21.27123 -164.349684)
		(stroke
			(width 0.0508)
			(type default)
		)
		(layer "In5.Cu")
	)
	(gr_arc
		(start 21.08581 -160.557718)
		(mid 20.975586 -160.488736)
		(end 20.846034 -160.477708)
		(stroke
			(width 0.0508)
			(type default)
		)
		(layer "In5.Cu")
	)
	(gr_line
		(start 21.08581 -160.557718)
		(end 21.301456 -160.77311)
		(stroke
			(width 0.0508)
			(type default)
		)
		(layer "In5.Cu")
	)
	(gr_arc
		(start 21.35124 -164.58946)
		(mid 21.34018 -164.45991)
		(end 21.27123 -164.349684)
		(stroke
			(width 0.0508)
			(type default)
		)
		(layer "In5.Cu")
	)
	(gr_arc
		(start 21.35124 -164.58946)
		(mid 21.362157 -164.718982)
		(end 21.430996 -164.829236)
		(stroke
			(width 0.0508)
			(type default)
		)
		(layer "In5.Cu")
	)
	(gr_arc
		(start 21.381212 -161.012886)
		(mid 21.370306 -160.883356)
		(end 21.301456 -160.77311)
		(stroke
			(width 0.0508)
			(type default)
		)
		(layer "In5.Cu")
	)
	(gr_arc
		(start 21.381212 -161.012886)
		(mid 21.392255 -161.142443)
		(end 21.461222 -161.252662)
		(stroke
			(width 0.0508)
			(type default)
		)
		(layer "In5.Cu")
	)
	(gr_arc
		(start 21.676868 -161.468308)
		(mid 21.787123 -161.537144)
		(end 21.916644 -161.548064)
		(stroke
			(width 0.0508)
			(type default)
		)
		(layer "In5.Cu")
	)
	(gr_line
		(start 21.678392 -161.937192)
		(end 22.062694 -162.321494)
		(stroke
			(width 0.0508)
			(type default)
		)
		(layer "In5.Cu")
	)
	(gr_arc
		(start 22.025102 -114.921538)
		(mid 22.094099 -114.811319)
		(end 22.105112 -114.681762)
		(stroke
			(width 0.0508)
			(type default)
		)
		(layer "In5.Cu")
	)
	(gr_arc
		(start 22.15642 -161.628074)
		(mid 22.046196 -161.559115)
		(end 21.916644 -161.548064)
		(stroke
			(width 0.0508)
			(type default)
		)
		(layer "In5.Cu")
	)
	(gr_line
		(start 22.15642 -161.628074)
		(end 22.371812 -161.843466)
		(stroke
			(width 0.0508)
			(type default)
		)
		(layer "In5.Cu")
	)
	(gr_arc
		(start 22.185122 -114.441986)
		(mid 22.116162 -114.552214)
		(end 22.105112 -114.681762)
		(stroke
			(width 0.0508)
			(type default)
		)
		(layer "In5.Cu")
	)
	(gr_line
		(start 22.185122 -114.441986)
		(end 22.400514 -114.22634)
		(stroke
			(width 0.0508)
			(type default)
		)
		(layer "In5.Cu")
	)
	(gr_arc
		(start 22.451822 -162.083242)
		(mid 22.440754 -161.953697)
		(end 22.371812 -161.843466)
		(stroke
			(width 0.0508)
			(type default)
		)
		(layer "In5.Cu")
	)
	(gr_arc
		(start 22.451822 -162.083242)
		(mid 22.462739 -162.212764)
		(end 22.531578 -162.323018)
		(stroke
			(width 0.0508)
			(type default)
		)
		(layer "In5.Cu")
	)
	(gr_line
		(start 22.493986 -114.920014)
		(end 23.086314 -114.327686)
		(stroke
			(width 0.0508)
			(type default)
		)
		(layer "In5.Cu")
	)
	(gr_arc
		(start 22.64029 -114.146584)
		(mid 22.510759 -114.157489)
		(end 22.400514 -114.22634)
		(stroke
			(width 0.0508)
			(type default)
		)
		(layer "In5.Cu")
	)
	(gr_arc
		(start 22.64029 -114.146584)
		(mid 22.769835 -114.135534)
		(end 22.880066 -114.066574)
		(stroke
			(width 0.0508)
			(type default)
		)
		(layer "In5.Cu")
	)
	(gr_arc
		(start 22.747224 -162.538664)
		(mid 22.857454 -162.607598)
		(end 22.987 -162.618674)
		(stroke
			(width 0.0508)
			(type default)
		)
		(layer "In5.Cu")
	)
	(gr_line
		(start 22.748748 -163.007548)
		(end 23.133304 -163.392104)
		(stroke
			(width 0.0508)
			(type default)
		)
		(layer "In5.Cu")
	)
	(gr_arc
		(start 23.095712 -113.851182)
		(mid 23.164646 -113.740952)
		(end 23.175722 -113.611406)
		(stroke
			(width 0.0508)
			(type default)
		)
		(layer "In5.Cu")
	)
	(gr_arc
		(start 23.226776 -162.69843)
		(mid 23.116521 -162.629601)
		(end 22.987 -162.618674)
		(stroke
			(width 0.0508)
			(type default)
		)
		(layer "In5.Cu")
	)
	(gr_line
		(start 23.226776 -162.69843)
		(end 23.442168 -162.914076)
		(stroke
			(width 0.0508)
			(type default)
		)
		(layer "In5.Cu")
	)
	(gr_arc
		(start 23.255478 -113.37163)
		(mid 23.186665 -113.481887)
		(end 23.175722 -113.611406)
		(stroke
			(width 0.0508)
			(type default)
		)
		(layer "In5.Cu")
	)
	(gr_line
		(start 23.255478 -113.37163)
		(end 23.471124 -113.155984)
		(stroke
			(width 0.0508)
			(type default)
		)
		(layer "In5.Cu")
	)
	(gr_line
		(start 23.35784 -114.05616)
		(end 24.155654 -113.258346)
		(stroke
			(width 0.0508)
			(type default)
		)
		(layer "In5.Cu")
	)
	(gr_arc
		(start 23.522178 -163.153852)
		(mid 23.511182 -163.02428)
		(end 23.442168 -162.914076)
		(stroke
			(width 0.0508)
			(type default)
		)
		(layer "In5.Cu")
	)
	(gr_arc
		(start 23.522178 -163.153852)
		(mid 23.533228 -163.283397)
		(end 23.602188 -163.393628)
		(stroke
			(width 0.0508)
			(type default)
		)
		(layer "In5.Cu")
	)
	(gr_arc
		(start 23.7109 -113.076228)
		(mid 23.581369 -113.08713)
		(end 23.471124 -113.155984)
		(stroke
			(width 0.0508)
			(type default)
		)
		(layer "In5.Cu")
	)
	(gr_arc
		(start 23.7109 -113.076228)
		(mid 23.840457 -113.065185)
		(end 23.950676 -112.996218)
		(stroke
			(width 0.0508)
			(type default)
		)
		(layer "In5.Cu")
	)
	(gr_arc
		(start 24.166068 -112.780572)
		(mid 24.235065 -112.670353)
		(end 24.246078 -112.540796)
		(stroke
			(width 0.0508)
			(type default)
		)
		(layer "In5.Cu")
	)
	(gr_line
		(start 24.2316 -140.060426)
		(end 24.2316 -140.603986)
		(stroke
			(width 0.0508)
			(type default)
		)
		(layer "In5.Cu")
	)
	(gr_line
		(start 24.2316 -138.546586)
		(end 24.2316 -139.090146)
		(stroke
			(width 0.0508)
			(type default)
		)
		(layer "In5.Cu")
	)
	(gr_line
		(start 24.2316 -137.032746)
		(end 24.2316 -137.576306)
		(stroke
			(width 0.0508)
			(type default)
		)
		(layer "In5.Cu")
	)
	(gr_arc
		(start 24.326088 -112.30102)
		(mid 24.257126 -112.411246)
		(end 24.246078 -112.540796)
		(stroke
			(width 0.0508)
			(type default)
		)
		(layer "In5.Cu")
	)
	(gr_line
		(start 24.326088 -112.30102)
		(end 24.54148 -112.085628)
		(stroke
			(width 0.0508)
			(type default)
		)
		(layer "In5.Cu")
	)
	(gr_line
		(start 24.42718 -112.98682)
		(end 25.019254 -112.394746)
		(stroke
			(width 0.0508)
			(type default)
		)
		(layer "In5.Cu")
	)
	(gr_arc
		(start 24.5618 -139.727686)
		(mid 24.591039 -139.854347)
		(end 24.67483 -139.953746)
		(stroke
			(width 0.0508)
			(type default)
		)
		(layer "In5.Cu")
	)
	(gr_arc
		(start 24.5618 -138.213846)
		(mid 24.591039 -138.340507)
		(end 24.67483 -138.439906)
		(stroke
			(width 0.0508)
			(type default)
		)
		(layer "In5.Cu")
	)
	(gr_arc
		(start 24.5618 -136.700006)
		(mid 24.591039 -136.826667)
		(end 24.67483 -136.926066)
		(stroke
			(width 0.0508)
			(type default)
		)
		(layer "In5.Cu")
	)
	(gr_arc
		(start 24.67483 -140.710666)
		(mid 24.590993 -140.810042)
		(end 24.5618 -140.936726)
		(stroke
			(width 0.0508)
			(type default)
		)
		(layer "In5.Cu")
	)
	(gr_arc
		(start 24.67483 -140.710666)
		(mid 24.758645 -140.611279)
		(end 24.78786 -140.484606)
		(stroke
			(width 0.0508)
			(type default)
		)
		(layer "In5.Cu")
	)
	(gr_arc
		(start 24.67483 -139.196826)
		(mid 24.590993 -139.296202)
		(end 24.5618 -139.422886)
		(stroke
			(width 0.0508)
			(type default)
		)
		(layer "In5.Cu")
	)
	(gr_arc
		(start 24.67483 -139.196826)
		(mid 24.758631 -139.097436)
		(end 24.78786 -138.970766)
		(stroke
			(width 0.0508)
			(type default)
		)
		(layer "In5.Cu")
	)
	(gr_arc
		(start 24.67483 -137.682986)
		(mid 24.590993 -137.782362)
		(end 24.5618 -137.909046)
		(stroke
			(width 0.0508)
			(type default)
		)
		(layer "In5.Cu")
	)
	(gr_arc
		(start 24.67483 -137.682986)
		(mid 24.758616 -137.583593)
		(end 24.78786 -137.456926)
		(stroke
			(width 0.0508)
			(type default)
		)
		(layer "In5.Cu")
	)
	(gr_arc
		(start 24.781256 -112.005618)
		(mid 24.651705 -112.016679)
		(end 24.54148 -112.085628)
		(stroke
			(width 0.0508)
			(type default)
		)
		(layer "In5.Cu")
	)
	(gr_arc
		(start 24.781256 -112.005618)
		(mid 24.910778 -111.994701)
		(end 25.021032 -111.925862)
		(stroke
			(width 0.0508)
			(type default)
		)
		(layer "In5.Cu")
	)
	(gr_arc
		(start 24.78786 -140.179806)
		(mid 24.758648 -140.05313)
		(end 24.67483 -139.953746)
		(stroke
			(width 0.0508)
			(type default)
		)
		(layer "In5.Cu")
	)
	(gr_line
		(start 24.78786 -140.179806)
		(end 24.78786 -140.484606)
		(stroke
			(width 0.0508)
			(type default)
		)
		(layer "In5.Cu")
	)
	(gr_arc
		(start 24.78786 -138.665966)
		(mid 24.758669 -138.539273)
		(end 24.67483 -138.439906)
		(stroke
			(width 0.0508)
			(type default)
		)
		(layer "In5.Cu")
	)
	(gr_line
		(start 24.78786 -138.665966)
		(end 24.78786 -138.970766)
		(stroke
			(width 0.0508)
			(type default)
		)
		(layer "In5.Cu")
	)
	(gr_arc
		(start 24.78786 -137.152126)
		(mid 24.758655 -137.025445)
		(end 24.67483 -136.926066)
		(stroke
			(width 0.0508)
			(type default)
		)
		(layer "In5.Cu")
	)
	(gr_line
		(start 24.78786 -137.152126)
		(end 24.78786 -137.456926)
		(stroke
			(width 0.0508)
			(type default)
		)
		(layer "In5.Cu")
	)
	(gr_arc
		(start 27.098752 -109.848142)
		(mid 27.167588 -109.737887)
		(end 27.178508 -109.608366)
		(stroke
			(width 0.0508)
			(type default)
		)
		(layer "In5.Cu")
	)
	(gr_arc
		(start 27.258518 -109.36859)
		(mid 27.189577 -109.478816)
		(end 27.178508 -109.608366)
		(stroke
			(width 0.0508)
			(type default)
		)
		(layer "In5.Cu")
	)
	(gr_line
		(start 27.258518 -109.36859)
		(end 27.474164 -109.153198)
		(stroke
			(width 0.0508)
			(type default)
		)
		(layer "In5.Cu")
	)
	(gr_line
		(start 27.567636 -109.846364)
		(end 27.951938 -109.462062)
		(stroke
			(width 0.0508)
			(type default)
		)
		(layer "In5.Cu")
	)
	(gr_arc
		(start 27.71394 -109.073188)
		(mid 27.584369 -109.084188)
		(end 27.474164 -109.153198)
		(stroke
			(width 0.0508)
			(type default)
		)
		(layer "In5.Cu")
	)
	(gr_arc
		(start 27.71394 -109.073188)
		(mid 27.843485 -109.062138)
		(end 27.953716 -108.993178)
		(stroke
			(width 0.0508)
			(type default)
		)
		(layer "In5.Cu")
	)
	(gr_arc
		(start 28.169108 -108.777786)
		(mid 28.238042 -108.667556)
		(end 28.249118 -108.53801)
		(stroke
			(width 0.0508)
			(type default)
		)
		(layer "In5.Cu")
	)
	(gr_arc
		(start 28.328874 -108.298234)
		(mid 28.260063 -108.408492)
		(end 28.249118 -108.53801)
		(stroke
			(width 0.0508)
			(type default)
		)
		(layer "In5.Cu")
	)
	(gr_line
		(start 28.328874 -108.298234)
		(end 28.54452 -108.082588)
		(stroke
			(width 0.0508)
			(type default)
		)
		(layer "In5.Cu")
	)
	(gr_line
		(start 28.637992 -108.776008)
		(end 29.022294 -108.391706)
		(stroke
			(width 0.0508)
			(type default)
		)
		(layer "In5.Cu")
	)
	(gr_arc
		(start 28.784296 -108.002832)
		(mid 28.654766 -108.013735)
		(end 28.54452 -108.082588)
		(stroke
			(width 0.0508)
			(type default)
		)
		(layer "In5.Cu")
	)
	(gr_arc
		(start 28.784296 -108.002832)
		(mid 28.913853 -107.991789)
		(end 29.024072 -107.922822)
		(stroke
			(width 0.0508)
			(type default)
		)
		(layer "In5.Cu")
	)
	(gr_arc
		(start 29.239464 -107.70743)
		(mid 29.308461 -107.597211)
		(end 29.319474 -107.467654)
		(stroke
			(width 0.0508)
			(type default)
		)
		(layer "In5.Cu")
	)
	(gr_arc
		(start 29.399484 -107.227878)
		(mid 29.330506 -107.338103)
		(end 29.319474 -107.467654)
		(stroke
			(width 0.0508)
			(type default)
		)
		(layer "In5.Cu")
	)
	(gr_line
		(start 29.399484 -107.227878)
		(end 29.614876 -107.012232)
		(stroke
			(width 0.0508)
			(type default)
		)
		(layer "In5.Cu")
	)
	(gr_line
		(start 29.708348 -107.705652)
		(end 30.09265 -107.32135)
		(stroke
			(width 0.0508)
			(type default)
		)
		(layer "In5.Cu")
	)
	(gr_arc
		(start 29.854652 -106.932222)
		(mid 29.725102 -106.943284)
		(end 29.614876 -107.012232)
		(stroke
			(width 0.0508)
			(type default)
		)
		(layer "In5.Cu")
	)
	(gr_arc
		(start 29.854652 -106.932222)
		(mid 29.984174 -106.921305)
		(end 30.094428 -106.852466)
		(stroke
			(width 0.0508)
			(type default)
		)
		(layer "In5.Cu")
	)
	(gr_line
		(start 32.334454 -90.096086)
		(end 32.349948 -90.11158)
		(stroke
			(width 0.0508)
			(type default)
		)
		(layer "In5.Cu")
	)
	(gr_arc
		(start 32.6898 -90.932)
		(mid 32.60148 -90.487983)
		(end 32.349948 -90.11158)
		(stroke
			(width 0.0508)
			(type default)
		)
		(layer "In5.Cu")
	)
	(gr_line
		(start 33.02 -90.477086)
		(end 33.02 -90.890852)
		(stroke
			(width 0.0508)
			(type default)
		)
		(layer "In5.Cu")
	)
	(gr_arc
		(start 33.049972 -90.325956)
		(mid 33.027568 -90.400048)
		(end 33.02 -90.477086)
		(stroke
			(width 0.0508)
			(type default)
		)
		(layer "In5.Cu")
	)
	(gr_line
		(start 33.049972 -90.325956)
		(end 33.093914 -90.219784)
		(stroke
			(width 0.0508)
			(type default)
		)
		(layer "In5.Cu")
	)
	(gr_arc
		(start 33.27908 -90.096086)
		(mid 33.167744 -90.129858)
		(end 33.093914 -90.219784)
		(stroke
			(width 0.0508)
			(type default)
		)
		(layer "In5.Cu")
	)
	(gr_line
		(start 33.27908 -90.096086)
		(end 33.311338 -90.096086)
		(stroke
			(width 0.0508)
			(type default)
		)
		(layer "In5.Cu")
	)
	(gr_line
		(start 35.382454 -90.096086)
		(end 35.65779 -90.371422)
		(stroke
			(width 0.0508)
			(type default)
		)
		(layer "In5.Cu")
	)
	(gr_arc
		(start 35.7378 -90.564716)
		(mid 35.717011 -90.460113)
		(end 35.65779 -90.371422)
		(stroke
			(width 0.0508)
			(type default)
		)
		(layer "In5.Cu")
	)
	(gr_arc
		(start 36.181284 -90.20937)
		(mid 36.097494 -90.334631)
		(end 36.068 -90.48242)
		(stroke
			(width 0.0508)
			(type default)
		)
		(layer "In5.Cu")
	)
	(gr_line
		(start 36.181284 -90.20937)
		(end 36.2712 -90.1192)
		(stroke
			(width 0.0508)
			(type default)
		)
		(layer "In5.Cu")
	)
	(gr_arc
		(start 36.326826 -90.096086)
		(mid 36.296708 -90.102095)
		(end 36.2712 -90.1192)
		(stroke
			(width 0.0508)
			(type default)
		)
		(layer "In5.Cu")
	)
	(gr_line
		(start 36.326826 -90.096086)
		(end 36.359338 -90.096086)
		(stroke
			(width 0.0508)
			(type default)
		)
		(layer "In5.Cu")
	)
	(gr_line
		(start 38.430454 -90.096086)
		(end 38.57879 -90.244422)
		(stroke
			(width 0.0508)
			(type default)
		)
		(layer "In5.Cu")
	)
	(gr_arc
		(start 38.6588 -90.437716)
		(mid 38.637992 -90.333123)
		(end 38.57879 -90.244422)
		(stroke
			(width 0.0508)
			(type default)
		)
		(layer "In5.Cu")
	)
	(gr_arc
		(start 39.014908 -90.488516)
		(mid 38.995712 -90.517173)
		(end 38.989 -90.551)
		(stroke
			(width 0.0508)
			(type default)
		)
		(layer "In5.Cu")
	)
	(gr_line
		(start 39.014908 -90.488516)
		(end 39.407338 -90.096086)
		(stroke
			(width 0.0508)
			(type default)
		)
		(layer "In5.Cu")
	)
	(gr_line
		(start 41.351454 -90.096086)
		(end 41.49979 -90.244422)
		(stroke
			(width 0.0508)
			(type default)
		)
		(layer "In5.Cu")
	)
	(gr_arc
		(start 41.5798 -90.437716)
		(mid 41.558992 -90.333123)
		(end 41.49979 -90.244422)
		(stroke
			(width 0.0508)
			(type default)
		)
		(layer "In5.Cu")
	)
	(gr_line
		(start 41.693338 -83.489546)
		(end 41.848786 -83.644994)
		(stroke
			(width 0.0508)
			(type default)
		)
		(layer "In5.Cu")
	)
	(gr_arc
		(start 41.935908 -90.488516)
		(mid 41.916712 -90.517173)
		(end 41.91 -90.551)
		(stroke
			(width 0.0508)
			(type default)
		)
		(layer "In5.Cu")
	)
	(gr_line
		(start 41.935908 -90.488516)
		(end 42.328338 -90.096086)
		(stroke
			(width 0.0508)
			(type default)
		)
		(layer "In5.Cu")
	)
	(gr_arc
		(start 41.9608 -83.915504)
		(mid 41.931703 -83.769109)
		(end 41.848786 -83.644994)
		(stroke
			(width 0.0508)
			(type default)
		)
		(layer "In5.Cu")
	)
	(gr_line
		(start 42.048684 -101.10216)
		(end 42.048684 -101.64572)
		(stroke
			(width 0.0508)
			(type default)
		)
		(layer "In5.Cu")
	)
	(gr_line
		(start 42.048684 -99.58832)
		(end 42.048684 -100.13188)
		(stroke
			(width 0.0508)
			(type default)
		)
		(layer "In5.Cu")
	)
	(gr_arc
		(start 42.378884 -100.76942)
		(mid 42.408123 -100.896081)
		(end 42.491914 -100.99548)
		(stroke
			(width 0.0508)
			(type default)
		)
		(layer "In5.Cu")
	)
	(gr_arc
		(start 42.378884 -99.25558)
		(mid 42.408123 -99.382241)
		(end 42.491914 -99.48164)
		(stroke
			(width 0.0508)
			(type default)
		)
		(layer "In5.Cu")
	)
	(gr_arc
		(start 42.47134 -83.589114)
		(mid 42.337894 -83.78845)
		(end 42.291 -84.023708)
		(stroke
			(width 0.0508)
			(type default)
		)
		(layer "In5.Cu")
	)
	(gr_line
		(start 42.47134 -83.589114)
		(end 42.500804 -83.55965)
		(stroke
			(width 0.0508)
			(type default)
		)
		(layer "In5.Cu")
	)
	(gr_arc
		(start 42.491914 -101.7524)
		(mid 42.408077 -101.851776)
		(end 42.378884 -101.97846)
		(stroke
			(width 0.0508)
			(type default)
		)
		(layer "In5.Cu")
	)
	(gr_arc
		(start 42.491914 -101.7524)
		(mid 42.575681 -101.653001)
		(end 42.604944 -101.52634)
		(stroke
			(width 0.0508)
			(type default)
		)
		(layer "In5.Cu")
	)
	(gr_arc
		(start 42.491914 -100.23856)
		(mid 42.408077 -100.337936)
		(end 42.378884 -100.46462)
		(stroke
			(width 0.0508)
			(type default)
		)
		(layer "In5.Cu")
	)
	(gr_arc
		(start 42.491914 -100.23856)
		(mid 42.575703 -100.139165)
		(end 42.604944 -100.0125)
		(stroke
			(width 0.0508)
			(type default)
		)
		(layer "In5.Cu")
	)
	(gr_arc
		(start 42.604944 -101.22154)
		(mid 42.575743 -101.094856)
		(end 42.491914 -100.99548)
		(stroke
			(width 0.0508)
			(type default)
		)
		(layer "In5.Cu")
	)
	(gr_line
		(start 42.604944 -101.22154)
		(end 42.604944 -101.52634)
		(stroke
			(width 0.0508)
			(type default)
		)
		(layer "In5.Cu")
	)
	(gr_arc
		(start 42.604944 -99.7077)
		(mid 42.575728 -99.581028)
		(end 42.491914 -99.48164)
		(stroke
			(width 0.0508)
			(type default)
		)
		(layer "In5.Cu")
	)
	(gr_line
		(start 42.604944 -99.7077)
		(end 42.604944 -100.0125)
		(stroke
			(width 0.0508)
			(type default)
		)
		(layer "In5.Cu")
	)
	(gr_arc
		(start 42.669968 -83.489546)
		(mid 42.578429 -83.507812)
		(end 42.500804 -83.55965)
		(stroke
			(width 0.0508)
			(type default)
		)
		(layer "In5.Cu")
	)
	(gr_line
		(start 42.669968 -83.489546)
		(end 42.670222 -83.489546)
		(stroke
			(width 0.0508)
			(type default)
		)
		(layer "In5.Cu")
	)
	(gr_line
		(start 44.647104 -83.502246)
		(end 44.940728 -83.79587)
		(stroke
			(width 0.0508)
			(type default)
		)
		(layer "In5.Cu")
	)
	(gr_arc
		(start 44.970446 -83.867752)
		(mid 44.962717 -83.828862)
		(end 44.940728 -83.79587)
		(stroke
			(width 0.0508)
			(type default)
		)
		(layer "In5.Cu")
	)
	(gr_line
		(start 44.970446 -83.867752)
		(end 44.970446 -83.969352)
		(stroke
			(width 0.0508)
			(type default)
		)
		(layer "In5.Cu")
	)
	(gr_line
		(start 45.2882 -84.118704)
		(end 45.2882 -84.299552)
		(stroke
			(width 0.0508)
			(type default)
		)
		(layer "In5.Cu")
	)
	(gr_arc
		(start 45.330364 -83.79587)
		(mid 45.308381 -83.828864)
		(end 45.300646 -83.867752)
		(stroke
			(width 0.0508)
			(type default)
		)
		(layer "In5.Cu")
	)
	(gr_line
		(start 45.330364 -83.79587)
		(end 45.623988 -83.502246)
		(stroke
			(width 0.0508)
			(type default)
		)
		(layer "In5.Cu")
	)
	(gr_arc
		(start 47.551848 -163.9316)
		(mid 47.66207 -164.000578)
		(end 47.791624 -164.01161)
		(stroke
			(width 0.0508)
			(type default)
		)
		(layer "In5.Cu")
	)
	(gr_line
		(start 47.553626 -164.400484)
		(end 47.937928 -164.784786)
		(stroke
			(width 0.0508)
			(type default)
		)
		(layer "In5.Cu")
	)
	(gr_arc
		(start 48.0314 -164.091366)
		(mid 47.921145 -164.02253)
		(end 47.791624 -164.01161)
		(stroke
			(width 0.0508)
			(type default)
		)
		(layer "In5.Cu")
	)
	(gr_line
		(start 48.0314 -164.091366)
		(end 48.246792 -164.307012)
		(stroke
			(width 0.0508)
			(type default)
		)
		(layer "In5.Cu")
	)
	(gr_arc
		(start 48.326802 -164.546788)
		(mid 48.315752 -164.417243)
		(end 48.246792 -164.307012)
		(stroke
			(width 0.0508)
			(type default)
		)
		(layer "In5.Cu")
	)
	(gr_arc
		(start 48.326802 -164.546788)
		(mid 48.337814 -164.676351)
		(end 48.406812 -164.786564)
		(stroke
			(width 0.0508)
			(type default)
		)
		(layer "In5.Cu")
	)
	(gr_arc
		(start 48.622204 -165.001956)
		(mid 48.732431 -165.070914)
		(end 48.86198 -165.081966)
		(stroke
			(width 0.0508)
			(type default)
		)
		(layer "In5.Cu")
	)
	(gr_line
		(start 48.623982 -165.47084)
		(end 49.008284 -165.855142)
		(stroke
			(width 0.0508)
			(type default)
		)
		(layer "In5.Cu")
	)
	(gr_arc
		(start 49.008538 -161.952178)
		(mid 49.072837 -162.000979)
		(end 49.148492 -162.02914)
		(stroke
			(width 0.0508)
			(type default)
		)
		(layer "In5.Cu")
	)
	(gr_line
		(start 49.010062 -162.421062)
		(end 49.394618 -162.805618)
		(stroke
			(width 0.0508)
			(type default)
		)
		(layer "In5.Cu")
	)
	(gr_arc
		(start 49.101756 -165.161976)
		(mid 48.991537 -165.092979)
		(end 48.86198 -165.081966)
		(stroke
			(width 0.0508)
			(type default)
		)
		(layer "In5.Cu")
	)
	(gr_line
		(start 49.101756 -165.161976)
		(end 49.317402 -165.377368)
		(stroke
			(width 0.0508)
			(type default)
		)
		(layer "In5.Cu")
	)
	(gr_arc
		(start 49.148492 -162.02914)
		(mid 49.198264 -162.035216)
		(end 49.248314 -162.032188)
		(stroke
			(width 0.0508)
			(type default)
		)
		(layer "In5.Cu")
	)
	(gr_arc
		(start 49.397158 -165.617144)
		(mid 49.386241 -165.487622)
		(end 49.317402 -165.377368)
		(stroke
			(width 0.0508)
			(type default)
		)
		(layer "In5.Cu")
	)
	(gr_arc
		(start 49.397158 -165.617144)
		(mid 49.40822 -165.746693)
		(end 49.477168 -165.85692)
		(stroke
			(width 0.0508)
			(type default)
		)
		(layer "In5.Cu")
	)
	(gr_arc
		(start 49.48809 -162.112198)
		(mid 49.377871 -162.043201)
		(end 49.248314 -162.032188)
		(stroke
			(width 0.0508)
			(type default)
		)
		(layer "In5.Cu")
	)
	(gr_line
		(start 49.48809 -162.112198)
		(end 49.703736 -162.32759)
		(stroke
			(width 0.0508)
			(type default)
		)
		(layer "In5.Cu")
	)
	(gr_arc
		(start 49.783492 -162.567366)
		(mid 49.772575 -162.437844)
		(end 49.703736 -162.32759)
		(stroke
			(width 0.0508)
			(type default)
		)
		(layer "In5.Cu")
	)
	(gr_arc
		(start 49.783492 -162.567366)
		(mid 49.794564 -162.696908)
		(end 49.863502 -162.807142)
		(stroke
			(width 0.0508)
			(type default)
		)
		(layer "In5.Cu")
	)
	(gr_arc
		(start 50.079148 -163.022788)
		(mid 50.189402 -163.091644)
		(end 50.318924 -163.102544)
		(stroke
			(width 0.0508)
			(type default)
		)
		(layer "In5.Cu")
	)
	(gr_line
		(start 50.080672 -163.491672)
		(end 50.465228 -163.876228)
		(stroke
			(width 0.0508)
			(type default)
		)
		(layer "In5.Cu")
	)
	(gr_arc
		(start 50.25136 -160.274)
		(mid 50.361579 -160.342997)
		(end 50.491136 -160.35401)
		(stroke
			(width 0.0508)
			(type default)
		)
		(layer "In5.Cu")
	)
	(gr_line
		(start 50.252884 -160.742884)
		(end 50.63744 -161.12744)
		(stroke
			(width 0.0508)
			(type default)
		)
		(layer "In5.Cu")
	)
	(gr_line
		(start 50.511456 -82.117438)
		(end 50.695098 -82.30108)
		(stroke
			(width 0.0508)
			(type default)
		)
		(layer "In5.Cu")
	)
	(gr_arc
		(start 50.5587 -163.182554)
		(mid 50.44847 -163.11362)
		(end 50.318924 -163.102544)
		(stroke
			(width 0.0508)
			(type default)
		)
		(layer "In5.Cu")
	)
	(gr_line
		(start 50.5587 -163.182554)
		(end 50.774092 -163.3982)
		(stroke
			(width 0.0508)
			(type default)
		)
		(layer "In5.Cu")
	)
	(gr_arc
		(start 50.730912 -160.43402)
		(mid 50.620688 -160.365037)
		(end 50.491136 -160.35401)
		(stroke
			(width 0.0508)
			(type default)
		)
		(layer "In5.Cu")
	)
	(gr_line
		(start 50.730912 -160.43402)
		(end 50.946558 -160.649412)
		(stroke
			(width 0.0508)
			(type default)
		)
		(layer "In5.Cu")
	)
	(gr_line
		(start 50.8508 -88.900254)
		(end 50.8508 -89.443814)
		(stroke
			(width 0.0508)
			(type default)
		)
		(layer "In5.Cu")
	)
	(gr_line
		(start 50.8508 -86.738968)
		(end 50.8508 -87.282528)
		(stroke
			(width 0.0508)
			(type default)
		)
		(layer "In5.Cu")
	)
	(gr_line
		(start 50.8508 -85.225128)
		(end 50.8508 -85.768688)
		(stroke
			(width 0.0508)
			(type default)
		)
		(layer "In5.Cu")
	)
	(gr_line
		(start 50.8508 -83.711288)
		(end 50.8508 -84.254848)
		(stroke
			(width 0.0508)
			(type default)
		)
		(layer "In5.Cu")
	)
	(gr_arc
		(start 50.8508 -82.677)
		(mid 50.810331 -82.473558)
		(end 50.695098 -82.30108)
		(stroke
			(width 0.0508)
			(type default)
		)
		(layer "In5.Cu")
	)
	(gr_arc
		(start 50.854102 -163.637976)
		(mid 50.843052 -163.508431)
		(end 50.774092 -163.3982)
		(stroke
			(width 0.0508)
			(type default)
		)
		(layer "In5.Cu")
	)
	(gr_arc
		(start 50.854102 -163.637976)
		(mid 50.865109 -163.767542)
		(end 50.934112 -163.877752)
		(stroke
			(width 0.0508)
			(type default)
		)
		(layer "In5.Cu")
	)
	(gr_arc
		(start 51.026568 -160.889188)
		(mid 51.015479 -160.759654)
		(end 50.946558 -160.649412)
		(stroke
			(width 0.0508)
			(type default)
		)
		(layer "In5.Cu")
	)
	(gr_arc
		(start 51.026568 -160.889188)
		(mid 51.037485 -161.01871)
		(end 51.106324 -161.128964)
		(stroke
			(width 0.0508)
			(type default)
		)
		(layer "In5.Cu")
	)
	(gr_arc
		(start 51.181 -88.567514)
		(mid 51.210239 -88.694175)
		(end 51.29403 -88.793574)
		(stroke
			(width 0.0508)
			(type default)
		)
		(layer "In5.Cu")
	)
	(gr_arc
		(start 51.181 -86.406228)
		(mid 51.210239 -86.532889)
		(end 51.29403 -86.632288)
		(stroke
			(width 0.0508)
			(type default)
		)
		(layer "In5.Cu")
	)
	(gr_arc
		(start 51.181 -84.892388)
		(mid 51.210239 -85.019049)
		(end 51.29403 -85.118448)
		(stroke
			(width 0.0508)
			(type default)
		)
		(layer "In5.Cu")
	)
	(gr_arc
		(start 51.181 -83.378548)
		(mid 51.210239 -83.505209)
		(end 51.29403 -83.604608)
		(stroke
			(width 0.0508)
			(type default)
		)
		(layer "In5.Cu")
	)
	(gr_arc
		(start 51.29403 -89.550494)
		(mid 51.210193 -89.64987)
		(end 51.181 -89.776554)
		(stroke
			(width 0.0508)
			(type default)
		)
		(layer "In5.Cu")
	)
	(gr_arc
		(start 51.29403 -89.550494)
		(mid 51.377819 -89.451102)
		(end 51.40706 -89.324434)
		(stroke
			(width 0.0508)
			(type default)
		)
		(layer "In5.Cu")
	)
	(gr_arc
		(start 51.29403 -87.389208)
		(mid 51.210193 -87.488584)
		(end 51.181 -87.615268)
		(stroke
			(width 0.0508)
			(type default)
		)
		(layer "In5.Cu")
	)
	(gr_arc
		(start 51.29403 -87.389208)
		(mid 51.377824 -87.289817)
		(end 51.40706 -87.163148)
		(stroke
			(width 0.0508)
			(type default)
		)
		(layer "In5.Cu")
	)
	(gr_arc
		(start 51.29403 -85.875368)
		(mid 51.210193 -85.974744)
		(end 51.181 -86.101428)
		(stroke
			(width 0.0508)
			(type default)
		)
		(layer "In5.Cu")
	)
	(gr_arc
		(start 51.29403 -85.875368)
		(mid 51.377846 -85.775981)
		(end 51.40706 -85.649308)
		(stroke
			(width 0.0508)
			(type default)
		)
		(layer "In5.Cu")
	)
	(gr_arc
		(start 51.29403 -84.361528)
		(mid 51.210193 -84.460904)
		(end 51.181 -84.587588)
		(stroke
			(width 0.0508)
			(type default)
		)
		(layer "In5.Cu")
	)
	(gr_arc
		(start 51.29403 -84.361528)
		(mid 51.377832 -84.262138)
		(end 51.40706 -84.135468)
		(stroke
			(width 0.0508)
			(type default)
		)
		(layer "In5.Cu")
	)
	(gr_arc
		(start 51.359308 -82.24647)
		(mid 51.227323 -82.443999)
		(end 51.181 -82.677)
		(stroke
			(width 0.0508)
			(type default)
		)
		(layer "In5.Cu")
	)
	(gr_line
		(start 51.359308 -82.24647)
		(end 51.48834 -82.117438)
		(stroke
			(width 0.0508)
			(type default)
		)
		(layer "In5.Cu")
	)
	(gr_arc
		(start 51.40706 -89.019634)
		(mid 51.377858 -88.89295)
		(end 51.29403 -88.793574)
		(stroke
			(width 0.0508)
			(type default)
		)
		(layer "In5.Cu")
	)
	(gr_line
		(start 51.40706 -89.019634)
		(end 51.40706 -89.324434)
		(stroke
			(width 0.0508)
			(type default)
		)
		(layer "In5.Cu")
	)
	(gr_arc
		(start 51.40706 -86.858348)
		(mid 51.377863 -86.73166)
		(end 51.29403 -86.632288)
		(stroke
			(width 0.0508)
			(type default)
		)
		(layer "In5.Cu")
	)
	(gr_line
		(start 51.40706 -86.858348)
		(end 51.40706 -87.163148)
		(stroke
			(width 0.0508)
			(type default)
		)
		(layer "In5.Cu")
	)
	(gr_arc
		(start 51.40706 -85.344508)
		(mid 51.377848 -85.217832)
		(end 51.29403 -85.118448)
		(stroke
			(width 0.0508)
			(type default)
		)
		(layer "In5.Cu")
	)
	(gr_line
		(start 51.40706 -85.344508)
		(end 51.40706 -85.649308)
		(stroke
			(width 0.0508)
			(type default)
		)
		(layer "In5.Cu")
	)
	(gr_arc
		(start 51.40706 -83.830668)
		(mid 51.37787 -83.703974)
		(end 51.29403 -83.604608)
		(stroke
			(width 0.0508)
			(type default)
		)
		(layer "In5.Cu")
	)
	(gr_line
		(start 51.40706 -83.830668)
		(end 51.40706 -84.135468)
		(stroke
			(width 0.0508)
			(type default)
		)
		(layer "In5.Cu")
	)
	(gr_line
		(start 52.917852 -82.117438)
		(end 53.023008 -82.222594)
		(stroke
			(width 0.0508)
			(type default)
		)
		(layer "In5.Cu")
	)
	(gr_line
		(start 53.2638 -86.10473)
		(end 53.2638 -86.64829)
		(stroke
			(width 0.0508)
			(type default)
		)
		(layer "In5.Cu")
	)
	(gr_line
		(start 53.2638 -84.59089)
		(end 53.2638 -85.13445)
		(stroke
			(width 0.0508)
			(type default)
		)
		(layer "In5.Cu")
	)
	(gr_arc
		(start 53.2638 -82.804)
		(mid 53.201235 -82.489348)
		(end 53.023008 -82.222594)
		(stroke
			(width 0.0508)
			(type default)
		)
		(layer "In5.Cu")
	)
	(gr_arc
		(start 53.594 -85.77199)
		(mid 53.623239 -85.898651)
		(end 53.70703 -85.99805)
		(stroke
			(width 0.0508)
			(type default)
		)
		(layer "In5.Cu")
	)
	(gr_arc
		(start 53.594 -84.25815)
		(mid 53.623239 -84.384811)
		(end 53.70703 -84.48421)
		(stroke
			(width 0.0508)
			(type default)
		)
		(layer "In5.Cu")
	)
	(gr_arc
		(start 53.70703 -86.75497)
		(mid 53.623193 -86.854346)
		(end 53.594 -86.98103)
		(stroke
			(width 0.0508)
			(type default)
		)
		(layer "In5.Cu")
	)
	(gr_arc
		(start 53.70703 -86.75497)
		(mid 53.790847 -86.655584)
		(end 53.82006 -86.52891)
		(stroke
			(width 0.0508)
			(type default)
		)
		(layer "In5.Cu")
	)
	(gr_arc
		(start 53.70703 -85.24113)
		(mid 53.623193 -85.340506)
		(end 53.594 -85.46719)
		(stroke
			(width 0.0508)
			(type default)
		)
		(layer "In5.Cu")
	)
	(gr_arc
		(start 53.70703 -85.24113)
		(mid 53.790832 -85.141741)
		(end 53.82006 -85.01507)
		(stroke
			(width 0.0508)
			(type default)
		)
		(layer "In5.Cu")
	)
	(gr_arc
		(start 53.76799 -82.177382)
		(mid 53.639316 -82.364385)
		(end 53.594 -82.58683)
		(stroke
			(width 0.0508)
			(type default)
		)
		(layer "In5.Cu")
	)
	(gr_line
		(start 53.76799 -82.177382)
		(end 53.793898 -82.15249)
		(stroke
			(width 0.0508)
			(type default)
		)
		(layer "In5.Cu")
	)
	(gr_arc
		(start 53.82006 -86.22411)
		(mid 53.790849 -86.097433)
		(end 53.70703 -85.99805)
		(stroke
			(width 0.0508)
			(type default)
		)
		(layer "In5.Cu")
	)
	(gr_line
		(start 53.82006 -86.22411)
		(end 53.82006 -86.52891)
		(stroke
			(width 0.0508)
			(type default)
		)
		(layer "In5.Cu")
	)
	(gr_arc
		(start 53.82006 -84.71027)
		(mid 53.790871 -84.583576)
		(end 53.70703 -84.48421)
		(stroke
			(width 0.0508)
			(type default)
		)
		(layer "In5.Cu")
	)
	(gr_line
		(start 53.82006 -84.71027)
		(end 53.82006 -85.01507)
		(stroke
			(width 0.0508)
			(type default)
		)
		(layer "In5.Cu")
	)
	(gr_arc
		(start 53.880766 -82.117438)
		(mid 53.833926 -82.126528)
		(end 53.793898 -82.15249)
		(stroke
			(width 0.0508)
			(type default)
		)
		(layer "In5.Cu")
	)
	(gr_line
		(start 53.880766 -82.117438)
		(end 53.882036 -82.117438)
		(stroke
			(width 0.0508)
			(type default)
		)
		(layer "In5.Cu")
	)
	(gr_line
		(start 83.01736 -52.266088)
		(end 83.01736 -52.809648)
		(stroke
			(width 0.0508)
			(type default)
		)
		(layer "In5.Cu")
	)
	(gr_line
		(start 83.01736 -50.752248)
		(end 83.01736 -51.295808)
		(stroke
			(width 0.0508)
			(type default)
		)
		(layer "In5.Cu")
	)
	(gr_line
		(start 83.01736 -49.238408)
		(end 83.01736 -49.781968)
		(stroke
			(width 0.0508)
			(type default)
		)
		(layer "In5.Cu")
	)
	(gr_line
		(start 83.01736 -44.845224)
		(end 83.01736 -45.388784)
		(stroke
			(width 0.0508)
			(type default)
		)
		(layer "In5.Cu")
	)
	(gr_arc
		(start 83.34756 -51.933348)
		(mid 83.376757 -52.060035)
		(end 83.46059 -52.159408)
		(stroke
			(width 0.0508)
			(type default)
		)
		(layer "In5.Cu")
	)
	(gr_arc
		(start 83.34756 -50.419508)
		(mid 83.376742 -50.546207)
		(end 83.46059 -50.645568)
		(stroke
			(width 0.0508)
			(type default)
		)
		(layer "In5.Cu")
	)
	(gr_arc
		(start 83.34756 -48.905668)
		(mid 83.376764 -49.032349)
		(end 83.46059 -49.131728)
		(stroke
			(width 0.0508)
			(type default)
		)
		(layer "In5.Cu")
	)
	(gr_arc
		(start 83.34756 -44.512484)
		(mid 83.37677 -44.639161)
		(end 83.46059 -44.738544)
		(stroke
			(width 0.0508)
			(type default)
		)
		(layer "In5.Cu")
	)
	(gr_arc
		(start 83.46059 -52.916328)
		(mid 83.376832 -53.015729)
		(end 83.34756 -53.142388)
		(stroke
			(width 0.0508)
			(type default)
		)
		(layer "In5.Cu")
	)
	(gr_arc
		(start 83.46059 -52.916328)
		(mid 83.544427 -52.816952)
		(end 83.57362 -52.690268)
		(stroke
			(width 0.0508)
			(type default)
		)
		(layer "In5.Cu")
	)
	(gr_arc
		(start 83.46059 -51.402488)
		(mid 83.376818 -51.501886)
		(end 83.34756 -51.628548)
		(stroke
			(width 0.0508)
			(type default)
		)
		(layer "In5.Cu")
	)
	(gr_arc
		(start 83.46059 -51.402488)
		(mid 83.544427 -51.303112)
		(end 83.57362 -51.176428)
		(stroke
			(width 0.0508)
			(type default)
		)
		(layer "In5.Cu")
	)
	(gr_arc
		(start 83.46059 -49.888648)
		(mid 83.376803 -49.988043)
		(end 83.34756 -50.114708)
		(stroke
			(width 0.0508)
			(type default)
		)
		(layer "In5.Cu")
	)
	(gr_arc
		(start 83.46059 -49.888648)
		(mid 83.544427 -49.789272)
		(end 83.57362 -49.662588)
		(stroke
			(width 0.0508)
			(type default)
		)
		(layer "In5.Cu")
	)
	(gr_arc
		(start 83.46059 -45.495464)
		(mid 83.376809 -45.59486)
		(end 83.34756 -45.721524)
		(stroke
			(width 0.0508)
			(type default)
		)
		(layer "In5.Cu")
	)
	(gr_arc
		(start 83.46059 -45.495464)
		(mid 83.544427 -45.396088)
		(end 83.57362 -45.269404)
		(stroke
			(width 0.0508)
			(type default)
		)
		(layer "In5.Cu")
	)
	(gr_arc
		(start 83.57362 -52.385468)
		(mid 83.544381 -52.258807)
		(end 83.46059 -52.159408)
		(stroke
			(width 0.0508)
			(type default)
		)
		(layer "In5.Cu")
	)
	(gr_line
		(start 83.57362 -52.385468)
		(end 83.57362 -52.690268)
		(stroke
			(width 0.0508)
			(type default)
		)
		(layer "In5.Cu")
	)
	(gr_arc
		(start 83.57362 -50.871628)
		(mid 83.544381 -50.744967)
		(end 83.46059 -50.645568)
		(stroke
			(width 0.0508)
			(type default)
		)
		(layer "In5.Cu")
	)
	(gr_line
		(start 83.57362 -50.871628)
		(end 83.57362 -51.176428)
		(stroke
			(width 0.0508)
			(type default)
		)
		(layer "In5.Cu")
	)
	(gr_arc
		(start 83.57362 -49.357788)
		(mid 83.544381 -49.231127)
		(end 83.46059 -49.131728)
		(stroke
			(width 0.0508)
			(type default)
		)
		(layer "In5.Cu")
	)
	(gr_line
		(start 83.57362 -49.357788)
		(end 83.57362 -49.662588)
		(stroke
			(width 0.0508)
			(type default)
		)
		(layer "In5.Cu")
	)
	(gr_arc
		(start 83.57362 -44.964604)
		(mid 83.544381 -44.837943)
		(end 83.46059 -44.738544)
		(stroke
			(width 0.0508)
			(type default)
		)
		(layer "In5.Cu")
	)
	(gr_line
		(start 83.57362 -44.964604)
		(end 83.57362 -45.269404)
		(stroke
			(width 0.0508)
			(type default)
		)
		(layer "In5.Cu")
	)
	(gr_arc
		(start 84.748116 -55.95239)
		(mid 84.858372 -56.021217)
		(end 84.987892 -56.032146)
		(stroke
			(width 0.0508)
			(type default)
		)
		(layer "In5.Cu")
	)
	(gr_line
		(start 84.749894 -56.421274)
		(end 85.134196 -56.805576)
		(stroke
			(width 0.0508)
			(type default)
		)
		(layer "In5.Cu")
	)
	(gr_line
		(start 85.071966 -47.834296)
		(end 85.071966 -48.377856)
		(stroke
			(width 0.0508)
			(type default)
		)
		(layer "In5.Cu")
	)
	(gr_line
		(start 85.071966 -46.320456)
		(end 85.071966 -46.864016)
		(stroke
			(width 0.0508)
			(type default)
		)
		(layer "In5.Cu")
	)
	(gr_line
		(start 85.071966 -44.806616)
		(end 85.071966 -45.350176)
		(stroke
			(width 0.0508)
			(type default)
		)
		(layer "In5.Cu")
	)
	(gr_arc
		(start 85.227668 -56.112156)
		(mid 85.117438 -56.043222)
		(end 84.987892 -56.032146)
		(stroke
			(width 0.0508)
			(type default)
		)
		(layer "In5.Cu")
	)
	(gr_line
		(start 85.227668 -56.112156)
		(end 85.44306 -56.327802)
		(stroke
			(width 0.0508)
			(type default)
		)
		(layer "In5.Cu")
	)
	(gr_line
		(start 85.264752 -38.433502)
		(end 85.649308 -38.048946)
		(stroke
			(width 0.0508)
			(type default)
		)
		(layer "In5.Cu")
	)
	(gr_arc
		(start 85.402166 -47.501556)
		(mid 85.431405 -47.628217)
		(end 85.515196 -47.727616)
		(stroke
			(width 0.0508)
			(type default)
		)
		(layer "In5.Cu")
	)
	(gr_arc
		(start 85.402166 -45.987716)
		(mid 85.431405 -46.114377)
		(end 85.515196 -46.213776)
		(stroke
			(width 0.0508)
			(type default)
		)
		(layer "In5.Cu")
	)
	(gr_arc
		(start 85.402166 -44.473876)
		(mid 85.431405 -44.600537)
		(end 85.515196 -44.699936)
		(stroke
			(width 0.0508)
			(type default)
		)
		(layer "In5.Cu")
	)
	(gr_arc
		(start 85.503004 -38.82263)
		(mid 85.373472 -38.83353)
		(end 85.263228 -38.902386)
		(stroke
			(width 0.0508)
			(type default)
		)
		(layer "In5.Cu")
	)
	(gr_arc
		(start 85.503004 -38.82263)
		(mid 85.632561 -38.811587)
		(end 85.74278 -38.74262)
		(stroke
			(width 0.0508)
			(type default)
		)
		(layer "In5.Cu")
	)
	(gr_arc
		(start 85.515196 -48.484536)
		(mid 85.431359 -48.583912)
		(end 85.402166 -48.710596)
		(stroke
			(width 0.0508)
			(type default)
		)
		(layer "In5.Cu")
	)
	(gr_arc
		(start 85.515196 -48.484536)
		(mid 85.598981 -48.385141)
		(end 85.628226 -48.258476)
		(stroke
			(width 0.0508)
			(type default)
		)
		(layer "In5.Cu")
	)
	(gr_arc
		(start 85.515196 -46.970696)
		(mid 85.431359 -47.070072)
		(end 85.402166 -47.196756)
		(stroke
			(width 0.0508)
			(type default)
		)
		(layer "In5.Cu")
	)
	(gr_arc
		(start 85.515196 -46.970696)
		(mid 85.598967 -46.871298)
		(end 85.628226 -46.744636)
		(stroke
			(width 0.0508)
			(type default)
		)
		(layer "In5.Cu")
	)
	(gr_arc
		(start 85.515196 -45.456856)
		(mid 85.431359 -45.556232)
		(end 85.402166 -45.682916)
		(stroke
			(width 0.0508)
			(type default)
		)
		(layer "In5.Cu")
	)
	(gr_arc
		(start 85.515196 -45.456856)
		(mid 85.598988 -45.357462)
		(end 85.628226 -45.230796)
		(stroke
			(width 0.0508)
			(type default)
		)
		(layer "In5.Cu")
	)
	(gr_arc
		(start 85.52307 -56.567578)
		(mid 85.51202 -56.438033)
		(end 85.44306 -56.327802)
		(stroke
			(width 0.0508)
			(type default)
		)
		(layer "In5.Cu")
	)
	(gr_arc
		(start 85.52307 -56.567578)
		(mid 85.534077 -56.697145)
		(end 85.60308 -56.807354)
		(stroke
			(width 0.0508)
			(type default)
		)
		(layer "In5.Cu")
	)
	(gr_arc
		(start 85.628226 -47.953676)
		(mid 85.599044 -47.826974)
		(end 85.515196 -47.727616)
		(stroke
			(width 0.0508)
			(type default)
		)
		(layer "In5.Cu")
	)
	(gr_line
		(start 85.628226 -47.953676)
		(end 85.628226 -48.258476)
		(stroke
			(width 0.0508)
			(type default)
		)
		(layer "In5.Cu")
	)
	(gr_arc
		(start 85.628226 -46.439836)
		(mid 85.599029 -46.313146)
		(end 85.515196 -46.213776)
		(stroke
			(width 0.0508)
			(type default)
		)
		(layer "In5.Cu")
	)
	(gr_line
		(start 85.628226 -46.439836)
		(end 85.628226 -46.744636)
		(stroke
			(width 0.0508)
			(type default)
		)
		(layer "In5.Cu")
	)
	(gr_arc
		(start 85.628226 -44.925996)
		(mid 85.599051 -44.799288)
		(end 85.515196 -44.699936)
		(stroke
			(width 0.0508)
			(type default)
		)
		(layer "In5.Cu")
	)
	(gr_line
		(start 85.628226 -44.925996)
		(end 85.628226 -45.230796)
		(stroke
			(width 0.0508)
			(type default)
		)
		(layer "In5.Cu")
	)
	(gr_line
		(start 85.74278 -38.74262)
		(end 85.958172 -38.526974)
		(stroke
			(width 0.0508)
			(type default)
		)
		(layer "In5.Cu")
	)
	(gr_arc
		(start 85.818472 -57.022746)
		(mid 85.928696 -57.091703)
		(end 86.058248 -57.102756)
		(stroke
			(width 0.0508)
			(type default)
		)
		(layer "In5.Cu")
	)
	(gr_line
		(start 85.82025 -57.49163)
		(end 86.204552 -57.875932)
		(stroke
			(width 0.0508)
			(type default)
		)
		(layer "In5.Cu")
	)
	(gr_arc
		(start 85.958172 -38.526974)
		(mid 86.027169 -38.416755)
		(end 86.038182 -38.287198)
		(stroke
			(width 0.0508)
			(type default)
		)
		(layer "In5.Cu")
	)
	(gr_arc
		(start 86.118192 -38.047422)
		(mid 86.04923 -38.157648)
		(end 86.038182 -38.287198)
		(stroke
			(width 0.0508)
			(type default)
		)
		(layer "In5.Cu")
	)
	(gr_arc
		(start 86.298024 -57.182512)
		(mid 86.187769 -57.113676)
		(end 86.058248 -57.102756)
		(stroke
			(width 0.0508)
			(type default)
		)
		(layer "In5.Cu")
	)
	(gr_line
		(start 86.298024 -57.182512)
		(end 86.51367 -57.398158)
		(stroke
			(width 0.0508)
			(type default)
		)
		(layer "In5.Cu")
	)
	(gr_line
		(start 86.335108 -37.363146)
		(end 86.719664 -36.97859)
		(stroke
			(width 0.0508)
			(type default)
		)
		(layer "In5.Cu")
	)
	(gr_arc
		(start 86.57336 -37.75202)
		(mid 86.443808 -37.763079)
		(end 86.333584 -37.83203)
		(stroke
			(width 0.0508)
			(type default)
		)
		(layer "In5.Cu")
	)
	(gr_arc
		(start 86.57336 -37.75202)
		(mid 86.702882 -37.741103)
		(end 86.813136 -37.672264)
		(stroke
			(width 0.0508)
			(type default)
		)
		(layer "In5.Cu")
	)
	(gr_arc
		(start 86.593426 -57.637934)
		(mid 86.582509 -57.508412)
		(end 86.51367 -57.398158)
		(stroke
			(width 0.0508)
			(type default)
		)
		(layer "In5.Cu")
	)
	(gr_arc
		(start 86.593426 -57.637934)
		(mid 86.604483 -57.767487)
		(end 86.673436 -57.87771)
		(stroke
			(width 0.0508)
			(type default)
		)
		(layer "In5.Cu")
	)
	(gr_line
		(start 86.813136 -37.672264)
		(end 87.028782 -37.456618)
		(stroke
			(width 0.0508)
			(type default)
		)
		(layer "In5.Cu")
	)
	(gr_arc
		(start 86.888828 -58.093102)
		(mid 86.999054 -58.162063)
		(end 87.128604 -58.173112)
		(stroke
			(width 0.0508)
			(type default)
		)
		(layer "In5.Cu")
	)
	(gr_line
		(start 86.890606 -58.561986)
		(end 87.274908 -58.946288)
		(stroke
			(width 0.0508)
			(type default)
		)
		(layer "In5.Cu")
	)
	(gr_arc
		(start 87.028782 -37.456618)
		(mid 87.097618 -37.346363)
		(end 87.108538 -37.216842)
		(stroke
			(width 0.0508)
			(type default)
		)
		(layer "In5.Cu")
	)
	(gr_arc
		(start 87.188548 -36.977066)
		(mid 87.11959 -37.08729)
		(end 87.108538 -37.216842)
		(stroke
			(width 0.0508)
			(type default)
		)
		(layer "In5.Cu")
	)
	(gr_line
		(start 87.22868 -39.237412)
		(end 87.612982 -38.85311)
		(stroke
			(width 0.0508)
			(type default)
		)
		(layer "In5.Cu")
	)
	(gr_arc
		(start 87.36838 -58.253122)
		(mid 87.258161 -58.184125)
		(end 87.128604 -58.173112)
		(stroke
			(width 0.0508)
			(type default)
		)
		(layer "In5.Cu")
	)
	(gr_line
		(start 87.36838 -58.253122)
		(end 87.584026 -58.468514)
		(stroke
			(width 0.0508)
			(type default)
		)
		(layer "In5.Cu")
	)
	(gr_line
		(start 87.405464 -36.29279)
		(end 87.79002 -35.908234)
		(stroke
			(width 0.0508)
			(type default)
		)
		(layer "In5.Cu")
	)
	(gr_arc
		(start 87.466932 -39.62654)
		(mid 87.33741 -39.637457)
		(end 87.227156 -39.706296)
		(stroke
			(width 0.0508)
			(type default)
		)
		(layer "In5.Cu")
	)
	(gr_arc
		(start 87.466932 -39.62654)
		(mid 87.596484 -39.615483)
		(end 87.706708 -39.54653)
		(stroke
			(width 0.0508)
			(type default)
		)
		(layer "In5.Cu")
	)
	(gr_arc
		(start 87.643716 -36.681664)
		(mid 87.51415 -36.692674)
		(end 87.40394 -36.761674)
		(stroke
			(width 0.0508)
			(type default)
		)
		(layer "In5.Cu")
	)
	(gr_arc
		(start 87.643716 -36.681664)
		(mid 87.773261 -36.670614)
		(end 87.883492 -36.601654)
		(stroke
			(width 0.0508)
			(type default)
		)
		(layer "In5.Cu")
	)
	(gr_arc
		(start 87.664036 -58.70829)
		(mid 87.652993 -58.578733)
		(end 87.584026 -58.468514)
		(stroke
			(width 0.0508)
			(type default)
		)
		(layer "In5.Cu")
	)
	(gr_arc
		(start 87.664036 -58.70829)
		(mid 87.674975 -58.837799)
		(end 87.743792 -58.948066)
		(stroke
			(width 0.0508)
			(type default)
		)
		(layer "In5.Cu")
	)
	(gr_line
		(start 87.706708 -39.54653)
		(end 87.9221 -39.331138)
		(stroke
			(width 0.0508)
			(type default)
		)
		(layer "In5.Cu")
	)
	(gr_line
		(start 87.883492 -36.601654)
		(end 88.099138 -36.386262)
		(stroke
			(width 0.0508)
			(type default)
		)
		(layer "In5.Cu")
	)
	(gr_arc
		(start 87.9221 -39.331138)
		(mid 87.991072 -39.220916)
		(end 88.00211 -39.091362)
		(stroke
			(width 0.0508)
			(type default)
		)
		(layer "In5.Cu")
	)
	(gr_arc
		(start 88.081866 -38.851586)
		(mid 88.01303 -38.961841)
		(end 88.00211 -39.091362)
		(stroke
			(width 0.0508)
			(type default)
		)
		(layer "In5.Cu")
	)
	(gr_arc
		(start 88.099138 -36.386262)
		(mid 88.168072 -36.276032)
		(end 88.179148 -36.146486)
		(stroke
			(width 0.0508)
			(type default)
		)
		(layer "In5.Cu")
	)
	(gr_arc
		(start 88.258904 -35.90671)
		(mid 88.190076 -36.016966)
		(end 88.179148 -36.146486)
		(stroke
			(width 0.0508)
			(type default)
		)
		(layer "In5.Cu")
	)
	(gr_line
		(start 89.369392 -37.0967)
		(end 89.753948 -36.712144)
		(stroke
			(width 0.0508)
			(type default)
		)
		(layer "In5.Cu")
	)
	(gr_arc
		(start 89.607644 -37.485574)
		(mid 89.478099 -37.496624)
		(end 89.367868 -37.565584)
		(stroke
			(width 0.0508)
			(type default)
		)
		(layer "In5.Cu")
	)
	(gr_arc
		(start 89.607644 -37.485574)
		(mid 89.737192 -37.474538)
		(end 89.84742 -37.405564)
		(stroke
			(width 0.0508)
			(type default)
		)
		(layer "In5.Cu")
	)
	(gr_line
		(start 89.84742 -37.405564)
		(end 90.063066 -37.190172)
		(stroke
			(width 0.0508)
			(type default)
		)
		(layer "In5.Cu")
	)
	(gr_arc
		(start 89.993978 -54.332378)
		(mid 90.104232 -54.401224)
		(end 90.233754 -54.412134)
		(stroke
			(width 0.0508)
			(type default)
		)
		(layer "In5.Cu")
	)
	(gr_line
		(start 89.995502 -54.801262)
		(end 90.379804 -55.185564)
		(stroke
			(width 0.0508)
			(type default)
		)
		(layer "In5.Cu")
	)
	(gr_arc
		(start 90.063066 -37.190172)
		(mid 90.132036 -37.079948)
		(end 90.143076 -36.950396)
		(stroke
			(width 0.0508)
			(type default)
		)
		(layer "In5.Cu")
	)
	(gr_arc
		(start 90.222832 -36.71062)
		(mid 90.153996 -36.820875)
		(end 90.143076 -36.950396)
		(stroke
			(width 0.0508)
			(type default)
		)
		(layer "In5.Cu")
	)
	(gr_arc
		(start 90.47353 -54.492144)
		(mid 90.3633 -54.42321)
		(end 90.233754 -54.412134)
		(stroke
			(width 0.0508)
			(type default)
		)
		(layer "In5.Cu")
	)
	(gr_line
		(start 90.47353 -54.492144)
		(end 90.688922 -54.707536)
		(stroke
			(width 0.0508)
			(type default)
		)
		(layer "In5.Cu")
	)
	(gr_arc
		(start 90.768932 -54.947312)
		(mid 90.757889 -54.817755)
		(end 90.688922 -54.707536)
		(stroke
			(width 0.0508)
			(type default)
		)
		(layer "In5.Cu")
	)
	(gr_arc
		(start 90.768932 -54.947312)
		(mid 90.779839 -55.07684)
		(end 90.848688 -55.187088)
		(stroke
			(width 0.0508)
			(type default)
		)
		(layer "In5.Cu")
	)
	(gr_line
		(start 91.472004 -38.797738)
		(end 91.487498 -38.782244)
		(stroke
			(width 0.04445)
			(type default)
		)
		(layer "In5.Cu")
	)
	(gr_line
		(start 91.487498 -38.782244)
		(end 91.528138 -38.782244)
		(stroke
			(width 0.04445)
			(type default)
		)
		(layer "In5.Cu")
	)
	(gr_line
		(start 91.530678 -38.782244)
		(end 91.585796 -38.782244)
		(stroke
			(width 0.04445)
			(type default)
		)
		(layer "In5.Cu")
	)
	(gr_line
		(start 91.705684 -39.031164)
		(end 91.721178 -39.01567)
		(stroke
			(width 0.04445)
			(type default)
		)
		(layer "In5.Cu")
	)
	(gr_line
		(start 91.721178 -38.975284)
		(end 91.721178 -39.01567)
		(stroke
			(width 0.04445)
			(type default)
		)
		(layer "In5.Cu")
	)
	(gr_line
		(start 91.721178 -38.916356)
		(end 91.721178 -38.972744)
		(stroke
			(width 0.04445)
			(type default)
		)
		(layer "In5.Cu")
	)
	(gr_arc
		(start 91.935046 -57.787286)
		(mid 92.045271 -57.856244)
		(end 92.174822 -57.867296)
		(stroke
			(width 0.0508)
			(type default)
		)
		(layer "In5.Cu")
	)
	(gr_line
		(start 91.93657 -58.25617)
		(end 92.321126 -58.640726)
		(stroke
			(width 0.0508)
			(type default)
		)
		(layer "In5.Cu")
	)
	(gr_arc
		(start 92.414598 -57.947306)
		(mid 92.304379 -57.878309)
		(end 92.174822 -57.867296)
		(stroke
			(width 0.0508)
			(type default)
		)
		(layer "In5.Cu")
	)
	(gr_line
		(start 92.414598 -57.947306)
		(end 92.630244 -58.162698)
		(stroke
			(width 0.0508)
			(type default)
		)
		(layer "In5.Cu")
	)
	(gr_arc
		(start 92.456 -34.606484)
		(mid 92.564438 -34.593464)
		(end 92.66682 -34.55543)
		(stroke
			(width 0.0508)
			(type default)
		)
		(layer "In5.Cu")
	)
	(gr_arc
		(start 92.66682 -34.55543)
		(mid 92.728142 -34.517785)
		(end 92.782898 -34.471102)
		(stroke
			(width 0.0508)
			(type default)
		)
		(layer "In5.Cu")
	)
	(gr_arc
		(start 92.710254 -58.402474)
		(mid 92.699211 -58.272917)
		(end 92.630244 -58.162698)
		(stroke
			(width 0.0508)
			(type default)
		)
		(layer "In5.Cu")
	)
	(gr_arc
		(start 92.710254 -58.402474)
		(mid 92.721187 -58.531986)
		(end 92.79001 -58.64225)
		(stroke
			(width 0.0508)
			(type default)
		)
		(layer "In5.Cu")
	)
	(gr_arc
		(start 92.715334 -61.370464)
		(mid 92.825553 -61.439461)
		(end 92.95511 -61.450474)
		(stroke
			(width 0.0508)
			(type default)
		)
		(layer "In5.Cu")
	)
	(gr_line
		(start 92.717112 -61.839348)
		(end 93.101414 -62.22365)
		(stroke
			(width 0.0508)
			(type default)
		)
		(layer "In5.Cu")
	)
	(gr_line
		(start 92.782898 -34.471102)
		(end 92.964 -34.29)
		(stroke
			(width 0.0508)
			(type default)
		)
		(layer "In5.Cu")
	)
	(gr_line
		(start 92.78874 -34.936684)
		(end 92.8624 -34.936684)
		(stroke
			(width 0.0508)
			(type default)
		)
		(layer "In5.Cu")
	)
	(gr_line
		(start 92.964 -34.29)
		(end 92.973652 -34.280094)
		(stroke
			(width 0.0508)
			(type default)
		)
		(layer "In5.Cu")
	)
	(gr_line
		(start 93.048582 -36.953444)
		(end 93.432884 -36.953444)
		(stroke
			(width 0.0508)
			(type default)
		)
		(layer "In5.Cu")
	)
	(gr_arc
		(start 93.070426 -36.60267)
		(mid 92.944647 -36.627689)
		(end 92.838016 -36.698936)
		(stroke
			(width 0.0508)
			(type default)
		)
		(layer "In5.Cu")
	)
	(gr_line
		(start 93.070426 -36.60267)
		(end 93.2434 -36.60267)
		(stroke
			(width 0.0508)
			(type default)
		)
		(layer "In5.Cu")
	)
	(gr_arc
		(start 93.143832 -37.973)
		(mid 93.36721 -37.928586)
		(end 93.556582 -37.802058)
		(stroke
			(width 0.04445)
			(type default)
		)
		(layer "In5.Cu")
	)
	(gr_arc
		(start 93.1672 -34.200084)
		(mid 93.06246 -34.220824)
		(end 92.973652 -34.280094)
		(stroke
			(width 0.0508)
			(type default)
		)
		(layer "In5.Cu")
	)
	(gr_line
		(start 93.1672 -34.200084)
		(end 93.6244 -34.200084)
		(stroke
			(width 0.04445)
			(type default)
		)
		(layer "In5.Cu")
	)
	(gr_arc
		(start 93.182948 -59.035188)
		(mid 93.293174 -59.104144)
		(end 93.422724 -59.115198)
		(stroke
			(width 0.0508)
			(type default)
		)
		(layer "In5.Cu")
	)
	(gr_line
		(start 93.184472 -59.504072)
		(end 93.569028 -59.888628)
		(stroke
			(width 0.0508)
			(type default)
		)
		(layer "In5.Cu")
	)
	(gr_arc
		(start 93.194886 -61.530484)
		(mid 93.08466 -61.461521)
		(end 92.95511 -61.450474)
		(stroke
			(width 0.0508)
			(type default)
		)
		(layer "In5.Cu")
	)
	(gr_line
		(start 93.194886 -61.530484)
		(end 93.410532 -61.745876)
		(stroke
			(width 0.0508)
			(type default)
		)
		(layer "In5.Cu")
	)
	(gr_arc
		(start 93.198188 -38.239446)
		(mid 93.114049 -38.183226)
		(end 93.0148 -38.1635)
		(stroke
			(width 0.04445)
			(type default)
		)
		(layer "In5.Cu")
	)
	(gr_line
		(start 93.198188 -38.239446)
		(end 93.555566 -38.596824)
		(stroke
			(width 0.04445)
			(type default)
		)
		(layer "In5.Cu")
	)
	(gr_arc
		(start 93.219016 -35.833304)
		(mid 93.17533 -35.804021)
		(end 93.123766 -35.79368)
		(stroke
			(width 0.0508)
			(type default)
		)
		(layer "In5.Cu")
	)
	(gr_line
		(start 93.219016 -35.833304)
		(end 93.551756 -36.16579)
		(stroke
			(width 0.0508)
			(type default)
		)
		(layer "In5.Cu")
	)
	(gr_line
		(start 93.2434 -36.60267)
		(end 93.6752 -36.60267)
		(stroke
			(width 0.04445)
			(type default)
		)
		(layer "In5.Cu")
	)
	(gr_arc
		(start 93.415104 -35.46348)
		(mid 93.487811 -35.449018)
		(end 93.54947 -35.407854)
		(stroke
			(width 0.0508)
			(type default)
		)
		(layer "In5.Cu")
	)
	(gr_line
		(start 93.467682 -34.685986)
		(end 93.547184 -34.606484)
		(stroke
			(width 0.0508)
			(type default)
		)
		(layer "In5.Cu")
	)
	(gr_arc
		(start 93.490542 -61.985652)
		(mid 93.479479 -61.856104)
		(end 93.410532 -61.745876)
		(stroke
			(width 0.0508)
			(type default)
		)
		(layer "In5.Cu")
	)
	(gr_arc
		(start 93.490542 -61.985652)
		(mid 93.501459 -62.115174)
		(end 93.570298 -62.225428)
		(stroke
			(width 0.0508)
			(type default)
		)
		(layer "In5.Cu")
	)
	(gr_arc
		(start 93.551756 -37.00272)
		(mid 93.497227 -36.966243)
		(end 93.432884 -36.953444)
		(stroke
			(width 0.0508)
			(type default)
		)
		(layer "In5.Cu")
	)
	(gr_line
		(start 93.551756 -36.16579)
		(end 93.551756 -36.19627)
		(stroke
			(width 0.0508)
			(type default)
		)
		(layer "In5.Cu")
	)
	(gr_arc
		(start 93.6625 -59.195208)
		(mid 93.552281 -59.126211)
		(end 93.422724 -59.115198)
		(stroke
			(width 0.0508)
			(type default)
		)
		(layer "In5.Cu")
	)
	(gr_line
		(start 93.6625 -59.195208)
		(end 93.878146 -59.4106)
		(stroke
			(width 0.0508)
			(type default)
		)
		(layer "In5.Cu")
	)
	(gr_line
		(start 93.6752 -36.60267)
		(end 94.017084 -36.60267)
		(stroke
			(width 0.0508)
			(type default)
		)
		(layer "In5.Cu")
	)
	(gr_arc
		(start 93.785944 -62.441074)
		(mid 93.896199 -62.50991)
		(end 94.02572 -62.52083)
		(stroke
			(width 0.0508)
			(type default)
		)
		(layer "In5.Cu")
	)
	(gr_line
		(start 93.787722 -62.909958)
		(end 94.172024 -63.29426)
		(stroke
			(width 0.0508)
			(type default)
		)
		(layer "In5.Cu")
	)
	(gr_arc
		(start 93.957902 -59.650376)
		(mid 93.946985 -59.520854)
		(end 93.878146 -59.4106)
		(stroke
			(width 0.0508)
			(type default)
		)
		(layer "In5.Cu")
	)
	(gr_arc
		(start 93.957902 -59.650376)
		(mid 93.968975 -59.77992)
		(end 94.037912 -59.890152)
		(stroke
			(width 0.0508)
			(type default)
		)
		(layer "In5.Cu")
	)
	(gr_arc
		(start 94.179898 -34.430208)
		(mid 93.925033 -34.259913)
		(end 93.6244 -34.200084)
		(stroke
			(width 0.0508)
			(type default)
		)
		(layer "In5.Cu")
	)
	(gr_line
		(start 94.179898 -34.430208)
		(end 94.349824 -34.600134)
		(stroke
			(width 0.0508)
			(type default)
		)
		(layer "In5.Cu")
	)
	(gr_arc
		(start 94.253558 -60.105798)
		(mid 94.363812 -60.174647)
		(end 94.493334 -60.185554)
		(stroke
			(width 0.0508)
			(type default)
		)
		(layer "In5.Cu")
	)
	(gr_line
		(start 94.255082 -60.574682)
		(end 94.639384 -60.958984)
		(stroke
			(width 0.0508)
			(type default)
		)
		(layer "In5.Cu")
	)
	(gr_arc
		(start 94.2594 -36.703)
		(mid 94.148224 -36.628715)
		(end 94.017084 -36.60267)
		(stroke
			(width 0.0508)
			(type default)
		)
		(layer "In5.Cu")
	)
	(gr_arc
		(start 94.265496 -62.60084)
		(mid 94.155273 -62.531859)
		(end 94.02572 -62.52083)
		(stroke
			(width 0.0508)
			(type default)
		)
		(layer "In5.Cu")
	)
	(gr_line
		(start 94.265496 -62.60084)
		(end 94.480888 -62.816486)
		(stroke
			(width 0.0508)
			(type default)
		)
		(layer "In5.Cu")
	)
	(gr_arc
		(start 94.359222 -36.944046)
		(mid 94.333275 -36.813601)
		(end 94.2594 -36.703)
		(stroke
			(width 0.0508)
			(type default)
		)
		(layer "In5.Cu")
	)
	(gr_line
		(start 94.359222 -36.944046)
		(end 94.359222 -36.999418)
		(stroke
			(width 0.0508)
			(type default)
		)
		(layer "In5.Cu")
	)
	(gr_arc
		(start 94.560898 -63.056262)
		(mid 94.549865 -62.926711)
		(end 94.480888 -62.816486)
		(stroke
			(width 0.0508)
			(type default)
		)
		(layer "In5.Cu")
	)
	(gr_arc
		(start 94.560898 -63.056262)
		(mid 94.571948 -63.185807)
		(end 94.640908 -63.296038)
		(stroke
			(width 0.0508)
			(type default)
		)
		(layer "In5.Cu")
	)
	(gr_arc
		(start 94.73311 -60.265564)
		(mid 94.62288 -60.19663)
		(end 94.493334 -60.185554)
		(stroke
			(width 0.0508)
			(type default)
		)
		(layer "In5.Cu")
	)
	(gr_line
		(start 94.73311 -60.265564)
		(end 94.948502 -60.480956)
		(stroke
			(width 0.0508)
			(type default)
		)
		(layer "In5.Cu")
	)
	(gr_arc
		(start 95.028512 -60.720732)
		(mid 95.017469 -60.591175)
		(end 94.948502 -60.480956)
		(stroke
			(width 0.0508)
			(type default)
		)
		(layer "In5.Cu")
	)
	(gr_arc
		(start 95.028512 -60.720732)
		(mid 95.039426 -60.850256)
		(end 95.108268 -60.960508)
		(stroke
			(width 0.0508)
			(type default)
		)
		(layer "In5.Cu")
	)
	(gr_arc
		(start 95.323914 -61.176154)
		(mid 95.434142 -61.245108)
		(end 95.56369 -61.256164)
		(stroke
			(width 0.0508)
			(type default)
		)
		(layer "In5.Cu")
	)
	(gr_line
		(start 95.325438 -61.645038)
		(end 95.709994 -62.029594)
		(stroke
			(width 0.0508)
			(type default)
		)
		(layer "In5.Cu")
	)
	(gr_arc
		(start 95.803466 -61.336174)
		(mid 95.693247 -61.267177)
		(end 95.56369 -61.256164)
		(stroke
			(width 0.0508)
			(type default)
		)
		(layer "In5.Cu")
	)
	(gr_line
		(start 95.803466 -61.336174)
		(end 96.019112 -61.551566)
		(stroke
			(width 0.0508)
			(type default)
		)
		(layer "In5.Cu")
	)
	(gr_arc
		(start 96.098868 -61.791342)
		(mid 96.087951 -61.66182)
		(end 96.019112 -61.551566)
		(stroke
			(width 0.0508)
			(type default)
		)
		(layer "In5.Cu")
	)
	(gr_arc
		(start 96.098868 -61.791342)
		(mid 96.109929 -61.920891)
		(end 96.178878 -62.031118)
		(stroke
			(width 0.0508)
			(type default)
		)
		(layer "In5.Cu")
	)
	(gr_arc
		(start 98.210624 -63.5)
		(mid 98.337324 -63.470816)
		(end 98.436684 -63.38697)
		(stroke
			(width 0.0508)
			(type default)
		)
		(layer "In5.Cu")
	)
	(gr_line
		(start 98.543364 -63.8302)
		(end 99.086924 -63.8302)
		(stroke
			(width 0.0508)
			(type default)
		)
		(layer "In5.Cu")
	)
	(gr_arc
		(start 98.662744 -63.27394)
		(mid 98.536083 -63.303179)
		(end 98.436684 -63.38697)
		(stroke
			(width 0.0508)
			(type default)
		)
		(layer "In5.Cu")
	)
	(gr_line
		(start 98.662744 -63.27394)
		(end 98.967544 -63.27394)
		(stroke
			(width 0.0508)
			(type default)
		)
		(layer "In5.Cu")
	)
	(gr_arc
		(start 99.193604 -63.38697)
		(mid 99.094228 -63.303133)
		(end 98.967544 -63.27394)
		(stroke
			(width 0.0508)
			(type default)
		)
		(layer "In5.Cu")
	)
	(gr_arc
		(start 99.193604 -63.38697)
		(mid 99.292999 -63.470748)
		(end 99.419664 -63.5)
		(stroke
			(width 0.0508)
			(type default)
		)
		(layer "In5.Cu")
	)
	(gr_arc
		(start 102.945438 -63.5)
		(mid 103.072134 -63.470811)
		(end 103.171498 -63.38697)
		(stroke
			(width 0.0508)
			(type default)
		)
		(layer "In5.Cu")
	)
	(gr_line
		(start 103.278178 -63.8302)
		(end 103.821738 -63.8302)
		(stroke
			(width 0.0508)
			(type default)
		)
		(layer "In5.Cu")
	)
	(gr_arc
		(start 103.397558 -63.27394)
		(mid 103.270897 -63.303179)
		(end 103.171498 -63.38697)
		(stroke
			(width 0.0508)
			(type default)
		)
		(layer "In5.Cu")
	)
	(gr_line
		(start 103.397558 -63.27394)
		(end 103.702358 -63.27394)
		(stroke
			(width 0.0508)
			(type default)
		)
		(layer "In5.Cu")
	)
	(gr_arc
		(start 103.928418 -63.38697)
		(mid 103.829042 -63.303133)
		(end 103.702358 -63.27394)
		(stroke
			(width 0.0508)
			(type default)
		)
		(layer "In5.Cu")
	)
	(gr_arc
		(start 103.928418 -63.38697)
		(mid 104.027814 -63.470743)
		(end 104.154478 -63.5)
		(stroke
			(width 0.0508)
			(type default)
		)
		(layer "In5.Cu")
	)
	(gr_arc
		(start 106.523282 -64.19215)
		(mid 106.633535 -64.261001)
		(end 106.763058 -64.271906)
		(stroke
			(width 0.0508)
			(type default)
		)
		(layer "In5.Cu")
	)
	(gr_line
		(start 106.524806 -64.661034)
		(end 106.909108 -65.045336)
		(stroke
			(width 0.0508)
			(type default)
		)
		(layer "In5.Cu")
	)
	(gr_arc
		(start 107.002834 -64.351916)
		(mid 106.892604 -64.282982)
		(end 106.763058 -64.271906)
		(stroke
			(width 0.0508)
			(type default)
		)
		(layer "In5.Cu")
	)
	(gr_line
		(start 107.002834 -64.351916)
		(end 107.218226 -64.567308)
		(stroke
			(width 0.0508)
			(type default)
		)
		(layer "In5.Cu")
	)
	(gr_arc
		(start 107.298236 -64.807084)
		(mid 107.287193 -64.677527)
		(end 107.218226 -64.567308)
		(stroke
			(width 0.0508)
			(type default)
		)
		(layer "In5.Cu")
	)
	(gr_arc
		(start 107.298236 -64.807084)
		(mid 107.309172 -64.936594)
		(end 107.377992 -65.04686)
		(stroke
			(width 0.0508)
			(type default)
		)
		(layer "In5.Cu")
	)
	(gr_arc
		(start 107.593638 -65.262506)
		(mid 107.70386 -65.331487)
		(end 107.833414 -65.342516)
		(stroke
			(width 0.0508)
			(type default)
		)
		(layer "In5.Cu")
	)
	(gr_line
		(start 107.595162 -65.73139)
		(end 107.979718 -66.115946)
		(stroke
			(width 0.0508)
			(type default)
		)
		(layer "In5.Cu")
	)
	(gr_arc
		(start 108.07319 -65.422272)
		(mid 107.962935 -65.353436)
		(end 107.833414 -65.342516)
		(stroke
			(width 0.0508)
			(type default)
		)
		(layer "In5.Cu")
	)
	(gr_line
		(start 108.07319 -65.422272)
		(end 108.288582 -65.637918)
		(stroke
			(width 0.0508)
			(type default)
		)
		(layer "In5.Cu")
	)
	(gr_arc
		(start 108.368592 -65.877694)
		(mid 108.357542 -65.748149)
		(end 108.288582 -65.637918)
		(stroke
			(width 0.0508)
			(type default)
		)
		(layer "In5.Cu")
	)
	(gr_arc
		(start 108.368592 -65.877694)
		(mid 108.379606 -66.007256)
		(end 108.448602 -66.11747)
		(stroke
			(width 0.0508)
			(type default)
		)
		(layer "In5.Cu")
	)
	(gr_arc
		(start 110.26521 -67.934078)
		(mid 110.375465 -68.002911)
		(end 110.504986 -68.013834)
		(stroke
			(width 0.0508)
			(type default)
		)
		(layer "In5.Cu")
	)
	(gr_line
		(start 110.266734 -68.402962)
		(end 110.651036 -68.787264)
		(stroke
			(width 0.0508)
			(type default)
		)
		(layer "In5.Cu")
	)
	(gr_arc
		(start 110.744762 -68.093844)
		(mid 110.634532 -68.02491)
		(end 110.504986 -68.013834)
		(stroke
			(width 0.0508)
			(type default)
		)
		(layer "In5.Cu")
	)
	(gr_line
		(start 110.744762 -68.093844)
		(end 110.960154 -68.309236)
		(stroke
			(width 0.0508)
			(type default)
		)
		(layer "In5.Cu")
	)
	(gr_arc
		(start 111.040164 -68.549012)
		(mid 111.029121 -68.419455)
		(end 110.960154 -68.309236)
		(stroke
			(width 0.0508)
			(type default)
		)
		(layer "In5.Cu")
	)
	(gr_arc
		(start 111.040164 -68.549012)
		(mid 111.051072 -68.678539)
		(end 111.11992 -68.788788)
		(stroke
			(width 0.0508)
			(type default)
		)
		(layer "In5.Cu")
	)
	(gr_arc
		(start 122.850148 -88.849708)
		(mid 123.440404 -89.244104)
		(end 124.136658 -89.3826)
		(stroke
			(width 0.0508)
			(type default)
		)
		(layer "In5.Cu")
	)
	(gr_line
		(start 122.850148 -87.84971)
		(end 123.100592 -88.100154)
		(stroke
			(width 0.0508)
			(type default)
		)
		(layer "In5.Cu")
	)
	(gr_line
		(start 122.850148 -86.849712)
		(end 122.93219 -86.931754)
		(stroke
			(width 0.0508)
			(type default)
		)
		(layer "In5.Cu")
	)
	(gr_arc
		(start 122.93219 -86.931754)
		(mid 123.283532 -87.166577)
		(end 123.698 -87.249)
		(stroke
			(width 0.0508)
			(type default)
		)
		(layer "In5.Cu")
	)
	(gr_arc
		(start 123.100592 -88.100154)
		(mid 123.273299 -88.215553)
		(end 123.47702 -88.25611)
		(stroke
			(width 0.0508)
			(type default)
		)
		(layer "In5.Cu")
	)
	(gr_arc
		(start 123.33986 -86.052406)
		(mid 123.115163 -85.902361)
		(end 122.850148 -85.849714)
		(stroke
			(width 0.0508)
			(type default)
		)
		(layer "In5.Cu")
	)
	(gr_line
		(start 123.33986 -86.052406)
		(end 123.5202 -86.233)
		(stroke
			(width 0.0508)
			(type default)
		)
		(layer "In5.Cu")
	)
	(gr_line
		(start 123.47702 -88.25611)
		(end 123.701302 -88.25611)
		(stroke
			(width 0.0508)
			(type default)
		)
		(layer "In5.Cu")
	)
	(gr_arc
		(start 123.5202 -86.233)
		(mid 123.576493 -86.270591)
		(end 123.642882 -86.2838)
		(stroke
			(width 0.0508)
			(type default)
		)
		(layer "In5.Cu")
	)
	(gr_line
		(start 123.642882 -86.2838)
		(end 124.04471 -86.2838)
		(stroke
			(width 0.0508)
			(type default)
		)
		(layer "In5.Cu")
	)
	(gr_arc
		(start 123.850146 -88.849708)
		(mid 124.074725 -88.999715)
		(end 124.339604 -89.0524)
		(stroke
			(width 0.0508)
			(type default)
		)
		(layer "In5.Cu")
	)
	(gr_arc
		(start 123.850146 -87.84971)
		(mid 123.93451 -87.906111)
		(end 124.034042 -87.92591)
		(stroke
			(width 0.0508)
			(type default)
		)
		(layer "In5.Cu")
	)
	(gr_line
		(start 123.850146 -85.849714)
		(end 123.962668 -85.849714)
		(stroke
			(width 0.0508)
			(type default)
		)
		(layer "In5.Cu")
	)
	(gr_arc
		(start 123.914408 -87.338662)
		(mid 123.815119 -87.272319)
		(end 123.698 -87.249)
		(stroke
			(width 0.0508)
			(type default)
		)
		(layer "In5.Cu")
	)
	(gr_arc
		(start 123.923044 -86.879938)
		(mid 123.889608 -86.857558)
		(end 123.850146 -86.849712)
		(stroke
			(width 0.0508)
			(type default)
		)
		(layer "In5.Cu")
	)
	(gr_arc
		(start 124.04471 -86.2838)
		(mid 124.180371 -86.256753)
		(end 124.295408 -86.179914)
		(stroke
			(width 0.0508)
			(type default)
		)
		(layer "In5.Cu")
	)
	(gr_arc
		(start 125.765814 -68.6816)
		(mid 125.892475 -68.652361)
		(end 125.991874 -68.56857)
		(stroke
			(width 0.0508)
			(type default)
		)
		(layer "In5.Cu")
	)
	(gr_line
		(start 126.098554 -69.0118)
		(end 126.642114 -69.0118)
		(stroke
			(width 0.0508)
			(type default)
		)
		(layer "In5.Cu")
	)
	(gr_arc
		(start 126.217934 -68.45554)
		(mid 126.09125 -68.484742)
		(end 125.991874 -68.56857)
		(stroke
			(width 0.0508)
			(type default)
		)
		(layer "In5.Cu")
	)
	(gr_line
		(start 126.217934 -68.45554)
		(end 126.522734 -68.45554)
		(stroke
			(width 0.0508)
			(type default)
		)
		(layer "In5.Cu")
	)
	(gr_arc
		(start 126.748794 -68.56857)
		(mid 126.649402 -68.484781)
		(end 126.522734 -68.45554)
		(stroke
			(width 0.0508)
			(type default)
		)
		(layer "In5.Cu")
	)
	(gr_arc
		(start 126.748794 -68.56857)
		(mid 126.84817 -68.652407)
		(end 126.974854 -68.6816)
		(stroke
			(width 0.0508)
			(type default)
		)
		(layer "In5.Cu")
	)
	(gr_arc
		(start 130.849116 -72.59701)
		(mid 130.959342 -72.665974)
		(end 131.088892 -72.67702)
		(stroke
			(width 0.0508)
			(type default)
		)
		(layer "In5.Cu")
	)
	(gr_line
		(start 130.850894 -73.065894)
		(end 131.235196 -73.450196)
		(stroke
			(width 0.0508)
			(type default)
		)
		(layer "In5.Cu")
	)
	(gr_line
		(start 131.02844 -79.756)
		(end 131.250436 -79.534004)
		(stroke
			(width 0.0508)
			(type default)
		)
		(layer "In5.Cu")
	)
	(gr_arc
		(start 131.250436 -79.534004)
		(mid 131.338024 -79.402899)
		(end 131.3688 -79.248254)
		(stroke
			(width 0.0508)
			(type default)
		)
		(layer "In5.Cu")
	)
	(gr_arc
		(start 131.328668 -72.75703)
		(mid 131.218449 -72.688033)
		(end 131.088892 -72.67702)
		(stroke
			(width 0.0508)
			(type default)
		)
		(layer "In5.Cu")
	)
	(gr_line
		(start 131.328668 -72.75703)
		(end 131.544314 -72.972422)
		(stroke
			(width 0.0508)
			(type default)
		)
		(layer "In5.Cu")
	)
	(gr_arc
		(start 131.62407 -73.212198)
		(mid 131.613153 -73.082676)
		(end 131.544314 -72.972422)
		(stroke
			(width 0.0508)
			(type default)
		)
		(layer "In5.Cu")
	)
	(gr_arc
		(start 131.62407 -73.212198)
		(mid 131.635154 -73.341733)
		(end 131.70408 -73.451974)
		(stroke
			(width 0.0508)
			(type default)
		)
		(layer "In5.Cu")
	)
	(gr_arc
		(start 131.699 -79.248)
		(mid 131.735994 -79.434382)
		(end 131.841494 -79.592424)
		(stroke
			(width 0.0508)
			(type default)
		)
		(layer "In5.Cu")
	)
	(gr_line
		(start 131.841494 -79.592424)
		(end 132.005324 -79.756)
		(stroke
			(width 0.0508)
			(type default)
		)
		(layer "In5.Cu")
	)
	(gr_arc
		(start 131.919726 -73.66762)
		(mid 132.029983 -73.736436)
		(end 132.159502 -73.747376)
		(stroke
			(width 0.0508)
			(type default)
		)
		(layer "In5.Cu")
	)
	(gr_line
		(start 131.921504 -74.136504)
		(end 132.305552 -74.520552)
		(stroke
			(width 0.0508)
			(type default)
		)
		(layer "In5.Cu")
	)
	(gr_line
		(start 132.207 -92.075)
		(end 132.360924 -91.920822)
		(stroke
			(width 0.0508)
			(type default)
		)
		(layer "In5.Cu")
	)
	(gr_line
		(start 132.207 -91.169998)
		(end 132.387594 -91.350592)
		(stroke
			(width 0.0508)
			(type default)
		)
		(layer "In5.Cu")
	)
	(gr_line
		(start 132.207 -89.281)
		(end 132.34289 -89.145364)
		(stroke
			(width 0.0508)
			(type default)
		)
		(layer "In5.Cu")
	)
	(gr_line
		(start 132.207 -88.375998)
		(end 132.370068 -88.539066)
		(stroke
			(width 0.0508)
			(type default)
		)
		(layer "In5.Cu")
	)
	(gr_arc
		(start 132.370068 -88.539066)
		(mid 132.516678 -88.636994)
		(end 132.6896 -88.6714)
		(stroke
			(width 0.0508)
			(type default)
		)
		(layer "In5.Cu")
	)
	(gr_arc
		(start 132.387594 -91.350592)
		(mid 132.514507 -91.435371)
		(end 132.6642 -91.465146)
		(stroke
			(width 0.0508)
			(type default)
		)
		(layer "In5.Cu")
	)
	(gr_arc
		(start 132.399278 -73.827386)
		(mid 132.289048 -73.758452)
		(end 132.159502 -73.747376)
		(stroke
			(width 0.0508)
			(type default)
		)
		(layer "In5.Cu")
	)
	(gr_line
		(start 132.399278 -73.827386)
		(end 132.61467 -74.042778)
		(stroke
			(width 0.0508)
			(type default)
		)
		(layer "In5.Cu")
	)
	(gr_arc
		(start 132.6642 -91.795346)
		(mid 132.50007 -91.8279)
		(end 132.360924 -91.920822)
		(stroke
			(width 0.0508)
			(type default)
		)
		(layer "In5.Cu")
	)
	(gr_arc
		(start 132.6896 -89.0016)
		(mid 132.501957 -89.039018)
		(end 132.34289 -89.145364)
		(stroke
			(width 0.0508)
			(type default)
		)
		(layer "In5.Cu")
	)
	(gr_arc
		(start 132.69468 -74.282554)
		(mid 132.683637 -74.152997)
		(end 132.61467 -74.042778)
		(stroke
			(width 0.0508)
			(type default)
		)
		(layer "In5.Cu")
	)
	(gr_arc
		(start 132.69468 -74.282554)
		(mid 132.705605 -74.41207)
		(end 132.774436 -74.52233)
		(stroke
			(width 0.0508)
			(type default)
		)
		(layer "In5.Cu")
	)
	(gr_line
		(start 132.930392 -81.117186)
		(end 133.124702 -80.922622)
		(stroke
			(width 0.0508)
			(type default)
		)
		(layer "In5.Cu")
	)
	(gr_arc
		(start 132.990082 -74.737976)
		(mid 133.100308 -74.806921)
		(end 133.229858 -74.817986)
		(stroke
			(width 0.0508)
			(type default)
		)
		(layer "In5.Cu")
	)
	(gr_line
		(start 132.99186 -75.20686)
		(end 133.376162 -75.591162)
		(stroke
			(width 0.0508)
			(type default)
		)
		(layer "In5.Cu")
	)
	(gr_arc
		(start 133.124702 -80.922622)
		(mid 133.202107 -80.806917)
		(end 133.22935 -80.6704)
		(stroke
			(width 0.0508)
			(type default)
		)
		(layer "In5.Cu")
	)
	(gr_arc
		(start 133.469634 -74.897742)
		(mid 133.359379 -74.828906)
		(end 133.229858 -74.817986)
		(stroke
			(width 0.0508)
			(type default)
		)
		(layer "In5.Cu")
	)
	(gr_line
		(start 133.469634 -74.897742)
		(end 133.685026 -75.113388)
		(stroke
			(width 0.0508)
			(type default)
		)
		(layer "In5.Cu")
	)
	(gr_arc
		(start 133.55955 -80.6704)
		(mid 133.586798 -80.806915)
		(end 133.664198 -80.922622)
		(stroke
			(width 0.0508)
			(type default)
		)
		(layer "In5.Cu")
	)
	(gr_line
		(start 133.664198 -80.922622)
		(end 133.858508 -81.117186)
		(stroke
			(width 0.0508)
			(type default)
		)
		(layer "In5.Cu")
	)
	(gr_line
		(start 133.731 -90.559128)
		(end 133.850888 -90.43924)
		(stroke
			(width 0.0508)
			(type default)
		)
		(layer "In5.Cu")
	)
	(gr_arc
		(start 133.731 -89.654126)
		(mid 133.865389 -89.903536)
		(end 134.112 -90.043)
		(stroke
			(width 0.0508)
			(type default)
		)
		(layer "In5.Cu")
	)
	(gr_line
		(start 133.731 -88.019128)
		(end 133.855206 -87.894922)
		(stroke
			(width 0.0508)
			(type default)
		)
		(layer "In5.Cu")
	)
	(gr_line
		(start 133.731 -87.114126)
		(end 133.941312 -87.324692)
		(stroke
			(width 0.0508)
			(type default)
		)
		(layer "In5.Cu")
	)
	(gr_arc
		(start 133.765036 -75.353164)
		(mid 133.753986 -75.223619)
		(end 133.685026 -75.113388)
		(stroke
			(width 0.0508)
			(type default)
		)
		(layer "In5.Cu")
	)
	(gr_arc
		(start 133.765036 -75.353164)
		(mid 133.776039 -75.482731)
		(end 133.845046 -75.59294)
		(stroke
			(width 0.0508)
			(type default)
		)
		(layer "In5.Cu")
	)
	(gr_arc
		(start 133.941312 -87.324692)
		(mid 134.054592 -87.400322)
		(end 134.1882 -87.4268)
		(stroke
			(width 0.0508)
			(type default)
		)
		(layer "In5.Cu")
	)
	(gr_arc
		(start 134.0104 -90.3732)
		(mid 133.924085 -90.390369)
		(end 133.850888 -90.43924)
		(stroke
			(width 0.0508)
			(type default)
		)
		(layer "In5.Cu")
	)
	(gr_line
		(start 134.057644 -71.940928)
		(end 134.855458 -72.738742)
		(stroke
			(width 0.0508)
			(type default)
		)
		(layer "In5.Cu")
	)
	(gr_arc
		(start 134.1882 -87.757)
		(mid 134.007988 -87.792846)
		(end 133.855206 -87.894922)
		(stroke
			(width 0.0508)
			(type default)
		)
		(layer "In5.Cu")
	)
	(gr_arc
		(start 134.262876 -71.679054)
		(mid 134.373131 -71.74789)
		(end 134.502652 -71.75881)
		(stroke
			(width 0.0508)
			(type default)
		)
		(layer "In5.Cu")
	)
	(gr_arc
		(start 134.581392 -82.677)
		(mid 134.73955 -82.441838)
		(end 134.797546 -82.164428)
		(stroke
			(width 0.0508)
			(type default)
		)
		(layer "In5.Cu")
	)
	(gr_arc
		(start 134.742428 -71.83882)
		(mid 134.632202 -71.769872)
		(end 134.502652 -71.75881)
		(stroke
			(width 0.0508)
			(type default)
		)
		(layer "In5.Cu")
	)
	(gr_line
		(start 134.742428 -71.83882)
		(end 134.958074 -72.054466)
		(stroke
			(width 0.0508)
			(type default)
		)
		(layer "In5.Cu")
	)
	(gr_arc
		(start 134.797546 -82.164428)
		(mid 134.79769 -82.159475)
		(end 134.7978 -82.154522)
		(stroke
			(width 0.0508)
			(type default)
		)
		(layer "In5.Cu")
	)
	(gr_arc
		(start 135.038084 -72.294242)
		(mid 135.027018 -72.164694)
		(end 134.958074 -72.054466)
		(stroke
			(width 0.0508)
			(type default)
		)
		(layer "In5.Cu")
	)
	(gr_arc
		(start 135.038084 -72.294242)
		(mid 135.049001 -72.423764)
		(end 135.11784 -72.534018)
		(stroke
			(width 0.0508)
			(type default)
		)
		(layer "In5.Cu")
	)
	(gr_line
		(start 135.127746 -73.010776)
		(end 135.719566 -73.602596)
		(stroke
			(width 0.0508)
			(type default)
		)
		(layer "In5.Cu")
	)
	(gr_arc
		(start 135.128 -82.243422)
		(mid 135.16101 -82.409342)
		(end 135.255 -82.55)
		(stroke
			(width 0.0508)
			(type default)
		)
		(layer "In5.Cu")
	)
	(gr_line
		(start 135.255 -82.55)
		(end 135.29183 -82.58683)
		(stroke
			(width 0.0508)
			(type default)
		)
		(layer "In5.Cu")
	)
	(gr_arc
		(start 135.29183 -82.58683)
		(mid 135.391699 -82.65357)
		(end 135.509508 -82.677)
		(stroke
			(width 0.0508)
			(type default)
		)
		(layer "In5.Cu")
	)
	(gr_arc
		(start 135.333486 -72.74941)
		(mid 135.443716 -72.818344)
		(end 135.573262 -72.82942)
		(stroke
			(width 0.0508)
			(type default)
		)
		(layer "In5.Cu")
	)
	(gr_arc
		(start 135.813038 -72.909176)
		(mid 135.702782 -72.840335)
		(end 135.573262 -72.82942)
		(stroke
			(width 0.0508)
			(type default)
		)
		(layer "In5.Cu")
	)
	(gr_line
		(start 135.813038 -72.909176)
		(end 136.02843 -73.124822)
		(stroke
			(width 0.0508)
			(type default)
		)
		(layer "In5.Cu")
	)
	(gr_line
		(start 135.87984 -81.534)
		(end 136.03097 -81.38287)
		(stroke
			(width 0.0508)
			(type default)
		)
		(layer "In5.Cu")
	)
	(gr_arc
		(start 136.03097 -81.38287)
		(mid 136.140394 -81.219142)
		(end 136.178798 -81.026)
		(stroke
			(width 0.0508)
			(type default)
		)
		(layer "In5.Cu")
	)
	(gr_arc
		(start 136.10844 -73.364598)
		(mid 136.097423 -73.235037)
		(end 136.02843 -73.124822)
		(stroke
			(width 0.0508)
			(type default)
		)
		(layer "In5.Cu")
	)
	(gr_arc
		(start 136.10844 -73.364598)
		(mid 136.11949 -73.494143)
		(end 136.18845 -73.604374)
		(stroke
			(width 0.0508)
			(type default)
		)
		(layer "In5.Cu")
	)
	(gr_arc
		(start 136.508998 -81.026)
		(mid 136.547416 -81.21914)
		(end 136.656826 -81.38287)
		(stroke
			(width 0.0508)
			(type default)
		)
		(layer "In5.Cu")
	)
	(gr_line
		(start 136.656826 -81.38287)
		(end 136.807956 -81.534)
		(stroke
			(width 0.0508)
			(type default)
		)
		(layer "In5.Cu")
	)
	(gr_line
		(start 140.450316 -80.25003)
		(end 140.773912 -79.926434)
		(stroke
			(width 0.0635)
			(type default)
		)
		(layer "In5.Cu")
	)
	(gr_arc
		(start 140.55979 -79.148178)
		(mid 140.540255 -79.14678)
		(end 140.520674 -79.1464)
		(stroke
			(width 0.0635)
			(type default)
		)
		(layer "In5.Cu")
	)
	(gr_arc
		(start 140.773912 -79.926434)
		(mid 140.866123 -79.789533)
		(end 140.899896 -79.627984)
		(stroke
			(width 0.0635)
			(type default)
		)
		(layer "In5.Cu")
	)
	(gr_line
		(start 140.802614 -78.867)
		(end 140.9192 -78.867)
		(stroke
			(width 0.0635)
			(type default)
		)
		(layer "In5.Cu")
	)
	(gr_arc
		(start 140.899896 -79.525622)
		(mid 140.802325 -79.271592)
		(end 140.55979 -79.148178)
		(stroke
			(width 0.0635)
			(type default)
		)
		(layer "In5.Cu")
	)
	(gr_line
		(start 140.899896 -79.525622)
		(end 140.899896 -79.627984)
		(stroke
			(width 0.0635)
			(type default)
		)
		(layer "In5.Cu")
	)
	(gr_arc
		(start 140.9192 -78.867)
		(mid 141.294393 -78.711589)
		(end 141.449806 -78.336394)
		(stroke
			(width 0.0635)
			(type default)
		)
		(layer "In5.Cu")
	)
	(gr_line
		(start 141.449806 -78.24978)
		(end 141.449806 -78.336394)
		(stroke
			(width 0.0635)
			(type default)
		)
		(layer "In5.Cu")
	)
	(gr_line
		(start 142.27937 -74.163428)
		(end 142.27937 -75.016106)
		(stroke
			(width 0.0635)
			(type default)
		)
		(layer "In5.Cu")
	)
	(gr_arc
		(start 142.450566 -73.75017)
		(mid 142.323876 -73.939774)
		(end 142.27937 -74.163428)
		(stroke
			(width 0.0635)
			(type default)
		)
		(layer "In5.Cu")
	)
	(gr_arc
		(start 142.71117 -74.93)
		(mid 142.598341 -75.098861)
		(end 142.55877 -75.298046)
		(stroke
			(width 0.0635)
			(type default)
		)
		(layer "In5.Cu")
	)
	(gr_line
		(start 142.71117 -74.93)
		(end 142.86357 -74.7776)
		(stroke
			(width 0.0635)
			(type default)
		)
		(layer "In5.Cu")
	)
	(gr_arc
		(start 143.1163 -74.643996)
		(mid 142.979859 -74.691741)
		(end 142.86357 -74.7776)
		(stroke
			(width 0.0635)
			(type default)
		)
		(layer "In5.Cu")
	)
	(gr_arc
		(start 143.369792 -74.749152)
		(mid 143.253504 -74.671358)
		(end 143.1163 -74.643996)
		(stroke
			(width 0.0635)
			(type default)
		)
		(layer "In5.Cu")
	)
	(gr_line
		(start 143.369792 -74.749152)
		(end 143.397986 -74.777092)
		(stroke
			(width 0.0635)
			(type default)
		)
		(layer "In5.Cu")
	)
	(gr_line
		(start 143.397986 -74.777092)
		(end 143.481044 -74.86015)
		(stroke
			(width 0.0635)
			(type default)
		)
		(layer "In5.Cu")
	)
	(gr_arc
		(start 143.450056 -75.75042)
		(mid 143.49444 -75.683994)
		(end 143.51 -75.60564)
		(stroke
			(width 0.0635)
			(type default)
		)
		(layer "In5.Cu")
	)
	(gr_arc
		(start 143.51 -74.93)
		(mid 143.502479 -74.892189)
		(end 143.481044 -74.86015)
		(stroke
			(width 0.0635)
			(type default)
		)
		(layer "In5.Cu")
	)
	(gr_line
		(start 143.51 -74.93)
		(end 143.51 -75.60564)
		(stroke
			(width 0.0635)
			(type default)
		)
		(layer "In5.Cu")
	)
	(gr_line
		(start 144.449546 -80.25003)
		(end 144.8308 -79.488284)
		(stroke
			(width 0.0635)
			(type default)
		)
		(layer "In5.Cu")
	)
	(gr_arc
		(start 145.001234 -79.431642)
		(mid 144.904265 -79.424642)
		(end 144.8308 -79.488284)
		(stroke
			(width 0.0635)
			(type default)
		)
		(layer "In5.Cu")
	)
	(gr_line
		(start 145.001234 -79.431642)
		(end 145.001488 -79.431642)
		(stroke
			(width 0.0635)
			(type default)
		)
		(layer "In5.Cu")
	)
	(gr_arc
		(start 145.069306 -79.011018)
		(mid 145.062329 -79.107966)
		(end 145.125948 -79.181452)
		(stroke
			(width 0.0635)
			(type default)
		)
		(layer "In5.Cu")
	)
	(gr_line
		(start 145.069306 -79.011018)
		(end 145.450306 -78.24978)
		(stroke
			(width 0.0635)
			(type default)
		)
		(layer "In5.Cu")
	)
	(gr_line
		(start 145.125948 -79.181452)
		(end 145.126202 -79.181452)
		(stroke
			(width 0.0635)
			(type default)
		)
		(layer "In5.Cu")
	)
	(gr_line
		(start 145.272252 -79.254858)
		(end 145.276824 -79.257144)
		(stroke
			(width 0.0635)
			(type default)
		)
		(layer "In5.Cu")
	)
	(gr_arc
		(start 146.28749 -74.983848)
		(mid 146.408589 -74.667391)
		(end 146.449796 -74.331068)
		(stroke
			(width 0.0635)
			(type default)
		)
		(layer "In5.Cu")
	)
	(gr_line
		(start 146.449796 -73.75017)
		(end 146.449796 -74.331068)
		(stroke
			(width 0.0635)
			(type default)
		)
		(layer "In5.Cu")
	)
	(gr_line
		(start 146.534632 -75.114912)
		(end 146.534886 -75.114658)
		(stroke
			(width 0.0635)
			(type default)
		)
		(layer "In5.Cu")
	)
	(gr_line
		(start 146.72437 -75.036172)
		(end 146.983196 -75.036172)
		(stroke
			(width 0.0635)
			(type default)
		)
		(layer "In5.Cu")
	)
	(gr_arc
		(start 147.15617 -75.1078)
		(mid 147.076809 -75.054773)
		(end 146.983196 -75.036172)
		(stroke
			(width 0.0635)
			(type default)
		)
		(layer "In5.Cu")
	)
	(gr_line
		(start 147.15617 -75.1078)
		(end 147.20443 -75.155806)
		(stroke
			(width 0.0635)
			(type default)
		)
		(layer "In5.Cu")
	)
	(gr_arc
		(start 147.450556 -75.75042)
		(mid 147.386641 -75.428629)
		(end 147.20443 -75.155806)
		(stroke
			(width 0.0635)
			(type default)
		)
		(layer "In5.Cu")
	)
	(gr_line
		(start 148.450046 -80.25003)
		(end 148.830538 -79.488538)
		(stroke
			(width 0.0635)
			(type default)
		)
		(layer "In5.Cu")
	)
	(gr_line
		(start 148.623528 -79.243682)
		(end 148.628354 -79.246222)
		(stroke
			(width 0.0635)
			(type default)
		)
		(layer "In5.Cu")
	)
	(gr_line
		(start 148.773388 -79.318104)
		(end 148.773642 -79.318104)
		(stroke
			(width 0.0635)
			(type default)
		)
		(layer "In5.Cu")
	)
	(gr_arc
		(start 148.830538 -79.488538)
		(mid 148.837297 -79.391593)
		(end 148.773642 -79.318104)
		(stroke
			(width 0.0635)
			(type default)
		)
		(layer "In5.Cu")
	)
	(gr_line
		(start 148.89861 -79.068168)
		(end 148.898864 -79.068168)
		(stroke
			(width 0.0635)
			(type default)
		)
		(layer "In5.Cu")
	)
	(gr_arc
		(start 148.898864 -79.068168)
		(mid 148.995848 -79.074997)
		(end 149.069298 -79.011272)
		(stroke
			(width 0.0635)
			(type default)
		)
		(layer "In5.Cu")
	)
	(gr_line
		(start 149.069298 -79.011272)
		(end 149.449536 -78.24978)
		(stroke
			(width 0.0635)
			(type default)
		)
		(layer "In5.Cu")
	)
	(gr_arc
		(start 149.841458 -74.937112)
		(mid 150.114978 -75.119842)
		(end 150.437596 -75.184)
		(stroke
			(width 0.0635)
			(type default)
		)
		(layer "In5.Cu")
	)
	(gr_arc
		(start 149.854158 -74.554588)
		(mid 150.171785 -74.686101)
		(end 150.489412 -74.554588)
		(stroke
			(width 0.0635)
			(type default)
		)
		(layer "In5.Cu")
	)
	(gr_line
		(start 150.437596 -75.184)
		(end 150.749 -75.184)
		(stroke
			(width 0.0635)
			(type default)
		)
		(layer "In5.Cu")
	)
	(gr_line
		(start 150.450296 -73.75017)
		(end 150.579328 -73.879202)
		(stroke
			(width 0.0635)
			(type default)
		)
		(layer "In5.Cu")
	)
	(gr_line
		(start 150.489412 -74.554588)
		(end 150.579328 -74.464672)
		(stroke
			(width 0.0635)
			(type default)
		)
		(layer "In5.Cu")
	)
	(gr_arc
		(start 150.579328 -74.464672)
		(mid 150.700728 -74.171926)
		(end 150.579328 -73.879202)
		(stroke
			(width 0.0635)
			(type default)
		)
		(layer "In5.Cu")
	)
	(gr_arc
		(start 150.978362 -75.278996)
		(mid 150.87313 -75.208682)
		(end 150.749 -75.184)
		(stroke
			(width 0.0635)
			(type default)
		)
		(layer "In5.Cu")
	)
	(gr_line
		(start 150.978362 -75.278996)
		(end 151.449786 -75.75042)
		(stroke
			(width 0.0635)
			(type default)
		)
		(layer "In5.Cu")
	)
	(gr_line
		(start 152.450546 -80.25003)
		(end 152.831038 -79.488538)
		(stroke
			(width 0.0635)
			(type default)
		)
		(layer "In5.Cu")
	)
	(gr_line
		(start 152.626568 -79.244698)
		(end 152.627584 -79.245206)
		(stroke
			(width 0.0635)
			(type default)
		)
		(layer "In5.Cu")
	)
	(gr_line
		(start 152.774142 -79.318104)
		(end 152.773888 -79.318104)
		(stroke
			(width 0.0635)
			(type default)
		)
		(layer "In5.Cu")
	)
	(gr_arc
		(start 152.831038 -79.488538)
		(mid 152.837797 -79.391593)
		(end 152.774142 -79.318104)
		(stroke
			(width 0.0635)
			(type default)
		)
		(layer "In5.Cu")
	)
	(gr_line
		(start 152.893014 -79.06512)
		(end 152.898348 -79.067914)
		(stroke
			(width 0.0635)
			(type default)
		)
		(layer "In5.Cu")
	)
	(gr_line
		(start 152.898348 -79.067914)
		(end 152.898856 -79.068168)
		(stroke
			(width 0.0635)
			(type default)
		)
		(layer "In5.Cu")
	)
	(gr_line
		(start 152.89911 -79.068168)
		(end 152.899364 -79.068168)
		(stroke
			(width 0.0635)
			(type default)
		)
		(layer "In5.Cu")
	)
	(gr_arc
		(start 152.899364 -79.068168)
		(mid 152.996348 -79.074997)
		(end 153.069798 -79.011272)
		(stroke
			(width 0.0635)
			(type default)
		)
		(layer "In5.Cu")
	)
	(gr_line
		(start 153.069798 -79.011272)
		(end 153.450036 -78.24978)
		(stroke
			(width 0.0635)
			(type default)
		)
		(layer "In5.Cu")
	)
	(gr_line
		(start 154.432 -74.803)
		(end 154.453844 -74.803)
		(stroke
			(width 0.0635)
			(type default)
		)
		(layer "In5.Cu")
	)
	(gr_line
		(start 154.449526 -73.75017)
		(end 154.940254 -74.240898)
		(stroke
			(width 0.0635)
			(type default)
		)
		(layer "In5.Cu")
	)
	(gr_line
		(start 154.850338 -74.638916)
		(end 154.940254 -74.548746)
		(stroke
			(width 0.0635)
			(type default)
		)
		(layer "In5.Cu")
	)
	(gr_arc
		(start 154.940254 -74.548746)
		(mid 155.004018 -74.394816)
		(end 154.940254 -74.240898)
		(stroke
			(width 0.0635)
			(type default)
		)
		(layer "In5.Cu")
	)
	(gr_arc
		(start 155.029916 -75.329796)
		(mid 154.755691 -75.146658)
		(end 154.432254 -75.0824)
		(stroke
			(width 0.0635)
			(type default)
		)
		(layer "In5.Cu")
	)
	(gr_line
		(start 155.029916 -75.329796)
		(end 155.450286 -75.75042)
		(stroke
			(width 0.0635)
			(type default)
		)
		(layer "In5.Cu")
	)
	(gr_arc
		(start 156.440124 -64.74333)
		(mid 156.373398 -64.689453)
		(end 156.290264 -64.6684)
		(stroke
			(width 0.0635)
			(type default)
		)
		(layer "In5.Cu")
	)
	(gr_arc
		(start 156.440124 -64.74333)
		(mid 156.506869 -64.797154)
		(end 156.589984 -64.81826)
		(stroke
			(width 0.0635)
			(type default)
		)
		(layer "In5.Cu")
	)
	(gr_line
		(start 156.572204 -64.389)
		(end 156.988764 -64.389)
		(stroke
			(width 0.0635)
			(type default)
		)
		(layer "In5.Cu")
	)
	(gr_line
		(start 156.589984 -64.81826)
		(end 156.970984 -64.81826)
		(stroke
			(width 0.0635)
			(type default)
		)
		(layer "In5.Cu")
	)
	(gr_arc
		(start 156.970984 -64.81826)
		(mid 157.05412 -64.797196)
		(end 157.120844 -64.74333)
		(stroke
			(width 0.0635)
			(type default)
		)
		(layer "In5.Cu")
	)
	(gr_arc
		(start 157.270704 -64.6684)
		(mid 157.187597 -64.68951)
		(end 157.120844 -64.74333)
		(stroke
			(width 0.0635)
			(type default)
		)
		(layer "In5.Cu")
	)
	(gr_arc
		(start 157.801564 -64.74333)
		(mid 157.734833 -64.689473)
		(end 157.651704 -64.6684)
		(stroke
			(width 0.0635)
			(type default)
		)
		(layer "In5.Cu")
	)
	(gr_arc
		(start 157.801564 -64.74333)
		(mid 157.868309 -64.797154)
		(end 157.951424 -64.81826)
		(stroke
			(width 0.0635)
			(type default)
		)
		(layer "In5.Cu")
	)
	(gr_line
		(start 157.933644 -64.389)
		(end 158.350204 -64.389)
		(stroke
			(width 0.0635)
			(type default)
		)
		(layer "In5.Cu")
	)
	(gr_line
		(start 157.951424 -64.81826)
		(end 158.332424 -64.81826)
		(stroke
			(width 0.0635)
			(type default)
		)
		(layer "In5.Cu")
	)
	(gr_arc
		(start 158.332424 -64.81826)
		(mid 158.41556 -64.797196)
		(end 158.482284 -64.74333)
		(stroke
			(width 0.0635)
			(type default)
		)
		(layer "In5.Cu")
	)
	(gr_arc
		(start 158.632144 -64.6684)
		(mid 158.549027 -64.689497)
		(end 158.482284 -64.74333)
		(stroke
			(width 0.0635)
			(type default)
		)
		(layer "In5.Cu")
	)
	(gr_arc
		(start 158.837122 -71.22033)
		(mid 158.770396 -71.166453)
		(end 158.687262 -71.1454)
		(stroke
			(width 0.0635)
			(type default)
		)
		(layer "In5.Cu")
	)
	(gr_arc
		(start 158.837122 -71.22033)
		(mid 158.903846 -71.274219)
		(end 158.986982 -71.29526)
		(stroke
			(width 0.0635)
			(type default)
		)
		(layer "In5.Cu")
	)
	(gr_line
		(start 158.969202 -70.866)
		(end 159.385762 -70.866)
		(stroke
			(width 0.0635)
			(type default)
		)
		(layer "In5.Cu")
	)
	(gr_line
		(start 158.986982 -71.29526)
		(end 159.367982 -71.29526)
		(stroke
			(width 0.0635)
			(type default)
		)
		(layer "In5.Cu")
	)
	(gr_arc
		(start 159.163004 -64.74333)
		(mid 159.096276 -64.689459)
		(end 159.013144 -64.6684)
		(stroke
			(width 0.0635)
			(type default)
		)
		(layer "In5.Cu")
	)
	(gr_arc
		(start 159.163004 -64.74333)
		(mid 159.229749 -64.797154)
		(end 159.312864 -64.81826)
		(stroke
			(width 0.0635)
			(type default)
		)
		(layer "In5.Cu")
	)
	(gr_line
		(start 159.295084 -64.389)
		(end 159.711644 -64.389)
		(stroke
			(width 0.0635)
			(type default)
		)
		(layer "In5.Cu")
	)
	(gr_line
		(start 159.312864 -64.81826)
		(end 159.693864 -64.81826)
		(stroke
			(width 0.0635)
			(type default)
		)
		(layer "In5.Cu")
	)
	(gr_arc
		(start 159.367982 -71.29526)
		(mid 159.451118 -71.274196)
		(end 159.517842 -71.22033)
		(stroke
			(width 0.0635)
			(type default)
		)
		(layer "In5.Cu")
	)
	(gr_arc
		(start 159.429704 -88.392)
		(mid 159.51284 -88.370936)
		(end 159.579564 -88.31707)
		(stroke
			(width 0.0635)
			(type default)
		)
		(layer "In5.Cu")
	)
	(gr_arc
		(start 159.667702 -71.1454)
		(mid 159.584551 -71.16643)
		(end 159.517842 -71.22033)
		(stroke
			(width 0.0635)
			(type default)
		)
		(layer "In5.Cu")
	)
	(gr_arc
		(start 159.693864 -64.81826)
		(mid 159.777 -64.797196)
		(end 159.843724 -64.74333)
		(stroke
			(width 0.0635)
			(type default)
		)
		(layer "In5.Cu")
	)
	(gr_line
		(start 159.711644 -88.6714)
		(end 160.128204 -88.6714)
		(stroke
			(width 0.0635)
			(type default)
		)
		(layer "In5.Cu")
	)
	(gr_arc
		(start 159.729424 -88.24214)
		(mid 159.646296 -88.263199)
		(end 159.579564 -88.31707)
		(stroke
			(width 0.0635)
			(type default)
		)
		(layer "In5.Cu")
	)
	(gr_line
		(start 159.729424 -88.24214)
		(end 160.110424 -88.24214)
		(stroke
			(width 0.0635)
			(type default)
		)
		(layer "In5.Cu")
	)
	(gr_arc
		(start 159.993584 -64.6684)
		(mid 159.910482 -64.689517)
		(end 159.843724 -64.74333)
		(stroke
			(width 0.0635)
			(type default)
		)
		(layer "In5.Cu")
	)
	(gr_arc
		(start 160.198562 -71.22033)
		(mid 160.131831 -71.166473)
		(end 160.048702 -71.1454)
		(stroke
			(width 0.0635)
			(type default)
		)
		(layer "In5.Cu")
	)
	(gr_arc
		(start 160.198562 -71.22033)
		(mid 160.265286 -71.274219)
		(end 160.348422 -71.29526)
		(stroke
			(width 0.0635)
			(type default)
		)
		(layer "In5.Cu")
	)
	(gr_arc
		(start 160.260284 -88.31707)
		(mid 160.193558 -88.263196)
		(end 160.110424 -88.24214)
		(stroke
			(width 0.0635)
			(type default)
		)
		(layer "In5.Cu")
	)
	(gr_arc
		(start 160.260284 -88.31707)
		(mid 160.327008 -88.370959)
		(end 160.410144 -88.392)
		(stroke
			(width 0.0635)
			(type default)
		)
		(layer "In5.Cu")
	)
	(gr_line
		(start 160.330642 -70.866)
		(end 160.747202 -70.866)
		(stroke
			(width 0.0635)
			(type default)
		)
		(layer "In5.Cu")
	)
	(gr_line
		(start 160.348422 -71.29526)
		(end 160.729422 -71.29526)
		(stroke
			(width 0.0635)
			(type default)
		)
		(layer "In5.Cu")
	)
	(gr_arc
		(start 160.729422 -71.29526)
		(mid 160.812558 -71.274196)
		(end 160.879282 -71.22033)
		(stroke
			(width 0.0635)
			(type default)
		)
		(layer "In5.Cu")
	)
	(gr_arc
		(start 160.791144 -88.392)
		(mid 160.87428 -88.370936)
		(end 160.941004 -88.31707)
		(stroke
			(width 0.0635)
			(type default)
		)
		(layer "In5.Cu")
	)
	(gr_arc
		(start 161.029142 -71.1454)
		(mid 160.946006 -71.16645)
		(end 160.879282 -71.22033)
		(stroke
			(width 0.0635)
			(type default)
		)
		(layer "In5.Cu")
	)
	(gr_line
		(start 161.073084 -88.6714)
		(end 161.489644 -88.6714)
		(stroke
			(width 0.0635)
			(type default)
		)
		(layer "In5.Cu")
	)
	(gr_arc
		(start 161.090864 -88.24214)
		(mid 161.007726 -88.263186)
		(end 160.941004 -88.31707)
		(stroke
			(width 0.0635)
			(type default)
		)
		(layer "In5.Cu")
	)
	(gr_line
		(start 161.090864 -88.24214)
		(end 161.471864 -88.24214)
		(stroke
			(width 0.0635)
			(type default)
		)
		(layer "In5.Cu")
	)
	(gr_arc
		(start 161.560002 -71.22033)
		(mid 161.493274 -71.16646)
		(end 161.410142 -71.1454)
		(stroke
			(width 0.0635)
			(type default)
		)
		(layer "In5.Cu")
	)
	(gr_arc
		(start 161.560002 -71.22033)
		(mid 161.626726 -71.274219)
		(end 161.709862 -71.29526)
		(stroke
			(width 0.0635)
			(type default)
		)
		(layer "In5.Cu")
	)
	(gr_arc
		(start 161.621724 -88.31707)
		(mid 161.555001 -88.263182)
		(end 161.471864 -88.24214)
		(stroke
			(width 0.0635)
			(type default)
		)
		(layer "In5.Cu")
	)
	(gr_arc
		(start 161.621724 -88.31707)
		(mid 161.688448 -88.370959)
		(end 161.771584 -88.392)
		(stroke
			(width 0.0635)
			(type default)
		)
		(layer "In5.Cu")
	)
	(gr_line
		(start 161.692082 -70.866)
		(end 162.108642 -70.866)
		(stroke
			(width 0.0635)
			(type default)
		)
		(layer "In5.Cu")
	)
	(gr_line
		(start 161.709862 -71.29526)
		(end 162.090862 -71.29526)
		(stroke
			(width 0.0635)
			(type default)
		)
		(layer "In5.Cu")
	)
	(gr_arc
		(start 162.090862 -71.29526)
		(mid 162.173998 -71.274196)
		(end 162.240722 -71.22033)
		(stroke
			(width 0.0635)
			(type default)
		)
		(layer "In5.Cu")
	)
	(gr_arc
		(start 162.152584 -88.392)
		(mid 162.23572 -88.370936)
		(end 162.302444 -88.31707)
		(stroke
			(width 0.0635)
			(type default)
		)
		(layer "In5.Cu")
	)
	(gr_arc
		(start 162.28695 -64.74333)
		(mid 162.220208 -64.689488)
		(end 162.13709 -64.6684)
		(stroke
			(width 0.0635)
			(type default)
		)
		(layer "In5.Cu")
	)
	(gr_arc
		(start 162.28695 -64.74333)
		(mid 162.353695 -64.797154)
		(end 162.43681 -64.81826)
		(stroke
			(width 0.0635)
			(type default)
		)
		(layer "In5.Cu")
	)
	(gr_arc
		(start 162.390582 -71.1454)
		(mid 162.307436 -71.166437)
		(end 162.240722 -71.22033)
		(stroke
			(width 0.0635)
			(type default)
		)
		(layer "In5.Cu")
	)
	(gr_line
		(start 162.41903 -64.389)
		(end 162.83559 -64.389)
		(stroke
			(width 0.0635)
			(type default)
		)
		(layer "In5.Cu")
	)
	(gr_line
		(start 162.434524 -88.6714)
		(end 162.851084 -88.6714)
		(stroke
			(width 0.0635)
			(type default)
		)
		(layer "In5.Cu")
	)
	(gr_line
		(start 162.43681 -64.81826)
		(end 162.81781 -64.81826)
		(stroke
			(width 0.0635)
			(type default)
		)
		(layer "In5.Cu")
	)
	(gr_arc
		(start 162.452304 -88.24214)
		(mid 162.369156 -88.263172)
		(end 162.302444 -88.31707)
		(stroke
			(width 0.0635)
			(type default)
		)
		(layer "In5.Cu")
	)
	(gr_line
		(start 162.452304 -88.24214)
		(end 162.833304 -88.24214)
		(stroke
			(width 0.0635)
			(type default)
		)
		(layer "In5.Cu")
	)
	(gr_arc
		(start 162.81781 -64.81826)
		(mid 162.900925 -64.797177)
		(end 162.96767 -64.74333)
		(stroke
			(width 0.0635)
			(type default)
		)
		(layer "In5.Cu")
	)
	(gr_arc
		(start 162.983164 -88.31707)
		(mid 162.916437 -88.263202)
		(end 162.833304 -88.24214)
		(stroke
			(width 0.0635)
			(type default)
		)
		(layer "In5.Cu")
	)
	(gr_arc
		(start 162.983164 -88.31707)
		(mid 163.049888 -88.370959)
		(end 163.133024 -88.392)
		(stroke
			(width 0.0635)
			(type default)
		)
		(layer "In5.Cu")
	)
	(gr_arc
		(start 163.11753 -64.6684)
		(mid 163.034417 -64.689501)
		(end 162.96767 -64.74333)
		(stroke
			(width 0.0635)
			(type default)
		)
		(layer "In5.Cu")
	)
	(gr_arc
		(start 163.64839 -64.74333)
		(mid 163.581644 -64.689508)
		(end 163.49853 -64.6684)
		(stroke
			(width 0.0635)
			(type default)
		)
		(layer "In5.Cu")
	)
	(gr_arc
		(start 163.64839 -64.74333)
		(mid 163.715135 -64.797154)
		(end 163.79825 -64.81826)
		(stroke
			(width 0.0635)
			(type default)
		)
		(layer "In5.Cu")
	)
	(gr_line
		(start 163.78047 -64.389)
		(end 164.19703 -64.389)
		(stroke
			(width 0.0635)
			(type default)
		)
		(layer "In5.Cu")
	)
	(gr_line
		(start 163.79825 -64.81826)
		(end 164.17925 -64.81826)
		(stroke
			(width 0.0635)
			(type default)
		)
		(layer "In5.Cu")
	)
	(gr_arc
		(start 164.17925 -64.81826)
		(mid 164.262365 -64.797177)
		(end 164.32911 -64.74333)
		(stroke
			(width 0.0635)
			(type default)
		)
		(layer "In5.Cu")
	)
	(gr_arc
		(start 164.204142 -71.22033)
		(mid 164.137417 -71.166447)
		(end 164.054282 -71.1454)
		(stroke
			(width 0.0635)
			(type default)
		)
		(layer "In5.Cu")
	)
	(gr_arc
		(start 164.204142 -71.22033)
		(mid 164.270887 -71.274154)
		(end 164.354002 -71.29526)
		(stroke
			(width 0.0635)
			(type default)
		)
		(layer "In5.Cu")
	)
	(gr_arc
		(start 164.20973 -88.392)
		(mid 164.292866 -88.370936)
		(end 164.35959 -88.31707)
		(stroke
			(width 0.0635)
			(type default)
		)
		(layer "In5.Cu")
	)
	(gr_line
		(start 164.336222 -70.866)
		(end 164.752782 -70.866)
		(stroke
			(width 0.0635)
			(type default)
		)
		(layer "In5.Cu")
	)
	(gr_line
		(start 164.354002 -71.29526)
		(end 164.735002 -71.29526)
		(stroke
			(width 0.0635)
			(type default)
		)
		(layer "In5.Cu")
	)
	(gr_arc
		(start 164.47897 -64.6684)
		(mid 164.395846 -64.689488)
		(end 164.32911 -64.74333)
		(stroke
			(width 0.0635)
			(type default)
		)
		(layer "In5.Cu")
	)
	(gr_line
		(start 164.49167 -88.6714)
		(end 164.90823 -88.6714)
		(stroke
			(width 0.0635)
			(type default)
		)
		(layer "In5.Cu")
	)
	(gr_arc
		(start 164.50945 -88.24214)
		(mid 164.426335 -88.263238)
		(end 164.35959 -88.31707)
		(stroke
			(width 0.0635)
			(type default)
		)
		(layer "In5.Cu")
	)
	(gr_line
		(start 164.50945 -88.24214)
		(end 164.89045 -88.24214)
		(stroke
			(width 0.0635)
			(type default)
		)
		(layer "In5.Cu")
	)
	(gr_arc
		(start 164.735002 -71.29526)
		(mid 164.818138 -71.274196)
		(end 164.884862 -71.22033)
		(stroke
			(width 0.0635)
			(type default)
		)
		(layer "In5.Cu")
	)
	(gr_arc
		(start 165.00983 -64.74333)
		(mid 164.943087 -64.689495)
		(end 164.85997 -64.6684)
		(stroke
			(width 0.0635)
			(type default)
		)
		(layer "In5.Cu")
	)
	(gr_arc
		(start 165.00983 -64.74333)
		(mid 165.076575 -64.797154)
		(end 165.15969 -64.81826)
		(stroke
			(width 0.0635)
			(type default)
		)
		(layer "In5.Cu")
	)
	(gr_arc
		(start 165.034722 -71.1454)
		(mid 164.951611 -71.166504)
		(end 164.884862 -71.22033)
		(stroke
			(width 0.0635)
			(type default)
		)
		(layer "In5.Cu")
	)
	(gr_arc
		(start 165.04031 -88.31707)
		(mid 164.973586 -88.263187)
		(end 164.89045 -88.24214)
		(stroke
			(width 0.0635)
			(type default)
		)
		(layer "In5.Cu")
	)
	(gr_arc
		(start 165.04031 -88.31707)
		(mid 165.107055 -88.370894)
		(end 165.19017 -88.392)
		(stroke
			(width 0.0635)
			(type default)
		)
		(layer "In5.Cu")
	)
	(gr_line
		(start 165.14191 -64.389)
		(end 165.55847 -64.389)
		(stroke
			(width 0.0635)
			(type default)
		)
		(layer "In5.Cu")
	)
	(gr_line
		(start 165.15969 -64.81826)
		(end 165.54069 -64.81826)
		(stroke
			(width 0.0635)
			(type default)
		)
		(layer "In5.Cu")
	)
	(gr_arc
		(start 165.54069 -64.81826)
		(mid 165.623805 -64.797177)
		(end 165.69055 -64.74333)
		(stroke
			(width 0.0635)
			(type default)
		)
		(layer "In5.Cu")
	)
	(gr_arc
		(start 165.565582 -71.22033)
		(mid 165.498853 -71.166467)
		(end 165.415722 -71.1454)
		(stroke
			(width 0.0635)
			(type default)
		)
		(layer "In5.Cu")
	)
	(gr_arc
		(start 165.565582 -71.22033)
		(mid 165.632327 -71.274154)
		(end 165.715442 -71.29526)
		(stroke
			(width 0.0635)
			(type default)
		)
		(layer "In5.Cu")
	)
	(gr_arc
		(start 165.57117 -88.392)
		(mid 165.654306 -88.370936)
		(end 165.72103 -88.31707)
		(stroke
			(width 0.0635)
			(type default)
		)
		(layer "In5.Cu")
	)
	(gr_line
		(start 165.697662 -70.866)
		(end 166.114222 -70.866)
		(stroke
			(width 0.0635)
			(type default)
		)
		(layer "In5.Cu")
	)
	(gr_line
		(start 165.715442 -71.29526)
		(end 166.096442 -71.29526)
		(stroke
			(width 0.0635)
			(type default)
		)
		(layer "In5.Cu")
	)
	(gr_arc
		(start 165.84041 -64.6684)
		(mid 165.757302 -64.689508)
		(end 165.69055 -64.74333)
		(stroke
			(width 0.0635)
			(type default)
		)
		(layer "In5.Cu")
	)
	(gr_line
		(start 165.85311 -88.6714)
		(end 166.26967 -88.6714)
		(stroke
			(width 0.0635)
			(type default)
		)
		(layer "In5.Cu")
	)
	(gr_arc
		(start 165.87089 -88.24214)
		(mid 165.78779 -88.263258)
		(end 165.72103 -88.31707)
		(stroke
			(width 0.0635)
			(type default)
		)
		(layer "In5.Cu")
	)
	(gr_line
		(start 165.87089 -88.24214)
		(end 166.25189 -88.24214)
		(stroke
			(width 0.0635)
			(type default)
		)
		(layer "In5.Cu")
	)
	(gr_arc
		(start 166.096442 -71.29526)
		(mid 166.179578 -71.274196)
		(end 166.246302 -71.22033)
		(stroke
			(width 0.0635)
			(type default)
		)
		(layer "In5.Cu")
	)
	(gr_arc
		(start 166.396162 -71.1454)
		(mid 166.31304 -71.166491)
		(end 166.246302 -71.22033)
		(stroke
			(width 0.0635)
			(type default)
		)
		(layer "In5.Cu")
	)
	(gr_arc
		(start 166.40175 -88.31707)
		(mid 166.335022 -88.263207)
		(end 166.25189 -88.24214)
		(stroke
			(width 0.0635)
			(type default)
		)
		(layer "In5.Cu")
	)
	(gr_arc
		(start 166.40175 -88.31707)
		(mid 166.468495 -88.370894)
		(end 166.55161 -88.392)
		(stroke
			(width 0.0635)
			(type default)
		)
		(layer "In5.Cu")
	)
	(gr_arc
		(start 166.927022 -71.22033)
		(mid 166.860296 -71.166453)
		(end 166.777162 -71.1454)
		(stroke
			(width 0.0635)
			(type default)
		)
		(layer "In5.Cu")
	)
	(gr_arc
		(start 166.927022 -71.22033)
		(mid 166.993767 -71.274154)
		(end 167.076882 -71.29526)
		(stroke
			(width 0.0635)
			(type default)
		)
		(layer "In5.Cu")
	)
	(gr_arc
		(start 166.93261 -88.392)
		(mid 167.015746 -88.370936)
		(end 167.08247 -88.31707)
		(stroke
			(width 0.0635)
			(type default)
		)
		(layer "In5.Cu")
	)
	(gr_line
		(start 167.059102 -70.866)
		(end 167.475662 -70.866)
		(stroke
			(width 0.0635)
			(type default)
		)
		(layer "In5.Cu")
	)
	(gr_line
		(start 167.076882 -71.29526)
		(end 167.457882 -71.29526)
		(stroke
			(width 0.0635)
			(type default)
		)
		(layer "In5.Cu")
	)
	(gr_line
		(start 167.21455 -88.6714)
		(end 167.63111 -88.6714)
		(stroke
			(width 0.0635)
			(type default)
		)
		(layer "In5.Cu")
	)
	(gr_arc
		(start 167.23233 -88.24214)
		(mid 167.14922 -88.263244)
		(end 167.08247 -88.31707)
		(stroke
			(width 0.0635)
			(type default)
		)
		(layer "In5.Cu")
	)
	(gr_line
		(start 167.23233 -88.24214)
		(end 167.61333 -88.24214)
		(stroke
			(width 0.0635)
			(type default)
		)
		(layer "In5.Cu")
	)
	(gr_arc
		(start 167.457882 -71.29526)
		(mid 167.541018 -71.274196)
		(end 167.607742 -71.22033)
		(stroke
			(width 0.0635)
			(type default)
		)
		(layer "In5.Cu")
	)
	(gr_arc
		(start 167.757602 -71.1454)
		(mid 167.674496 -71.166511)
		(end 167.607742 -71.22033)
		(stroke
			(width 0.0635)
			(type default)
		)
		(layer "In5.Cu")
	)
	(gr_arc
		(start 167.76319 -88.31707)
		(mid 167.696465 -88.263194)
		(end 167.61333 -88.24214)
		(stroke
			(width 0.0635)
			(type default)
		)
		(layer "In5.Cu")
	)
	(gr_arc
		(start 167.76319 -88.31707)
		(mid 167.829935 -88.370894)
		(end 167.91305 -88.392)
		(stroke
			(width 0.0635)
			(type default)
		)
		(layer "In5.Cu")
	)
	(gr_arc
		(start 168.32199 -64.74333)
		(mid 168.255261 -64.689464)
		(end 168.17213 -64.6684)
		(stroke
			(width 0.0635)
			(type default)
		)
		(layer "In5.Cu")
	)
	(gr_arc
		(start 168.32199 -64.74333)
		(mid 168.388735 -64.797154)
		(end 168.47185 -64.81826)
		(stroke
			(width 0.0635)
			(type default)
		)
		(layer "In5.Cu")
	)
	(gr_line
		(start 168.45407 -64.389)
		(end 168.87063 -64.389)
		(stroke
			(width 0.0635)
			(type default)
		)
		(layer "In5.Cu")
	)
	(gr_line
		(start 168.47185 -64.81826)
		(end 168.85285 -64.81826)
		(stroke
			(width 0.0635)
			(type default)
		)
		(layer "In5.Cu")
	)
	(gr_arc
		(start 168.85285 -64.81826)
		(mid 168.935986 -64.797196)
		(end 169.00271 -64.74333)
		(stroke
			(width 0.0635)
			(type default)
		)
		(layer "In5.Cu")
	)
	(gr_arc
		(start 169.15257 -64.6684)
		(mid 169.069446 -64.689488)
		(end 169.00271 -64.74333)
		(stroke
			(width 0.0635)
			(type default)
		)
		(layer "In5.Cu")
	)
	(gr_arc
		(start 172.760894 -88.392)
		(mid 172.844009 -88.370917)
		(end 172.910754 -88.31707)
		(stroke
			(width 0.0635)
			(type default)
		)
		(layer "In5.Cu")
	)
	(gr_line
		(start 173.042834 -88.6714)
		(end 173.459394 -88.6714)
		(stroke
			(width 0.0635)
			(type default)
		)
		(layer "In5.Cu")
	)
	(gr_arc
		(start 173.060614 -88.24214)
		(mid 172.977508 -88.26325)
		(end 172.910754 -88.31707)
		(stroke
			(width 0.0635)
			(type default)
		)
		(layer "In5.Cu")
	)
	(gr_line
		(start 173.060614 -88.24214)
		(end 173.441614 -88.24214)
		(stroke
			(width 0.0635)
			(type default)
		)
		(layer "In5.Cu")
	)
	(gr_arc
		(start 173.591474 -88.31707)
		(mid 173.524737 -88.26321)
		(end 173.441614 -88.24214)
		(stroke
			(width 0.0635)
			(type default)
		)
		(layer "In5.Cu")
	)
	(gr_arc
		(start 173.591474 -88.31707)
		(mid 173.658219 -88.370894)
		(end 173.741334 -88.392)
		(stroke
			(width 0.0635)
			(type default)
		)
		(layer "In5.Cu")
	)
	(gr_arc
		(start 174.122334 -88.392)
		(mid 174.205449 -88.370917)
		(end 174.272194 -88.31707)
		(stroke
			(width 0.0635)
			(type default)
		)
		(layer "In5.Cu")
	)
	(gr_line
		(start 174.404274 -88.6714)
		(end 174.820834 -88.6714)
		(stroke
			(width 0.0635)
			(type default)
		)
		(layer "In5.Cu")
	)
	(gr_arc
		(start 174.422054 -88.24214)
		(mid 174.338938 -88.263236)
		(end 174.272194 -88.31707)
		(stroke
			(width 0.0635)
			(type default)
		)
		(layer "In5.Cu")
	)
	(gr_line
		(start 174.422054 -88.24214)
		(end 174.803054 -88.24214)
		(stroke
			(width 0.0635)
			(type default)
		)
		(layer "In5.Cu")
	)
	(gr_arc
		(start 174.952914 -88.31707)
		(mid 174.886173 -88.26323)
		(end 174.803054 -88.24214)
		(stroke
			(width 0.0635)
			(type default)
		)
		(layer "In5.Cu")
	)
	(gr_arc
		(start 174.952914 -88.31707)
		(mid 175.019659 -88.370894)
		(end 175.102774 -88.392)
		(stroke
			(width 0.0635)
			(type default)
		)
		(layer "In5.Cu")
	)
	(gr_arc
		(start 175.483774 -88.392)
		(mid 175.566889 -88.370917)
		(end 175.633634 -88.31707)
		(stroke
			(width 0.0635)
			(type default)
		)
		(layer "In5.Cu")
	)
	(gr_line
		(start 175.765714 -88.6714)
		(end 176.182274 -88.6714)
		(stroke
			(width 0.0635)
			(type default)
		)
		(layer "In5.Cu")
	)
	(gr_arc
		(start 175.783494 -88.24214)
		(mid 175.700393 -88.263256)
		(end 175.633634 -88.31707)
		(stroke
			(width 0.0635)
			(type default)
		)
		(layer "In5.Cu")
	)
	(gr_line
		(start 175.783494 -88.24214)
		(end 176.164494 -88.24214)
		(stroke
			(width 0.0635)
			(type default)
		)
		(layer "In5.Cu")
	)
	(gr_arc
		(start 176.314354 -88.31707)
		(mid 176.247616 -88.263216)
		(end 176.164494 -88.24214)
		(stroke
			(width 0.0635)
			(type default)
		)
		(layer "In5.Cu")
	)
	(gr_arc
		(start 176.314354 -88.31707)
		(mid 176.381099 -88.370894)
		(end 176.464214 -88.392)
		(stroke
			(width 0.0635)
			(type default)
		)
		(layer "In5.Cu")
	)
	(gr_line
		(start 182.450232 -74.134472)
		(end 182.450486 -73.75017)
		(stroke
			(width 0.0635)
			(type default)
		)
		(layer "In5.Cu")
	)
	(gr_arc
		(start 182.450232 -74.134472)
		(mid 182.627042 -74.444222)
		(end 182.983632 -74.44994)
		(stroke
			(width 0.0635)
			(type default)
		)
		(layer "In5.Cu")
	)
	(gr_arc
		(start 182.983632 -74.44994)
		(mid 183.010143 -74.433894)
		(end 183.035194 -74.41565)
		(stroke
			(width 0.0635)
			(type default)
		)
		(layer "In5.Cu")
	)
	(gr_arc
		(start 183.035194 -74.41565)
		(mid 183.050547 -74.402858)
		(end 183.065166 -74.389234)
		(stroke
			(width 0.0635)
			(type default)
		)
		(layer "In5.Cu")
	)
	(gr_line
		(start 183.065166 -74.389234)
		(end 183.178704 -74.27595)
		(stroke
			(width 0.0635)
			(type default)
		)
		(layer "In5.Cu")
	)
	(gr_arc
		(start 183.275478 -75.329034)
		(mid 183.320798 -75.557089)
		(end 183.449976 -75.75042)
		(stroke
			(width 0.0635)
			(type default)
		)
		(layer "In5.Cu")
	)
	(gr_line
		(start 183.275478 -74.867516)
		(end 183.275478 -75.329034)
		(stroke
			(width 0.0635)
			(type default)
		)
		(layer "In5.Cu")
	)
	(gr_arc
		(start 183.40324 -74.55916)
		(mid 183.308673 -74.700625)
		(end 183.275478 -74.867516)
		(stroke
			(width 0.0635)
			(type default)
		)
		(layer "In5.Cu")
	)
	(gr_line
		(start 184.449466 -80.25003)
		(end 184.976516 -79.72298)
		(stroke
			(width 0.0635)
			(type default)
		)
		(layer "In5.Cu")
	)
	(gr_line
		(start 184.976516 -79.72298)
		(end 185.0898 -79.60995)
		(stroke
			(width 0.0635)
			(type default)
		)
		(layer "In5.Cu")
	)
	(gr_arc
		(start 185.166 -79.121)
		(mid 185.278574 -79.19622)
		(end 185.411364 -79.2226)
		(stroke
			(width 0.0635)
			(type default)
		)
		(layer "In5.Cu")
	)
	(gr_arc
		(start 185.166 -78.534006)
		(mid 185.044377 -78.82754)
		(end 185.166 -79.121)
		(stroke
			(width 0.0635)
			(type default)
		)
		(layer "In5.Cu")
	)
	(gr_line
		(start 185.166 -78.534006)
		(end 185.450226 -78.24978)
		(stroke
			(width 0.0635)
			(type default)
		)
		(layer "In5.Cu")
	)
	(gr_arc
		(start 185.31078 -79.518256)
		(mid 185.191179 -79.542136)
		(end 185.0898 -79.60995)
		(stroke
			(width 0.0635)
			(type default)
		)
		(layer "In5.Cu")
	)
	(gr_line
		(start 185.31078 -79.518256)
		(end 185.5978 -79.518256)
		(stroke
			(width 0.0635)
			(type default)
		)
		(layer "In5.Cu")
	)
	(gr_line
		(start 185.411364 -79.2226)
		(end 185.608468 -79.2226)
		(stroke
			(width 0.0635)
			(type default)
		)
		(layer "In5.Cu")
	)
	(gr_arc
		(start 185.608468 -79.2226)
		(mid 185.683119 -79.207751)
		(end 185.74639 -79.16545)
		(stroke
			(width 0.0635)
			(type default)
		)
		(layer "In5.Cu")
	)
	(gr_arc
		(start 238.529876 -72.97293)
		(mid 238.463146 -72.919069)
		(end 238.380016 -72.898)
		(stroke
			(width 0.0635)
			(type default)
		)
		(layer "In5.Cu")
	)
	(gr_arc
		(start 238.529876 -72.97293)
		(mid 238.596621 -73.026754)
		(end 238.679736 -73.04786)
		(stroke
			(width 0.0635)
			(type default)
		)
		(layer "In5.Cu")
	)
	(gr_line
		(start 238.661956 -72.6186)
		(end 239.078516 -72.6186)
		(stroke
			(width 0.0635)
			(type default)
		)
		(layer "In5.Cu")
	)
	(gr_line
		(start 238.679736 -73.04786)
		(end 239.060736 -73.04786)
		(stroke
			(width 0.0635)
			(type default)
		)
		(layer "In5.Cu")
	)
	(gr_arc
		(start 239.060736 -73.04786)
		(mid 239.143872 -73.026796)
		(end 239.210596 -72.97293)
		(stroke
			(width 0.0635)
			(type default)
		)
		(layer "In5.Cu")
	)
	(gr_arc
		(start 239.360456 -72.898)
		(mid 239.277336 -72.919093)
		(end 239.210596 -72.97293)
		(stroke
			(width 0.0635)
			(type default)
		)
		(layer "In5.Cu")
	)
	(gr_arc
		(start 239.891316 -72.97293)
		(mid 239.824589 -72.919055)
		(end 239.741456 -72.898)
		(stroke
			(width 0.0635)
			(type default)
		)
		(layer "In5.Cu")
	)
	(gr_arc
		(start 239.891316 -72.97293)
		(mid 239.958061 -73.026754)
		(end 240.041176 -73.04786)
		(stroke
			(width 0.0635)
			(type default)
		)
		(layer "In5.Cu")
	)
	(gr_line
		(start 240.023396 -72.6186)
		(end 240.439956 -72.6186)
		(stroke
			(width 0.0635)
			(type default)
		)
		(layer "In5.Cu")
	)
	(gr_line
		(start 240.041176 -73.04786)
		(end 240.422176 -73.04786)
		(stroke
			(width 0.0635)
			(type default)
		)
		(layer "In5.Cu")
	)
	(gr_arc
		(start 240.422176 -73.04786)
		(mid 240.505312 -73.026796)
		(end 240.572036 -72.97293)
		(stroke
			(width 0.0635)
			(type default)
		)
		(layer "In5.Cu")
	)
	(gr_arc
		(start 240.721896 -72.898)
		(mid 240.638791 -72.919113)
		(end 240.572036 -72.97293)
		(stroke
			(width 0.0635)
			(type default)
		)
		(layer "In5.Cu")
	)
	(gr_arc
		(start 241.252756 -72.97293)
		(mid 241.186025 -72.919075)
		(end 241.102896 -72.898)
		(stroke
			(width 0.0635)
			(type default)
		)
		(layer "In5.Cu")
	)
	(gr_arc
		(start 241.252756 -72.97293)
		(mid 241.319501 -73.026754)
		(end 241.402616 -73.04786)
		(stroke
			(width 0.0635)
			(type default)
		)
		(layer "In5.Cu")
	)
	(gr_line
		(start 241.384836 -72.6186)
		(end 241.801396 -72.6186)
		(stroke
			(width 0.0635)
			(type default)
		)
		(layer "In5.Cu")
	)
	(gr_line
		(start 241.402616 -73.04786)
		(end 241.783616 -73.04786)
		(stroke
			(width 0.0635)
			(type default)
		)
		(layer "In5.Cu")
	)
	(gr_arc
		(start 241.783616 -73.04786)
		(mid 241.866752 -73.026796)
		(end 241.933476 -72.97293)
		(stroke
			(width 0.0635)
			(type default)
		)
		(layer "In5.Cu")
	)
	(gr_arc
		(start 242.083336 -72.898)
		(mid 242.000221 -72.919099)
		(end 241.933476 -72.97293)
		(stroke
			(width 0.0635)
			(type default)
		)
		(layer "In5.Cu")
	)
	(gr_arc
		(start 247.351296 -72.97293)
		(mid 247.284568 -72.919062)
		(end 247.201436 -72.898)
		(stroke
			(width 0.0635)
			(type default)
		)
		(layer "In5.Cu")
	)
	(gr_arc
		(start 247.351296 -72.97293)
		(mid 247.41802 -73.026819)
		(end 247.501156 -73.04786)
		(stroke
			(width 0.0635)
			(type default)
		)
		(layer "In5.Cu")
	)
	(gr_line
		(start 247.483376 -72.6186)
		(end 247.899936 -72.6186)
		(stroke
			(width 0.0635)
			(type default)
		)
		(layer "In5.Cu")
	)
	(gr_line
		(start 247.501156 -73.04786)
		(end 247.882156 -73.04786)
		(stroke
			(width 0.0635)
			(type default)
		)
		(layer "In5.Cu")
	)
	(gr_arc
		(start 247.882156 -73.04786)
		(mid 247.965292 -73.026796)
		(end 248.032016 -72.97293)
		(stroke
			(width 0.0635)
			(type default)
		)
		(layer "In5.Cu")
	)
	(gr_arc
		(start 248.181876 -72.898)
		(mid 248.098732 -72.919039)
		(end 248.032016 -72.97293)
		(stroke
			(width 0.0635)
			(type default)
		)
		(layer "In5.Cu")
	)
	(gr_arc
		(start 248.712736 -72.97293)
		(mid 248.646011 -72.919049)
		(end 248.562876 -72.898)
		(stroke
			(width 0.0635)
			(type default)
		)
		(layer "In5.Cu")
	)
	(gr_arc
		(start 248.712736 -72.97293)
		(mid 248.77946 -73.026819)
		(end 248.862596 -73.04786)
		(stroke
			(width 0.0635)
			(type default)
		)
		(layer "In5.Cu")
	)
	(gr_line
		(start 248.844816 -72.6186)
		(end 249.261376 -72.6186)
		(stroke
			(width 0.0635)
			(type default)
		)
		(layer "In5.Cu")
	)
	(gr_line
		(start 248.862596 -73.04786)
		(end 249.243596 -73.04786)
		(stroke
			(width 0.0635)
			(type default)
		)
		(layer "In5.Cu")
	)
	(gr_arc
		(start 249.243596 -73.04786)
		(mid 249.326732 -73.026796)
		(end 249.393456 -72.97293)
		(stroke
			(width 0.0635)
			(type default)
		)
		(layer "In5.Cu")
	)
	(gr_arc
		(start 249.543316 -72.898)
		(mid 249.460187 -72.919059)
		(end 249.393456 -72.97293)
		(stroke
			(width 0.0635)
			(type default)
		)
		(layer "In5.Cu")
	)
	(gr_arc
		(start 250.074176 -72.97293)
		(mid 250.007446 -72.919069)
		(end 249.924316 -72.898)
		(stroke
			(width 0.0635)
			(type default)
		)
		(layer "In5.Cu")
	)
	(gr_arc
		(start 250.074176 -72.97293)
		(mid 250.1409 -73.026819)
		(end 250.224036 -73.04786)
		(stroke
			(width 0.0635)
			(type default)
		)
		(layer "In5.Cu")
	)
	(gr_line
		(start 250.206256 -72.6186)
		(end 250.622816 -72.6186)
		(stroke
			(width 0.0635)
			(type default)
		)
		(layer "In5.Cu")
	)
	(gr_line
		(start 250.224036 -73.04786)
		(end 250.605036 -73.04786)
		(stroke
			(width 0.0635)
			(type default)
		)
		(layer "In5.Cu")
	)
	(gr_arc
		(start 250.605036 -73.04786)
		(mid 250.688172 -73.026796)
		(end 250.754896 -72.97293)
		(stroke
			(width 0.0635)
			(type default)
		)
		(layer "In5.Cu")
	)
	(gr_arc
		(start 250.904756 -72.898)
		(mid 250.821617 -72.919045)
		(end 250.754896 -72.97293)
		(stroke
			(width 0.0635)
			(type default)
		)
		(layer "In5.Cu")
	)
	(gr_arc
		(start 255.619758 -72.97293)
		(mid 255.553027 -72.919075)
		(end 255.469898 -72.898)
		(stroke
			(width 0.0635)
			(type default)
		)
		(layer "In5.Cu")
	)
	(gr_arc
		(start 255.619758 -72.97293)
		(mid 255.686482 -73.026819)
		(end 255.769618 -73.04786)
		(stroke
			(width 0.0635)
			(type default)
		)
		(layer "In5.Cu")
	)
	(gr_line
		(start 255.751838 -72.6186)
		(end 256.168398 -72.6186)
		(stroke
			(width 0.0635)
			(type default)
		)
		(layer "In5.Cu")
	)
	(gr_line
		(start 255.769618 -73.04786)
		(end 256.150618 -73.04786)
		(stroke
			(width 0.0635)
			(type default)
		)
		(layer "In5.Cu")
	)
	(gr_arc
		(start 256.150618 -73.04786)
		(mid 256.233754 -73.026796)
		(end 256.300478 -72.97293)
		(stroke
			(width 0.0635)
			(type default)
		)
		(layer "In5.Cu")
	)
	(gr_arc
		(start 256.450338 -72.898)
		(mid 256.367203 -72.919051)
		(end 256.300478 -72.97293)
		(stroke
			(width 0.0635)
			(type default)
		)
		(layer "In5.Cu")
	)
	(gr_arc
		(start 256.981198 -72.97293)
		(mid 256.91447 -72.919061)
		(end 256.831338 -72.898)
		(stroke
			(width 0.0635)
			(type default)
		)
		(layer "In5.Cu")
	)
	(gr_arc
		(start 256.981198 -72.97293)
		(mid 257.047922 -73.026819)
		(end 257.131058 -73.04786)
		(stroke
			(width 0.0635)
			(type default)
		)
		(layer "In5.Cu")
	)
	(gr_line
		(start 257.113278 -72.6186)
		(end 257.529838 -72.6186)
		(stroke
			(width 0.0635)
			(type default)
		)
		(layer "In5.Cu")
	)
	(gr_line
		(start 257.131058 -73.04786)
		(end 257.512058 -73.04786)
		(stroke
			(width 0.0635)
			(type default)
		)
		(layer "In5.Cu")
	)
	(gr_arc
		(start 257.512058 -73.04786)
		(mid 257.595194 -73.026796)
		(end 257.661918 -72.97293)
		(stroke
			(width 0.0635)
			(type default)
		)
		(layer "In5.Cu")
	)
	(gr_arc
		(start 257.811778 -72.898)
		(mid 257.728633 -72.919038)
		(end 257.661918 -72.97293)
		(stroke
			(width 0.0635)
			(type default)
		)
		(layer "In5.Cu")
	)
	(gr_arc
		(start 258.342638 -72.97293)
		(mid 258.275913 -72.919048)
		(end 258.192778 -72.898)
		(stroke
			(width 0.0635)
			(type default)
		)
		(layer "In5.Cu")
	)
	(gr_arc
		(start 258.342638 -72.97293)
		(mid 258.409362 -73.026819)
		(end 258.492498 -73.04786)
		(stroke
			(width 0.0635)
			(type default)
		)
		(layer "In5.Cu")
	)
	(gr_line
		(start 258.474718 -72.6186)
		(end 258.891278 -72.6186)
		(stroke
			(width 0.0635)
			(type default)
		)
		(layer "In5.Cu")
	)
	(gr_line
		(start 258.492498 -73.04786)
		(end 258.873498 -73.04786)
		(stroke
			(width 0.0635)
			(type default)
		)
		(layer "In5.Cu")
	)
	(gr_arc
		(start 258.873498 -73.04786)
		(mid 258.956634 -73.026796)
		(end 259.023358 -72.97293)
		(stroke
			(width 0.0635)
			(type default)
		)
		(layer "In5.Cu")
	)
	(gr_arc
		(start 259.173218 -72.898)
		(mid 259.090089 -72.919058)
		(end 259.023358 -72.97293)
		(stroke
			(width 0.0635)
			(type default)
		)
		(layer "In5.Cu")
	)
	(gr_line
		(start 284.607 -185.293)
		(end 284.739588 -185.425588)
		(stroke
			(width 0.0635)
			(type default)
		)
		(layer "In5.Cu")
	)
	(gr_line
		(start 285.2166 -185.840624)
		(end 285.2166 -185.9026)
		(stroke
			(width 0.0635)
			(type default)
		)
		(layer "In5.Cu")
	)
	(gr_arc
		(start 285.496 -185.166)
		(mid 285.289185 -185.47552)
		(end 285.2166 -185.840624)
		(stroke
			(width 0.0635)
			(type default)
		)
		(layer "In5.Cu")
	)
	(gr_arc
		(start 293.116 -79.7306)
		(mid 293.349425 -79.684075)
		(end 293.547292 -79.551784)
		(stroke
			(width 0.0635)
			(type default)
		)
		(layer "In5.Cu")
	)
	(gr_line
		(start 293.1668 -200.3806)
		(end 293.390828 -200.156572)
		(stroke
			(width 0.0508)
			(type default)
		)
		(layer "In5.Cu")
	)
	(gr_line
		(start 293.2557 -196.039232)
		(end 293.2557 -196.118226)
		(stroke
			(width 0.0508)
			(type default)
		)
		(layer "In5.Cu")
	)
	(gr_line
		(start 293.296848 -201.34326)
		(end 293.624 -201.34326)
		(stroke
			(width 0.0508)
			(type default)
		)
		(layer "In5.Cu")
	)
	(gr_line
		(start 293.393368 -199.427084)
		(end 293.3954 -199.424544)
		(stroke
			(width 0.0508)
			(type default)
		)
		(layer "In5.Cu")
	)
	(gr_arc
		(start 293.417498 -80.134714)
		(mid 293.279158 -80.04236)
		(end 293.116 -80.01)
		(stroke
			(width 0.0635)
			(type default)
		)
		(layer "In5.Cu")
	)
	(gr_line
		(start 293.417498 -80.134714)
		(end 293.6494 -80.36687)
		(stroke
			(width 0.0635)
			(type default)
		)
		(layer "In5.Cu")
	)
	(gr_line
		(start 293.4716 -195.709032)
		(end 293.4716 -195.788026)
		(stroke
			(width 0.0508)
			(type default)
		)
		(layer "In5.Cu")
	)
	(gr_line
		(start 293.547292 -79.551784)
		(end 293.6494 -79.44993)
		(stroke
			(width 0.0635)
			(type default)
		)
		(layer "In5.Cu")
	)
	(gr_line
		(start 293.5478 -200.814432)
		(end 293.723568 -200.9902)
		(stroke
			(width 0.0508)
			(type default)
		)
		(layer "In5.Cu")
	)
	(gr_line
		(start 293.5478 -200.6854)
		(end 293.5478 -200.814432)
		(stroke
			(width 0.0508)
			(type default)
		)
		(layer "In5.Cu")
	)
	(gr_line
		(start 293.5478 -200.6854)
		(end 293.723568 -200.509632)
		(stroke
			(width 0.0508)
			(type default)
		)
		(layer "In5.Cu")
	)
	(gr_line
		(start 293.624 -201.34326)
		(end 293.723568 -201.243692)
		(stroke
			(width 0.0508)
			(type default)
		)
		(layer "In5.Cu")
	)
	(gr_line
		(start 293.723568 -200.9902)
		(end 293.723568 -201.243692)
		(stroke
			(width 0.0508)
			(type default)
		)
		(layer "In5.Cu")
	)
	(gr_line
		(start 293.723568 -200.486772)
		(end 293.723568 -200.509632)
		(stroke
			(width 0.0508)
			(type default)
		)
		(layer "In5.Cu")
	)
	(gr_line
		(start 293.878 -186.563)
		(end 293.878 -186.657996)
		(stroke
			(width 0.0508)
			(type default)
		)
		(layer "In5.Cu")
	)
	(gr_line
		(start 293.906448 -185.852308)
		(end 294.2844 -186.23026)
		(stroke
			(width 0.0508)
			(type default)
		)
		(layer "In5.Cu")
	)
	(gr_line
		(start 294.21074 -186.988196)
		(end 294.2844 -186.914536)
		(stroke
			(width 0.0508)
			(type default)
		)
		(layer "In5.Cu")
	)
	(gr_line
		(start 294.2844 -186.23026)
		(end 294.2844 -186.914536)
		(stroke
			(width 0.0508)
			(type default)
		)
		(layer "In5.Cu")
	)
	(gr_line
		(start 295.324022 -198.31685)
		(end 295.324022 -198.33971)
		(stroke
			(width 0.0508)
			(type default)
		)
		(layer "In5.Cu")
	)
	(gr_line
		(start 295.3258 -197.43801)
		(end 295.393872 -197.369938)
		(stroke
			(width 0.0508)
			(type default)
		)
		(layer "In5.Cu")
	)
	(gr_arc
		(start 295.4274 -77.724)
		(mid 295.536557 -77.702287)
		(end 295.629076 -77.640434)
		(stroke
			(width 0.0635)
			(type default)
		)
		(layer "In5.Cu")
	)
	(gr_line
		(start 295.602406 -197.161404)
		(end 295.670478 -197.093332)
		(stroke
			(width 0.0508)
			(type default)
		)
		(layer "In5.Cu")
	)
	(gr_line
		(start 295.629076 -77.640434)
		(end 295.91 -77.35951)
		(stroke
			(width 0.0635)
			(type default)
		)
		(layer "In5.Cu")
	)
	(gr_line
		(start 295.726104 -198.054214)
		(end 296.034968 -198.363078)
		(stroke
			(width 0.0508)
			(type default)
		)
		(layer "In5.Cu")
	)
	(gr_line
		(start 295.783762 -197.4469)
		(end 296.000678 -197.229984)
		(stroke
			(width 0.0508)
			(type default)
		)
		(layer "In5.Cu")
	)
	(gr_arc
		(start 295.892728 -78.259432)
		(mid 295.609322 -78.069991)
		(end 295.275 -78.0034)
		(stroke
			(width 0.0635)
			(type default)
		)
		(layer "In5.Cu")
	)
	(gr_line
		(start 295.892728 -78.259432)
		(end 295.91 -78.27645)
		(stroke
			(width 0.0635)
			(type default)
		)
		(layer "In5.Cu")
	)
	(gr_line
		(start 296.418 -184.785)
		(end 296.591228 -184.958228)
		(stroke
			(width 0.0508)
			(type default)
		)
		(layer "In5.Cu")
	)
	(gr_line
		(start 296.591228 -185.626756)
		(end 296.59326 -185.628788)
		(stroke
			(width 0.0508)
			(type default)
		)
		(layer "In5.Cu")
	)
	(gr_line
		(start 296.591228 -184.958228)
		(end 296.591228 -185.626756)
		(stroke
			(width 0.0508)
			(type default)
		)
		(layer "In5.Cu")
	)
	(gr_line
		(start 296.926 -185.41746)
		(end 296.997628 -185.345832)
		(stroke
			(width 0.0508)
			(type default)
		)
		(layer "In5.Cu")
	)
	(gr_line
		(start 297.05681 -82.223864)
		(end 297.280584 -82.447638)
		(stroke
			(width 0.0635)
			(type default)
		)
		(layer "In5.Cu")
	)
	(gr_line
		(start 297.061382 -186.88685)
		(end 297.1292 -186.954922)
		(stroke
			(width 0.0508)
			(type default)
		)
		(layer "In5.Cu")
	)
	(gr_line
		(start 297.123358 -73.69175)
		(end 297.34383 -73.471278)
		(stroke
			(width 0.0635)
			(type default)
		)
		(layer "In5.Cu")
	)
	(gr_arc
		(start 297.34383 -73.471278)
		(mid 297.410572 -73.371409)
		(end 297.434 -73.2536)
		(stroke
			(width 0.0635)
			(type default)
		)
		(layer "In5.Cu")
	)
	(gr_arc
		(start 297.37558 -82.677)
		(mid 297.35089 -82.552874)
		(end 297.280584 -82.447638)
		(stroke
			(width 0.0635)
			(type default)
		)
		(layer "In5.Cu")
	)
	(gr_arc
		(start 297.7134 -73.265792)
		(mid 297.83816 -73.56699)
		(end 298.139358 -73.69175)
		(stroke
			(width 0.0635)
			(type default)
		)
		(layer "In5.Cu")
	)
	(gr_arc
		(start 297.749976 -82.447638)
		(mid 297.679675 -82.552874)
		(end 297.65498 -82.677)
		(stroke
			(width 0.0635)
			(type default)
		)
		(layer "In5.Cu")
	)
	(gr_line
		(start 297.749976 -82.447638)
		(end 297.97375 -82.223864)
		(stroke
			(width 0.0635)
			(type default)
		)
		(layer "In5.Cu")
	)
	(gr_arc
		(start 298.721018 -80.2894)
		(mid 298.804154 -80.268336)
		(end 298.870878 -80.21447)
		(stroke
			(width 0.0635)
			(type default)
		)
		(layer "In5.Cu")
	)
	(gr_line
		(start 299.002958 -80.5688)
		(end 299.419518 -80.5688)
		(stroke
			(width 0.0635)
			(type default)
		)
		(layer "In5.Cu")
	)
	(gr_arc
		(start 299.020738 -80.13954)
		(mid 298.937626 -80.160642)
		(end 298.870878 -80.21447)
		(stroke
			(width 0.0635)
			(type default)
		)
		(layer "In5.Cu")
	)
	(gr_line
		(start 299.020738 -80.13954)
		(end 299.401738 -80.13954)
		(stroke
			(width 0.0635)
			(type default)
		)
		(layer "In5.Cu")
	)
	(gr_arc
		(start 299.551598 -80.21447)
		(mid 299.484873 -80.160591)
		(end 299.401738 -80.13954)
		(stroke
			(width 0.0635)
			(type default)
		)
		(layer "In5.Cu")
	)
	(gr_arc
		(start 299.551598 -80.21447)
		(mid 299.618343 -80.268294)
		(end 299.701458 -80.2894)
		(stroke
			(width 0.0635)
			(type default)
		)
		(layer "In5.Cu")
	)
	(gr_line
		(start 299.638212 -175.034194)
		(end 300.349412 -175.745394)
		(stroke
			(width 0.0635)
			(type default)
		)
		(layer "In5.Cu")
	)
	(gr_arc
		(start 300.082458 -80.2894)
		(mid 300.165573 -80.268317)
		(end 300.232318 -80.21447)
		(stroke
			(width 0.0635)
			(type default)
		)
		(layer "In5.Cu")
	)
	(gr_line
		(start 300.349412 -175.745394)
		(end 300.358302 -175.745394)
		(stroke
			(width 0.0635)
			(type default)
		)
		(layer "In5.Cu")
	)
	(gr_line
		(start 300.364398 -80.5688)
		(end 300.780958 -80.5688)
		(stroke
			(width 0.0635)
			(type default)
		)
		(layer "In5.Cu")
	)
	(gr_arc
		(start 300.382178 -80.13954)
		(mid 300.299055 -80.160628)
		(end 300.232318 -80.21447)
		(stroke
			(width 0.0635)
			(type default)
		)
		(layer "In5.Cu")
	)
	(gr_line
		(start 300.382178 -80.13954)
		(end 300.763178 -80.13954)
		(stroke
			(width 0.0635)
			(type default)
		)
		(layer "In5.Cu")
	)
	(gr_line
		(start 300.435518 -175.26127)
		(end 300.637702 -175.463454)
		(stroke
			(width 0.0635)
			(type default)
		)
		(layer "In5.Cu")
	)
	(gr_line
		(start 300.435518 -175.04537)
		(end 300.435518 -175.26127)
		(stroke
			(width 0.0635)
			(type default)
		)
		(layer "In5.Cu")
	)
	(gr_arc
		(start 300.913038 -80.21447)
		(mid 300.846299 -80.160622)
		(end 300.763178 -80.13954)
		(stroke
			(width 0.0635)
			(type default)
		)
		(layer "In5.Cu")
	)
	(gr_arc
		(start 300.913038 -80.21447)
		(mid 300.979783 -80.268294)
		(end 301.062898 -80.2894)
		(stroke
			(width 0.0635)
			(type default)
		)
		(layer "In5.Cu")
	)
	(gr_arc
		(start 301.443898 -80.2894)
		(mid 301.527013 -80.268317)
		(end 301.593758 -80.21447)
		(stroke
			(width 0.0635)
			(type default)
		)
		(layer "In5.Cu")
	)
	(gr_line
		(start 301.725838 -80.5688)
		(end 302.142398 -80.5688)
		(stroke
			(width 0.0635)
			(type default)
		)
		(layer "In5.Cu")
	)
	(gr_arc
		(start 301.743618 -80.13954)
		(mid 301.660511 -80.160648)
		(end 301.593758 -80.21447)
		(stroke
			(width 0.0635)
			(type default)
		)
		(layer "In5.Cu")
	)
	(gr_line
		(start 301.743618 -80.13954)
		(end 302.124618 -80.13954)
		(stroke
			(width 0.0635)
			(type default)
		)
		(layer "In5.Cu")
	)
	(gr_line
		(start 301.974758 -73.6092)
		(end 302.258476 -73.325482)
		(stroke
			(width 0.0635)
			(type default)
		)
		(layer "In5.Cu")
	)
	(gr_arc
		(start 302.104552 -75.25893)
		(mid 302.03782 -75.205077)
		(end 301.954692 -75.184)
		(stroke
			(width 0.0635)
			(type default)
		)
		(layer "In5.Cu")
	)
	(gr_arc
		(start 302.104552 -75.25893)
		(mid 302.171297 -75.312754)
		(end 302.254412 -75.33386)
		(stroke
			(width 0.0635)
			(type default)
		)
		(layer "In5.Cu")
	)
	(gr_line
		(start 302.23206 -173.749462)
		(end 302.244252 -174.011082)
		(stroke
			(width 0.0635)
			(type default)
		)
		(layer "In5.Cu")
	)
	(gr_line
		(start 302.236632 -74.9046)
		(end 302.653192 -74.9046)
		(stroke
			(width 0.0635)
			(type default)
		)
		(layer "In5.Cu")
	)
	(gr_line
		(start 302.244252 -174.011082)
		(end 302.742854 -174.509684)
		(stroke
			(width 0.0635)
			(type default)
		)
		(layer "In5.Cu")
	)
	(gr_line
		(start 302.254412 -75.33386)
		(end 302.635412 -75.33386)
		(stroke
			(width 0.0635)
			(type default)
		)
		(layer "In5.Cu")
	)
	(gr_arc
		(start 302.258476 -73.325482)
		(mid 302.311703 -73.245899)
		(end 302.330358 -73.152)
		(stroke
			(width 0.0635)
			(type default)
		)
		(layer "In5.Cu")
	)
	(gr_arc
		(start 302.274478 -80.21447)
		(mid 302.207742 -80.160608)
		(end 302.124618 -80.13954)
		(stroke
			(width 0.0635)
			(type default)
		)
		(layer "In5.Cu")
	)
	(gr_arc
		(start 302.274478 -80.21447)
		(mid 302.341223 -80.268294)
		(end 302.424338 -80.2894)
		(stroke
			(width 0.0635)
			(type default)
		)
		(layer "In5.Cu")
	)
	(gr_arc
		(start 302.609758 -73.152)
		(mid 302.630021 -73.253867)
		(end 302.687736 -73.340214)
		(stroke
			(width 0.0635)
			(type default)
		)
		(layer "In5.Cu")
	)
	(gr_arc
		(start 302.635412 -75.33386)
		(mid 302.718548 -75.312796)
		(end 302.785272 -75.25893)
		(stroke
			(width 0.0635)
			(type default)
		)
		(layer "In5.Cu")
	)
	(gr_line
		(start 302.687736 -73.340214)
		(end 302.956722 -73.6092)
		(stroke
			(width 0.0635)
			(type default)
		)
		(layer "In5.Cu")
	)
	(gr_line
		(start 302.7426 -200.151492)
		(end 302.747426 -200.138284)
		(stroke
			(width 0.0635)
			(type default)
		)
		(layer "In5.Cu")
	)
	(gr_arc
		(start 302.805338 -80.2894)
		(mid 302.888453 -80.268317)
		(end 302.955198 -80.21447)
		(stroke
			(width 0.0635)
			(type default)
		)
		(layer "In5.Cu")
	)
	(gr_arc
		(start 302.935132 -75.184)
		(mid 302.852018 -75.205101)
		(end 302.785272 -75.25893)
		(stroke
			(width 0.0635)
			(type default)
		)
		(layer "In5.Cu")
	)
	(gr_line
		(start 303.005998 -173.713394)
		(end 303.024794 -174.113444)
		(stroke
			(width 0.0635)
			(type default)
		)
		(layer "In5.Cu")
	)
	(gr_line
		(start 303.024794 -174.113444)
		(end 303.024794 -174.230284)
		(stroke
			(width 0.0635)
			(type default)
		)
		(layer "In5.Cu")
	)
	(gr_line
		(start 303.087278 -80.5688)
		(end 303.503838 -80.5688)
		(stroke
			(width 0.0635)
			(type default)
		)
		(layer "In5.Cu")
	)
	(gr_arc
		(start 303.105058 -80.13954)
		(mid 303.021941 -80.160635)
		(end 302.955198 -80.21447)
		(stroke
			(width 0.0635)
			(type default)
		)
		(layer "In5.Cu")
	)
	(gr_line
		(start 303.105058 -80.13954)
		(end 303.486058 -80.13954)
		(stroke
			(width 0.0635)
			(type default)
		)
		(layer "In5.Cu")
	)
	(gr_line
		(start 303.420272 -199.140572)
		(end 303.422812 -199.13346)
		(stroke
			(width 0.0635)
			(type default)
		)
		(layer "In5.Cu")
	)
	(gr_arc
		(start 303.465992 -75.25893)
		(mid 303.399263 -75.205063)
		(end 303.316132 -75.184)
		(stroke
			(width 0.0635)
			(type default)
		)
		(layer "In5.Cu")
	)
	(gr_arc
		(start 303.465992 -75.25893)
		(mid 303.532737 -75.312754)
		(end 303.615852 -75.33386)
		(stroke
			(width 0.0635)
			(type default)
		)
		(layer "In5.Cu")
	)
	(gr_line
		(start 303.598072 -74.9046)
		(end 304.014632 -74.9046)
		(stroke
			(width 0.0635)
			(type default)
		)
		(layer "In5.Cu")
	)
	(gr_line
		(start 303.615852 -75.33386)
		(end 303.996852 -75.33386)
		(stroke
			(width 0.0635)
			(type default)
		)
		(layer "In5.Cu")
	)
	(gr_arc
		(start 303.635918 -80.21447)
		(mid 303.569177 -80.160628)
		(end 303.486058 -80.13954)
		(stroke
			(width 0.0635)
			(type default)
		)
		(layer "In5.Cu")
	)
	(gr_arc
		(start 303.635918 -80.21447)
		(mid 303.702663 -80.268294)
		(end 303.785778 -80.2894)
		(stroke
			(width 0.0635)
			(type default)
		)
		(layer "In5.Cu")
	)
	(gr_line
		(start 303.80305 -87.525352)
		(end 304.06213 -87.266526)
		(stroke
			(width 0.0635)
			(type default)
		)
		(layer "In5.Cu")
	)
	(gr_arc
		(start 303.996852 -75.33386)
		(mid 304.079988 -75.312796)
		(end 304.146712 -75.25893)
		(stroke
			(width 0.0635)
			(type default)
		)
		(layer "In5.Cu")
	)
	(gr_arc
		(start 304.06213 -87.266526)
		(mid 304.106337 -87.200199)
		(end 304.12182 -87.122)
		(stroke
			(width 0.0635)
			(type default)
		)
		(layer "In5.Cu")
	)
	(gr_arc
		(start 304.296572 -75.184)
		(mid 304.213448 -75.205087)
		(end 304.146712 -75.25893)
		(stroke
			(width 0.0635)
			(type default)
		)
		(layer "In5.Cu")
	)
	(gr_arc
		(start 304.40122 -87.122)
		(mid 304.416682 -87.200204)
		(end 304.46091 -87.266526)
		(stroke
			(width 0.0635)
			(type default)
		)
		(layer "In5.Cu")
	)
	(gr_line
		(start 304.46091 -87.266526)
		(end 304.71999 -87.525352)
		(stroke
			(width 0.0635)
			(type default)
		)
		(layer "In5.Cu")
	)
	(gr_arc
		(start 304.827432 -75.25893)
		(mid 304.760706 -75.20505)
		(end 304.677572 -75.184)
		(stroke
			(width 0.0635)
			(type default)
		)
		(layer "In5.Cu")
	)
	(gr_arc
		(start 304.827432 -75.25893)
		(mid 304.894177 -75.312754)
		(end 304.977292 -75.33386)
		(stroke
			(width 0.0635)
			(type default)
		)
		(layer "In5.Cu")
	)
	(gr_line
		(start 304.959512 -74.9046)
		(end 305.376072 -74.9046)
		(stroke
			(width 0.0635)
			(type default)
		)
		(layer "In5.Cu")
	)
	(gr_line
		(start 304.977292 -75.33386)
		(end 305.358292 -75.33386)
		(stroke
			(width 0.0635)
			(type default)
		)
		(layer "In5.Cu")
	)
	(gr_arc
		(start 305.358292 -75.33386)
		(mid 305.441428 -75.312796)
		(end 305.508152 -75.25893)
		(stroke
			(width 0.0635)
			(type default)
		)
		(layer "In5.Cu")
	)
	(gr_arc
		(start 305.658012 -75.184)
		(mid 305.574903 -75.205107)
		(end 305.508152 -75.25893)
		(stroke
			(width 0.0635)
			(type default)
		)
		(layer "In5.Cu")
	)
	(gr_arc
		(start 305.936396 -80.2894)
		(mid 306.019532 -80.268336)
		(end 306.086256 -80.21447)
		(stroke
			(width 0.0635)
			(type default)
		)
		(layer "In5.Cu")
	)
	(gr_line
		(start 306.218336 -80.5688)
		(end 306.634896 -80.5688)
		(stroke
			(width 0.0635)
			(type default)
		)
		(layer "In5.Cu")
	)
	(gr_arc
		(start 306.236116 -80.13954)
		(mid 306.153009 -80.160649)
		(end 306.086256 -80.21447)
		(stroke
			(width 0.0635)
			(type default)
		)
		(layer "In5.Cu")
	)
	(gr_line
		(start 306.236116 -80.13954)
		(end 306.617116 -80.13954)
		(stroke
			(width 0.0635)
			(type default)
		)
		(layer "In5.Cu")
	)
	(gr_arc
		(start 306.766976 -80.21447)
		(mid 306.700249 -80.160598)
		(end 306.617116 -80.13954)
		(stroke
			(width 0.0635)
			(type default)
		)
		(layer "In5.Cu")
	)
	(gr_arc
		(start 306.766976 -80.21447)
		(mid 306.833721 -80.268294)
		(end 306.916836 -80.2894)
		(stroke
			(width 0.0635)
			(type default)
		)
		(layer "In5.Cu")
	)
	(gr_arc
		(start 307.297836 -80.2894)
		(mid 307.380972 -80.268336)
		(end 307.447696 -80.21447)
		(stroke
			(width 0.0635)
			(type default)
		)
		(layer "In5.Cu")
	)
	(gr_line
		(start 307.579776 -80.5688)
		(end 307.996336 -80.5688)
		(stroke
			(width 0.0635)
			(type default)
		)
		(layer "In5.Cu")
	)
	(gr_arc
		(start 307.597556 -80.13954)
		(mid 307.514439 -80.160636)
		(end 307.447696 -80.21447)
		(stroke
			(width 0.0635)
			(type default)
		)
		(layer "In5.Cu")
	)
	(gr_line
		(start 307.597556 -80.13954)
		(end 307.978556 -80.13954)
		(stroke
			(width 0.0635)
			(type default)
		)
		(layer "In5.Cu")
	)
	(gr_line
		(start 307.764942 -73.915016)
		(end 308.059328 -73.62063)
		(stroke
			(width 0.0635)
			(type default)
		)
		(layer "In5.Cu")
	)
	(gr_arc
		(start 307.921914 -74.259186)
		(mid 307.836761 -74.268253)
		(end 307.763164 -74.312018)
		(stroke
			(width 0.0635)
			(type default)
		)
		(layer "In5.Cu")
	)
	(gr_arc
		(start 307.921914 -74.259186)
		(mid 308.007238 -74.250069)
		(end 308.080918 -74.2061)
		(stroke
			(width 0.0635)
			(type default)
		)
		(layer "In5.Cu")
	)
	(gr_line
		(start 308.080918 -74.2061)
		(end 308.350412 -73.936606)
		(stroke
			(width 0.0635)
			(type default)
		)
		(layer "In5.Cu")
	)
	(gr_arc
		(start 308.128416 -80.21447)
		(mid 308.061693 -80.160585)
		(end 307.978556 -80.13954)
		(stroke
			(width 0.0635)
			(type default)
		)
		(layer "In5.Cu")
	)
	(gr_arc
		(start 308.128416 -80.21447)
		(mid 308.195161 -80.268294)
		(end 308.278276 -80.2894)
		(stroke
			(width 0.0635)
			(type default)
		)
		(layer "In5.Cu")
	)
	(gr_arc
		(start 308.350412 -73.936606)
		(mid 308.394158 -73.863001)
		(end 308.403244 -73.777856)
		(stroke
			(width 0.0635)
			(type default)
		)
		(layer "In5.Cu")
	)
	(gr_arc
		(start 308.45633 -73.618852)
		(mid 308.41233 -73.69253)
		(end 308.403244 -73.777856)
		(stroke
			(width 0.0635)
			(type default)
		)
		(layer "In5.Cu")
	)
	(gr_line
		(start 308.727602 -72.952356)
		(end 309.021988 -72.65797)
		(stroke
			(width 0.0635)
			(type default)
		)
		(layer "In5.Cu")
	)
	(gr_arc
		(start 308.884828 -73.296526)
		(mid 308.799556 -73.305575)
		(end 308.725824 -73.349358)
		(stroke
			(width 0.0635)
			(type default)
		)
		(layer "In5.Cu")
	)
	(gr_arc
		(start 308.884828 -73.296526)
		(mid 308.970009 -73.287343)
		(end 309.043578 -73.24344)
		(stroke
			(width 0.0635)
			(type default)
		)
		(layer "In5.Cu")
	)
	(gr_line
		(start 309.043578 -73.24344)
		(end 309.313072 -72.973946)
		(stroke
			(width 0.0635)
			(type default)
		)
		(layer "In5.Cu")
	)
	(gr_arc
		(start 309.313072 -72.973946)
		(mid 309.356964 -72.900374)
		(end 309.366158 -72.815196)
		(stroke
			(width 0.0635)
			(type default)
		)
		(layer "In5.Cu")
	)
	(gr_arc
		(start 309.41899 -72.656192)
		(mid 309.375129 -72.729902)
		(end 309.366158 -72.815196)
		(stroke
			(width 0.0635)
			(type default)
		)
		(layer "In5.Cu")
	)
	(gr_line
		(start 309.690262 -71.989696)
		(end 309.984648 -71.69531)
		(stroke
			(width 0.0635)
			(type default)
		)
		(layer "In5.Cu")
	)
	(gr_arc
		(start 309.847488 -72.333866)
		(mid 309.762205 -72.342893)
		(end 309.688484 -72.386698)
		(stroke
			(width 0.0635)
			(type default)
		)
		(layer "In5.Cu")
	)
	(gr_arc
		(start 309.847488 -72.333866)
		(mid 309.93268 -72.324691)
		(end 310.006238 -72.28078)
		(stroke
			(width 0.0635)
			(type default)
		)
		(layer "In5.Cu")
	)
	(gr_line
		(start 310.006238 -72.28078)
		(end 310.275732 -72.011286)
		(stroke
			(width 0.0635)
			(type default)
		)
		(layer "In5.Cu")
	)
	(gr_arc
		(start 310.275732 -72.011286)
		(mid 310.319624 -71.937714)
		(end 310.328818 -71.852536)
		(stroke
			(width 0.0635)
			(type default)
		)
		(layer "In5.Cu")
	)
	(gr_arc
		(start 310.38165 -71.693532)
		(mid 310.337812 -71.767245)
		(end 310.328818 -71.852536)
		(stroke
			(width 0.0635)
			(type default)
		)
		(layer "In5.Cu")
	)
	(gr_line
		(start 312.172858 -176.926494)
		(end 312.320178 -177.073814)
		(stroke
			(width 0.0635)
			(type default)
		)
		(layer "In5.Cu")
	)
	(gr_arc
		(start 312.188606 -70.91553)
		(mid 312.121878 -70.861659)
		(end 312.038746 -70.8406)
		(stroke
			(width 0.0635)
			(type default)
		)
		(layer "In5.Cu")
	)
	(gr_arc
		(start 312.188606 -70.91553)
		(mid 312.255351 -70.969354)
		(end 312.338466 -70.99046)
		(stroke
			(width 0.0635)
			(type default)
		)
		(layer "In5.Cu")
	)
	(gr_line
		(start 312.320178 -177.073814)
		(end 312.701178 -177.073814)
		(stroke
			(width 0.0635)
			(type default)
		)
		(layer "In5.Cu")
	)
	(gr_line
		(start 312.320686 -70.5612)
		(end 312.737246 -70.5612)
		(stroke
			(width 0.0635)
			(type default)
		)
		(layer "In5.Cu")
	)
	(gr_line
		(start 312.338466 -70.99046)
		(end 312.719466 -70.99046)
		(stroke
			(width 0.0635)
			(type default)
		)
		(layer "In5.Cu")
	)
	(gr_line
		(start 312.452258 -176.644554)
		(end 312.569098 -176.644554)
		(stroke
			(width 0.0635)
			(type default)
		)
		(layer "In5.Cu")
	)
	(gr_line
		(start 312.701178 -177.073814)
		(end 312.848498 -176.926494)
		(stroke
			(width 0.0635)
			(type default)
		)
		(layer "In5.Cu")
	)
	(gr_arc
		(start 312.719466 -70.99046)
		(mid 312.802602 -70.969396)
		(end 312.869326 -70.91553)
		(stroke
			(width 0.0635)
			(type default)
		)
		(layer "In5.Cu")
	)
	(gr_arc
		(start 313.019186 -70.8406)
		(mid 312.936084 -70.861716)
		(end 312.869326 -70.91553)
		(stroke
			(width 0.0635)
			(type default)
		)
		(layer "In5.Cu")
	)
	(gr_arc
		(start 313.550046 -70.91553)
		(mid 313.483321 -70.861645)
		(end 313.400186 -70.8406)
		(stroke
			(width 0.0635)
			(type default)
		)
		(layer "In5.Cu")
	)
	(gr_arc
		(start 313.550046 -70.91553)
		(mid 313.616791 -70.969354)
		(end 313.699906 -70.99046)
		(stroke
			(width 0.0635)
			(type default)
		)
		(layer "In5.Cu")
	)
	(gr_line
		(start 313.659774 -176.926494)
		(end 313.807094 -177.073814)
		(stroke
			(width 0.0635)
			(type default)
		)
		(layer "In5.Cu")
	)
	(gr_line
		(start 313.682126 -70.5612)
		(end 314.098686 -70.5612)
		(stroke
			(width 0.0635)
			(type default)
		)
		(layer "In5.Cu")
	)
	(gr_line
		(start 313.699906 -70.99046)
		(end 314.080906 -70.99046)
		(stroke
			(width 0.0635)
			(type default)
		)
		(layer "In5.Cu")
	)
	(gr_line
		(start 313.807094 -177.073814)
		(end 314.188094 -177.073814)
		(stroke
			(width 0.0635)
			(type default)
		)
		(layer "In5.Cu")
	)
	(gr_line
		(start 313.939174 -176.644554)
		(end 314.056014 -176.644554)
		(stroke
			(width 0.0635)
			(type default)
		)
		(layer "In5.Cu")
	)
	(gr_arc
		(start 314.080906 -70.99046)
		(mid 314.164042 -70.969396)
		(end 314.230766 -70.91553)
		(stroke
			(width 0.0635)
			(type default)
		)
		(layer "In5.Cu")
	)
	(gr_line
		(start 314.188094 -177.073814)
		(end 314.335414 -176.926494)
		(stroke
			(width 0.0635)
			(type default)
		)
		(layer "In5.Cu")
	)
	(gr_arc
		(start 314.380626 -70.8406)
		(mid 314.297514 -70.861703)
		(end 314.230766 -70.91553)
		(stroke
			(width 0.0635)
			(type default)
		)
		(layer "In5.Cu")
	)
	(gr_line
		(start 314.721494 -176.926494)
		(end 314.868814 -177.073814)
		(stroke
			(width 0.0635)
			(type default)
		)
		(layer "In5.Cu")
	)
	(gr_line
		(start 314.868814 -177.073814)
		(end 315.249814 -177.073814)
		(stroke
			(width 0.0635)
			(type default)
		)
		(layer "In5.Cu")
	)
	(gr_arc
		(start 314.911486 -70.91553)
		(mid 314.844757 -70.861665)
		(end 314.761626 -70.8406)
		(stroke
			(width 0.0635)
			(type default)
		)
		(layer "In5.Cu")
	)
	(gr_arc
		(start 314.911486 -70.91553)
		(mid 314.978231 -70.969354)
		(end 315.061346 -70.99046)
		(stroke
			(width 0.0635)
			(type default)
		)
		(layer "In5.Cu")
	)
	(gr_line
		(start 315.000894 -176.644554)
		(end 315.117734 -176.644554)
		(stroke
			(width 0.0635)
			(type default)
		)
		(layer "In5.Cu")
	)
	(gr_line
		(start 315.043566 -70.5612)
		(end 315.460126 -70.5612)
		(stroke
			(width 0.0635)
			(type default)
		)
		(layer "In5.Cu")
	)
	(gr_line
		(start 315.061346 -70.99046)
		(end 315.442346 -70.99046)
		(stroke
			(width 0.0635)
			(type default)
		)
		(layer "In5.Cu")
	)
	(gr_line
		(start 315.249814 -177.073814)
		(end 315.397134 -176.926494)
		(stroke
			(width 0.0635)
			(type default)
		)
		(layer "In5.Cu")
	)
	(gr_arc
		(start 315.442346 -70.99046)
		(mid 315.525482 -70.969396)
		(end 315.592206 -70.91553)
		(stroke
			(width 0.0635)
			(type default)
		)
		(layer "In5.Cu")
	)
	(gr_arc
		(start 315.742066 -70.8406)
		(mid 315.658943 -70.861689)
		(end 315.592206 -70.91553)
		(stroke
			(width 0.0635)
			(type default)
		)
		(layer "In5.Cu")
	)
	(gr_line
		(start 315.783214 -176.926494)
		(end 315.930534 -177.073814)
		(stroke
			(width 0.0635)
			(type default)
		)
		(layer "In5.Cu")
	)
	(gr_line
		(start 315.930534 -177.073814)
		(end 316.311534 -177.073814)
		(stroke
			(width 0.0635)
			(type default)
		)
		(layer "In5.Cu")
	)
	(gr_line
		(start 316.062614 -176.644554)
		(end 316.179454 -176.644554)
		(stroke
			(width 0.0635)
			(type default)
		)
		(layer "In5.Cu")
	)
	(gr_line
		(start 316.311534 -177.073814)
		(end 316.458854 -176.926494)
		(stroke
			(width 0.0635)
			(type default)
		)
		(layer "In5.Cu")
	)
	(gr_arc
		(start 317.063882 -72.723248)
		(mid 317.025052 -72.720906)
		(end 316.986158 -72.7202)
		(stroke
			(width 0.0635)
			(type default)
		)
		(layer "In5.Cu")
	)
	(gr_arc
		(start 317.087758 -72.4408)
		(mid 317.228657 -72.412867)
		(end 317.348108 -72.333104)
		(stroke
			(width 0.0635)
			(type default)
		)
		(layer "In5.Cu")
	)
	(gr_arc
		(start 317.194692 -72.744076)
		(mid 317.129664 -72.731294)
		(end 317.063882 -72.723248)
		(stroke
			(width 0.0635)
			(type default)
		)
		(layer "In5.Cu")
	)
	(gr_line
		(start 317.348108 -72.333104)
		(end 317.671958 -72.009)
		(stroke
			(width 0.0635)
			(type default)
		)
		(layer "In5.Cu")
	)
	(gr_arc
		(start 317.636398 -72.989694)
		(mid 317.432758 -72.83593)
		(end 317.194692 -72.744076)
		(stroke
			(width 0.0635)
			(type default)
		)
		(layer "In5.Cu")
	)
	(gr_line
		(start 317.636398 -72.989694)
		(end 317.671958 -73.025)
		(stroke
			(width 0.0635)
			(type default)
		)
		(layer "In5.Cu")
	)
	(gr_arc
		(start 317.85814 -81.7372)
		(mid 317.967006 -81.715545)
		(end 318.059308 -81.653888)
		(stroke
			(width 0.0635)
			(type default)
		)
		(layer "In5.Cu")
	)
	(gr_arc
		(start 317.96228 -78.8035)
		(mid 318.010798 -78.793867)
		(end 318.051942 -78.766416)
		(stroke
			(width 0.0635)
			(type default)
		)
		(layer "In5.Cu")
	)
	(gr_arc
		(start 318.051942 -79.119984)
		(mid 318.010795 -79.092536)
		(end 317.96228 -79.0829)
		(stroke
			(width 0.0635)
			(type default)
		)
		(layer "In5.Cu")
	)
	(gr_line
		(start 318.051942 -79.119984)
		(end 318.383158 -79.4512)
		(stroke
			(width 0.0635)
			(type default)
		)
		(layer "In5.Cu")
	)
	(gr_line
		(start 318.051942 -78.766416)
		(end 318.383158 -78.4352)
		(stroke
			(width 0.0635)
			(type default)
		)
		(layer "In5.Cu")
	)
	(gr_line
		(start 318.059308 -81.653888)
		(end 318.306958 -81.407)
		(stroke
			(width 0.0635)
			(type default)
		)
		(layer "In5.Cu")
	)
	(gr_arc
		(start 318.179958 -82.0928)
		(mid 318.095595 -82.036395)
		(end 317.996062 -82.0166)
		(stroke
			(width 0.0635)
			(type default)
		)
		(layer "In5.Cu")
	)
	(gr_arc
		(start 318.306958 -82.399378)
		(mid 318.273951 -82.233455)
		(end 318.179958 -82.0928)
		(stroke
			(width 0.0635)
			(type default)
		)
		(layer "In5.Cu")
	)
	(gr_line
		(start 318.306958 -82.399378)
		(end 318.306958 -82.423)
		(stroke
			(width 0.0635)
			(type default)
		)
		(layer "In5.Cu")
	)
	(gr_line
		(start 318.383158 -78.4352)
		(end 318.408558 -78.4352)
		(stroke
			(width 0.0635)
			(type default)
		)
		(layer "In5.Cu")
	)
	(gr_arc
		(start 319.274952 -73.998328)
		(mid 319.272366 -74.000951)
		(end 319.269872 -74.003662)
		(stroke
			(width 0.0635)
			(type default)
		)
		(layer "In5.Cu")
	)
	(gr_line
		(start 320.085466 -75.311)
		(end 320.186558 -75.209908)
		(stroke
			(width 0.0635)
			(type default)
		)
		(layer "In5.Cu")
	)
	(gr_arc
		(start 320.186558 -76.03109)
		(mid 320.084791 -75.794025)
		(end 319.842896 -75.704446)
		(stroke
			(width 0.0635)
			(type default)
		)
		(layer "In5.Cu")
	)
	(gr_line
		(start 320.186558 -76.03109)
		(end 320.186558 -76.191872)
		(stroke
			(width 0.0635)
			(type default)
		)
		(layer "In5.Cu")
	)
	(gr_line
		(start 336.812128 -174.87646)
		(end 336.959448 -174.72914)
		(stroke
			(width 0.0635)
			(type default)
		)
		(layer "In5.Cu")
	)
	(gr_line
		(start 336.959448 -174.72914)
		(end 337.340448 -174.72914)
		(stroke
			(width 0.0635)
			(type default)
		)
		(layer "In5.Cu")
	)
	(gr_line
		(start 337.091528 -175.1584)
		(end 337.208368 -175.1584)
		(stroke
			(width 0.0635)
			(type default)
		)
		(layer "In5.Cu")
	)
	(gr_line
		(start 337.201002 -176.70526)
		(end 337.348322 -176.55794)
		(stroke
			(width 0.0635)
			(type default)
		)
		(layer "In5.Cu")
	)
	(gr_line
		(start 337.340448 -174.72914)
		(end 337.487768 -174.87646)
		(stroke
			(width 0.0635)
			(type default)
		)
		(layer "In5.Cu")
	)
	(gr_line
		(start 337.348322 -176.55794)
		(end 337.729322 -176.55794)
		(stroke
			(width 0.0635)
			(type default)
		)
		(layer "In5.Cu")
	)
	(gr_line
		(start 337.480402 -176.9872)
		(end 337.597242 -176.9872)
		(stroke
			(width 0.0635)
			(type default)
		)
		(layer "In5.Cu")
	)
	(gr_line
		(start 337.729322 -176.55794)
		(end 337.876642 -176.70526)
		(stroke
			(width 0.0635)
			(type default)
		)
		(layer "In5.Cu")
	)
	(gr_line
		(start 337.873848 -174.87646)
		(end 338.021168 -174.72914)
		(stroke
			(width 0.0635)
			(type default)
		)
		(layer "In5.Cu")
	)
	(gr_line
		(start 338.021168 -174.72914)
		(end 338.402168 -174.72914)
		(stroke
			(width 0.0635)
			(type default)
		)
		(layer "In5.Cu")
	)
	(gr_line
		(start 338.153248 -175.1584)
		(end 338.270088 -175.1584)
		(stroke
			(width 0.0635)
			(type default)
		)
		(layer "In5.Cu")
	)
	(gr_line
		(start 338.262722 -176.70526)
		(end 338.410042 -176.55794)
		(stroke
			(width 0.0635)
			(type default)
		)
		(layer "In5.Cu")
	)
	(gr_line
		(start 338.402168 -174.72914)
		(end 338.549488 -174.87646)
		(stroke
			(width 0.0635)
			(type default)
		)
		(layer "In5.Cu")
	)
	(gr_line
		(start 338.410042 -176.55794)
		(end 338.791042 -176.55794)
		(stroke
			(width 0.0635)
			(type default)
		)
		(layer "In5.Cu")
	)
	(gr_line
		(start 338.542122 -176.9872)
		(end 338.658962 -176.9872)
		(stroke
			(width 0.0635)
			(type default)
		)
		(layer "In5.Cu")
	)
	(gr_line
		(start 338.791042 -176.55794)
		(end 338.938362 -176.70526)
		(stroke
			(width 0.0635)
			(type default)
		)
		(layer "In5.Cu")
	)
	(gr_line
		(start 338.935568 -174.87646)
		(end 339.082888 -174.72914)
		(stroke
			(width 0.0635)
			(type default)
		)
		(layer "In5.Cu")
	)
	(gr_line
		(start 339.082888 -174.72914)
		(end 339.463888 -174.72914)
		(stroke
			(width 0.0635)
			(type default)
		)
		(layer "In5.Cu")
	)
	(gr_line
		(start 339.214968 -175.1584)
		(end 339.331808 -175.1584)
		(stroke
			(width 0.0635)
			(type default)
		)
		(layer "In5.Cu")
	)
	(gr_line
		(start 339.324442 -176.70526)
		(end 339.471762 -176.55794)
		(stroke
			(width 0.0635)
			(type default)
		)
		(layer "In5.Cu")
	)
	(gr_line
		(start 339.463888 -174.72914)
		(end 339.611208 -174.87646)
		(stroke
			(width 0.0635)
			(type default)
		)
		(layer "In5.Cu")
	)
	(gr_line
		(start 339.471762 -176.55794)
		(end 339.852762 -176.55794)
		(stroke
			(width 0.0635)
			(type default)
		)
		(layer "In5.Cu")
	)
	(gr_line
		(start 339.603842 -176.9872)
		(end 339.720682 -176.9872)
		(stroke
			(width 0.0635)
			(type default)
		)
		(layer "In5.Cu")
	)
	(gr_line
		(start 339.852762 -176.55794)
		(end 340.000082 -176.70526)
		(stroke
			(width 0.0635)
			(type default)
		)
		(layer "In5.Cu")
	)
	(gr_line
		(start 340.218014 -173.73854)
		(end 340.365334 -173.88586)
		(stroke
			(width 0.0635)
			(type default)
		)
		(layer "In5.Cu")
	)
	(gr_line
		(start 340.365334 -173.88586)
		(end 340.746334 -173.88586)
		(stroke
			(width 0.0635)
			(type default)
		)
		(layer "In5.Cu")
	)
	(gr_line
		(start 340.497414 -173.4566)
		(end 340.614254 -173.4566)
		(stroke
			(width 0.0635)
			(type default)
		)
		(layer "In5.Cu")
	)
	(gr_line
		(start 340.746334 -173.88586)
		(end 340.893654 -173.73854)
		(stroke
			(width 0.0635)
			(type default)
		)
		(layer "In5.Cu")
	)
	(gr_line
		(start 340.802976 -176.70526)
		(end 340.950296 -176.55794)
		(stroke
			(width 0.0635)
			(type default)
		)
		(layer "In5.Cu")
	)
	(gr_line
		(start 340.950296 -176.55794)
		(end 341.331296 -176.55794)
		(stroke
			(width 0.0635)
			(type default)
		)
		(layer "In5.Cu")
	)
	(gr_line
		(start 341.082376 -176.9872)
		(end 341.199216 -176.9872)
		(stroke
			(width 0.0635)
			(type default)
		)
		(layer "In5.Cu")
	)
	(gr_line
		(start 341.279734 -173.73854)
		(end 341.427054 -173.88586)
		(stroke
			(width 0.0635)
			(type default)
		)
		(layer "In5.Cu")
	)
	(gr_line
		(start 341.331296 -176.55794)
		(end 341.478616 -176.70526)
		(stroke
			(width 0.0635)
			(type default)
		)
		(layer "In5.Cu")
	)
	(gr_line
		(start 341.427054 -173.88586)
		(end 341.808054 -173.88586)
		(stroke
			(width 0.0635)
			(type default)
		)
		(layer "In5.Cu")
	)
	(gr_line
		(start 341.559134 -173.4566)
		(end 341.675974 -173.4566)
		(stroke
			(width 0.0635)
			(type default)
		)
		(layer "In5.Cu")
	)
	(gr_line
		(start 341.808054 -173.88586)
		(end 341.955374 -173.73854)
		(stroke
			(width 0.0635)
			(type default)
		)
		(layer "In5.Cu")
	)
	(gr_line
		(start 341.864696 -176.70526)
		(end 342.012016 -176.55794)
		(stroke
			(width 0.0635)
			(type default)
		)
		(layer "In5.Cu")
	)
	(gr_line
		(start 342.012016 -176.55794)
		(end 342.393016 -176.55794)
		(stroke
			(width 0.0635)
			(type default)
		)
		(layer "In5.Cu")
	)
	(gr_line
		(start 342.144096 -176.9872)
		(end 342.260936 -176.9872)
		(stroke
			(width 0.0635)
			(type default)
		)
		(layer "In5.Cu")
	)
	(gr_line
		(start 342.341454 -173.73854)
		(end 342.488774 -173.88586)
		(stroke
			(width 0.0635)
			(type default)
		)
		(layer "In5.Cu")
	)
	(gr_line
		(start 342.393016 -176.55794)
		(end 342.540336 -176.70526)
		(stroke
			(width 0.0635)
			(type default)
		)
		(layer "In5.Cu")
	)
	(gr_line
		(start 342.488774 -173.88586)
		(end 342.869774 -173.88586)
		(stroke
			(width 0.0635)
			(type default)
		)
		(layer "In5.Cu")
	)
	(gr_line
		(start 342.620854 -173.4566)
		(end 342.737694 -173.4566)
		(stroke
			(width 0.0635)
			(type default)
		)
		(layer "In5.Cu")
	)
	(gr_line
		(start 342.869774 -173.88586)
		(end 343.017094 -173.73854)
		(stroke
			(width 0.0635)
			(type default)
		)
		(layer "In5.Cu")
	)
	(gr_line
		(start 342.926416 -176.70526)
		(end 343.073736 -176.55794)
		(stroke
			(width 0.0635)
			(type default)
		)
		(layer "In5.Cu")
	)
	(gr_line
		(start 343.073736 -176.55794)
		(end 343.454736 -176.55794)
		(stroke
			(width 0.0635)
			(type default)
		)
		(layer "In5.Cu")
	)
	(gr_line
		(start 343.205816 -176.9872)
		(end 343.322656 -176.9872)
		(stroke
			(width 0.0635)
			(type default)
		)
		(layer "In5.Cu")
	)
	(gr_line
		(start 343.268046 -174.87646)
		(end 343.415366 -174.72914)
		(stroke
			(width 0.0635)
			(type default)
		)
		(layer "In5.Cu")
	)
	(gr_line
		(start 343.415366 -174.72914)
		(end 343.796366 -174.72914)
		(stroke
			(width 0.0635)
			(type default)
		)
		(layer "In5.Cu")
	)
	(gr_line
		(start 343.454736 -176.55794)
		(end 343.602056 -176.70526)
		(stroke
			(width 0.0635)
			(type default)
		)
		(layer "In5.Cu")
	)
	(gr_line
		(start 343.547446 -175.1584)
		(end 343.664286 -175.1584)
		(stroke
			(width 0.0635)
			(type default)
		)
		(layer "In5.Cu")
	)
	(gr_line
		(start 343.796366 -174.72914)
		(end 343.943686 -174.87646)
		(stroke
			(width 0.0635)
			(type default)
		)
		(layer "In5.Cu")
	)
	(gr_line
		(start 344.329766 -174.87646)
		(end 344.477086 -174.72914)
		(stroke
			(width 0.0635)
			(type default)
		)
		(layer "In5.Cu")
	)
	(gr_line
		(start 344.477086 -174.72914)
		(end 344.858086 -174.72914)
		(stroke
			(width 0.0635)
			(type default)
		)
		(layer "In5.Cu")
	)
	(gr_line
		(start 344.609166 -175.1584)
		(end 344.726006 -175.1584)
		(stroke
			(width 0.0635)
			(type default)
		)
		(layer "In5.Cu")
	)
	(gr_line
		(start 344.858086 -174.72914)
		(end 345.005406 -174.87646)
		(stroke
			(width 0.0635)
			(type default)
		)
		(layer "In5.Cu")
	)
	(gr_line
		(start 344.911934 -176.70526)
		(end 345.059254 -176.55794)
		(stroke
			(width 0.0635)
			(type default)
		)
		(layer "In5.Cu")
	)
	(gr_line
		(start 345.059254 -176.55794)
		(end 345.440254 -176.55794)
		(stroke
			(width 0.0635)
			(type default)
		)
		(layer "In5.Cu")
	)
	(gr_line
		(start 345.191334 -176.9872)
		(end 345.308174 -176.9872)
		(stroke
			(width 0.0635)
			(type default)
		)
		(layer "In5.Cu")
	)
	(gr_line
		(start 345.391486 -174.87646)
		(end 345.538806 -174.72914)
		(stroke
			(width 0.0635)
			(type default)
		)
		(layer "In5.Cu")
	)
	(gr_line
		(start 345.440254 -176.55794)
		(end 345.587574 -176.70526)
		(stroke
			(width 0.0635)
			(type default)
		)
		(layer "In5.Cu")
	)
	(gr_line
		(start 345.538806 -174.72914)
		(end 345.919806 -174.72914)
		(stroke
			(width 0.0635)
			(type default)
		)
		(layer "In5.Cu")
	)
	(gr_line
		(start 345.670886 -175.1584)
		(end 345.787726 -175.1584)
		(stroke
			(width 0.0635)
			(type default)
		)
		(layer "In5.Cu")
	)
	(gr_line
		(start 345.919806 -174.72914)
		(end 346.067126 -174.87646)
		(stroke
			(width 0.0635)
			(type default)
		)
		(layer "In5.Cu")
	)
	(gr_line
		(start 345.973654 -176.70526)
		(end 346.120974 -176.55794)
		(stroke
			(width 0.0635)
			(type default)
		)
		(layer "In5.Cu")
	)
	(gr_line
		(start 346.120974 -176.55794)
		(end 346.501974 -176.55794)
		(stroke
			(width 0.0635)
			(type default)
		)
		(layer "In5.Cu")
	)
	(gr_line
		(start 346.253054 -176.9872)
		(end 346.369894 -176.9872)
		(stroke
			(width 0.0635)
			(type default)
		)
		(layer "In5.Cu")
	)
	(gr_line
		(start 346.501974 -176.55794)
		(end 346.649294 -176.70526)
		(stroke
			(width 0.0635)
			(type default)
		)
		(layer "In5.Cu")
	)
	(gr_line
		(start 348.608904 -176.07026)
		(end 348.608904 -176.27854)
		(stroke
			(width 0.0635)
			(type default)
		)
		(layer "In5.Cu")
	)
	(gr_line
		(start 348.608904 -176.07026)
		(end 348.878144 -175.800766)
		(stroke
			(width 0.0635)
			(type default)
		)
		(layer "In5.Cu")
	)
	(gr_line
		(start 348.878144 -175.800766)
		(end 349.086678 -175.800766)
		(stroke
			(width 0.0635)
			(type default)
		)
		(layer "In5.Cu")
	)
	(gr_line
		(start 348.880684 -171.184316)
		(end 348.963234 -171.101766)
		(stroke
			(width 0.0635)
			(type default)
		)
		(layer "In5.Cu")
	)
	(gr_line
		(start 348.882462 -171.581318)
		(end 349.090742 -171.581318)
		(stroke
			(width 0.0635)
			(type default)
		)
		(layer "In5.Cu")
	)
	(gr_line
		(start 349.005906 -176.280318)
		(end 349.088456 -176.197768)
		(stroke
			(width 0.0635)
			(type default)
		)
		(layer "In5.Cu")
	)
	(gr_line
		(start 349.090742 -171.581318)
		(end 349.360236 -171.312078)
		(stroke
			(width 0.0635)
			(type default)
		)
		(layer "In5.Cu")
	)
	(gr_line
		(start 349.359474 -175.319436)
		(end 349.359474 -175.52797)
		(stroke
			(width 0.0635)
			(type default)
		)
		(layer "In5.Cu")
	)
	(gr_line
		(start 349.359474 -175.319436)
		(end 349.628968 -175.050196)
		(stroke
			(width 0.0635)
			(type default)
		)
		(layer "In5.Cu")
	)
	(gr_line
		(start 349.360236 -171.103544)
		(end 349.360236 -171.312078)
		(stroke
			(width 0.0635)
			(type default)
		)
		(layer "In5.Cu")
	)
	(gr_line
		(start 349.628968 -175.050196)
		(end 349.837248 -175.050196)
		(stroke
			(width 0.0635)
			(type default)
		)
		(layer "In5.Cu")
	)
	(gr_line
		(start 349.756476 -175.529748)
		(end 349.839026 -175.447198)
		(stroke
			(width 0.0635)
			(type default)
		)
		(layer "In5.Cu")
	)
	(gr_line
		(start 349.758 -169.082466)
		(end 349.758 -169.199306)
		(stroke
			(width 0.0635)
			(type default)
		)
		(layer "In5.Cu")
	)
	(gr_line
		(start 349.758 -168.020746)
		(end 349.758 -168.137586)
		(stroke
			(width 0.0635)
			(type default)
		)
		(layer "In5.Cu")
	)
	(gr_line
		(start 349.758 -166.959026)
		(end 349.758 -167.075866)
		(stroke
			(width 0.0635)
			(type default)
		)
		(layer "In5.Cu")
	)
	(gr_line
		(start 349.770192 -154.914346)
		(end 350.010984 -155.155138)
		(stroke
			(width 0.0635)
			(type default)
		)
		(layer "In5.Cu")
	)
	(gr_line
		(start 349.770192 -154.51582)
		(end 350.010984 -154.275028)
		(stroke
			(width 0.0635)
			(type default)
		)
		(layer "In5.Cu")
	)
	(gr_line
		(start 350.03994 -169.478706)
		(end 350.18726 -169.331386)
		(stroke
			(width 0.0635)
			(type default)
		)
		(layer "In5.Cu")
	)
	(gr_line
		(start 350.03994 -168.803066)
		(end 350.18726 -168.950386)
		(stroke
			(width 0.0635)
			(type default)
		)
		(layer "In5.Cu")
	)
	(gr_line
		(start 350.03994 -168.416986)
		(end 350.18726 -168.269666)
		(stroke
			(width 0.0635)
			(type default)
		)
		(layer "In5.Cu")
	)
	(gr_line
		(start 350.03994 -167.741346)
		(end 350.18726 -167.888666)
		(stroke
			(width 0.0635)
			(type default)
		)
		(layer "In5.Cu")
	)
	(gr_line
		(start 350.03994 -167.355266)
		(end 350.18726 -167.207946)
		(stroke
			(width 0.0635)
			(type default)
		)
		(layer "In5.Cu")
	)
	(gr_line
		(start 350.03994 -166.679626)
		(end 350.18726 -166.826946)
		(stroke
			(width 0.0635)
			(type default)
		)
		(layer "In5.Cu")
	)
	(gr_line
		(start 350.110298 -174.568866)
		(end 350.110298 -174.777146)
		(stroke
			(width 0.0635)
			(type default)
		)
		(layer "In5.Cu")
	)
	(gr_line
		(start 350.110298 -174.568866)
		(end 350.379792 -174.299372)
		(stroke
			(width 0.0635)
			(type default)
		)
		(layer "In5.Cu")
	)
	(gr_line
		(start 350.18726 -168.950386)
		(end 350.18726 -169.331386)
		(stroke
			(width 0.0635)
			(type default)
		)
		(layer "In5.Cu")
	)
	(gr_line
		(start 350.18726 -167.888666)
		(end 350.18726 -168.269666)
		(stroke
			(width 0.0635)
			(type default)
		)
		(layer "In5.Cu")
	)
	(gr_line
		(start 350.18726 -166.826946)
		(end 350.18726 -167.207946)
		(stroke
			(width 0.0635)
			(type default)
		)
		(layer "In5.Cu")
	)
	(gr_line
		(start 350.379792 -174.299372)
		(end 350.588072 -174.299372)
		(stroke
			(width 0.0635)
			(type default)
		)
		(layer "In5.Cu")
	)
	(gr_line
		(start 350.50222 -152.66416)
		(end 350.75495 -152.91689)
		(stroke
			(width 0.0635)
			(type default)
		)
		(layer "In5.Cu")
	)
	(gr_line
		(start 350.50222 -152.26538)
		(end 350.75495 -152.01265)
		(stroke
			(width 0.0635)
			(type default)
		)
		(layer "In5.Cu")
	)
	(gr_line
		(start 350.5073 -174.778924)
		(end 350.58985 -174.696374)
		(stroke
			(width 0.0635)
			(type default)
		)
		(layer "In5.Cu")
	)
	(gr_line
		(start 350.75495 -151.97201)
		(end 350.75495 -152.01265)
		(stroke
			(width 0.0635)
			(type default)
		)
		(layer "In5.Cu")
	)
	(gr_line
		(start 350.87941 -147.62353)
		(end 351.15246 -147.89658)
		(stroke
			(width 0.0635)
			(type default)
		)
		(layer "In5.Cu")
	)
	(gr_line
		(start 351.132902 -173.546262)
		(end 351.132902 -173.754542)
		(stroke
			(width 0.0635)
			(type default)
		)
		(layer "In5.Cu")
	)
	(gr_line
		(start 351.132902 -173.546262)
		(end 351.402142 -173.276768)
		(stroke
			(width 0.0635)
			(type default)
		)
		(layer "In5.Cu")
	)
	(gr_line
		(start 351.402142 -173.276768)
		(end 351.610676 -173.276768)
		(stroke
			(width 0.0635)
			(type default)
		)
		(layer "In5.Cu")
	)
	(gr_line
		(start 351.529904 -173.75632)
		(end 351.612454 -173.67377)
		(stroke
			(width 0.0635)
			(type default)
		)
		(layer "In5.Cu")
	)
	(gr_line
		(start 351.55124 -147.89658)
		(end 351.82429 -147.62353)
		(stroke
			(width 0.0635)
			(type default)
		)
		(layer "In5.Cu")
	)
	(gr_line
		(start 0 -246.000016)
		(end 0 -81.009998)
		(stroke
			(width 1.524)
			(type default)
		)
		(layer "In6.Cu")
	)
	(gr_arc
		(start 0 -246.000016)
		(mid 1.464462 -249.535545)
		(end 4.99999 -251.000006)
		(stroke
			(width 1.524)
			(type default)
		)
		(layer "In6.Cu")
	)
	(gr_arc
		(start 2.999994 -78.010004)
		(mid 0.878678 -78.888682)
		(end 0 -81.009998)
		(stroke
			(width 1.524)
			(type default)
		)
		(layer "In6.Cu")
	)
	(gr_line
		(start 2.999994 -78.010004)
		(end 25.500076 -78.010004)
		(stroke
			(width 1.524)
			(type default)
		)
		(layer "In6.Cu")
	)
	(gr_arc
		(start 10.760964 -101.061266)
		(mid 10.821224 -101.206746)
		(end 10.966704 -101.267006)
		(stroke
			(width 0.2)
			(type default)
		)
		(layer "In6.Cu")
	)
	(gr_line
		(start 10.760964 -100.654866)
		(end 10.760964 -101.061266)
		(stroke
			(width 0.2)
			(type default)
		)
		(layer "In6.Cu")
	)
	(gr_arc
		(start 10.760964 -100.146866)
		(mid 10.821224 -100.292346)
		(end 10.966704 -100.352606)
		(stroke
			(width 0.2)
			(type default)
		)
		(layer "In6.Cu")
	)
	(gr_line
		(start 10.760964 -99.740466)
		(end 10.760964 -100.146866)
		(stroke
			(width 0.2)
			(type default)
		)
		(layer "In6.Cu")
	)
	(gr_line
		(start 10.966704 -101.267006)
		(end 11.373104 -101.267006)
		(stroke
			(width 0.2)
			(type default)
		)
		(layer "In6.Cu")
	)
	(gr_arc
		(start 10.966704 -100.449126)
		(mid 10.821224 -100.509386)
		(end 10.760964 -100.654866)
		(stroke
			(width 0.2)
			(type default)
		)
		(layer "In6.Cu")
	)
	(gr_line
		(start 10.966704 -100.352606)
		(end 11.373104 -100.352606)
		(stroke
			(width 0.2)
			(type default)
		)
		(layer "In6.Cu")
	)
	(gr_arc
		(start 10.966704 -99.534726)
		(mid 10.821224 -99.594986)
		(end 10.760964 -99.740466)
		(stroke
			(width 0.2)
			(type default)
		)
		(layer "In6.Cu")
	)
	(gr_line
		(start 11.14552 -98.876866)
		(end 12.059666 -98.878644)
		(stroke
			(width 0.2)
			(type default)
		)
		(layer "In6.Cu")
	)
	(gr_arc
		(start 11.147044 -98.109786)
		(mid 10.762742 -98.492564)
		(end 11.14552 -98.876866)
		(stroke
			(width 0.2)
			(type default)
		)
		(layer "In6.Cu")
	)
	(gr_arc
		(start 11.373104 -101.267006)
		(mid 11.518584 -101.206746)
		(end 11.578844 -101.061266)
		(stroke
			(width 0.2)
			(type default)
		)
		(layer "In6.Cu")
	)
	(gr_line
		(start 11.373104 -100.449126)
		(end 10.966704 -100.449126)
		(stroke
			(width 0.2)
			(type default)
		)
		(layer "In6.Cu")
	)
	(gr_arc
		(start 11.373104 -100.352606)
		(mid 11.518584 -100.292346)
		(end 11.578844 -100.146866)
		(stroke
			(width 0.2)
			(type default)
		)
		(layer "In6.Cu")
	)
	(gr_line
		(start 11.373104 -99.534726)
		(end 10.966704 -99.534726)
		(stroke
			(width 0.2)
			(type default)
		)
		(layer "In6.Cu")
	)
	(gr_line
		(start 11.578844 -101.061266)
		(end 11.578844 -100.654866)
		(stroke
			(width 0.2)
			(type default)
		)
		(layer "In6.Cu")
	)
	(gr_arc
		(start 11.578844 -100.654866)
		(mid 11.518584 -100.509386)
		(end 11.373104 -100.449126)
		(stroke
			(width 0.2)
			(type default)
		)
		(layer "In6.Cu")
	)
	(gr_line
		(start 11.578844 -100.146866)
		(end 11.578844 -99.740466)
		(stroke
			(width 0.2)
			(type default)
		)
		(layer "In6.Cu")
	)
	(gr_arc
		(start 11.578844 -99.740466)
		(mid 11.518584 -99.594986)
		(end 11.373104 -99.534726)
		(stroke
			(width 0.2)
			(type default)
		)
		(layer "In6.Cu")
	)
	(gr_arc
		(start 11.649964 -101.061266)
		(mid 11.710224 -101.206746)
		(end 11.855704 -101.267006)
		(stroke
			(width 0.2)
			(type default)
		)
		(layer "In6.Cu")
	)
	(gr_line
		(start 11.649964 -100.654866)
		(end 11.649964 -101.061266)
		(stroke
			(width 0.2)
			(type default)
		)
		(layer "In6.Cu")
	)
	(gr_arc
		(start 11.649964 -100.146866)
		(mid 11.710224 -100.292346)
		(end 11.855704 -100.352606)
		(stroke
			(width 0.2)
			(type default)
		)
		(layer "In6.Cu")
	)
	(gr_line
		(start 11.649964 -99.740466)
		(end 11.649964 -100.146866)
		(stroke
			(width 0.2)
			(type default)
		)
		(layer "In6.Cu")
	)
	(gr_line
		(start 11.855704 -101.267006)
		(end 12.262104 -101.267006)
		(stroke
			(width 0.2)
			(type default)
		)
		(layer "In6.Cu")
	)
	(gr_arc
		(start 11.855704 -100.449126)
		(mid 11.710224 -100.509386)
		(end 11.649964 -100.654866)
		(stroke
			(width 0.2)
			(type default)
		)
		(layer "In6.Cu")
	)
	(gr_line
		(start 11.855704 -100.352606)
		(end 12.262104 -100.352606)
		(stroke
			(width 0.2)
			(type default)
		)
		(layer "In6.Cu")
	)
	(gr_arc
		(start 11.855704 -99.534726)
		(mid 11.710224 -99.594986)
		(end 11.649964 -99.740466)
		(stroke
			(width 0.2)
			(type default)
		)
		(layer "In6.Cu")
	)
	(gr_arc
		(start 12.059666 -98.878644)
		(mid 12.444222 -98.495993)
		(end 12.061444 -98.111564)
		(stroke
			(width 0.2)
			(type default)
		)
		(layer "In6.Cu")
	)
	(gr_line
		(start 12.061444 -98.111564)
		(end 11.147044 -98.109786)
		(stroke
			(width 0.2)
			(type default)
		)
		(layer "In6.Cu")
	)
	(gr_arc
		(start 12.262104 -101.267006)
		(mid 12.407584 -101.206746)
		(end 12.467844 -101.061266)
		(stroke
			(width 0.2)
			(type default)
		)
		(layer "In6.Cu")
	)
	(gr_line
		(start 12.262104 -100.449126)
		(end 11.855704 -100.449126)
		(stroke
			(width 0.2)
			(type default)
		)
		(layer "In6.Cu")
	)
	(gr_arc
		(start 12.262104 -100.352606)
		(mid 12.407584 -100.292346)
		(end 12.467844 -100.146866)
		(stroke
			(width 0.2)
			(type default)
		)
		(layer "In6.Cu")
	)
	(gr_line
		(start 12.262104 -99.534726)
		(end 11.855704 -99.534726)
		(stroke
			(width 0.2)
			(type default)
		)
		(layer "In6.Cu")
	)
	(gr_line
		(start 12.467844 -101.061266)
		(end 12.467844 -100.654866)
		(stroke
			(width 0.2)
			(type default)
		)
		(layer "In6.Cu")
	)
	(gr_arc
		(start 12.467844 -100.654866)
		(mid 12.407584 -100.509386)
		(end 12.262104 -100.449126)
		(stroke
			(width 0.2)
			(type default)
		)
		(layer "In6.Cu")
	)
	(gr_line
		(start 12.467844 -100.146866)
		(end 12.467844 -99.740466)
		(stroke
			(width 0.2)
			(type default)
		)
		(layer "In6.Cu")
	)
	(gr_arc
		(start 12.467844 -99.740466)
		(mid 12.407584 -99.594986)
		(end 12.262104 -99.534726)
		(stroke
			(width 0.2)
			(type default)
		)
		(layer "In6.Cu")
	)
	(gr_arc
		(start 13.173964 -101.061266)
		(mid 13.234224 -101.206746)
		(end 13.379704 -101.267006)
		(stroke
			(width 0.2)
			(type default)
		)
		(layer "In6.Cu")
	)
	(gr_line
		(start 13.173964 -100.654866)
		(end 13.173964 -101.061266)
		(stroke
			(width 0.2)
			(type default)
		)
		(layer "In6.Cu")
	)
	(gr_arc
		(start 13.173964 -100.146866)
		(mid 13.234224 -100.292346)
		(end 13.379704 -100.352606)
		(stroke
			(width 0.2)
			(type default)
		)
		(layer "In6.Cu")
	)
	(gr_line
		(start 13.173964 -99.740466)
		(end 13.173964 -100.146866)
		(stroke
			(width 0.2)
			(type default)
		)
		(layer "In6.Cu")
	)
	(gr_line
		(start 13.379704 -101.267006)
		(end 13.786104 -101.267006)
		(stroke
			(width 0.2)
			(type default)
		)
		(layer "In6.Cu")
	)
	(gr_arc
		(start 13.379704 -100.449126)
		(mid 13.234224 -100.509386)
		(end 13.173964 -100.654866)
		(stroke
			(width 0.2)
			(type default)
		)
		(layer "In6.Cu")
	)
	(gr_line
		(start 13.379704 -100.352606)
		(end 13.786104 -100.352606)
		(stroke
			(width 0.2)
			(type default)
		)
		(layer "In6.Cu")
	)
	(gr_arc
		(start 13.379704 -99.534726)
		(mid 13.234224 -99.594986)
		(end 13.173964 -99.740466)
		(stroke
			(width 0.2)
			(type default)
		)
		(layer "In6.Cu")
	)
	(gr_line
		(start 13.487654 -98.852736)
		(end 14.4272 -98.903536)
		(stroke
			(width 0.2)
			(type default)
		)
		(layer "In6.Cu")
	)
	(gr_arc
		(start 13.52931 -98.086672)
		(mid 13.12545 -98.448876)
		(end 13.487654 -98.852736)
		(stroke
			(width 0.2)
			(type default)
		)
		(layer "In6.Cu")
	)
	(gr_arc
		(start 13.786104 -101.267006)
		(mid 13.931584 -101.206746)
		(end 13.991844 -101.061266)
		(stroke
			(width 0.2)
			(type default)
		)
		(layer "In6.Cu")
	)
	(gr_line
		(start 13.786104 -100.449126)
		(end 13.379704 -100.449126)
		(stroke
			(width 0.2)
			(type default)
		)
		(layer "In6.Cu")
	)
	(gr_arc
		(start 13.786104 -100.352606)
		(mid 13.931584 -100.292346)
		(end 13.991844 -100.146866)
		(stroke
			(width 0.2)
			(type default)
		)
		(layer "In6.Cu")
	)
	(gr_line
		(start 13.786104 -99.534726)
		(end 13.379704 -99.534726)
		(stroke
			(width 0.2)
			(type default)
		)
		(layer "In6.Cu")
	)
	(gr_line
		(start 13.991844 -101.061266)
		(end 13.991844 -100.654866)
		(stroke
			(width 0.2)
			(type default)
		)
		(layer "In6.Cu")
	)
	(gr_arc
		(start 13.991844 -100.654866)
		(mid 13.931584 -100.509386)
		(end 13.786104 -100.449126)
		(stroke
			(width 0.2)
			(type default)
		)
		(layer "In6.Cu")
	)
	(gr_line
		(start 13.991844 -100.146866)
		(end 13.991844 -99.740466)
		(stroke
			(width 0.2)
			(type default)
		)
		(layer "In6.Cu")
	)
	(gr_arc
		(start 13.991844 -99.740466)
		(mid 13.931584 -99.594986)
		(end 13.786104 -99.534726)
		(stroke
			(width 0.2)
			(type default)
		)
		(layer "In6.Cu")
	)
	(gr_arc
		(start 14.062964 -101.061266)
		(mid 14.123224 -101.206746)
		(end 14.268704 -101.267006)
		(stroke
			(width 0.2)
			(type default)
		)
		(layer "In6.Cu")
	)
	(gr_line
		(start 14.062964 -100.654866)
		(end 14.062964 -101.061266)
		(stroke
			(width 0.2)
			(type default)
		)
		(layer "In6.Cu")
	)
	(gr_arc
		(start 14.062964 -100.146866)
		(mid 14.123224 -100.292346)
		(end 14.268704 -100.352606)
		(stroke
			(width 0.2)
			(type default)
		)
		(layer "In6.Cu")
	)
	(gr_line
		(start 14.062964 -99.740466)
		(end 14.062964 -100.146866)
		(stroke
			(width 0.2)
			(type default)
		)
		(layer "In6.Cu")
	)
	(gr_line
		(start 14.268704 -101.267006)
		(end 14.675104 -101.267006)
		(stroke
			(width 0.2)
			(type default)
		)
		(layer "In6.Cu")
	)
	(gr_arc
		(start 14.268704 -100.449126)
		(mid 14.123224 -100.509386)
		(end 14.062964 -100.654866)
		(stroke
			(width 0.2)
			(type default)
		)
		(layer "In6.Cu")
	)
	(gr_line
		(start 14.268704 -100.352606)
		(end 14.675104 -100.352606)
		(stroke
			(width 0.2)
			(type default)
		)
		(layer "In6.Cu")
	)
	(gr_arc
		(start 14.268704 -99.534726)
		(mid 14.123224 -99.594986)
		(end 14.062964 -99.740466)
		(stroke
			(width 0.2)
			(type default)
		)
		(layer "In6.Cu")
	)
	(gr_line
		(start 14.4272 -98.903536)
		(end 14.427454 -98.903536)
		(stroke
			(width 0.2)
			(type default)
		)
		(layer "In6.Cu")
	)
	(gr_arc
		(start 14.427454 -98.903536)
		(mid 14.831314 -98.541332)
		(end 14.46911 -98.137472)
		(stroke
			(width 0.2)
			(type default)
		)
		(layer "In6.Cu")
	)
	(gr_line
		(start 14.46911 -98.137472)
		(end 13.52931 -98.086672)
		(stroke
			(width 0.2)
			(type default)
		)
		(layer "In6.Cu")
	)
	(gr_arc
		(start 14.675104 -101.267006)
		(mid 14.820584 -101.206746)
		(end 14.880844 -101.061266)
		(stroke
			(width 0.2)
			(type default)
		)
		(layer "In6.Cu")
	)
	(gr_line
		(start 14.675104 -100.449126)
		(end 14.268704 -100.449126)
		(stroke
			(width 0.2)
			(type default)
		)
		(layer "In6.Cu")
	)
	(gr_arc
		(start 14.675104 -100.352606)
		(mid 14.820584 -100.292346)
		(end 14.880844 -100.146866)
		(stroke
			(width 0.2)
			(type default)
		)
		(layer "In6.Cu")
	)
	(gr_line
		(start 14.675104 -99.534726)
		(end 14.268704 -99.534726)
		(stroke
			(width 0.2)
			(type default)
		)
		(layer "In6.Cu")
	)
	(gr_line
		(start 14.880844 -101.061266)
		(end 14.880844 -100.654866)
		(stroke
			(width 0.2)
			(type default)
		)
		(layer "In6.Cu")
	)
	(gr_arc
		(start 14.880844 -100.654866)
		(mid 14.820584 -100.509386)
		(end 14.675104 -100.449126)
		(stroke
			(width 0.2)
			(type default)
		)
		(layer "In6.Cu")
	)
	(gr_line
		(start 14.880844 -100.146866)
		(end 14.880844 -99.740466)
		(stroke
			(width 0.2)
			(type default)
		)
		(layer "In6.Cu")
	)
	(gr_arc
		(start 14.880844 -99.740466)
		(mid 14.820584 -99.594986)
		(end 14.675104 -99.534726)
		(stroke
			(width 0.2)
			(type default)
		)
		(layer "In6.Cu")
	)
	(gr_arc
		(start 15.586964 -101.061266)
		(mid 15.647224 -101.206746)
		(end 15.792704 -101.267006)
		(stroke
			(width 0.2)
			(type default)
		)
		(layer "In6.Cu")
	)
	(gr_line
		(start 15.586964 -100.654866)
		(end 15.586964 -101.061266)
		(stroke
			(width 0.2)
			(type default)
		)
		(layer "In6.Cu")
	)
	(gr_arc
		(start 15.586964 -100.146866)
		(mid 15.647224 -100.292346)
		(end 15.792704 -100.352606)
		(stroke
			(width 0.2)
			(type default)
		)
		(layer "In6.Cu")
	)
	(gr_line
		(start 15.586964 -99.740466)
		(end 15.586964 -100.146866)
		(stroke
			(width 0.2)
			(type default)
		)
		(layer "In6.Cu")
	)
	(gr_line
		(start 15.792704 -101.267006)
		(end 16.199104 -101.267006)
		(stroke
			(width 0.2)
			(type default)
		)
		(layer "In6.Cu")
	)
	(gr_arc
		(start 15.792704 -100.449126)
		(mid 15.647224 -100.509386)
		(end 15.586964 -100.654866)
		(stroke
			(width 0.2)
			(type default)
		)
		(layer "In6.Cu")
	)
	(gr_line
		(start 15.792704 -100.352606)
		(end 16.199104 -100.352606)
		(stroke
			(width 0.2)
			(type default)
		)
		(layer "In6.Cu")
	)
	(gr_arc
		(start 15.792704 -99.534726)
		(mid 15.647224 -99.594986)
		(end 15.586964 -99.740466)
		(stroke
			(width 0.2)
			(type default)
		)
		(layer "In6.Cu")
	)
	(gr_line
		(start 15.936468 -98.88093)
		(end 16.876268 -98.90633)
		(stroke
			(width 0.2)
			(type default)
		)
		(layer "In6.Cu")
	)
	(gr_line
		(start 15.936468 -98.87839)
		(end 15.936468 -98.88093)
		(stroke
			(width 0.2)
			(type default)
		)
		(layer "In6.Cu")
	)
	(gr_arc
		(start 15.957296 -98.111818)
		(mid 15.563596 -98.48469)
		(end 15.936468 -98.87839)
		(stroke
			(width 0.2)
			(type default)
		)
		(layer "In6.Cu")
	)
	(gr_line
		(start 15.957296 -98.109532)
		(end 15.957296 -98.111818)
		(stroke
			(width 0.2)
			(type default)
		)
		(layer "In6.Cu")
	)
	(gr_line
		(start 15.95755 -98.109278)
		(end 15.957296 -98.109532)
		(stroke
			(width 0.2)
			(type default)
		)
		(layer "In6.Cu")
	)
	(gr_arc
		(start 16.199104 -101.267006)
		(mid 16.344584 -101.206746)
		(end 16.404844 -101.061266)
		(stroke
			(width 0.2)
			(type default)
		)
		(layer "In6.Cu")
	)
	(gr_line
		(start 16.199104 -100.449126)
		(end 15.792704 -100.449126)
		(stroke
			(width 0.2)
			(type default)
		)
		(layer "In6.Cu")
	)
	(gr_arc
		(start 16.199104 -100.352606)
		(mid 16.344584 -100.292346)
		(end 16.404844 -100.146866)
		(stroke
			(width 0.2)
			(type default)
		)
		(layer "In6.Cu")
	)
	(gr_line
		(start 16.199104 -99.534726)
		(end 15.792704 -99.534726)
		(stroke
			(width 0.2)
			(type default)
		)
		(layer "In6.Cu")
	)
	(gr_line
		(start 16.404844 -101.061266)
		(end 16.404844 -100.654866)
		(stroke
			(width 0.2)
			(type default)
		)
		(layer "In6.Cu")
	)
	(gr_arc
		(start 16.404844 -100.654866)
		(mid 16.344584 -100.509386)
		(end 16.199104 -100.449126)
		(stroke
			(width 0.2)
			(type default)
		)
		(layer "In6.Cu")
	)
	(gr_line
		(start 16.404844 -100.146866)
		(end 16.404844 -99.740466)
		(stroke
			(width 0.2)
			(type default)
		)
		(layer "In6.Cu")
	)
	(gr_arc
		(start 16.404844 -99.740466)
		(mid 16.344584 -99.594986)
		(end 16.199104 -99.534726)
		(stroke
			(width 0.2)
			(type default)
		)
		(layer "In6.Cu")
	)
	(gr_arc
		(start 16.475964 -101.061266)
		(mid 16.536224 -101.206746)
		(end 16.681704 -101.267006)
		(stroke
			(width 0.2)
			(type default)
		)
		(layer "In6.Cu")
	)
	(gr_line
		(start 16.475964 -100.654866)
		(end 16.475964 -101.061266)
		(stroke
			(width 0.2)
			(type default)
		)
		(layer "In6.Cu")
	)
	(gr_arc
		(start 16.475964 -100.146866)
		(mid 16.536224 -100.292346)
		(end 16.681704 -100.352606)
		(stroke
			(width 0.2)
			(type default)
		)
		(layer "In6.Cu")
	)
	(gr_line
		(start 16.475964 -99.740466)
		(end 16.475964 -100.146866)
		(stroke
			(width 0.2)
			(type default)
		)
		(layer "In6.Cu")
	)
	(gr_line
		(start 16.681704 -101.267006)
		(end 17.088104 -101.267006)
		(stroke
			(width 0.2)
			(type default)
		)
		(layer "In6.Cu")
	)
	(gr_arc
		(start 16.681704 -100.449126)
		(mid 16.536224 -100.509386)
		(end 16.475964 -100.654866)
		(stroke
			(width 0.2)
			(type default)
		)
		(layer "In6.Cu")
	)
	(gr_line
		(start 16.681704 -100.352606)
		(end 17.088104 -100.352606)
		(stroke
			(width 0.2)
			(type default)
		)
		(layer "In6.Cu")
	)
	(gr_arc
		(start 16.681704 -99.534726)
		(mid 16.536224 -99.594986)
		(end 16.475964 -99.740466)
		(stroke
			(width 0.2)
			(type default)
		)
		(layer "In6.Cu")
	)
	(gr_line
		(start 16.876268 -98.90633)
		(end 16.876268 -98.90379)
		(stroke
			(width 0.2)
			(type default)
		)
		(layer "In6.Cu")
	)
	(gr_arc
		(start 16.876268 -98.90379)
		(mid 17.269968 -98.530918)
		(end 16.897096 -98.137218)
		(stroke
			(width 0.2)
			(type default)
		)
		(layer "In6.Cu")
	)
	(gr_line
		(start 16.897096 -98.137218)
		(end 16.897096 -98.134678)
		(stroke
			(width 0.2)
			(type default)
		)
		(layer "In6.Cu")
	)
	(gr_line
		(start 16.897096 -98.134678)
		(end 15.95755 -98.109278)
		(stroke
			(width 0.2)
			(type default)
		)
		(layer "In6.Cu")
	)
	(gr_arc
		(start 17.088104 -101.267006)
		(mid 17.233584 -101.206746)
		(end 17.293844 -101.061266)
		(stroke
			(width 0.2)
			(type default)
		)
		(layer "In6.Cu")
	)
	(gr_line
		(start 17.088104 -100.449126)
		(end 16.681704 -100.449126)
		(stroke
			(width 0.2)
			(type default)
		)
		(layer "In6.Cu")
	)
	(gr_arc
		(start 17.088104 -100.352606)
		(mid 17.233584 -100.292346)
		(end 17.293844 -100.146866)
		(stroke
			(width 0.2)
			(type default)
		)
		(layer "In6.Cu")
	)
	(gr_line
		(start 17.088104 -99.534726)
		(end 16.681704 -99.534726)
		(stroke
			(width 0.2)
			(type default)
		)
		(layer "In6.Cu")
	)
	(gr_line
		(start 17.293844 -101.061266)
		(end 17.293844 -100.654866)
		(stroke
			(width 0.2)
			(type default)
		)
		(layer "In6.Cu")
	)
	(gr_arc
		(start 17.293844 -100.654866)
		(mid 17.233584 -100.509386)
		(end 17.088104 -100.449126)
		(stroke
			(width 0.2)
			(type default)
		)
		(layer "In6.Cu")
	)
	(gr_line
		(start 17.293844 -100.146866)
		(end 17.293844 -99.740466)
		(stroke
			(width 0.2)
			(type default)
		)
		(layer "In6.Cu")
	)
	(gr_arc
		(start 17.293844 -99.740466)
		(mid 17.233584 -99.594986)
		(end 17.088104 -99.534726)
		(stroke
			(width 0.2)
			(type default)
		)
		(layer "In6.Cu")
	)
	(gr_arc
		(start 17.872964 -101.061266)
		(mid 17.933224 -101.206746)
		(end 18.078704 -101.267006)
		(stroke
			(width 0.2)
			(type default)
		)
		(layer "In6.Cu")
	)
	(gr_line
		(start 17.872964 -100.654866)
		(end 17.872964 -101.061266)
		(stroke
			(width 0.2)
			(type default)
		)
		(layer "In6.Cu")
	)
	(gr_arc
		(start 17.872964 -100.146866)
		(mid 17.933224 -100.292346)
		(end 18.078704 -100.352606)
		(stroke
			(width 0.2)
			(type default)
		)
		(layer "In6.Cu")
	)
	(gr_line
		(start 17.872964 -99.740466)
		(end 17.872964 -100.146866)
		(stroke
			(width 0.2)
			(type default)
		)
		(layer "In6.Cu")
	)
	(gr_line
		(start 18.078704 -101.267006)
		(end 18.485104 -101.267006)
		(stroke
			(width 0.2)
			(type default)
		)
		(layer "In6.Cu")
	)
	(gr_arc
		(start 18.078704 -100.449126)
		(mid 17.933224 -100.509386)
		(end 17.872964 -100.654866)
		(stroke
			(width 0.2)
			(type default)
		)
		(layer "In6.Cu")
	)
	(gr_line
		(start 18.078704 -100.352606)
		(end 18.485104 -100.352606)
		(stroke
			(width 0.2)
			(type default)
		)
		(layer "In6.Cu")
	)
	(gr_arc
		(start 18.078704 -99.534726)
		(mid 17.933224 -99.594986)
		(end 17.872964 -99.740466)
		(stroke
			(width 0.2)
			(type default)
		)
		(layer "In6.Cu")
	)
	(gr_line
		(start 18.258282 -98.929444)
		(end 19.325082 -98.929444)
		(stroke
			(width 0.2)
			(type default)
		)
		(layer "In6.Cu")
	)
	(gr_arc
		(start 18.258536 -98.162364)
		(mid 17.874742 -98.545777)
		(end 18.258282 -98.929444)
		(stroke
			(width 0.2)
			(type default)
		)
		(layer "In6.Cu")
	)
	(gr_arc
		(start 18.485104 -101.267006)
		(mid 18.630584 -101.206746)
		(end 18.690844 -101.061266)
		(stroke
			(width 0.2)
			(type default)
		)
		(layer "In6.Cu")
	)
	(gr_line
		(start 18.485104 -100.449126)
		(end 18.078704 -100.449126)
		(stroke
			(width 0.2)
			(type default)
		)
		(layer "In6.Cu")
	)
	(gr_arc
		(start 18.485104 -100.352606)
		(mid 18.630584 -100.292346)
		(end 18.690844 -100.146866)
		(stroke
			(width 0.2)
			(type default)
		)
		(layer "In6.Cu")
	)
	(gr_line
		(start 18.485104 -99.534726)
		(end 18.078704 -99.534726)
		(stroke
			(width 0.2)
			(type default)
		)
		(layer "In6.Cu")
	)
	(gr_line
		(start 18.690844 -101.061266)
		(end 18.690844 -100.654866)
		(stroke
			(width 0.2)
			(type default)
		)
		(layer "In6.Cu")
	)
	(gr_arc
		(start 18.690844 -100.654866)
		(mid 18.630584 -100.509386)
		(end 18.485104 -100.449126)
		(stroke
			(width 0.2)
			(type default)
		)
		(layer "In6.Cu")
	)
	(gr_line
		(start 18.690844 -100.146866)
		(end 18.690844 -99.740466)
		(stroke
			(width 0.2)
			(type default)
		)
		(layer "In6.Cu")
	)
	(gr_arc
		(start 18.690844 -99.740466)
		(mid 18.630584 -99.594986)
		(end 18.485104 -99.534726)
		(stroke
			(width 0.2)
			(type default)
		)
		(layer "In6.Cu")
	)
	(gr_arc
		(start 18.761964 -101.061266)
		(mid 18.822224 -101.206746)
		(end 18.967704 -101.267006)
		(stroke
			(width 0.2)
			(type default)
		)
		(layer "In6.Cu")
	)
	(gr_line
		(start 18.761964 -100.654866)
		(end 18.761964 -101.061266)
		(stroke
			(width 0.2)
			(type default)
		)
		(layer "In6.Cu")
	)
	(gr_arc
		(start 18.761964 -100.146866)
		(mid 18.822224 -100.292346)
		(end 18.967704 -100.352606)
		(stroke
			(width 0.2)
			(type default)
		)
		(layer "In6.Cu")
	)
	(gr_line
		(start 18.761964 -99.740466)
		(end 18.761964 -100.146866)
		(stroke
			(width 0.2)
			(type default)
		)
		(layer "In6.Cu")
	)
	(gr_line
		(start 18.967704 -101.267006)
		(end 19.374104 -101.267006)
		(stroke
			(width 0.2)
			(type default)
		)
		(layer "In6.Cu")
	)
	(gr_arc
		(start 18.967704 -100.449126)
		(mid 18.822224 -100.509386)
		(end 18.761964 -100.654866)
		(stroke
			(width 0.2)
			(type default)
		)
		(layer "In6.Cu")
	)
	(gr_line
		(start 18.967704 -100.352606)
		(end 19.374104 -100.352606)
		(stroke
			(width 0.2)
			(type default)
		)
		(layer "In6.Cu")
	)
	(gr_arc
		(start 18.967704 -99.534726)
		(mid 18.822224 -99.594986)
		(end 18.761964 -99.740466)
		(stroke
			(width 0.2)
			(type default)
		)
		(layer "In6.Cu")
	)
	(gr_arc
		(start 19.325082 -98.929444)
		(mid 19.708622 -98.545904)
		(end 19.325082 -98.162364)
		(stroke
			(width 0.2)
			(type default)
		)
		(layer "In6.Cu")
	)
	(gr_line
		(start 19.325082 -98.162364)
		(end 18.258536 -98.162364)
		(stroke
			(width 0.2)
			(type default)
		)
		(layer "In6.Cu")
	)
	(gr_arc
		(start 19.374104 -101.267006)
		(mid 19.519584 -101.206746)
		(end 19.579844 -101.061266)
		(stroke
			(width 0.2)
			(type default)
		)
		(layer "In6.Cu")
	)
	(gr_line
		(start 19.374104 -100.449126)
		(end 18.967704 -100.449126)
		(stroke
			(width 0.2)
			(type default)
		)
		(layer "In6.Cu")
	)
	(gr_arc
		(start 19.374104 -100.352606)
		(mid 19.519584 -100.292346)
		(end 19.579844 -100.146866)
		(stroke
			(width 0.2)
			(type default)
		)
		(layer "In6.Cu")
	)
	(gr_line
		(start 19.374104 -99.534726)
		(end 18.967704 -99.534726)
		(stroke
			(width 0.2)
			(type default)
		)
		(layer "In6.Cu")
	)
	(gr_line
		(start 19.579844 -101.061266)
		(end 19.579844 -100.654866)
		(stroke
			(width 0.2)
			(type default)
		)
		(layer "In6.Cu")
	)
	(gr_arc
		(start 19.579844 -100.654866)
		(mid 19.519584 -100.509386)
		(end 19.374104 -100.449126)
		(stroke
			(width 0.2)
			(type default)
		)
		(layer "In6.Cu")
	)
	(gr_line
		(start 19.579844 -100.146866)
		(end 19.579844 -99.740466)
		(stroke
			(width 0.2)
			(type default)
		)
		(layer "In6.Cu")
	)
	(gr_arc
		(start 19.579844 -99.740466)
		(mid 19.519584 -99.594986)
		(end 19.374104 -99.534726)
		(stroke
			(width 0.2)
			(type default)
		)
		(layer "In6.Cu")
	)
	(gr_arc
		(start 25.500076 -78.010004)
		(mid 26.914287 -77.424219)
		(end 27.500072 -76.010008)
		(stroke
			(width 1.524)
			(type default)
		)
		(layer "In6.Cu")
	)
	(gr_line
		(start 26.34996 -251.000006)
		(end 4.99999 -251.000006)
		(stroke
			(width 1.524)
			(type default)
		)
		(layer "In6.Cu")
	)
	(gr_line
		(start 27.349958 -258.59994)
		(end 27.349958 -252.000004)
		(stroke
			(width 1.524)
			(type default)
		)
		(layer "In6.Cu")
	)
	(gr_arc
		(start 27.349958 -252.000004)
		(mid 27.057065 -251.292899)
		(end 26.34996 -251.000006)
		(stroke
			(width 1.524)
			(type default)
		)
		(layer "In6.Cu")
	)
	(gr_line
		(start 27.500072 -76.010008)
		(end 27.500072 -60.01004)
		(stroke
			(width 1.524)
			(type default)
		)
		(layer "In6.Cu")
	)
	(gr_arc
		(start 29.500068 -58.010044)
		(mid 28.085859 -58.59583)
		(end 27.500072 -60.01004)
		(stroke
			(width 1.524)
			(type default)
		)
		(layer "In6.Cu")
	)
	(gr_line
		(start 29.500068 -58.010044)
		(end 60.950094 -58.010044)
		(stroke
			(width 1.524)
			(type default)
		)
		(layer "In6.Cu")
	)
	(gr_line
		(start 32.334454 -90.479626)
		(end 33.311338 -90.479626)
		(stroke
			(width 0.2)
			(type default)
		)
		(layer "In6.Cu")
	)
	(gr_arc
		(start 32.334708 -89.712546)
		(mid 31.950914 -90.095959)
		(end 32.334454 -90.479626)
		(stroke
			(width 0.2)
			(type default)
		)
		(layer "In6.Cu")
	)
	(gr_arc
		(start 33.311338 -90.479626)
		(mid 33.694878 -90.096086)
		(end 33.311338 -89.712546)
		(stroke
			(width 0.2)
			(type default)
		)
		(layer "In6.Cu")
	)
	(gr_line
		(start 33.311338 -89.712546)
		(end 32.334708 -89.712546)
		(stroke
			(width 0.2)
			(type default)
		)
		(layer "In6.Cu")
	)
	(gr_line
		(start 34.550096 -258.59994)
		(end 27.349958 -258.59994)
		(stroke
			(width 5.08)
			(type default)
		)
		(layer "In6.Cu")
	)
	(gr_line
		(start 34.550096 -252.549914)
		(end 34.550096 -258.59994)
		(stroke
			(width 1.524)
			(type default)
		)
		(layer "In6.Cu")
	)
	(gr_line
		(start 35.382454 -90.479626)
		(end 36.359084 -90.479626)
		(stroke
			(width 0.2)
			(type default)
		)
		(layer "In6.Cu")
	)
	(gr_arc
		(start 35.382454 -89.712546)
		(mid 34.998914 -90.096086)
		(end 35.382454 -90.479626)
		(stroke
			(width 0.2)
			(type default)
		)
		(layer "In6.Cu")
	)
	(gr_arc
		(start 36.359084 -90.479626)
		(mid 36.742878 -90.096213)
		(end 36.359338 -89.712546)
		(stroke
			(width 0.2)
			(type default)
		)
		(layer "In6.Cu")
	)
	(gr_line
		(start 36.359338 -89.712546)
		(end 35.382454 -89.712546)
		(stroke
			(width 0.2)
			(type default)
		)
		(layer "In6.Cu")
	)
	(gr_line
		(start 36.450016 -258.59994)
		(end 36.450016 -252.549914)
		(stroke
			(width 1.524)
			(type default)
		)
		(layer "In6.Cu")
	)
	(gr_arc
		(start 36.450016 -252.549914)
		(mid 35.500056 -251.599954)
		(end 34.550096 -252.549914)
		(stroke
			(width 1.524)
			(type default)
		)
		(layer "In6.Cu")
	)
	(gr_line
		(start 38.430454 -90.479626)
		(end 39.407084 -90.479626)
		(stroke
			(width 0.2)
			(type default)
		)
		(layer "In6.Cu")
	)
	(gr_arc
		(start 38.430454 -89.712546)
		(mid 38.046914 -90.096086)
		(end 38.430454 -90.479626)
		(stroke
			(width 0.2)
			(type default)
		)
		(layer "In6.Cu")
	)
	(gr_arc
		(start 39.208456 -83.046824)
		(mid 39.591869 -83.430618)
		(end 39.975536 -83.047078)
		(stroke
			(width 0.2)
			(type default)
		)
		(layer "In6.Cu")
	)
	(gr_line
		(start 39.208456 -82.070194)
		(end 39.208456 -83.046824)
		(stroke
			(width 0.2)
			(type default)
		)
		(layer "In6.Cu")
	)
	(gr_arc
		(start 39.208456 -80.722978)
		(mid 39.591996 -81.106518)
		(end 39.975536 -80.722978)
		(stroke
			(width 0.2)
			(type default)
		)
		(layer "In6.Cu")
	)
	(gr_line
		(start 39.208456 -79.746094)
		(end 39.208456 -80.722978)
		(stroke
			(width 0.2)
			(type default)
		)
		(layer "In6.Cu")
	)
	(gr_arc
		(start 39.407084 -90.479626)
		(mid 39.790878 -90.096213)
		(end 39.407338 -89.712546)
		(stroke
			(width 0.2)
			(type default)
		)
		(layer "In6.Cu")
	)
	(gr_line
		(start 39.407338 -89.712546)
		(end 38.430454 -89.712546)
		(stroke
			(width 0.2)
			(type default)
		)
		(layer "In6.Cu")
	)
	(gr_line
		(start 39.975536 -83.047078)
		(end 39.975536 -82.070194)
		(stroke
			(width 0.2)
			(type default)
		)
		(layer "In6.Cu")
	)
	(gr_arc
		(start 39.975536 -82.070194)
		(mid 39.591996 -81.686654)
		(end 39.208456 -82.070194)
		(stroke
			(width 0.2)
			(type default)
		)
		(layer "In6.Cu")
	)
	(gr_line
		(start 39.975536 -80.722978)
		(end 39.975536 -79.746348)
		(stroke
			(width 0.2)
			(type default)
		)
		(layer "In6.Cu")
	)
	(gr_arc
		(start 39.975536 -79.746348)
		(mid 39.592123 -79.362554)
		(end 39.208456 -79.746094)
		(stroke
			(width 0.2)
			(type default)
		)
		(layer "In6.Cu")
	)
	(gr_line
		(start 41.351454 -90.479626)
		(end 42.328338 -90.479626)
		(stroke
			(width 0.2)
			(type default)
		)
		(layer "In6.Cu")
	)
	(gr_arc
		(start 41.351708 -89.712546)
		(mid 40.967914 -90.095959)
		(end 41.351454 -90.479626)
		(stroke
			(width 0.2)
			(type default)
		)
		(layer "In6.Cu")
	)
	(gr_line
		(start 41.693338 -83.873086)
		(end 42.670222 -83.873086)
		(stroke
			(width 0.2)
			(type default)
		)
		(layer "In6.Cu")
	)
	(gr_arc
		(start 41.693592 -83.106006)
		(mid 41.309798 -83.489419)
		(end 41.693338 -83.873086)
		(stroke
			(width 0.2)
			(type default)
		)
		(layer "In6.Cu")
	)
	(gr_arc
		(start 41.70299 -78.310486)
		(mid 41.76325 -78.455966)
		(end 41.90873 -78.516226)
		(stroke
			(width 0.2)
			(type default)
		)
		(layer "In6.Cu")
	)
	(gr_line
		(start 41.70299 -77.904086)
		(end 41.70299 -78.310486)
		(stroke
			(width 0.2)
			(type default)
		)
		(layer "In6.Cu")
	)
	(gr_arc
		(start 41.70299 -77.396086)
		(mid 41.76325 -77.541566)
		(end 41.90873 -77.601826)
		(stroke
			(width 0.2)
			(type default)
		)
		(layer "In6.Cu")
	)
	(gr_line
		(start 41.70299 -76.989686)
		(end 41.70299 -77.396086)
		(stroke
			(width 0.2)
			(type default)
		)
		(layer "In6.Cu")
	)
	(gr_line
		(start 41.90873 -78.516226)
		(end 42.31513 -78.516226)
		(stroke
			(width 0.2)
			(type default)
		)
		(layer "In6.Cu")
	)
	(gr_arc
		(start 41.90873 -77.698346)
		(mid 41.76325 -77.758606)
		(end 41.70299 -77.904086)
		(stroke
			(width 0.2)
			(type default)
		)
		(layer "In6.Cu")
	)
	(gr_line
		(start 41.90873 -77.601826)
		(end 42.31513 -77.601826)
		(stroke
			(width 0.2)
			(type default)
		)
		(layer "In6.Cu")
	)
	(gr_arc
		(start 41.90873 -76.783946)
		(mid 41.76325 -76.844206)
		(end 41.70299 -76.989686)
		(stroke
			(width 0.2)
			(type default)
		)
		(layer "In6.Cu")
	)
	(gr_line
		(start 42.111422 -75.138026)
		(end 43.088306 -75.138026)
		(stroke
			(width 0.2)
			(type default)
		)
		(layer "In6.Cu")
	)
	(gr_arc
		(start 42.111676 -74.370946)
		(mid 41.727882 -74.754359)
		(end 42.111422 -75.138026)
		(stroke
			(width 0.2)
			(type default)
		)
		(layer "In6.Cu")
	)
	(gr_arc
		(start 42.31513 -78.516226)
		(mid 42.46061 -78.455966)
		(end 42.52087 -78.310486)
		(stroke
			(width 0.2)
			(type default)
		)
		(layer "In6.Cu")
	)
	(gr_line
		(start 42.31513 -77.698346)
		(end 41.90873 -77.698346)
		(stroke
			(width 0.2)
			(type default)
		)
		(layer "In6.Cu")
	)
	(gr_arc
		(start 42.31513 -77.601826)
		(mid 42.46061 -77.541566)
		(end 42.52087 -77.396086)
		(stroke
			(width 0.2)
			(type default)
		)
		(layer "In6.Cu")
	)
	(gr_line
		(start 42.31513 -76.783946)
		(end 41.90873 -76.783946)
		(stroke
			(width 0.2)
			(type default)
		)
		(layer "In6.Cu")
	)
	(gr_arc
		(start 42.328338 -90.479626)
		(mid 42.711878 -90.096086)
		(end 42.328338 -89.712546)
		(stroke
			(width 0.2)
			(type default)
		)
		(layer "In6.Cu")
	)
	(gr_line
		(start 42.328338 -89.712546)
		(end 41.351708 -89.712546)
		(stroke
			(width 0.2)
			(type default)
		)
		(layer "In6.Cu")
	)
	(gr_line
		(start 42.52087 -78.310486)
		(end 42.52087 -77.904086)
		(stroke
			(width 0.2)
			(type default)
		)
		(layer "In6.Cu")
	)
	(gr_arc
		(start 42.52087 -77.904086)
		(mid 42.46061 -77.758606)
		(end 42.31513 -77.698346)
		(stroke
			(width 0.2)
			(type default)
		)
		(layer "In6.Cu")
	)
	(gr_line
		(start 42.52087 -77.396086)
		(end 42.52087 -76.989686)
		(stroke
			(width 0.2)
			(type default)
		)
		(layer "In6.Cu")
	)
	(gr_arc
		(start 42.52087 -76.989686)
		(mid 42.46061 -76.844206)
		(end 42.31513 -76.783946)
		(stroke
			(width 0.2)
			(type default)
		)
		(layer "In6.Cu")
	)
	(gr_arc
		(start 42.670222 -83.873086)
		(mid 43.053762 -83.489546)
		(end 42.670222 -83.106006)
		(stroke
			(width 0.2)
			(type default)
		)
		(layer "In6.Cu")
	)
	(gr_line
		(start 42.670222 -83.106006)
		(end 41.693592 -83.106006)
		(stroke
			(width 0.2)
			(type default)
		)
		(layer "In6.Cu")
	)
	(gr_arc
		(start 42.71899 -78.310486)
		(mid 42.77925 -78.455966)
		(end 42.92473 -78.516226)
		(stroke
			(width 0.2)
			(type default)
		)
		(layer "In6.Cu")
	)
	(gr_line
		(start 42.71899 -77.904086)
		(end 42.71899 -78.310486)
		(stroke
			(width 0.2)
			(type default)
		)
		(layer "In6.Cu")
	)
	(gr_arc
		(start 42.71899 -77.396086)
		(mid 42.77925 -77.541566)
		(end 42.92473 -77.601826)
		(stroke
			(width 0.2)
			(type default)
		)
		(layer "In6.Cu")
	)
	(gr_line
		(start 42.71899 -76.989686)
		(end 42.71899 -77.396086)
		(stroke
			(width 0.2)
			(type default)
		)
		(layer "In6.Cu")
	)
	(gr_line
		(start 42.92473 -78.516226)
		(end 43.33113 -78.516226)
		(stroke
			(width 0.2)
			(type default)
		)
		(layer "In6.Cu")
	)
	(gr_arc
		(start 42.92473 -77.698346)
		(mid 42.77925 -77.758606)
		(end 42.71899 -77.904086)
		(stroke
			(width 0.2)
			(type default)
		)
		(layer "In6.Cu")
	)
	(gr_line
		(start 42.92473 -77.601826)
		(end 43.33113 -77.601826)
		(stroke
			(width 0.2)
			(type default)
		)
		(layer "In6.Cu")
	)
	(gr_arc
		(start 42.92473 -76.783946)
		(mid 42.77925 -76.844206)
		(end 42.71899 -76.989686)
		(stroke
			(width 0.2)
			(type default)
		)
		(layer "In6.Cu")
	)
	(gr_arc
		(start 43.088306 -75.138026)
		(mid 43.471846 -74.754486)
		(end 43.088306 -74.370946)
		(stroke
			(width 0.2)
			(type default)
		)
		(layer "In6.Cu")
	)
	(gr_line
		(start 43.088306 -74.370946)
		(end 42.111676 -74.370946)
		(stroke
			(width 0.2)
			(type default)
		)
		(layer "In6.Cu")
	)
	(gr_arc
		(start 43.33113 -78.516226)
		(mid 43.47661 -78.455966)
		(end 43.53687 -78.310486)
		(stroke
			(width 0.2)
			(type default)
		)
		(layer "In6.Cu")
	)
	(gr_line
		(start 43.33113 -77.698346)
		(end 42.92473 -77.698346)
		(stroke
			(width 0.2)
			(type default)
		)
		(layer "In6.Cu")
	)
	(gr_arc
		(start 43.33113 -77.601826)
		(mid 43.47661 -77.541566)
		(end 43.53687 -77.396086)
		(stroke
			(width 0.2)
			(type default)
		)
		(layer "In6.Cu")
	)
	(gr_line
		(start 43.33113 -76.783946)
		(end 42.92473 -76.783946)
		(stroke
			(width 0.2)
			(type default)
		)
		(layer "In6.Cu")
	)
	(gr_line
		(start 43.53687 -78.310486)
		(end 43.53687 -77.904086)
		(stroke
			(width 0.2)
			(type default)
		)
		(layer "In6.Cu")
	)
	(gr_arc
		(start 43.53687 -77.904086)
		(mid 43.47661 -77.758606)
		(end 43.33113 -77.698346)
		(stroke
			(width 0.2)
			(type default)
		)
		(layer "In6.Cu")
	)
	(gr_line
		(start 43.53687 -77.396086)
		(end 43.53687 -76.989686)
		(stroke
			(width 0.2)
			(type default)
		)
		(layer "In6.Cu")
	)
	(gr_arc
		(start 43.53687 -76.989686)
		(mid 43.47661 -76.844206)
		(end 43.33113 -76.783946)
		(stroke
			(width 0.2)
			(type default)
		)
		(layer "In6.Cu")
	)
	(gr_arc
		(start 44.11599 -78.310486)
		(mid 44.17625 -78.455966)
		(end 44.32173 -78.516226)
		(stroke
			(width 0.2)
			(type default)
		)
		(layer "In6.Cu")
	)
	(gr_line
		(start 44.11599 -77.904086)
		(end 44.11599 -78.310486)
		(stroke
			(width 0.2)
			(type default)
		)
		(layer "In6.Cu")
	)
	(gr_arc
		(start 44.11599 -77.396086)
		(mid 44.17625 -77.541566)
		(end 44.32173 -77.601826)
		(stroke
			(width 0.2)
			(type default)
		)
		(layer "In6.Cu")
	)
	(gr_line
		(start 44.11599 -76.989686)
		(end 44.11599 -77.396086)
		(stroke
			(width 0.2)
			(type default)
		)
		(layer "In6.Cu")
	)
	(gr_line
		(start 44.32173 -78.516226)
		(end 44.72813 -78.516226)
		(stroke
			(width 0.2)
			(type default)
		)
		(layer "In6.Cu")
	)
	(gr_arc
		(start 44.32173 -77.698346)
		(mid 44.17625 -77.758606)
		(end 44.11599 -77.904086)
		(stroke
			(width 0.2)
			(type default)
		)
		(layer "In6.Cu")
	)
	(gr_line
		(start 44.32173 -77.601826)
		(end 44.72813 -77.601826)
		(stroke
			(width 0.2)
			(type default)
		)
		(layer "In6.Cu")
	)
	(gr_arc
		(start 44.32173 -76.783946)
		(mid 44.17625 -76.844206)
		(end 44.11599 -76.989686)
		(stroke
			(width 0.2)
			(type default)
		)
		(layer "In6.Cu")
	)
	(gr_line
		(start 44.511468 -75.290426)
		(end 45.488098 -75.290426)
		(stroke
			(width 0.2)
			(type default)
		)
		(layer "In6.Cu")
	)
	(gr_arc
		(start 44.511468 -74.523346)
		(mid 44.127928 -74.906886)
		(end 44.511468 -75.290426)
		(stroke
			(width 0.2)
			(type default)
		)
		(layer "In6.Cu")
	)
	(gr_line
		(start 44.647104 -83.885786)
		(end 45.623734 -83.885786)
		(stroke
			(width 0.2)
			(type default)
		)
		(layer "In6.Cu")
	)
	(gr_arc
		(start 44.647104 -83.118706)
		(mid 44.263564 -83.502246)
		(end 44.647104 -83.885786)
		(stroke
			(width 0.2)
			(type default)
		)
		(layer "In6.Cu")
	)
	(gr_arc
		(start 44.72813 -78.516226)
		(mid 44.87361 -78.455966)
		(end 44.93387 -78.310486)
		(stroke
			(width 0.2)
			(type default)
		)
		(layer "In6.Cu")
	)
	(gr_line
		(start 44.72813 -77.698346)
		(end 44.32173 -77.698346)
		(stroke
			(width 0.2)
			(type default)
		)
		(layer "In6.Cu")
	)
	(gr_arc
		(start 44.72813 -77.601826)
		(mid 44.87361 -77.541566)
		(end 44.93387 -77.396086)
		(stroke
			(width 0.2)
			(type default)
		)
		(layer "In6.Cu")
	)
	(gr_line
		(start 44.72813 -76.783946)
		(end 44.32173 -76.783946)
		(stroke
			(width 0.2)
			(type default)
		)
		(layer "In6.Cu")
	)
	(gr_line
		(start 44.93387 -78.310486)
		(end 44.93387 -77.904086)
		(stroke
			(width 0.2)
			(type default)
		)
		(layer "In6.Cu")
	)
	(gr_arc
		(start 44.93387 -77.904086)
		(mid 44.87361 -77.758606)
		(end 44.72813 -77.698346)
		(stroke
			(width 0.2)
			(type default)
		)
		(layer "In6.Cu")
	)
	(gr_line
		(start 44.93387 -77.396086)
		(end 44.93387 -76.989686)
		(stroke
			(width 0.2)
			(type default)
		)
		(layer "In6.Cu")
	)
	(gr_arc
		(start 44.93387 -76.989686)
		(mid 44.87361 -76.844206)
		(end 44.72813 -76.783946)
		(stroke
			(width 0.2)
			(type default)
		)
		(layer "In6.Cu")
	)
	(gr_arc
		(start 45.13199 -78.310486)
		(mid 45.19225 -78.455966)
		(end 45.33773 -78.516226)
		(stroke
			(width 0.2)
			(type default)
		)
		(layer "In6.Cu")
	)
	(gr_line
		(start 45.13199 -77.904086)
		(end 45.13199 -78.310486)
		(stroke
			(width 0.2)
			(type default)
		)
		(layer "In6.Cu")
	)
	(gr_arc
		(start 45.13199 -77.396086)
		(mid 45.19225 -77.541566)
		(end 45.33773 -77.601826)
		(stroke
			(width 0.2)
			(type default)
		)
		(layer "In6.Cu")
	)
	(gr_line
		(start 45.13199 -76.989686)
		(end 45.13199 -77.396086)
		(stroke
			(width 0.2)
			(type default)
		)
		(layer "In6.Cu")
	)
	(gr_line
		(start 45.33773 -78.516226)
		(end 45.74413 -78.516226)
		(stroke
			(width 0.2)
			(type default)
		)
		(layer "In6.Cu")
	)
	(gr_arc
		(start 45.33773 -77.698346)
		(mid 45.19225 -77.758606)
		(end 45.13199 -77.904086)
		(stroke
			(width 0.2)
			(type default)
		)
		(layer "In6.Cu")
	)
	(gr_line
		(start 45.33773 -77.601826)
		(end 45.74413 -77.601826)
		(stroke
			(width 0.2)
			(type default)
		)
		(layer "In6.Cu")
	)
	(gr_arc
		(start 45.33773 -76.783946)
		(mid 45.19225 -76.844206)
		(end 45.13199 -76.989686)
		(stroke
			(width 0.2)
			(type default)
		)
		(layer "In6.Cu")
	)
	(gr_arc
		(start 45.488098 -75.290426)
		(mid 45.871892 -74.907013)
		(end 45.488352 -74.523346)
		(stroke
			(width 0.2)
			(type default)
		)
		(layer "In6.Cu")
	)
	(gr_line
		(start 45.488352 -74.523346)
		(end 44.511468 -74.523346)
		(stroke
			(width 0.2)
			(type default)
		)
		(layer "In6.Cu")
	)
	(gr_arc
		(start 45.623734 -83.885786)
		(mid 46.007528 -83.502373)
		(end 45.623988 -83.118706)
		(stroke
			(width 0.2)
			(type default)
		)
		(layer "In6.Cu")
	)
	(gr_line
		(start 45.623988 -83.118706)
		(end 44.647104 -83.118706)
		(stroke
			(width 0.2)
			(type default)
		)
		(layer "In6.Cu")
	)
	(gr_arc
		(start 45.74413 -78.516226)
		(mid 45.88961 -78.455966)
		(end 45.94987 -78.310486)
		(stroke
			(width 0.2)
			(type default)
		)
		(layer "In6.Cu")
	)
	(gr_line
		(start 45.74413 -77.698346)
		(end 45.33773 -77.698346)
		(stroke
			(width 0.2)
			(type default)
		)
		(layer "In6.Cu")
	)
	(gr_arc
		(start 45.74413 -77.601826)
		(mid 45.88961 -77.541566)
		(end 45.94987 -77.396086)
		(stroke
			(width 0.2)
			(type default)
		)
		(layer "In6.Cu")
	)
	(gr_line
		(start 45.74413 -76.783946)
		(end 45.33773 -76.783946)
		(stroke
			(width 0.2)
			(type default)
		)
		(layer "In6.Cu")
	)
	(gr_line
		(start 45.94987 -78.310486)
		(end 45.94987 -77.904086)
		(stroke
			(width 0.2)
			(type default)
		)
		(layer "In6.Cu")
	)
	(gr_arc
		(start 45.94987 -77.904086)
		(mid 45.88961 -77.758606)
		(end 45.74413 -77.698346)
		(stroke
			(width 0.2)
			(type default)
		)
		(layer "In6.Cu")
	)
	(gr_line
		(start 45.94987 -77.396086)
		(end 45.94987 -76.989686)
		(stroke
			(width 0.2)
			(type default)
		)
		(layer "In6.Cu")
	)
	(gr_arc
		(start 45.94987 -76.989686)
		(mid 45.88961 -76.844206)
		(end 45.74413 -76.783946)
		(stroke
			(width 0.2)
			(type default)
		)
		(layer "In6.Cu")
	)
	(gr_line
		(start 47.649892 -258.59994)
		(end 36.450016 -258.59994)
		(stroke
			(width 5.08)
			(type default)
		)
		(layer "In6.Cu")
	)
	(gr_line
		(start 47.649892 -252.000004)
		(end 47.649892 -258.59994)
		(stroke
			(width 1.524)
			(type default)
		)
		(layer "In6.Cu")
	)
	(gr_arc
		(start 48.606456 -87.746078)
		(mid 48.989996 -88.129618)
		(end 49.373536 -87.746078)
		(stroke
			(width 0.2)
			(type default)
		)
		(layer "In6.Cu")
	)
	(gr_line
		(start 48.606456 -86.769194)
		(end 48.606456 -87.746078)
		(stroke
			(width 0.2)
			(type default)
		)
		(layer "In6.Cu")
	)
	(gr_arc
		(start 48.606456 -84.913724)
		(mid 48.989869 -85.297518)
		(end 49.373536 -84.913978)
		(stroke
			(width 0.2)
			(type default)
		)
		(layer "In6.Cu")
	)
	(gr_line
		(start 48.606456 -83.937094)
		(end 48.606456 -84.913724)
		(stroke
			(width 0.2)
			(type default)
		)
		(layer "In6.Cu")
	)
	(gr_arc
		(start 48.64989 -251.000006)
		(mid 47.942785 -251.292899)
		(end 47.649892 -252.000004)
		(stroke
			(width 1.524)
			(type default)
		)
		(layer "In6.Cu")
	)
	(gr_line
		(start 49.373536 -87.746078)
		(end 49.373536 -86.769448)
		(stroke
			(width 0.2)
			(type default)
		)
		(layer "In6.Cu")
	)
	(gr_arc
		(start 49.373536 -86.769448)
		(mid 48.990123 -86.385654)
		(end 48.606456 -86.769194)
		(stroke
			(width 0.2)
			(type default)
		)
		(layer "In6.Cu")
	)
	(gr_line
		(start 49.373536 -84.913978)
		(end 49.373536 -83.937094)
		(stroke
			(width 0.2)
			(type default)
		)
		(layer "In6.Cu")
	)
	(gr_arc
		(start 49.373536 -83.937094)
		(mid 48.989996 -83.553554)
		(end 48.606456 -83.937094)
		(stroke
			(width 0.2)
			(type default)
		)
		(layer "In6.Cu")
	)
	(gr_arc
		(start 50.46599 -77.421486)
		(mid 50.52625 -77.566966)
		(end 50.67173 -77.627226)
		(stroke
			(width 0.2)
			(type default)
		)
		(layer "In6.Cu")
	)
	(gr_line
		(start 50.46599 -77.015086)
		(end 50.46599 -77.421486)
		(stroke
			(width 0.2)
			(type default)
		)
		(layer "In6.Cu")
	)
	(gr_arc
		(start 50.46599 -76.507086)
		(mid 50.52625 -76.652566)
		(end 50.67173 -76.712826)
		(stroke
			(width 0.2)
			(type default)
		)
		(layer "In6.Cu")
	)
	(gr_line
		(start 50.46599 -76.100686)
		(end 50.46599 -76.507086)
		(stroke
			(width 0.2)
			(type default)
		)
		(layer "In6.Cu")
	)
	(gr_line
		(start 50.67173 -77.627226)
		(end 51.07813 -77.627226)
		(stroke
			(width 0.2)
			(type default)
		)
		(layer "In6.Cu")
	)
	(gr_arc
		(start 50.67173 -76.809346)
		(mid 50.52625 -76.869606)
		(end 50.46599 -77.015086)
		(stroke
			(width 0.2)
			(type default)
		)
		(layer "In6.Cu")
	)
	(gr_line
		(start 50.67173 -76.712826)
		(end 51.07813 -76.712826)
		(stroke
			(width 0.2)
			(type default)
		)
		(layer "In6.Cu")
	)
	(gr_arc
		(start 50.67173 -75.894946)
		(mid 50.52625 -75.955206)
		(end 50.46599 -76.100686)
		(stroke
			(width 0.2)
			(type default)
		)
		(layer "In6.Cu")
	)
	(gr_line
		(start 50.911506 -75.290426)
		(end 51.888136 -75.290426)
		(stroke
			(width 0.2)
			(type default)
		)
		(layer "In6.Cu")
	)
	(gr_arc
		(start 50.911506 -74.523346)
		(mid 50.527966 -74.906886)
		(end 50.911506 -75.290426)
		(stroke
			(width 0.2)
			(type default)
		)
		(layer "In6.Cu")
	)
	(gr_arc
		(start 51.07813 -77.627226)
		(mid 51.22361 -77.566966)
		(end 51.28387 -77.421486)
		(stroke
			(width 0.2)
			(type default)
		)
		(layer "In6.Cu")
	)
	(gr_line
		(start 51.07813 -76.809346)
		(end 50.67173 -76.809346)
		(stroke
			(width 0.2)
			(type default)
		)
		(layer "In6.Cu")
	)
	(gr_arc
		(start 51.07813 -76.712826)
		(mid 51.22361 -76.652566)
		(end 51.28387 -76.507086)
		(stroke
			(width 0.2)
			(type default)
		)
		(layer "In6.Cu")
	)
	(gr_line
		(start 51.07813 -75.894946)
		(end 50.67173 -75.894946)
		(stroke
			(width 0.2)
			(type default)
		)
		(layer "In6.Cu")
	)
	(gr_line
		(start 51.28387 -77.421486)
		(end 51.28387 -77.015086)
		(stroke
			(width 0.2)
			(type default)
		)
		(layer "In6.Cu")
	)
	(gr_arc
		(start 51.28387 -77.015086)
		(mid 51.22361 -76.869606)
		(end 51.07813 -76.809346)
		(stroke
			(width 0.2)
			(type default)
		)
		(layer "In6.Cu")
	)
	(gr_line
		(start 51.28387 -76.507086)
		(end 51.28387 -76.100686)
		(stroke
			(width 0.2)
			(type default)
		)
		(layer "In6.Cu")
	)
	(gr_arc
		(start 51.28387 -76.100686)
		(mid 51.22361 -75.955206)
		(end 51.07813 -75.894946)
		(stroke
			(width 0.2)
			(type default)
		)
		(layer "In6.Cu")
	)
	(gr_arc
		(start 51.35499 -77.421486)
		(mid 51.41525 -77.566966)
		(end 51.56073 -77.627226)
		(stroke
			(width 0.2)
			(type default)
		)
		(layer "In6.Cu")
	)
	(gr_line
		(start 51.35499 -77.015086)
		(end 51.35499 -77.421486)
		(stroke
			(width 0.2)
			(type default)
		)
		(layer "In6.Cu")
	)
	(gr_arc
		(start 51.35499 -76.507086)
		(mid 51.41525 -76.652566)
		(end 51.56073 -76.712826)
		(stroke
			(width 0.2)
			(type default)
		)
		(layer "In6.Cu")
	)
	(gr_line
		(start 51.35499 -76.100686)
		(end 51.35499 -76.507086)
		(stroke
			(width 0.2)
			(type default)
		)
		(layer "In6.Cu")
	)
	(gr_line
		(start 51.56073 -77.627226)
		(end 51.96713 -77.627226)
		(stroke
			(width 0.2)
			(type default)
		)
		(layer "In6.Cu")
	)
	(gr_arc
		(start 51.56073 -76.809346)
		(mid 51.41525 -76.869606)
		(end 51.35499 -77.015086)
		(stroke
			(width 0.2)
			(type default)
		)
		(layer "In6.Cu")
	)
	(gr_line
		(start 51.56073 -76.712826)
		(end 51.96713 -76.712826)
		(stroke
			(width 0.2)
			(type default)
		)
		(layer "In6.Cu")
	)
	(gr_arc
		(start 51.56073 -75.894946)
		(mid 51.41525 -75.955206)
		(end 51.35499 -76.100686)
		(stroke
			(width 0.2)
			(type default)
		)
		(layer "In6.Cu")
	)
	(gr_arc
		(start 51.888136 -75.290426)
		(mid 52.27193 -74.907013)
		(end 51.88839 -74.523346)
		(stroke
			(width 0.2)
			(type default)
		)
		(layer "In6.Cu")
	)
	(gr_line
		(start 51.88839 -74.523346)
		(end 50.911506 -74.523346)
		(stroke
			(width 0.2)
			(type default)
		)
		(layer "In6.Cu")
	)
	(gr_arc
		(start 51.96713 -77.627226)
		(mid 52.11261 -77.566966)
		(end 52.17287 -77.421486)
		(stroke
			(width 0.2)
			(type default)
		)
		(layer "In6.Cu")
	)
	(gr_line
		(start 51.96713 -76.809346)
		(end 51.56073 -76.809346)
		(stroke
			(width 0.2)
			(type default)
		)
		(layer "In6.Cu")
	)
	(gr_arc
		(start 51.96713 -76.712826)
		(mid 52.11261 -76.652566)
		(end 52.17287 -76.507086)
		(stroke
			(width 0.2)
			(type default)
		)
		(layer "In6.Cu")
	)
	(gr_line
		(start 51.96713 -75.894946)
		(end 51.56073 -75.894946)
		(stroke
			(width 0.2)
			(type default)
		)
		(layer "In6.Cu")
	)
	(gr_line
		(start 52.17287 -77.421486)
		(end 52.17287 -77.015086)
		(stroke
			(width 0.2)
			(type default)
		)
		(layer "In6.Cu")
	)
	(gr_arc
		(start 52.17287 -77.015086)
		(mid 52.11261 -76.869606)
		(end 51.96713 -76.809346)
		(stroke
			(width 0.2)
			(type default)
		)
		(layer "In6.Cu")
	)
	(gr_line
		(start 52.17287 -76.507086)
		(end 52.17287 -76.100686)
		(stroke
			(width 0.2)
			(type default)
		)
		(layer "In6.Cu")
	)
	(gr_arc
		(start 52.17287 -76.100686)
		(mid 52.11261 -75.955206)
		(end 51.96713 -75.894946)
		(stroke
			(width 0.2)
			(type default)
		)
		(layer "In6.Cu")
	)
	(gr_arc
		(start 52.87899 -77.421486)
		(mid 52.93925 -77.566966)
		(end 53.08473 -77.627226)
		(stroke
			(width 0.2)
			(type default)
		)
		(layer "In6.Cu")
	)
	(gr_line
		(start 52.87899 -77.015086)
		(end 52.87899 -77.421486)
		(stroke
			(width 0.2)
			(type default)
		)
		(layer "In6.Cu")
	)
	(gr_arc
		(start 52.87899 -76.507086)
		(mid 52.93925 -76.652566)
		(end 53.08473 -76.712826)
		(stroke
			(width 0.2)
			(type default)
		)
		(layer "In6.Cu")
	)
	(gr_line
		(start 52.87899 -76.100686)
		(end 52.87899 -76.507086)
		(stroke
			(width 0.2)
			(type default)
		)
		(layer "In6.Cu")
	)
	(gr_line
		(start 53.08473 -77.627226)
		(end 53.49113 -77.627226)
		(stroke
			(width 0.2)
			(type default)
		)
		(layer "In6.Cu")
	)
	(gr_arc
		(start 53.08473 -76.809346)
		(mid 52.93925 -76.869606)
		(end 52.87899 -77.015086)
		(stroke
			(width 0.2)
			(type default)
		)
		(layer "In6.Cu")
	)
	(gr_line
		(start 53.08473 -76.712826)
		(end 53.49113 -76.712826)
		(stroke
			(width 0.2)
			(type default)
		)
		(layer "In6.Cu")
	)
	(gr_arc
		(start 53.08473 -75.894946)
		(mid 52.93925 -75.955206)
		(end 52.87899 -76.100686)
		(stroke
			(width 0.2)
			(type default)
		)
		(layer "In6.Cu")
	)
	(gr_line
		(start 53.311298 -75.290426)
		(end 54.287928 -75.290426)
		(stroke
			(width 0.2)
			(type default)
		)
		(layer "In6.Cu")
	)
	(gr_arc
		(start 53.311298 -74.523346)
		(mid 52.927758 -74.906886)
		(end 53.311298 -75.290426)
		(stroke
			(width 0.2)
			(type default)
		)
		(layer "In6.Cu")
	)
	(gr_arc
		(start 53.49113 -77.627226)
		(mid 53.63661 -77.566966)
		(end 53.69687 -77.421486)
		(stroke
			(width 0.2)
			(type default)
		)
		(layer "In6.Cu")
	)
	(gr_line
		(start 53.49113 -76.809346)
		(end 53.08473 -76.809346)
		(stroke
			(width 0.2)
			(type default)
		)
		(layer "In6.Cu")
	)
	(gr_arc
		(start 53.49113 -76.712826)
		(mid 53.63661 -76.652566)
		(end 53.69687 -76.507086)
		(stroke
			(width 0.2)
			(type default)
		)
		(layer "In6.Cu")
	)
	(gr_line
		(start 53.49113 -75.894946)
		(end 53.08473 -75.894946)
		(stroke
			(width 0.2)
			(type default)
		)
		(layer "In6.Cu")
	)
	(gr_line
		(start 53.69687 -77.421486)
		(end 53.69687 -77.015086)
		(stroke
			(width 0.2)
			(type default)
		)
		(layer "In6.Cu")
	)
	(gr_arc
		(start 53.69687 -77.015086)
		(mid 53.63661 -76.869606)
		(end 53.49113 -76.809346)
		(stroke
			(width 0.2)
			(type default)
		)
		(layer "In6.Cu")
	)
	(gr_line
		(start 53.69687 -76.507086)
		(end 53.69687 -76.100686)
		(stroke
			(width 0.2)
			(type default)
		)
		(layer "In6.Cu")
	)
	(gr_arc
		(start 53.69687 -76.100686)
		(mid 53.63661 -75.955206)
		(end 53.49113 -75.894946)
		(stroke
			(width 0.2)
			(type default)
		)
		(layer "In6.Cu")
	)
	(gr_arc
		(start 53.89499 -77.421486)
		(mid 53.95525 -77.566966)
		(end 54.10073 -77.627226)
		(stroke
			(width 0.2)
			(type default)
		)
		(layer "In6.Cu")
	)
	(gr_line
		(start 53.89499 -77.015086)
		(end 53.89499 -77.421486)
		(stroke
			(width 0.2)
			(type default)
		)
		(layer "In6.Cu")
	)
	(gr_arc
		(start 53.89499 -76.507086)
		(mid 53.95525 -76.652566)
		(end 54.10073 -76.712826)
		(stroke
			(width 0.2)
			(type default)
		)
		(layer "In6.Cu")
	)
	(gr_line
		(start 53.89499 -76.100686)
		(end 53.89499 -76.507086)
		(stroke
			(width 0.2)
			(type default)
		)
		(layer "In6.Cu")
	)
	(gr_line
		(start 54.10073 -77.627226)
		(end 54.50713 -77.627226)
		(stroke
			(width 0.2)
			(type default)
		)
		(layer "In6.Cu")
	)
	(gr_arc
		(start 54.10073 -76.809346)
		(mid 53.95525 -76.869606)
		(end 53.89499 -77.015086)
		(stroke
			(width 0.2)
			(type default)
		)
		(layer "In6.Cu")
	)
	(gr_line
		(start 54.10073 -76.712826)
		(end 54.50713 -76.712826)
		(stroke
			(width 0.2)
			(type default)
		)
		(layer "In6.Cu")
	)
	(gr_arc
		(start 54.10073 -75.894946)
		(mid 53.95525 -75.955206)
		(end 53.89499 -76.100686)
		(stroke
			(width 0.2)
			(type default)
		)
		(layer "In6.Cu")
	)
	(gr_arc
		(start 54.287928 -75.290426)
		(mid 54.671722 -74.907013)
		(end 54.288182 -74.523346)
		(stroke
			(width 0.2)
			(type default)
		)
		(layer "In6.Cu")
	)
	(gr_line
		(start 54.288182 -74.523346)
		(end 53.311298 -74.523346)
		(stroke
			(width 0.2)
			(type default)
		)
		(layer "In6.Cu")
	)
	(gr_arc
		(start 54.50713 -77.627226)
		(mid 54.65261 -77.566966)
		(end 54.71287 -77.421486)
		(stroke
			(width 0.2)
			(type default)
		)
		(layer "In6.Cu")
	)
	(gr_line
		(start 54.50713 -76.809346)
		(end 54.10073 -76.809346)
		(stroke
			(width 0.2)
			(type default)
		)
		(layer "In6.Cu")
	)
	(gr_arc
		(start 54.50713 -76.712826)
		(mid 54.65261 -76.652566)
		(end 54.71287 -76.507086)
		(stroke
			(width 0.2)
			(type default)
		)
		(layer "In6.Cu")
	)
	(gr_line
		(start 54.50713 -75.894946)
		(end 54.10073 -75.894946)
		(stroke
			(width 0.2)
			(type default)
		)
		(layer "In6.Cu")
	)
	(gr_line
		(start 54.71287 -77.421486)
		(end 54.71287 -77.015086)
		(stroke
			(width 0.2)
			(type default)
		)
		(layer "In6.Cu")
	)
	(gr_arc
		(start 54.71287 -77.015086)
		(mid 54.65261 -76.869606)
		(end 54.50713 -76.809346)
		(stroke
			(width 0.2)
			(type default)
		)
		(layer "In6.Cu")
	)
	(gr_line
		(start 54.71287 -76.507086)
		(end 54.71287 -76.100686)
		(stroke
			(width 0.2)
			(type default)
		)
		(layer "In6.Cu")
	)
	(gr_arc
		(start 54.71287 -76.100686)
		(mid 54.65261 -75.955206)
		(end 54.50713 -75.894946)
		(stroke
			(width 0.2)
			(type default)
		)
		(layer "In6.Cu")
	)
	(gr_arc
		(start 60.950094 -58.010044)
		(mid 61.657199 -57.717151)
		(end 61.950092 -57.010046)
		(stroke
			(width 1.524)
			(type default)
		)
		(layer "In6.Cu")
	)
	(gr_line
		(start 61.950092 -57.010046)
		(end 61.950092 -17.999964)
		(stroke
			(width 1.524)
			(type default)
		)
		(layer "In6.Cu")
	)
	(gr_arc
		(start 62.95009 -16.999966)
		(mid 62.242978 -17.29286)
		(end 61.950092 -17.999964)
		(stroke
			(width 1.524)
			(type default)
		)
		(layer "In6.Cu")
	)
	(gr_line
		(start 62.95009 -16.999966)
		(end 73.449942 -16.999966)
		(stroke
			(width 1.524)
			(type default)
		)
		(layer "In6.Cu")
	)
	(gr_line
		(start 66.34988 -251.000006)
		(end 48.64989 -251.000006)
		(stroke
			(width 1.524)
			(type default)
		)
		(layer "In6.Cu")
	)
	(gr_rect
		(start 67.1322 -254.4064)
		(end 151.4602 -258.5974)
		(stroke
			(width 0)
			(type default)
		)
		(fill no)
		(layer "In6.Cu")
	)
	(gr_line
		(start 67.349878 -258.59994)
		(end 67.349878 -252.000004)
		(stroke
			(width 1.524)
			(type default)
		)
		(layer "In6.Cu")
	)
	(gr_arc
		(start 67.349878 -252.000004)
		(mid 67.056985 -251.292899)
		(end 66.34988 -251.000006)
		(stroke
			(width 1.524)
			(type default)
		)
		(layer "In6.Cu")
	)
	(gr_arc
		(start 73.449942 -16.999966)
		(mid 74.157047 -16.707073)
		(end 74.44994 -15.999968)
		(stroke
			(width 1.524)
			(type default)
		)
		(layer "In6.Cu")
	)
	(gr_line
		(start 74.44994 -15.999968)
		(end 74.44994 -0.999998)
		(stroke
			(width 1.524)
			(type default)
		)
		(layer "In6.Cu")
	)
	(gr_arc
		(start 75.449938 0)
		(mid 74.742807 -0.292879)
		(end 74.44994 -0.999998)
		(stroke
			(width 1.524)
			(type default)
		)
		(layer "In6.Cu")
	)
	(gr_line
		(start 75.449938 0)
		(end 281.485086 0)
		(stroke
			(width 1.524)
			(type default)
		)
		(layer "In6.Cu")
	)
	(gr_line
		(start 76.157074 -37.042852)
		(end 77.133958 -37.042852)
		(stroke
			(width 0.2)
			(type default)
		)
		(layer "In6.Cu")
	)
	(gr_arc
		(start 76.157328 -36.275772)
		(mid 75.773534 -36.659185)
		(end 76.157074 -37.042852)
		(stroke
			(width 0.2)
			(type default)
		)
		(layer "In6.Cu")
	)
	(gr_arc
		(start 77.133958 -37.042852)
		(mid 77.517498 -36.659312)
		(end 77.133958 -36.275772)
		(stroke
			(width 0.2)
			(type default)
		)
		(layer "In6.Cu")
	)
	(gr_line
		(start 77.133958 -36.275772)
		(end 76.157328 -36.275772)
		(stroke
			(width 0.2)
			(type default)
		)
		(layer "In6.Cu")
	)
	(gr_line
		(start 77.686408 -41.98874)
		(end 78.663038 -41.98874)
		(stroke
			(width 0.2)
			(type default)
		)
		(layer "In6.Cu")
	)
	(gr_arc
		(start 77.686408 -41.22166)
		(mid 77.302868 -41.6052)
		(end 77.686408 -41.98874)
		(stroke
			(width 0.2)
			(type default)
		)
		(layer "In6.Cu")
	)
	(gr_arc
		(start 78.663038 -41.98874)
		(mid 79.046832 -41.605327)
		(end 78.663292 -41.22166)
		(stroke
			(width 0.2)
			(type default)
		)
		(layer "In6.Cu")
	)
	(gr_line
		(start 78.663292 -41.22166)
		(end 77.686408 -41.22166)
		(stroke
			(width 0.2)
			(type default)
		)
		(layer "In6.Cu")
	)
	(gr_line
		(start 79.604108 -40.00754)
		(end 80.580738 -40.00754)
		(stroke
			(width 0.2)
			(type default)
		)
		(layer "In6.Cu")
	)
	(gr_arc
		(start 79.604108 -39.24046)
		(mid 79.220568 -39.624)
		(end 79.604108 -40.00754)
		(stroke
			(width 0.2)
			(type default)
		)
		(layer "In6.Cu")
	)
	(gr_arc
		(start 80.580738 -40.00754)
		(mid 80.964532 -39.624127)
		(end 80.580992 -39.24046)
		(stroke
			(width 0.2)
			(type default)
		)
		(layer "In6.Cu")
	)
	(gr_line
		(start 80.580992 -39.24046)
		(end 79.604108 -39.24046)
		(stroke
			(width 0.2)
			(type default)
		)
		(layer "In6.Cu")
	)
	(gr_arc
		(start 80.84566 -37.312092)
		(mid 81.2292 -37.695632)
		(end 81.61274 -37.312092)
		(stroke
			(width 0.2)
			(type default)
		)
		(layer "In6.Cu")
	)
	(gr_line
		(start 80.84566 -36.335208)
		(end 80.84566 -37.312092)
		(stroke
			(width 0.2)
			(type default)
		)
		(layer "In6.Cu")
	)
	(gr_line
		(start 81.61274 -37.312092)
		(end 81.61274 -36.335462)
		(stroke
			(width 0.2)
			(type default)
		)
		(layer "In6.Cu")
	)
	(gr_arc
		(start 81.61274 -36.335462)
		(mid 81.229327 -35.951668)
		(end 80.84566 -36.335208)
		(stroke
			(width 0.2)
			(type default)
		)
		(layer "In6.Cu")
	)
	(gr_arc
		(start 82.527648 -38.736524)
		(mid 82.911061 -39.120318)
		(end 83.294728 -38.736778)
		(stroke
			(width 0.2)
			(type default)
		)
		(layer "In6.Cu")
	)
	(gr_line
		(start 82.527648 -37.831776)
		(end 82.527648 -38.736524)
		(stroke
			(width 0.2)
			(type default)
		)
		(layer "In6.Cu")
	)
	(gr_arc
		(start 82.69986 -35.523678)
		(mid 83.0834 -35.907218)
		(end 83.46694 -35.523678)
		(stroke
			(width 0.2)
			(type default)
		)
		(layer "In6.Cu")
	)
	(gr_line
		(start 82.69986 -34.618676)
		(end 82.69986 -35.523678)
		(stroke
			(width 0.2)
			(type default)
		)
		(layer "In6.Cu")
	)
	(gr_line
		(start 83.294728 -38.736778)
		(end 83.294728 -37.831776)
		(stroke
			(width 0.2)
			(type default)
		)
		(layer "In6.Cu")
	)
	(gr_arc
		(start 83.294728 -37.831776)
		(mid 82.911188 -37.448236)
		(end 82.527648 -37.831776)
		(stroke
			(width 0.2)
			(type default)
		)
		(layer "In6.Cu")
	)
	(gr_line
		(start 83.46694 -35.523678)
		(end 83.46694 -34.61893)
		(stroke
			(width 0.2)
			(type default)
		)
		(layer "In6.Cu")
	)
	(gr_arc
		(start 83.46694 -34.61893)
		(mid 83.083527 -34.235136)
		(end 82.69986 -34.618676)
		(stroke
			(width 0.2)
			(type default)
		)
		(layer "In6.Cu")
	)
	(gr_line
		(start 83.69554 -37.754306)
		(end 83.723734 -38.770306)
		(stroke
			(width 0.2)
			(type default)
		)
		(layer "In6.Cu")
	)
	(gr_line
		(start 83.69808 -37.754306)
		(end 83.69554 -37.754306)
		(stroke
			(width 0.2)
			(type default)
		)
		(layer "In6.Cu")
	)
	(gr_line
		(start 83.723734 -38.770306)
		(end 83.723988 -38.77056)
		(stroke
			(width 0.2)
			(type default)
		)
		(layer "In6.Cu")
	)
	(gr_line
		(start 83.723988 -38.77056)
		(end 83.726274 -38.77056)
		(stroke
			(width 0.2)
			(type default)
		)
		(layer "In6.Cu")
	)
	(gr_arc
		(start 83.726274 -38.77056)
		(mid 84.094066 -39.11854)
		(end 84.442046 -38.750748)
		(stroke
			(width 0.2)
			(type default)
		)
		(layer "In6.Cu")
	)
	(gr_arc
		(start 84.413852 -37.734494)
		(mid 84.04606 -37.386514)
		(end 83.69808 -37.754306)
		(stroke
			(width 0.2)
			(type default)
		)
		(layer "In6.Cu")
	)
	(gr_line
		(start 84.416392 -37.734494)
		(end 84.413852 -37.734494)
		(stroke
			(width 0.2)
			(type default)
		)
		(layer "In6.Cu")
	)
	(gr_line
		(start 84.442046 -38.750748)
		(end 84.444586 -38.750748)
		(stroke
			(width 0.2)
			(type default)
		)
		(layer "In6.Cu")
	)
	(gr_line
		(start 84.444586 -38.750748)
		(end 84.416392 -37.734494)
		(stroke
			(width 0.2)
			(type default)
		)
		(layer "In6.Cu")
	)
	(gr_arc
		(start 84.60486 -33.789874)
		(mid 84.9884 -34.173414)
		(end 85.37194 -33.789874)
		(stroke
			(width 0.2)
			(type default)
		)
		(layer "In6.Cu")
	)
	(gr_line
		(start 84.60486 -32.884872)
		(end 84.60486 -33.789874)
		(stroke
			(width 0.2)
			(type default)
		)
		(layer "In6.Cu")
	)
	(gr_line
		(start 85.37194 -33.789874)
		(end 85.37194 -32.885126)
		(stroke
			(width 0.2)
			(type default)
		)
		(layer "In6.Cu")
	)
	(gr_arc
		(start 85.37194 -32.885126)
		(mid 84.988527 -32.501332)
		(end 84.60486 -32.884872)
		(stroke
			(width 0.2)
			(type default)
		)
		(layer "In6.Cu")
	)
	(gr_line
		(start 92.744798 -39.75354)
		(end 93.55582 -39.755318)
		(stroke
			(width 0.2)
			(type default)
		)
		(layer "In6.Cu")
	)
	(gr_line
		(start 92.746576 -42.154856)
		(end 93.550994 -42.16273)
		(stroke
			(width 0.2)
			(type default)
		)
		(layer "In6.Cu")
	)
	(gr_arc
		(start 92.746576 -39.03726)
		(mid 92.387674 -39.394511)
		(end 92.744798 -39.75354)
		(stroke
			(width 0.2)
			(type default)
		)
		(layer "In6.Cu")
	)
	(gr_arc
		(start 92.753942 -41.438576)
		(mid 92.392247 -41.793033)
		(end 92.746576 -42.154856)
		(stroke
			(width 0.2)
			(type default)
		)
		(layer "In6.Cu")
	)
	(gr_arc
		(start 93.09862 -32.0294)
		(mid 93.144001 -32.138959)
		(end 93.25356 -32.18434)
		(stroke
			(width 0.2)
			(type default)
		)
		(layer "In6.Cu")
	)
	(gr_line
		(start 93.09862 -31.7754)
		(end 93.09862 -32.0294)
		(stroke
			(width 0.2)
			(type default)
		)
		(layer "In6.Cu")
	)
	(gr_arc
		(start 93.09862 -31.4706)
		(mid 93.144001 -31.580159)
		(end 93.25356 -31.62554)
		(stroke
			(width 0.2)
			(type default)
		)
		(layer "In6.Cu")
	)
	(gr_line
		(start 93.09862 -31.2166)
		(end 93.09862 -31.4706)
		(stroke
			(width 0.2)
			(type default)
		)
		(layer "In6.Cu")
	)
	(gr_line
		(start 93.182694 -40.206422)
		(end 93.196664 -41.001696)
		(stroke
			(width 0.2)
			(type default)
		)
		(layer "In6.Cu")
	)
	(gr_line
		(start 93.19133 -35.40887)
		(end 93.193616 -36.197032)
		(stroke
			(width 0.2)
			(type default)
		)
		(layer "In6.Cu")
	)
	(gr_arc
		(start 93.192346 -43.387772)
		(mid 93.547565 -43.748961)
		(end 93.908626 -43.393614)
		(stroke
			(width 0.2)
			(type default)
		)
		(layer "In6.Cu")
	)
	(gr_arc
		(start 93.193616 -36.197032)
		(mid 93.552645 -36.55441)
		(end 93.909896 -36.195254)
		(stroke
			(width 0.2)
			(type default)
		)
		(layer "In6.Cu")
	)
	(gr_arc
		(start 93.196664 -41.001696)
		(mid 93.561027 -41.353738)
		(end 93.912944 -40.98925)
		(stroke
			(width 0.2)
			(type default)
		)
		(layer "In6.Cu")
	)
	(gr_arc
		(start 93.197426 -38.596316)
		(mid 93.555058 -38.954964)
		(end 93.913706 -38.597332)
		(stroke
			(width 0.2)
			(type default)
		)
		(layer "In6.Cu")
	)
	(gr_line
		(start 93.198442 -37.80155)
		(end 93.197426 -38.596316)
		(stroke
			(width 0.2)
			(type default)
		)
		(layer "In6.Cu")
	)
	(gr_line
		(start 93.198696 -42.59453)
		(end 93.192346 -43.387772)
		(stroke
			(width 0.2)
			(type default)
		)
		(layer "In6.Cu")
	)
	(gr_line
		(start 93.25356 -32.18434)
		(end 93.45676 -32.18434)
		(stroke
			(width 0.2)
			(type default)
		)
		(layer "In6.Cu")
	)
	(gr_line
		(start 93.25356 -31.62554)
		(end 93.45676 -31.62554)
		(stroke
			(width 0.2)
			(type default)
		)
		(layer "In6.Cu")
	)
	(gr_arc
		(start 93.25356 -31.62046)
		(mid 93.144001 -31.665841)
		(end 93.09862 -31.7754)
		(stroke
			(width 0.2)
			(type default)
		)
		(layer "In6.Cu")
	)
	(gr_arc
		(start 93.25356 -31.06166)
		(mid 93.144001 -31.107041)
		(end 93.09862 -31.2166)
		(stroke
			(width 0.2)
			(type default)
		)
		(layer "In6.Cu")
	)
	(gr_arc
		(start 93.45676 -32.18434)
		(mid 93.566319 -32.138959)
		(end 93.6117 -32.0294)
		(stroke
			(width 0.2)
			(type default)
		)
		(layer "In6.Cu")
	)
	(gr_arc
		(start 93.45676 -31.62554)
		(mid 93.566319 -31.580159)
		(end 93.6117 -31.4706)
		(stroke
			(width 0.2)
			(type default)
		)
		(layer "In6.Cu")
	)
	(gr_line
		(start 93.45676 -31.62046)
		(end 93.25356 -31.62046)
		(stroke
			(width 0.2)
			(type default)
		)
		(layer "In6.Cu")
	)
	(gr_line
		(start 93.45676 -31.06166)
		(end 93.25356 -31.06166)
		(stroke
			(width 0.2)
			(type default)
		)
		(layer "In6.Cu")
	)
	(gr_arc
		(start 93.544644 -34.248344)
		(mid 93.189297 -34.609151)
		(end 93.549978 -34.964624)
		(stroke
			(width 0.2)
			(type default)
		)
		(layer "In6.Cu")
	)
	(gr_line
		(start 93.549978 -34.964624)
		(end 94.352618 -34.958274)
		(stroke
			(width 0.2)
			(type default)
		)
		(layer "In6.Cu")
	)
	(gr_arc
		(start 93.550232 -36.64458)
		(mid 93.193616 -37.004244)
		(end 93.55328 -37.36086)
		(stroke
			(width 0.2)
			(type default)
		)
		(layer "In6.Cu")
	)
	(gr_arc
		(start 93.550994 -42.16273)
		(mid 93.91269 -41.808146)
		(end 93.558106 -41.44645)
		(stroke
			(width 0.2)
			(type default)
		)
		(layer "In6.Cu")
	)
	(gr_line
		(start 93.55328 -37.36086)
		(end 94.360492 -37.357558)
		(stroke
			(width 0.2)
			(type default)
		)
		(layer "In6.Cu")
	)
	(gr_arc
		(start 93.55582 -39.755318)
		(mid 93.914722 -39.39794)
		(end 93.557344 -39.039038)
		(stroke
			(width 0.2)
			(type default)
		)
		(layer "In6.Cu")
	)
	(gr_line
		(start 93.557344 -39.039038)
		(end 92.746576 -39.03726)
		(stroke
			(width 0.2)
			(type default)
		)
		(layer "In6.Cu")
	)
	(gr_line
		(start 93.558106 -41.44645)
		(end 92.753942 -41.438576)
		(stroke
			(width 0.2)
			(type default)
		)
		(layer "In6.Cu")
	)
	(gr_line
		(start 93.6117 -32.0294)
		(end 93.6117 -31.7754)
		(stroke
			(width 0.2)
			(type default)
		)
		(layer "In6.Cu")
	)
	(gr_arc
		(start 93.6117 -31.7754)
		(mid 93.566319 -31.665841)
		(end 93.45676 -31.62046)
		(stroke
			(width 0.2)
			(type default)
		)
		(layer "In6.Cu")
	)
	(gr_line
		(start 93.6117 -31.4706)
		(end 93.6117 -31.2166)
		(stroke
			(width 0.2)
			(type default)
		)
		(layer "In6.Cu")
	)
	(gr_arc
		(start 93.6117 -31.2166)
		(mid 93.566319 -31.107041)
		(end 93.45676 -31.06166)
		(stroke
			(width 0.2)
			(type default)
		)
		(layer "In6.Cu")
	)
	(gr_arc
		(start 93.73362 -32.0294)
		(mid 93.779001 -32.138959)
		(end 93.88856 -32.18434)
		(stroke
			(width 0.2)
			(type default)
		)
		(layer "In6.Cu")
	)
	(gr_line
		(start 93.73362 -31.7754)
		(end 93.73362 -32.0294)
		(stroke
			(width 0.2)
			(type default)
		)
		(layer "In6.Cu")
	)
	(gr_arc
		(start 93.73362 -31.4706)
		(mid 93.779001 -31.580159)
		(end 93.88856 -31.62554)
		(stroke
			(width 0.2)
			(type default)
		)
		(layer "In6.Cu")
	)
	(gr_line
		(start 93.73362 -31.2166)
		(end 93.73362 -31.4706)
		(stroke
			(width 0.2)
			(type default)
		)
		(layer "In6.Cu")
	)
	(gr_line
		(start 93.88856 -32.18434)
		(end 94.09176 -32.18434)
		(stroke
			(width 0.2)
			(type default)
		)
		(layer "In6.Cu")
	)
	(gr_line
		(start 93.88856 -31.62554)
		(end 94.09176 -31.62554)
		(stroke
			(width 0.2)
			(type default)
		)
		(layer "In6.Cu")
	)
	(gr_arc
		(start 93.88856 -31.62046)
		(mid 93.779001 -31.665841)
		(end 93.73362 -31.7754)
		(stroke
			(width 0.2)
			(type default)
		)
		(layer "In6.Cu")
	)
	(gr_arc
		(start 93.88856 -31.06166)
		(mid 93.779001 -31.107041)
		(end 93.73362 -31.2166)
		(stroke
			(width 0.2)
			(type default)
		)
		(layer "In6.Cu")
	)
	(gr_arc
		(start 93.898974 -40.193722)
		(mid 93.534484 -39.841932)
		(end 93.182694 -40.206422)
		(stroke
			(width 0.2)
			(type default)
		)
		(layer "In6.Cu")
	)
	(gr_line
		(start 93.90761 -35.407854)
		(end 93.90761 -35.406838)
		(stroke
			(width 0.2)
			(type default)
		)
		(layer "In6.Cu")
	)
	(gr_arc
		(start 93.90761 -35.406838)
		(mid 93.548454 -35.049714)
		(end 93.19133 -35.40887)
		(stroke
			(width 0.2)
			(type default)
		)
		(layer "In6.Cu")
	)
	(gr_line
		(start 93.908626 -43.393614)
		(end 93.914976 -42.600118)
		(stroke
			(width 0.2)
			(type default)
		)
		(layer "In6.Cu")
	)
	(gr_line
		(start 93.909896 -36.195254)
		(end 93.90761 -35.407854)
		(stroke
			(width 0.2)
			(type default)
		)
		(layer "In6.Cu")
	)
	(gr_line
		(start 93.912944 -40.98925)
		(end 93.898974 -40.193722)
		(stroke
			(width 0.2)
			(type default)
		)
		(layer "In6.Cu")
	)
	(gr_line
		(start 93.913706 -38.597332)
		(end 93.913706 -38.596824)
		(stroke
			(width 0.2)
			(type default)
		)
		(layer "In6.Cu")
	)
	(gr_line
		(start 93.913706 -38.596824)
		(end 93.914722 -37.80282)
		(stroke
			(width 0.2)
			(type default)
		)
		(layer "In6.Cu")
	)
	(gr_arc
		(start 93.914722 -37.80282)
		(mid 93.557217 -37.444172)
		(end 93.198442 -37.80155)
		(stroke
			(width 0.2)
			(type default)
		)
		(layer "In6.Cu")
	)
	(gr_arc
		(start 93.914976 -42.600118)
		(mid 93.55963 -42.239184)
		(end 93.198696 -42.59453)
		(stroke
			(width 0.2)
			(type default)
		)
		(layer "In6.Cu")
	)
	(gr_arc
		(start 94.09176 -32.18434)
		(mid 94.201319 -32.138959)
		(end 94.2467 -32.0294)
		(stroke
			(width 0.2)
			(type default)
		)
		(layer "In6.Cu")
	)
	(gr_arc
		(start 94.09176 -31.62554)
		(mid 94.201319 -31.580159)
		(end 94.2467 -31.4706)
		(stroke
			(width 0.2)
			(type default)
		)
		(layer "In6.Cu")
	)
	(gr_line
		(start 94.09176 -31.62046)
		(end 93.88856 -31.62046)
		(stroke
			(width 0.2)
			(type default)
		)
		(layer "In6.Cu")
	)
	(gr_line
		(start 94.09176 -31.06166)
		(end 93.88856 -31.06166)
		(stroke
			(width 0.2)
			(type default)
		)
		(layer "In6.Cu")
	)
	(gr_line
		(start 94.2467 -32.0294)
		(end 94.2467 -31.7754)
		(stroke
			(width 0.2)
			(type default)
		)
		(layer "In6.Cu")
	)
	(gr_arc
		(start 94.2467 -31.7754)
		(mid 94.201319 -31.665841)
		(end 94.09176 -31.62046)
		(stroke
			(width 0.2)
			(type default)
		)
		(layer "In6.Cu")
	)
	(gr_line
		(start 94.2467 -31.4706)
		(end 94.2467 -31.2166)
		(stroke
			(width 0.2)
			(type default)
		)
		(layer "In6.Cu")
	)
	(gr_arc
		(start 94.2467 -31.2166)
		(mid 94.201319 -31.107041)
		(end 94.09176 -31.06166)
		(stroke
			(width 0.2)
			(type default)
		)
		(layer "In6.Cu")
	)
	(gr_line
		(start 94.34703 -34.241994)
		(end 93.544644 -34.248344)
		(stroke
			(width 0.2)
			(type default)
		)
		(layer "In6.Cu")
	)
	(gr_arc
		(start 94.352618 -34.958274)
		(mid 94.707964 -34.59734)
		(end 94.34703 -34.241994)
		(stroke
			(width 0.2)
			(type default)
		)
		(layer "In6.Cu")
	)
	(gr_line
		(start 94.357698 -36.641278)
		(end 93.550232 -36.64458)
		(stroke
			(width 0.2)
			(type default)
		)
		(layer "In6.Cu")
	)
	(gr_arc
		(start 94.360492 -37.357558)
		(mid 94.717362 -36.998021)
		(end 94.357698 -36.641278)
		(stroke
			(width 0.2)
			(type default)
		)
		(layer "In6.Cu")
	)
	(gr_arc
		(start 94.62262 -32.0294)
		(mid 94.668001 -32.138959)
		(end 94.77756 -32.18434)
		(stroke
			(width 0.2)
			(type default)
		)
		(layer "In6.Cu")
	)
	(gr_line
		(start 94.62262 -31.7754)
		(end 94.62262 -32.0294)
		(stroke
			(width 0.2)
			(type default)
		)
		(layer "In6.Cu")
	)
	(gr_arc
		(start 94.62262 -31.4706)
		(mid 94.668001 -31.580159)
		(end 94.77756 -31.62554)
		(stroke
			(width 0.2)
			(type default)
		)
		(layer "In6.Cu")
	)
	(gr_line
		(start 94.62262 -31.2166)
		(end 94.62262 -31.4706)
		(stroke
			(width 0.2)
			(type default)
		)
		(layer "In6.Cu")
	)
	(gr_line
		(start 94.77756 -32.18434)
		(end 94.98076 -32.18434)
		(stroke
			(width 0.2)
			(type default)
		)
		(layer "In6.Cu")
	)
	(gr_line
		(start 94.77756 -31.62554)
		(end 94.98076 -31.62554)
		(stroke
			(width 0.2)
			(type default)
		)
		(layer "In6.Cu")
	)
	(gr_arc
		(start 94.77756 -31.62046)
		(mid 94.668001 -31.665841)
		(end 94.62262 -31.7754)
		(stroke
			(width 0.2)
			(type default)
		)
		(layer "In6.Cu")
	)
	(gr_arc
		(start 94.77756 -31.06166)
		(mid 94.668001 -31.107041)
		(end 94.62262 -31.2166)
		(stroke
			(width 0.2)
			(type default)
		)
		(layer "In6.Cu")
	)
	(gr_line
		(start 94.79026 -35.405822)
		(end 94.792038 -36.200588)
		(stroke
			(width 0.2)
			(type default)
		)
		(layer "In6.Cu")
	)
	(gr_arc
		(start 94.792038 -36.200588)
		(mid 95.150813 -36.55822)
		(end 95.508318 -36.199318)
		(stroke
			(width 0.2)
			(type default)
		)
		(layer "In6.Cu")
	)
	(gr_arc
		(start 94.98076 -32.18434)
		(mid 95.090319 -32.138959)
		(end 95.1357 -32.0294)
		(stroke
			(width 0.2)
			(type default)
		)
		(layer "In6.Cu")
	)
	(gr_arc
		(start 94.98076 -31.62554)
		(mid 95.090319 -31.580159)
		(end 95.1357 -31.4706)
		(stroke
			(width 0.2)
			(type default)
		)
		(layer "In6.Cu")
	)
	(gr_line
		(start 94.98076 -31.62046)
		(end 94.77756 -31.62046)
		(stroke
			(width 0.2)
			(type default)
		)
		(layer "In6.Cu")
	)
	(gr_line
		(start 94.98076 -31.06166)
		(end 94.77756 -31.06166)
		(stroke
			(width 0.2)
			(type default)
		)
		(layer "In6.Cu")
	)
	(gr_line
		(start 95.1357 -32.0294)
		(end 95.1357 -31.7754)
		(stroke
			(width 0.2)
			(type default)
		)
		(layer "In6.Cu")
	)
	(gr_arc
		(start 95.1357 -31.7754)
		(mid 95.090319 -31.665841)
		(end 94.98076 -31.62046)
		(stroke
			(width 0.2)
			(type default)
		)
		(layer "In6.Cu")
	)
	(gr_line
		(start 95.1357 -31.4706)
		(end 95.1357 -31.2166)
		(stroke
			(width 0.2)
			(type default)
		)
		(layer "In6.Cu")
	)
	(gr_arc
		(start 95.1357 -31.2166)
		(mid 95.090319 -31.107041)
		(end 94.98076 -31.06166)
		(stroke
			(width 0.2)
			(type default)
		)
		(layer "In6.Cu")
	)
	(gr_arc
		(start 95.25762 -32.0294)
		(mid 95.303001 -32.138959)
		(end 95.41256 -32.18434)
		(stroke
			(width 0.2)
			(type default)
		)
		(layer "In6.Cu")
	)
	(gr_line
		(start 95.25762 -31.7754)
		(end 95.25762 -32.0294)
		(stroke
			(width 0.2)
			(type default)
		)
		(layer "In6.Cu")
	)
	(gr_arc
		(start 95.25762 -31.4706)
		(mid 95.303001 -31.580159)
		(end 95.41256 -31.62554)
		(stroke
			(width 0.2)
			(type default)
		)
		(layer "In6.Cu")
	)
	(gr_line
		(start 95.25762 -31.2166)
		(end 95.25762 -31.4706)
		(stroke
			(width 0.2)
			(type default)
		)
		(layer "In6.Cu")
	)
	(gr_line
		(start 95.41256 -32.18434)
		(end 95.61576 -32.18434)
		(stroke
			(width 0.2)
			(type default)
		)
		(layer "In6.Cu")
	)
	(gr_line
		(start 95.41256 -31.62554)
		(end 95.61576 -31.62554)
		(stroke
			(width 0.2)
			(type default)
		)
		(layer "In6.Cu")
	)
	(gr_arc
		(start 95.41256 -31.62046)
		(mid 95.303001 -31.665841)
		(end 95.25762 -31.7754)
		(stroke
			(width 0.2)
			(type default)
		)
		(layer "In6.Cu")
	)
	(gr_arc
		(start 95.41256 -31.06166)
		(mid 95.303001 -31.107041)
		(end 95.25762 -31.2166)
		(stroke
			(width 0.2)
			(type default)
		)
		(layer "In6.Cu")
	)
	(gr_line
		(start 95.50654 -35.40506)
		(end 95.50654 -35.404298)
		(stroke
			(width 0.2)
			(type default)
		)
		(layer "In6.Cu")
	)
	(gr_arc
		(start 95.50654 -35.404298)
		(mid 95.147638 -35.04692)
		(end 94.79026 -35.405822)
		(stroke
			(width 0.2)
			(type default)
		)
		(layer "In6.Cu")
	)
	(gr_line
		(start 95.508318 -36.199318)
		(end 95.50654 -35.40506)
		(stroke
			(width 0.2)
			(type default)
		)
		(layer "In6.Cu")
	)
	(gr_line
		(start 95.59036 -35.408362)
		(end 95.592138 -36.200588)
		(stroke
			(width 0.2)
			(type default)
		)
		(layer "In6.Cu")
	)
	(gr_arc
		(start 95.592138 -36.200588)
		(mid 95.950913 -36.55822)
		(end 96.308418 -36.199318)
		(stroke
			(width 0.2)
			(type default)
		)
		(layer "In6.Cu")
	)
	(gr_arc
		(start 95.61576 -32.18434)
		(mid 95.725319 -32.138959)
		(end 95.7707 -32.0294)
		(stroke
			(width 0.2)
			(type default)
		)
		(layer "In6.Cu")
	)
	(gr_arc
		(start 95.61576 -31.62554)
		(mid 95.725319 -31.580159)
		(end 95.7707 -31.4706)
		(stroke
			(width 0.2)
			(type default)
		)
		(layer "In6.Cu")
	)
	(gr_line
		(start 95.61576 -31.62046)
		(end 95.41256 -31.62046)
		(stroke
			(width 0.2)
			(type default)
		)
		(layer "In6.Cu")
	)
	(gr_line
		(start 95.61576 -31.06166)
		(end 95.41256 -31.06166)
		(stroke
			(width 0.2)
			(type default)
		)
		(layer "In6.Cu")
	)
	(gr_line
		(start 95.7707 -32.0294)
		(end 95.7707 -31.7754)
		(stroke
			(width 0.2)
			(type default)
		)
		(layer "In6.Cu")
	)
	(gr_arc
		(start 95.7707 -31.7754)
		(mid 95.725319 -31.665841)
		(end 95.61576 -31.62046)
		(stroke
			(width 0.2)
			(type default)
		)
		(layer "In6.Cu")
	)
	(gr_line
		(start 95.7707 -31.4706)
		(end 95.7707 -31.2166)
		(stroke
			(width 0.2)
			(type default)
		)
		(layer "In6.Cu")
	)
	(gr_arc
		(start 95.7707 -31.2166)
		(mid 95.725319 -31.107041)
		(end 95.61576 -31.06166)
		(stroke
			(width 0.2)
			(type default)
		)
		(layer "In6.Cu")
	)
	(gr_arc
		(start 96.14662 -32.0294)
		(mid 96.192001 -32.138959)
		(end 96.30156 -32.18434)
		(stroke
			(width 0.2)
			(type default)
		)
		(layer "In6.Cu")
	)
	(gr_line
		(start 96.14662 -31.7754)
		(end 96.14662 -32.0294)
		(stroke
			(width 0.2)
			(type default)
		)
		(layer "In6.Cu")
	)
	(gr_arc
		(start 96.14662 -31.4706)
		(mid 96.192001 -31.580159)
		(end 96.30156 -31.62554)
		(stroke
			(width 0.2)
			(type default)
		)
		(layer "In6.Cu")
	)
	(gr_line
		(start 96.14662 -31.2166)
		(end 96.14662 -31.4706)
		(stroke
			(width 0.2)
			(type default)
		)
		(layer "In6.Cu")
	)
	(gr_line
		(start 96.30156 -32.18434)
		(end 96.50476 -32.18434)
		(stroke
			(width 0.2)
			(type default)
		)
		(layer "In6.Cu")
	)
	(gr_line
		(start 96.30156 -31.62554)
		(end 96.50476 -31.62554)
		(stroke
			(width 0.2)
			(type default)
		)
		(layer "In6.Cu")
	)
	(gr_arc
		(start 96.30156 -31.62046)
		(mid 96.192001 -31.665841)
		(end 96.14662 -31.7754)
		(stroke
			(width 0.2)
			(type default)
		)
		(layer "In6.Cu")
	)
	(gr_arc
		(start 96.30156 -31.06166)
		(mid 96.192001 -31.107041)
		(end 96.14662 -31.2166)
		(stroke
			(width 0.2)
			(type default)
		)
		(layer "In6.Cu")
	)
	(gr_line
		(start 96.30664 -35.4076)
		(end 96.30664 -35.406838)
		(stroke
			(width 0.2)
			(type default)
		)
		(layer "In6.Cu")
	)
	(gr_arc
		(start 96.30664 -35.406838)
		(mid 95.947738 -35.04946)
		(end 95.59036 -35.408362)
		(stroke
			(width 0.2)
			(type default)
		)
		(layer "In6.Cu")
	)
	(gr_line
		(start 96.308418 -36.199318)
		(end 96.30664 -35.4076)
		(stroke
			(width 0.2)
			(type default)
		)
		(layer "In6.Cu")
	)
	(gr_arc
		(start 96.50476 -32.18434)
		(mid 96.614319 -32.138959)
		(end 96.6597 -32.0294)
		(stroke
			(width 0.2)
			(type default)
		)
		(layer "In6.Cu")
	)
	(gr_arc
		(start 96.50476 -31.62554)
		(mid 96.614319 -31.580159)
		(end 96.6597 -31.4706)
		(stroke
			(width 0.2)
			(type default)
		)
		(layer "In6.Cu")
	)
	(gr_line
		(start 96.50476 -31.62046)
		(end 96.30156 -31.62046)
		(stroke
			(width 0.2)
			(type default)
		)
		(layer "In6.Cu")
	)
	(gr_line
		(start 96.50476 -31.06166)
		(end 96.30156 -31.06166)
		(stroke
			(width 0.2)
			(type default)
		)
		(layer "In6.Cu")
	)
	(gr_line
		(start 96.6597 -32.0294)
		(end 96.6597 -31.7754)
		(stroke
			(width 0.2)
			(type default)
		)
		(layer "In6.Cu")
	)
	(gr_arc
		(start 96.6597 -31.7754)
		(mid 96.614319 -31.665841)
		(end 96.50476 -31.62046)
		(stroke
			(width 0.2)
			(type default)
		)
		(layer "In6.Cu")
	)
	(gr_line
		(start 96.6597 -31.4706)
		(end 96.6597 -31.2166)
		(stroke
			(width 0.2)
			(type default)
		)
		(layer "In6.Cu")
	)
	(gr_arc
		(start 96.6597 -31.2166)
		(mid 96.614319 -31.107041)
		(end 96.50476 -31.06166)
		(stroke
			(width 0.2)
			(type default)
		)
		(layer "In6.Cu")
	)
	(gr_arc
		(start 96.78162 -32.0294)
		(mid 96.827001 -32.138959)
		(end 96.93656 -32.18434)
		(stroke
			(width 0.2)
			(type default)
		)
		(layer "In6.Cu")
	)
	(gr_line
		(start 96.78162 -31.7754)
		(end 96.78162 -32.0294)
		(stroke
			(width 0.2)
			(type default)
		)
		(layer "In6.Cu")
	)
	(gr_arc
		(start 96.78162 -31.4706)
		(mid 96.827001 -31.580159)
		(end 96.93656 -31.62554)
		(stroke
			(width 0.2)
			(type default)
		)
		(layer "In6.Cu")
	)
	(gr_line
		(start 96.78162 -31.2166)
		(end 96.78162 -31.4706)
		(stroke
			(width 0.2)
			(type default)
		)
		(layer "In6.Cu")
	)
	(gr_line
		(start 96.93656 -32.18434)
		(end 97.13976 -32.18434)
		(stroke
			(width 0.2)
			(type default)
		)
		(layer "In6.Cu")
	)
	(gr_line
		(start 96.93656 -31.62554)
		(end 97.13976 -31.62554)
		(stroke
			(width 0.2)
			(type default)
		)
		(layer "In6.Cu")
	)
	(gr_arc
		(start 96.93656 -31.62046)
		(mid 96.827001 -31.665841)
		(end 96.78162 -31.7754)
		(stroke
			(width 0.2)
			(type default)
		)
		(layer "In6.Cu")
	)
	(gr_arc
		(start 96.93656 -31.06166)
		(mid 96.827001 -31.107041)
		(end 96.78162 -31.2166)
		(stroke
			(width 0.2)
			(type default)
		)
		(layer "In6.Cu")
	)
	(gr_arc
		(start 97.13976 -32.18434)
		(mid 97.249319 -32.138959)
		(end 97.2947 -32.0294)
		(stroke
			(width 0.2)
			(type default)
		)
		(layer "In6.Cu")
	)
	(gr_arc
		(start 97.13976 -31.62554)
		(mid 97.249319 -31.580159)
		(end 97.2947 -31.4706)
		(stroke
			(width 0.2)
			(type default)
		)
		(layer "In6.Cu")
	)
	(gr_line
		(start 97.13976 -31.62046)
		(end 96.93656 -31.62046)
		(stroke
			(width 0.2)
			(type default)
		)
		(layer "In6.Cu")
	)
	(gr_line
		(start 97.13976 -31.06166)
		(end 96.93656 -31.06166)
		(stroke
			(width 0.2)
			(type default)
		)
		(layer "In6.Cu")
	)
	(gr_line
		(start 97.182686 -35.404552)
		(end 97.192084 -36.204144)
		(stroke
			(width 0.2)
			(type default)
		)
		(layer "In6.Cu")
	)
	(gr_arc
		(start 97.192084 -36.204144)
		(mid 97.554415 -36.558219)
		(end 97.908364 -36.195762)
		(stroke
			(width 0.2)
			(type default)
		)
		(layer "In6.Cu")
	)
	(gr_line
		(start 97.2947 -32.0294)
		(end 97.2947 -31.7754)
		(stroke
			(width 0.2)
			(type default)
		)
		(layer "In6.Cu")
	)
	(gr_arc
		(start 97.2947 -31.7754)
		(mid 97.249319 -31.665841)
		(end 97.13976 -31.62046)
		(stroke
			(width 0.2)
			(type default)
		)
		(layer "In6.Cu")
	)
	(gr_line
		(start 97.2947 -31.4706)
		(end 97.2947 -31.2166)
		(stroke
			(width 0.2)
			(type default)
		)
		(layer "In6.Cu")
	)
	(gr_arc
		(start 97.2947 -31.2166)
		(mid 97.249319 -31.107041)
		(end 97.13976 -31.06166)
		(stroke
			(width 0.2)
			(type default)
		)
		(layer "In6.Cu")
	)
	(gr_arc
		(start 97.67062 -32.0294)
		(mid 97.716001 -32.138959)
		(end 97.82556 -32.18434)
		(stroke
			(width 0.2)
			(type default)
		)
		(layer "In6.Cu")
	)
	(gr_line
		(start 97.67062 -31.7754)
		(end 97.67062 -32.0294)
		(stroke
			(width 0.2)
			(type default)
		)
		(layer "In6.Cu")
	)
	(gr_arc
		(start 97.67062 -31.4706)
		(mid 97.716001 -31.580159)
		(end 97.82556 -31.62554)
		(stroke
			(width 0.2)
			(type default)
		)
		(layer "In6.Cu")
	)
	(gr_line
		(start 97.67062 -31.2166)
		(end 97.67062 -31.4706)
		(stroke
			(width 0.2)
			(type default)
		)
		(layer "In6.Cu")
	)
	(gr_line
		(start 97.82556 -32.18434)
		(end 98.02876 -32.18434)
		(stroke
			(width 0.2)
			(type default)
		)
		(layer "In6.Cu")
	)
	(gr_line
		(start 97.82556 -31.62554)
		(end 98.02876 -31.62554)
		(stroke
			(width 0.2)
			(type default)
		)
		(layer "In6.Cu")
	)
	(gr_arc
		(start 97.82556 -31.62046)
		(mid 97.716001 -31.665841)
		(end 97.67062 -31.7754)
		(stroke
			(width 0.2)
			(type default)
		)
		(layer "In6.Cu")
	)
	(gr_arc
		(start 97.82556 -31.06166)
		(mid 97.716001 -31.107041)
		(end 97.67062 -31.2166)
		(stroke
			(width 0.2)
			(type default)
		)
		(layer "In6.Cu")
	)
	(gr_arc
		(start 97.898966 -35.395916)
		(mid 97.536508 -35.042094)
		(end 97.182686 -35.404552)
		(stroke
			(width 0.2)
			(type default)
		)
		(layer "In6.Cu")
	)
	(gr_line
		(start 97.908364 -36.195762)
		(end 97.898966 -35.395916)
		(stroke
			(width 0.2)
			(type default)
		)
		(layer "In6.Cu")
	)
	(gr_line
		(start 97.983802 -35.405314)
		(end 97.992184 -36.203636)
		(stroke
			(width 0.2)
			(type default)
		)
		(layer "In6.Cu")
	)
	(gr_arc
		(start 97.992184 -36.203636)
		(mid 98.354007 -36.558219)
		(end 98.708464 -36.19627)
		(stroke
			(width 0.2)
			(type default)
		)
		(layer "In6.Cu")
	)
	(gr_arc
		(start 98.02876 -32.18434)
		(mid 98.138319 -32.138959)
		(end 98.1837 -32.0294)
		(stroke
			(width 0.2)
			(type default)
		)
		(layer "In6.Cu")
	)
	(gr_arc
		(start 98.02876 -31.62554)
		(mid 98.138319 -31.580159)
		(end 98.1837 -31.4706)
		(stroke
			(width 0.2)
			(type default)
		)
		(layer "In6.Cu")
	)
	(gr_line
		(start 98.02876 -31.62046)
		(end 97.82556 -31.62046)
		(stroke
			(width 0.2)
			(type default)
		)
		(layer "In6.Cu")
	)
	(gr_line
		(start 98.02876 -31.06166)
		(end 97.82556 -31.06166)
		(stroke
			(width 0.2)
			(type default)
		)
		(layer "In6.Cu")
	)
	(gr_line
		(start 98.1837 -32.0294)
		(end 98.1837 -31.7754)
		(stroke
			(width 0.2)
			(type default)
		)
		(layer "In6.Cu")
	)
	(gr_arc
		(start 98.1837 -31.7754)
		(mid 98.138319 -31.665841)
		(end 98.02876 -31.62046)
		(stroke
			(width 0.2)
			(type default)
		)
		(layer "In6.Cu")
	)
	(gr_line
		(start 98.1837 -31.4706)
		(end 98.1837 -31.2166)
		(stroke
			(width 0.2)
			(type default)
		)
		(layer "In6.Cu")
	)
	(gr_arc
		(start 98.1837 -31.2166)
		(mid 98.138319 -31.107041)
		(end 98.02876 -31.06166)
		(stroke
			(width 0.2)
			(type default)
		)
		(layer "In6.Cu")
	)
	(gr_arc
		(start 98.30562 -32.0294)
		(mid 98.351001 -32.138959)
		(end 98.46056 -32.18434)
		(stroke
			(width 0.2)
			(type default)
		)
		(layer "In6.Cu")
	)
	(gr_line
		(start 98.30562 -31.7754)
		(end 98.30562 -32.0294)
		(stroke
			(width 0.2)
			(type default)
		)
		(layer "In6.Cu")
	)
	(gr_arc
		(start 98.30562 -31.4706)
		(mid 98.351001 -31.580159)
		(end 98.46056 -31.62554)
		(stroke
			(width 0.2)
			(type default)
		)
		(layer "In6.Cu")
	)
	(gr_line
		(start 98.30562 -31.2166)
		(end 98.30562 -31.4706)
		(stroke
			(width 0.2)
			(type default)
		)
		(layer "In6.Cu")
	)
	(gr_line
		(start 98.46056 -32.18434)
		(end 98.66376 -32.18434)
		(stroke
			(width 0.2)
			(type default)
		)
		(layer "In6.Cu")
	)
	(gr_line
		(start 98.46056 -31.62554)
		(end 98.66376 -31.62554)
		(stroke
			(width 0.2)
			(type default)
		)
		(layer "In6.Cu")
	)
	(gr_arc
		(start 98.46056 -31.62046)
		(mid 98.351001 -31.665841)
		(end 98.30562 -31.7754)
		(stroke
			(width 0.2)
			(type default)
		)
		(layer "In6.Cu")
	)
	(gr_arc
		(start 98.46056 -31.06166)
		(mid 98.351001 -31.107041)
		(end 98.30562 -31.2166)
		(stroke
			(width 0.2)
			(type default)
		)
		(layer "In6.Cu")
	)
	(gr_arc
		(start 98.66376 -32.18434)
		(mid 98.773319 -32.138959)
		(end 98.8187 -32.0294)
		(stroke
			(width 0.2)
			(type default)
		)
		(layer "In6.Cu")
	)
	(gr_arc
		(start 98.66376 -31.62554)
		(mid 98.773319 -31.580159)
		(end 98.8187 -31.4706)
		(stroke
			(width 0.2)
			(type default)
		)
		(layer "In6.Cu")
	)
	(gr_line
		(start 98.66376 -31.62046)
		(end 98.46056 -31.62046)
		(stroke
			(width 0.2)
			(type default)
		)
		(layer "In6.Cu")
	)
	(gr_line
		(start 98.66376 -31.06166)
		(end 98.46056 -31.06166)
		(stroke
			(width 0.2)
			(type default)
		)
		(layer "In6.Cu")
	)
	(gr_arc
		(start 98.700082 -35.397694)
		(mid 98.338132 -35.043364)
		(end 97.983802 -35.405314)
		(stroke
			(width 0.2)
			(type default)
		)
		(layer "In6.Cu")
	)
	(gr_line
		(start 98.708464 -36.19627)
		(end 98.700082 -35.397694)
		(stroke
			(width 0.2)
			(type default)
		)
		(layer "In6.Cu")
	)
	(gr_line
		(start 98.8187 -32.0294)
		(end 98.8187 -31.7754)
		(stroke
			(width 0.2)
			(type default)
		)
		(layer "In6.Cu")
	)
	(gr_arc
		(start 98.8187 -31.7754)
		(mid 98.773319 -31.665841)
		(end 98.66376 -31.62046)
		(stroke
			(width 0.2)
			(type default)
		)
		(layer "In6.Cu")
	)
	(gr_line
		(start 98.8187 -31.4706)
		(end 98.8187 -31.2166)
		(stroke
			(width 0.2)
			(type default)
		)
		(layer "In6.Cu")
	)
	(gr_arc
		(start 98.8187 -31.2166)
		(mid 98.773319 -31.107041)
		(end 98.66376 -31.06166)
		(stroke
			(width 0.2)
			(type default)
		)
		(layer "In6.Cu")
	)
	(gr_arc
		(start 99.19462 -32.0294)
		(mid 99.240001 -32.138959)
		(end 99.34956 -32.18434)
		(stroke
			(width 0.2)
			(type default)
		)
		(layer "In6.Cu")
	)
	(gr_line
		(start 99.19462 -31.7754)
		(end 99.19462 -32.0294)
		(stroke
			(width 0.2)
			(type default)
		)
		(layer "In6.Cu")
	)
	(gr_arc
		(start 99.19462 -31.4706)
		(mid 99.240001 -31.580159)
		(end 99.34956 -31.62554)
		(stroke
			(width 0.2)
			(type default)
		)
		(layer "In6.Cu")
	)
	(gr_line
		(start 99.19462 -31.2166)
		(end 99.19462 -31.4706)
		(stroke
			(width 0.2)
			(type default)
		)
		(layer "In6.Cu")
	)
	(gr_line
		(start 99.34956 -32.18434)
		(end 99.55276 -32.18434)
		(stroke
			(width 0.2)
			(type default)
		)
		(layer "In6.Cu")
	)
	(gr_line
		(start 99.34956 -31.62554)
		(end 99.55276 -31.62554)
		(stroke
			(width 0.2)
			(type default)
		)
		(layer "In6.Cu")
	)
	(gr_arc
		(start 99.34956 -31.62046)
		(mid 99.240001 -31.665841)
		(end 99.19462 -31.7754)
		(stroke
			(width 0.2)
			(type default)
		)
		(layer "In6.Cu")
	)
	(gr_arc
		(start 99.34956 -31.06166)
		(mid 99.240001 -31.107041)
		(end 99.19462 -31.2166)
		(stroke
			(width 0.2)
			(type default)
		)
		(layer "In6.Cu")
	)
	(gr_arc
		(start 99.55276 -32.18434)
		(mid 99.662319 -32.138959)
		(end 99.7077 -32.0294)
		(stroke
			(width 0.2)
			(type default)
		)
		(layer "In6.Cu")
	)
	(gr_arc
		(start 99.55276 -31.62554)
		(mid 99.662319 -31.580159)
		(end 99.7077 -31.4706)
		(stroke
			(width 0.2)
			(type default)
		)
		(layer "In6.Cu")
	)
	(gr_line
		(start 99.55276 -31.62046)
		(end 99.34956 -31.62046)
		(stroke
			(width 0.2)
			(type default)
		)
		(layer "In6.Cu")
	)
	(gr_line
		(start 99.55276 -31.06166)
		(end 99.34956 -31.06166)
		(stroke
			(width 0.2)
			(type default)
		)
		(layer "In6.Cu")
	)
	(gr_arc
		(start 99.59213 -36.199318)
		(mid 99.949635 -36.55822)
		(end 100.30841 -36.200588)
		(stroke
			(width 0.2)
			(type default)
		)
		(layer "In6.Cu")
	)
	(gr_line
		(start 99.5934 -35.391852)
		(end 99.59213 -36.199318)
		(stroke
			(width 0.2)
			(type default)
		)
		(layer "In6.Cu")
	)
	(gr_line
		(start 99.7077 -32.0294)
		(end 99.7077 -31.7754)
		(stroke
			(width 0.2)
			(type default)
		)
		(layer "In6.Cu")
	)
	(gr_arc
		(start 99.7077 -31.7754)
		(mid 99.662319 -31.665841)
		(end 99.55276 -31.62046)
		(stroke
			(width 0.2)
			(type default)
		)
		(layer "In6.Cu")
	)
	(gr_line
		(start 99.7077 -31.4706)
		(end 99.7077 -31.2166)
		(stroke
			(width 0.2)
			(type default)
		)
		(layer "In6.Cu")
	)
	(gr_arc
		(start 99.7077 -31.2166)
		(mid 99.662319 -31.107041)
		(end 99.55276 -31.06166)
		(stroke
			(width 0.2)
			(type default)
		)
		(layer "In6.Cu")
	)
	(gr_arc
		(start 99.82962 -32.0294)
		(mid 99.875001 -32.138959)
		(end 99.98456 -32.18434)
		(stroke
			(width 0.2)
			(type default)
		)
		(layer "In6.Cu")
	)
	(gr_line
		(start 99.82962 -31.7754)
		(end 99.82962 -32.0294)
		(stroke
			(width 0.2)
			(type default)
		)
		(layer "In6.Cu")
	)
	(gr_arc
		(start 99.82962 -31.4706)
		(mid 99.875001 -31.580159)
		(end 99.98456 -31.62554)
		(stroke
			(width 0.2)
			(type default)
		)
		(layer "In6.Cu")
	)
	(gr_line
		(start 99.82962 -31.2166)
		(end 99.82962 -31.4706)
		(stroke
			(width 0.2)
			(type default)
		)
		(layer "In6.Cu")
	)
	(gr_line
		(start 99.98456 -32.18434)
		(end 100.18776 -32.18434)
		(stroke
			(width 0.2)
			(type default)
		)
		(layer "In6.Cu")
	)
	(gr_line
		(start 99.98456 -31.62554)
		(end 100.18776 -31.62554)
		(stroke
			(width 0.2)
			(type default)
		)
		(layer "In6.Cu")
	)
	(gr_arc
		(start 99.98456 -31.62046)
		(mid 99.875001 -31.665841)
		(end 99.82962 -31.7754)
		(stroke
			(width 0.2)
			(type default)
		)
		(layer "In6.Cu")
	)
	(gr_arc
		(start 99.98456 -31.06166)
		(mid 99.875001 -31.107041)
		(end 99.82962 -31.2166)
		(stroke
			(width 0.2)
			(type default)
		)
		(layer "In6.Cu")
	)
	(gr_arc
		(start 100.18776 -32.18434)
		(mid 100.297319 -32.138959)
		(end 100.3427 -32.0294)
		(stroke
			(width 0.2)
			(type default)
		)
		(layer "In6.Cu")
	)
	(gr_arc
		(start 100.18776 -31.62554)
		(mid 100.297319 -31.580159)
		(end 100.3427 -31.4706)
		(stroke
			(width 0.2)
			(type default)
		)
		(layer "In6.Cu")
	)
	(gr_line
		(start 100.18776 -31.62046)
		(end 99.98456 -31.62046)
		(stroke
			(width 0.2)
			(type default)
		)
		(layer "In6.Cu")
	)
	(gr_line
		(start 100.18776 -31.06166)
		(end 99.98456 -31.06166)
		(stroke
			(width 0.2)
			(type default)
		)
		(layer "In6.Cu")
	)
	(gr_line
		(start 100.30841 -36.200588)
		(end 100.30841 -36.20008)
		(stroke
			(width 0.2)
			(type default)
		)
		(layer "In6.Cu")
	)
	(gr_line
		(start 100.30841 -36.20008)
		(end 100.30968 -35.392868)
		(stroke
			(width 0.2)
			(type default)
		)
		(layer "In6.Cu")
	)
	(gr_arc
		(start 100.30968 -35.392868)
		(mid 99.952048 -35.03422)
		(end 99.5934 -35.391852)
		(stroke
			(width 0.2)
			(type default)
		)
		(layer "In6.Cu")
	)
	(gr_line
		(start 100.3427 -32.0294)
		(end 100.3427 -31.7754)
		(stroke
			(width 0.2)
			(type default)
		)
		(layer "In6.Cu")
	)
	(gr_arc
		(start 100.3427 -31.7754)
		(mid 100.297319 -31.665841)
		(end 100.18776 -31.62046)
		(stroke
			(width 0.2)
			(type default)
		)
		(layer "In6.Cu")
	)
	(gr_line
		(start 100.3427 -31.4706)
		(end 100.3427 -31.2166)
		(stroke
			(width 0.2)
			(type default)
		)
		(layer "In6.Cu")
	)
	(gr_arc
		(start 100.3427 -31.2166)
		(mid 100.297319 -31.107041)
		(end 100.18776 -31.06166)
		(stroke
			(width 0.2)
			(type default)
		)
		(layer "In6.Cu")
	)
	(gr_arc
		(start 100.39223 -36.196524)
		(mid 100.746941 -36.558221)
		(end 101.10851 -36.203382)
		(stroke
			(width 0.2)
			(type default)
		)
		(layer "In6.Cu")
	)
	(gr_line
		(start 100.399342 -35.394646)
		(end 100.39223 -36.196524)
		(stroke
			(width 0.2)
			(type default)
		)
		(layer "In6.Cu")
	)
	(gr_arc
		(start 100.71862 -32.046418)
		(mid 100.764001 -32.155977)
		(end 100.87356 -32.201358)
		(stroke
			(width 0.2)
			(type default)
		)
		(layer "In6.Cu")
	)
	(gr_line
		(start 100.71862 -31.792418)
		(end 100.71862 -32.046418)
		(stroke
			(width 0.2)
			(type default)
		)
		(layer "In6.Cu")
	)
	(gr_arc
		(start 100.71862 -31.487618)
		(mid 100.764001 -31.597177)
		(end 100.87356 -31.642558)
		(stroke
			(width 0.2)
			(type default)
		)
		(layer "In6.Cu")
	)
	(gr_line
		(start 100.71862 -31.233618)
		(end 100.71862 -31.487618)
		(stroke
			(width 0.2)
			(type default)
		)
		(layer "In6.Cu")
	)
	(gr_line
		(start 100.87356 -32.201358)
		(end 101.07676 -32.201358)
		(stroke
			(width 0.2)
			(type default)
		)
		(layer "In6.Cu")
	)
	(gr_line
		(start 100.87356 -31.642558)
		(end 101.07676 -31.642558)
		(stroke
			(width 0.2)
			(type default)
		)
		(layer "In6.Cu")
	)
	(gr_arc
		(start 100.87356 -31.637478)
		(mid 100.764001 -31.682859)
		(end 100.71862 -31.792418)
		(stroke
			(width 0.2)
			(type default)
		)
		(layer "In6.Cu")
	)
	(gr_arc
		(start 100.87356 -31.078678)
		(mid 100.764001 -31.124059)
		(end 100.71862 -31.233618)
		(stroke
			(width 0.2)
			(type default)
		)
		(layer "In6.Cu")
	)
	(gr_arc
		(start 101.07676 -32.201358)
		(mid 101.186319 -32.155977)
		(end 101.2317 -32.046418)
		(stroke
			(width 0.2)
			(type default)
		)
		(layer "In6.Cu")
	)
	(gr_arc
		(start 101.07676 -31.642558)
		(mid 101.186319 -31.597177)
		(end 101.2317 -31.487618)
		(stroke
			(width 0.2)
			(type default)
		)
		(layer "In6.Cu")
	)
	(gr_line
		(start 101.07676 -31.637478)
		(end 100.87356 -31.637478)
		(stroke
			(width 0.2)
			(type default)
		)
		(layer "In6.Cu")
	)
	(gr_line
		(start 101.07676 -31.078678)
		(end 100.87356 -31.078678)
		(stroke
			(width 0.2)
			(type default)
		)
		(layer "In6.Cu")
	)
	(gr_line
		(start 101.10851 -36.203382)
		(end 101.115622 -35.40125)
		(stroke
			(width 0.2)
			(type default)
		)
		(layer "In6.Cu")
	)
	(gr_arc
		(start 101.115622 -35.40125)
		(mid 100.760784 -35.039808)
		(end 100.399342 -35.394646)
		(stroke
			(width 0.2)
			(type default)
		)
		(layer "In6.Cu")
	)
	(gr_line
		(start 101.2317 -32.046418)
		(end 101.2317 -31.792418)
		(stroke
			(width 0.2)
			(type default)
		)
		(layer "In6.Cu")
	)
	(gr_arc
		(start 101.2317 -31.792418)
		(mid 101.186319 -31.682859)
		(end 101.07676 -31.637478)
		(stroke
			(width 0.2)
			(type default)
		)
		(layer "In6.Cu")
	)
	(gr_line
		(start 101.2317 -31.487618)
		(end 101.2317 -31.233618)
		(stroke
			(width 0.2)
			(type default)
		)
		(layer "In6.Cu")
	)
	(gr_arc
		(start 101.2317 -31.233618)
		(mid 101.186319 -31.124059)
		(end 101.07676 -31.078678)
		(stroke
			(width 0.2)
			(type default)
		)
		(layer "In6.Cu")
	)
	(gr_arc
		(start 101.35362 -32.046418)
		(mid 101.399001 -32.155977)
		(end 101.50856 -32.201358)
		(stroke
			(width 0.2)
			(type default)
		)
		(layer "In6.Cu")
	)
	(gr_line
		(start 101.35362 -31.792418)
		(end 101.35362 -32.046418)
		(stroke
			(width 0.2)
			(type default)
		)
		(layer "In6.Cu")
	)
	(gr_arc
		(start 101.35362 -31.487618)
		(mid 101.399001 -31.597177)
		(end 101.50856 -31.642558)
		(stroke
			(width 0.2)
			(type default)
		)
		(layer "In6.Cu")
	)
	(gr_line
		(start 101.35362 -31.233618)
		(end 101.35362 -31.487618)
		(stroke
			(width 0.2)
			(type default)
		)
		(layer "In6.Cu")
	)
	(gr_line
		(start 101.50856 -32.201358)
		(end 101.71176 -32.201358)
		(stroke
			(width 0.2)
			(type default)
		)
		(layer "In6.Cu")
	)
	(gr_line
		(start 101.50856 -31.642558)
		(end 101.71176 -31.642558)
		(stroke
			(width 0.2)
			(type default)
		)
		(layer "In6.Cu")
	)
	(gr_arc
		(start 101.50856 -31.637478)
		(mid 101.399001 -31.682859)
		(end 101.35362 -31.792418)
		(stroke
			(width 0.2)
			(type default)
		)
		(layer "In6.Cu")
	)
	(gr_arc
		(start 101.50856 -31.078678)
		(mid 101.399001 -31.124059)
		(end 101.35362 -31.233618)
		(stroke
			(width 0.2)
			(type default)
		)
		(layer "In6.Cu")
	)
	(gr_arc
		(start 101.71176 -32.201358)
		(mid 101.821319 -32.155977)
		(end 101.8667 -32.046418)
		(stroke
			(width 0.2)
			(type default)
		)
		(layer "In6.Cu")
	)
	(gr_arc
		(start 101.71176 -31.642558)
		(mid 101.821319 -31.597177)
		(end 101.8667 -31.487618)
		(stroke
			(width 0.2)
			(type default)
		)
		(layer "In6.Cu")
	)
	(gr_line
		(start 101.71176 -31.637478)
		(end 101.50856 -31.637478)
		(stroke
			(width 0.2)
			(type default)
		)
		(layer "In6.Cu")
	)
	(gr_line
		(start 101.71176 -31.078678)
		(end 101.50856 -31.078678)
		(stroke
			(width 0.2)
			(type default)
		)
		(layer "In6.Cu")
	)
	(gr_line
		(start 101.8667 -32.046418)
		(end 101.8667 -31.792418)
		(stroke
			(width 0.2)
			(type default)
		)
		(layer "In6.Cu")
	)
	(gr_arc
		(start 101.8667 -31.792418)
		(mid 101.821319 -31.682859)
		(end 101.71176 -31.637478)
		(stroke
			(width 0.2)
			(type default)
		)
		(layer "In6.Cu")
	)
	(gr_line
		(start 101.8667 -31.487618)
		(end 101.8667 -31.233618)
		(stroke
			(width 0.2)
			(type default)
		)
		(layer "In6.Cu")
	)
	(gr_arc
		(start 101.8667 -31.233618)
		(mid 101.821319 -31.124059)
		(end 101.71176 -31.078678)
		(stroke
			(width 0.2)
			(type default)
		)
		(layer "In6.Cu")
	)
	(gr_line
		(start 101.991922 -35.400234)
		(end 101.992176 -36.199826)
		(stroke
			(width 0.2)
			(type default)
		)
		(layer "In6.Cu")
	)
	(gr_arc
		(start 101.992176 -36.199826)
		(mid 102.350316 -36.55822)
		(end 102.708456 -36.199826)
		(stroke
			(width 0.2)
			(type default)
		)
		(layer "In6.Cu")
	)
	(gr_arc
		(start 102.24262 -32.0294)
		(mid 102.288001 -32.138959)
		(end 102.39756 -32.18434)
		(stroke
			(width 0.2)
			(type default)
		)
		(layer "In6.Cu")
	)
	(gr_line
		(start 102.24262 -31.7754)
		(end 102.24262 -32.0294)
		(stroke
			(width 0.2)
			(type default)
		)
		(layer "In6.Cu")
	)
	(gr_arc
		(start 102.24262 -31.4706)
		(mid 102.288001 -31.580159)
		(end 102.39756 -31.62554)
		(stroke
			(width 0.2)
			(type default)
		)
		(layer "In6.Cu")
	)
	(gr_line
		(start 102.24262 -31.2166)
		(end 102.24262 -31.4706)
		(stroke
			(width 0.2)
			(type default)
		)
		(layer "In6.Cu")
	)
	(gr_circle
		(center 102.350062 -5.999988)
		(end 103.025702 -5.999988)
		(stroke
			(width 0.2)
			(type default)
		)
		(fill no)
		(layer "In6.Cu")
	)
	(gr_line
		(start 102.39756 -32.18434)
		(end 102.60076 -32.18434)
		(stroke
			(width 0.2)
			(type default)
		)
		(layer "In6.Cu")
	)
	(gr_line
		(start 102.39756 -31.62554)
		(end 102.60076 -31.62554)
		(stroke
			(width 0.2)
			(type default)
		)
		(layer "In6.Cu")
	)
	(gr_arc
		(start 102.39756 -31.62046)
		(mid 102.288001 -31.665841)
		(end 102.24262 -31.7754)
		(stroke
			(width 0.2)
			(type default)
		)
		(layer "In6.Cu")
	)
	(gr_arc
		(start 102.39756 -31.06166)
		(mid 102.288001 -31.107041)
		(end 102.24262 -31.2166)
		(stroke
			(width 0.2)
			(type default)
		)
		(layer "In6.Cu")
	)
	(gr_arc
		(start 102.60076 -32.18434)
		(mid 102.710319 -32.138959)
		(end 102.7557 -32.0294)
		(stroke
			(width 0.2)
			(type default)
		)
		(layer "In6.Cu")
	)
	(gr_arc
		(start 102.60076 -31.62554)
		(mid 102.710319 -31.580159)
		(end 102.7557 -31.4706)
		(stroke
			(width 0.2)
			(type default)
		)
		(layer "In6.Cu")
	)
	(gr_line
		(start 102.60076 -31.62046)
		(end 102.39756 -31.62046)
		(stroke
			(width 0.2)
			(type default)
		)
		(layer "In6.Cu")
	)
	(gr_line
		(start 102.60076 -31.06166)
		(end 102.39756 -31.06166)
		(stroke
			(width 0.2)
			(type default)
		)
		(layer "In6.Cu")
	)
	(gr_line
		(start 102.708202 -35.75812)
		(end 102.708202 -35.39998)
		(stroke
			(width 0.2)
			(type default)
		)
		(layer "In6.Cu")
	)
	(gr_arc
		(start 102.708202 -35.39998)
		(mid 102.349935 -35.04184)
		(end 101.991922 -35.400234)
		(stroke
			(width 0.2)
			(type default)
		)
		(layer "In6.Cu")
	)
	(gr_line
		(start 102.708456 -36.199826)
		(end 102.708202 -35.75812)
		(stroke
			(width 0.2)
			(type default)
		)
		(layer "In6.Cu")
	)
	(gr_line
		(start 102.7557 -32.0294)
		(end 102.7557 -31.7754)
		(stroke
			(width 0.2)
			(type default)
		)
		(layer "In6.Cu")
	)
	(gr_arc
		(start 102.7557 -31.7754)
		(mid 102.710319 -31.665841)
		(end 102.60076 -31.62046)
		(stroke
			(width 0.2)
			(type default)
		)
		(layer "In6.Cu")
	)
	(gr_line
		(start 102.7557 -31.4706)
		(end 102.7557 -31.2166)
		(stroke
			(width 0.2)
			(type default)
		)
		(layer "In6.Cu")
	)
	(gr_arc
		(start 102.7557 -31.2166)
		(mid 102.710319 -31.107041)
		(end 102.60076 -31.06166)
		(stroke
			(width 0.2)
			(type default)
		)
		(layer "In6.Cu")
	)
	(gr_arc
		(start 102.792022 -36.199826)
		(mid 103.150035 -36.55822)
		(end 103.508302 -36.20008)
		(stroke
			(width 0.2)
			(type default)
		)
		(layer "In6.Cu")
	)
	(gr_line
		(start 102.792022 -35.400234)
		(end 102.792022 -36.199826)
		(stroke
			(width 0.2)
			(type default)
		)
		(layer "In6.Cu")
	)
	(gr_arc
		(start 102.87762 -32.0294)
		(mid 102.923001 -32.138959)
		(end 103.03256 -32.18434)
		(stroke
			(width 0.2)
			(type default)
		)
		(layer "In6.Cu")
	)
	(gr_line
		(start 102.87762 -31.7754)
		(end 102.87762 -32.0294)
		(stroke
			(width 0.2)
			(type default)
		)
		(layer "In6.Cu")
	)
	(gr_arc
		(start 102.87762 -31.4706)
		(mid 102.923001 -31.580159)
		(end 103.03256 -31.62554)
		(stroke
			(width 0.2)
			(type default)
		)
		(layer "In6.Cu")
	)
	(gr_line
		(start 102.87762 -31.2166)
		(end 102.87762 -31.4706)
		(stroke
			(width 0.2)
			(type default)
		)
		(layer "In6.Cu")
	)
	(gr_line
		(start 103.03256 -32.18434)
		(end 103.23576 -32.18434)
		(stroke
			(width 0.2)
			(type default)
		)
		(layer "In6.Cu")
	)
	(gr_line
		(start 103.03256 -31.62554)
		(end 103.23576 -31.62554)
		(stroke
			(width 0.2)
			(type default)
		)
		(layer "In6.Cu")
	)
	(gr_arc
		(start 103.03256 -31.62046)
		(mid 102.923001 -31.665841)
		(end 102.87762 -31.7754)
		(stroke
			(width 0.2)
			(type default)
		)
		(layer "In6.Cu")
	)
	(gr_arc
		(start 103.03256 -31.06166)
		(mid 102.923001 -31.107041)
		(end 102.87762 -31.2166)
		(stroke
			(width 0.2)
			(type default)
		)
		(layer "In6.Cu")
	)
	(gr_arc
		(start 103.23576 -32.18434)
		(mid 103.345319 -32.138959)
		(end 103.3907 -32.0294)
		(stroke
			(width 0.2)
			(type default)
		)
		(layer "In6.Cu")
	)
	(gr_arc
		(start 103.23576 -31.62554)
		(mid 103.345319 -31.580159)
		(end 103.3907 -31.4706)
		(stroke
			(width 0.2)
			(type default)
		)
		(layer "In6.Cu")
	)
	(gr_line
		(start 103.23576 -31.62046)
		(end 103.03256 -31.62046)
		(stroke
			(width 0.2)
			(type default)
		)
		(layer "In6.Cu")
	)
	(gr_line
		(start 103.23576 -31.06166)
		(end 103.03256 -31.06166)
		(stroke
			(width 0.2)
			(type default)
		)
		(layer "In6.Cu")
	)
	(gr_line
		(start 103.3907 -32.0294)
		(end 103.3907 -31.7754)
		(stroke
			(width 0.2)
			(type default)
		)
		(layer "In6.Cu")
	)
	(gr_arc
		(start 103.3907 -31.7754)
		(mid 103.345319 -31.665841)
		(end 103.23576 -31.62046)
		(stroke
			(width 0.2)
			(type default)
		)
		(layer "In6.Cu")
	)
	(gr_line
		(start 103.3907 -31.4706)
		(end 103.3907 -31.2166)
		(stroke
			(width 0.2)
			(type default)
		)
		(layer "In6.Cu")
	)
	(gr_arc
		(start 103.3907 -31.2166)
		(mid 103.345319 -31.107041)
		(end 103.23576 -31.06166)
		(stroke
			(width 0.2)
			(type default)
		)
		(layer "In6.Cu")
	)
	(gr_line
		(start 103.508302 -36.20008)
		(end 103.508302 -35.400234)
		(stroke
			(width 0.2)
			(type default)
		)
		(layer "In6.Cu")
	)
	(gr_arc
		(start 103.508302 -35.400234)
		(mid 103.150162 -35.042094)
		(end 102.792022 -35.400234)
		(stroke
			(width 0.2)
			(type default)
		)
		(layer "In6.Cu")
	)
	(gr_arc
		(start 103.76662 -32.0294)
		(mid 103.812001 -32.138959)
		(end 103.92156 -32.18434)
		(stroke
			(width 0.2)
			(type default)
		)
		(layer "In6.Cu")
	)
	(gr_line
		(start 103.76662 -31.7754)
		(end 103.76662 -32.0294)
		(stroke
			(width 0.2)
			(type default)
		)
		(layer "In6.Cu")
	)
	(gr_arc
		(start 103.76662 -31.4706)
		(mid 103.812001 -31.580159)
		(end 103.92156 -31.62554)
		(stroke
			(width 0.2)
			(type default)
		)
		(layer "In6.Cu")
	)
	(gr_line
		(start 103.76662 -31.2166)
		(end 103.76662 -31.4706)
		(stroke
			(width 0.2)
			(type default)
		)
		(layer "In6.Cu")
	)
	(gr_line
		(start 103.92156 -32.18434)
		(end 104.12476 -32.18434)
		(stroke
			(width 0.2)
			(type default)
		)
		(layer "In6.Cu")
	)
	(gr_line
		(start 103.92156 -31.62554)
		(end 104.12476 -31.62554)
		(stroke
			(width 0.2)
			(type default)
		)
		(layer "In6.Cu")
	)
	(gr_arc
		(start 103.92156 -31.62046)
		(mid 103.812001 -31.665841)
		(end 103.76662 -31.7754)
		(stroke
			(width 0.2)
			(type default)
		)
		(layer "In6.Cu")
	)
	(gr_arc
		(start 103.92156 -31.06166)
		(mid 103.812001 -31.107041)
		(end 103.76662 -31.2166)
		(stroke
			(width 0.2)
			(type default)
		)
		(layer "In6.Cu")
	)
	(gr_arc
		(start 104.12476 -32.18434)
		(mid 104.234319 -32.138959)
		(end 104.2797 -32.0294)
		(stroke
			(width 0.2)
			(type default)
		)
		(layer "In6.Cu")
	)
	(gr_arc
		(start 104.12476 -31.62554)
		(mid 104.234319 -31.580159)
		(end 104.2797 -31.4706)
		(stroke
			(width 0.2)
			(type default)
		)
		(layer "In6.Cu")
	)
	(gr_line
		(start 104.12476 -31.62046)
		(end 103.92156 -31.62046)
		(stroke
			(width 0.2)
			(type default)
		)
		(layer "In6.Cu")
	)
	(gr_line
		(start 104.12476 -31.06166)
		(end 103.92156 -31.06166)
		(stroke
			(width 0.2)
			(type default)
		)
		(layer "In6.Cu")
	)
	(gr_line
		(start 104.2797 -32.0294)
		(end 104.2797 -31.7754)
		(stroke
			(width 0.2)
			(type default)
		)
		(layer "In6.Cu")
	)
	(gr_arc
		(start 104.2797 -31.7754)
		(mid 104.234319 -31.665841)
		(end 104.12476 -31.62046)
		(stroke
			(width 0.2)
			(type default)
		)
		(layer "In6.Cu")
	)
	(gr_line
		(start 104.2797 -31.4706)
		(end 104.2797 -31.2166)
		(stroke
			(width 0.2)
			(type default)
		)
		(layer "In6.Cu")
	)
	(gr_arc
		(start 104.2797 -31.2166)
		(mid 104.234319 -31.107041)
		(end 104.12476 -31.06166)
		(stroke
			(width 0.2)
			(type default)
		)
		(layer "In6.Cu")
	)
	(gr_arc
		(start 104.40162 -32.0294)
		(mid 104.447001 -32.138959)
		(end 104.55656 -32.18434)
		(stroke
			(width 0.2)
			(type default)
		)
		(layer "In6.Cu")
	)
	(gr_line
		(start 104.40162 -31.7754)
		(end 104.40162 -32.0294)
		(stroke
			(width 0.2)
			(type default)
		)
		(layer "In6.Cu")
	)
	(gr_arc
		(start 104.40162 -31.4706)
		(mid 104.447001 -31.580159)
		(end 104.55656 -31.62554)
		(stroke
			(width 0.2)
			(type default)
		)
		(layer "In6.Cu")
	)
	(gr_line
		(start 104.40162 -31.2166)
		(end 104.40162 -31.4706)
		(stroke
			(width 0.2)
			(type default)
		)
		(layer "In6.Cu")
	)
	(gr_line
		(start 104.55656 -32.18434)
		(end 104.75976 -32.18434)
		(stroke
			(width 0.2)
			(type default)
		)
		(layer "In6.Cu")
	)
	(gr_line
		(start 104.55656 -31.62554)
		(end 104.75976 -31.62554)
		(stroke
			(width 0.2)
			(type default)
		)
		(layer "In6.Cu")
	)
	(gr_arc
		(start 104.55656 -31.62046)
		(mid 104.447001 -31.665841)
		(end 104.40162 -31.7754)
		(stroke
			(width 0.2)
			(type default)
		)
		(layer "In6.Cu")
	)
	(gr_arc
		(start 104.55656 -31.06166)
		(mid 104.447001 -31.107041)
		(end 104.40162 -31.2166)
		(stroke
			(width 0.2)
			(type default)
		)
		(layer "In6.Cu")
	)
	(gr_arc
		(start 104.75976 -32.18434)
		(mid 104.869319 -32.138959)
		(end 104.9147 -32.0294)
		(stroke
			(width 0.2)
			(type default)
		)
		(layer "In6.Cu")
	)
	(gr_arc
		(start 104.75976 -31.62554)
		(mid 104.869319 -31.580159)
		(end 104.9147 -31.4706)
		(stroke
			(width 0.2)
			(type default)
		)
		(layer "In6.Cu")
	)
	(gr_line
		(start 104.75976 -31.62046)
		(end 104.55656 -31.62046)
		(stroke
			(width 0.2)
			(type default)
		)
		(layer "In6.Cu")
	)
	(gr_line
		(start 104.75976 -31.06166)
		(end 104.55656 -31.06166)
		(stroke
			(width 0.2)
			(type default)
		)
		(layer "In6.Cu")
	)
	(gr_line
		(start 104.9147 -32.0294)
		(end 104.9147 -31.7754)
		(stroke
			(width 0.2)
			(type default)
		)
		(layer "In6.Cu")
	)
	(gr_arc
		(start 104.9147 -31.7754)
		(mid 104.869319 -31.665841)
		(end 104.75976 -31.62046)
		(stroke
			(width 0.2)
			(type default)
		)
		(layer "In6.Cu")
	)
	(gr_line
		(start 104.9147 -31.4706)
		(end 104.9147 -31.2166)
		(stroke
			(width 0.2)
			(type default)
		)
		(layer "In6.Cu")
	)
	(gr_arc
		(start 104.9147 -31.2166)
		(mid 104.869319 -31.107041)
		(end 104.75976 -31.06166)
		(stroke
			(width 0.2)
			(type default)
		)
		(layer "In6.Cu")
	)
	(gr_circle
		(center 104.950006 -5.999988)
		(end 105.625646 -5.999988)
		(stroke
			(width 0.2)
			(type default)
		)
		(fill no)
		(layer "In6.Cu")
	)
	(gr_arc
		(start 106.491532 -103.850186)
		(mid 106.849672 -104.208326)
		(end 107.207812 -103.850186)
		(stroke
			(width 0.2)
			(type default)
		)
		(layer "In6.Cu")
	)
	(gr_line
		(start 106.491532 -102.850188)
		(end 106.491532 -103.850186)
		(stroke
			(width 0.2)
			(type default)
		)
		(layer "In6.Cu")
	)
	(gr_line
		(start 107.207812 -103.850186)
		(end 107.207812 -102.850442)
		(stroke
			(width 0.2)
			(type default)
		)
		(layer "In6.Cu")
	)
	(gr_arc
		(start 107.207812 -102.850442)
		(mid 106.849799 -102.492048)
		(end 106.491532 -102.850188)
		(stroke
			(width 0.2)
			(type default)
		)
		(layer "In6.Cu")
	)
	(gr_arc
		(start 107.49153 -103.850186)
		(mid 107.84967 -104.208326)
		(end 108.20781 -103.850186)
		(stroke
			(width 0.2)
			(type default)
		)
		(layer "In6.Cu")
	)
	(gr_line
		(start 107.49153 -102.850188)
		(end 107.49153 -103.850186)
		(stroke
			(width 0.2)
			(type default)
		)
		(layer "In6.Cu")
	)
	(gr_circle
		(center 107.54995 -5.999988)
		(end 108.22559 -5.999988)
		(stroke
			(width 0.2)
			(type default)
		)
		(fill no)
		(layer "In6.Cu")
	)
	(gr_arc
		(start 107.637072 -206.4766)
		(mid 107.697332 -206.62208)
		(end 107.842812 -206.68234)
		(stroke
			(width 0.2)
			(type default)
		)
		(layer "In6.Cu")
	)
	(gr_line
		(start 107.637072 -206.121)
		(end 107.637072 -206.4766)
		(stroke
			(width 0.2)
			(type default)
		)
		(layer "In6.Cu")
	)
	(gr_arc
		(start 107.637072 -205.613)
		(mid 107.697332 -205.75848)
		(end 107.842812 -205.81874)
		(stroke
			(width 0.2)
			(type default)
		)
		(layer "In6.Cu")
	)
	(gr_line
		(start 107.637072 -205.2574)
		(end 107.637072 -205.613)
		(stroke
			(width 0.2)
			(type default)
		)
		(layer "In6.Cu")
	)
	(gr_arc
		(start 107.637072 -204.724)
		(mid 107.697332 -204.86948)
		(end 107.842812 -204.92974)
		(stroke
			(width 0.2)
			(type default)
		)
		(layer "In6.Cu")
	)
	(gr_line
		(start 107.637072 -204.3684)
		(end 107.637072 -204.724)
		(stroke
			(width 0.2)
			(type default)
		)
		(layer "In6.Cu")
	)
	(gr_line
		(start 107.842812 -206.68234)
		(end 108.198412 -206.68234)
		(stroke
			(width 0.2)
			(type default)
		)
		(layer "In6.Cu")
	)
	(gr_arc
		(start 107.842812 -205.91526)
		(mid 107.697332 -205.97552)
		(end 107.637072 -206.121)
		(stroke
			(width 0.2)
			(type default)
		)
		(layer "In6.Cu")
	)
	(gr_line
		(start 107.842812 -205.81874)
		(end 108.198412 -205.81874)
		(stroke
			(width 0.2)
			(type default)
		)
		(layer "In6.Cu")
	)
	(gr_arc
		(start 107.842812 -205.05166)
		(mid 107.697332 -205.11192)
		(end 107.637072 -205.2574)
		(stroke
			(width 0.2)
			(type default)
		)
		(layer "In6.Cu")
	)
	(gr_line
		(start 107.842812 -204.92974)
		(end 108.198412 -204.92974)
		(stroke
			(width 0.2)
			(type default)
		)
		(layer "In6.Cu")
	)
	(gr_arc
		(start 107.842812 -204.16266)
		(mid 107.697332 -204.22292)
		(end 107.637072 -204.3684)
		(stroke
			(width 0.2)
			(type default)
		)
		(layer "In6.Cu")
	)
	(gr_arc
		(start 108.198412 -206.68234)
		(mid 108.343892 -206.62208)
		(end 108.404152 -206.4766)
		(stroke
			(width 0.2)
			(type default)
		)
		(layer "In6.Cu")
	)
	(gr_line
		(start 108.198412 -205.91526)
		(end 107.842812 -205.91526)
		(stroke
			(width 0.2)
			(type default)
		)
		(layer "In6.Cu")
	)
	(gr_arc
		(start 108.198412 -205.81874)
		(mid 108.343892 -205.75848)
		(end 108.404152 -205.613)
		(stroke
			(width 0.2)
			(type default)
		)
		(layer "In6.Cu")
	)
	(gr_line
		(start 108.198412 -205.05166)
		(end 107.842812 -205.05166)
		(stroke
			(width 0.2)
			(type default)
		)
		(layer "In6.Cu")
	)
	(gr_arc
		(start 108.198412 -204.92974)
		(mid 108.343892 -204.86948)
		(end 108.404152 -204.724)
		(stroke
			(width 0.2)
			(type default)
		)
		(layer "In6.Cu")
	)
	(gr_line
		(start 108.198412 -204.16266)
		(end 107.842812 -204.16266)
		(stroke
			(width 0.2)
			(type default)
		)
		(layer "In6.Cu")
	)
	(gr_line
		(start 108.20781 -103.850186)
		(end 108.20781 -102.850442)
		(stroke
			(width 0.2)
			(type default)
		)
		(layer "In6.Cu")
	)
	(gr_arc
		(start 108.20781 -102.850442)
		(mid 107.849797 -102.492048)
		(end 107.49153 -102.850188)
		(stroke
			(width 0.2)
			(type default)
		)
		(layer "In6.Cu")
	)
	(gr_line
		(start 108.404152 -206.4766)
		(end 108.404152 -206.121)
		(stroke
			(width 0.2)
			(type default)
		)
		(layer "In6.Cu")
	)
	(gr_arc
		(start 108.404152 -206.121)
		(mid 108.343892 -205.97552)
		(end 108.198412 -205.91526)
		(stroke
			(width 0.2)
			(type default)
		)
		(layer "In6.Cu")
	)
	(gr_line
		(start 108.404152 -205.613)
		(end 108.404152 -205.2574)
		(stroke
			(width 0.2)
			(type default)
		)
		(layer "In6.Cu")
	)
	(gr_arc
		(start 108.404152 -205.2574)
		(mid 108.343892 -205.11192)
		(end 108.198412 -205.05166)
		(stroke
			(width 0.2)
			(type default)
		)
		(layer "In6.Cu")
	)
	(gr_line
		(start 108.404152 -204.724)
		(end 108.404152 -204.3684)
		(stroke
			(width 0.2)
			(type default)
		)
		(layer "In6.Cu")
	)
	(gr_arc
		(start 108.404152 -204.3684)
		(mid 108.343892 -204.22292)
		(end 108.198412 -204.16266)
		(stroke
			(width 0.2)
			(type default)
		)
		(layer "In6.Cu")
	)
	(gr_arc
		(start 108.491528 -103.849932)
		(mid 108.849541 -104.208326)
		(end 109.207808 -103.850186)
		(stroke
			(width 0.2)
			(type default)
		)
		(layer "In6.Cu")
	)
	(gr_line
		(start 108.491528 -102.850188)
		(end 108.491528 -103.849932)
		(stroke
			(width 0.2)
			(type default)
		)
		(layer "In6.Cu")
	)
	(gr_arc
		(start 109.161072 -223.4946)
		(mid 109.221332 -223.64008)
		(end 109.366812 -223.70034)
		(stroke
			(width 0.2)
			(type default)
		)
		(layer "In6.Cu")
	)
	(gr_line
		(start 109.161072 -223.139)
		(end 109.161072 -223.4946)
		(stroke
			(width 0.2)
			(type default)
		)
		(layer "In6.Cu")
	)
	(gr_arc
		(start 109.161072 -222.6056)
		(mid 109.221332 -222.75108)
		(end 109.366812 -222.81134)
		(stroke
			(width 0.2)
			(type default)
		)
		(layer "In6.Cu")
	)
	(gr_line
		(start 109.161072 -222.25)
		(end 109.161072 -222.6056)
		(stroke
			(width 0.2)
			(type default)
		)
		(layer "In6.Cu")
	)
	(gr_arc
		(start 109.161072 -221.742)
		(mid 109.221332 -221.88748)
		(end 109.366812 -221.94774)
		(stroke
			(width 0.2)
			(type default)
		)
		(layer "In6.Cu")
	)
	(gr_line
		(start 109.161072 -221.3864)
		(end 109.161072 -221.742)
		(stroke
			(width 0.2)
			(type default)
		)
		(layer "In6.Cu")
	)
	(gr_line
		(start 109.207808 -103.850186)
		(end 109.207808 -102.850188)
		(stroke
			(width 0.2)
			(type default)
		)
		(layer "In6.Cu")
	)
	(gr_arc
		(start 109.207808 -102.850188)
		(mid 108.849668 -102.492048)
		(end 108.491528 -102.850188)
		(stroke
			(width 0.2)
			(type default)
		)
		(layer "In6.Cu")
	)
	(gr_arc
		(start 109.288072 -206.4766)
		(mid 109.348332 -206.62208)
		(end 109.493812 -206.68234)
		(stroke
			(width 0.2)
			(type default)
		)
		(layer "In6.Cu")
	)
	(gr_line
		(start 109.288072 -206.121)
		(end 109.288072 -206.4766)
		(stroke
			(width 0.2)
			(type default)
		)
		(layer "In6.Cu")
	)
	(gr_arc
		(start 109.288072 -205.613)
		(mid 109.348332 -205.75848)
		(end 109.493812 -205.81874)
		(stroke
			(width 0.2)
			(type default)
		)
		(layer "In6.Cu")
	)
	(gr_line
		(start 109.288072 -205.2574)
		(end 109.288072 -205.613)
		(stroke
			(width 0.2)
			(type default)
		)
		(layer "In6.Cu")
	)
	(gr_arc
		(start 109.288072 -204.724)
		(mid 109.348332 -204.86948)
		(end 109.493812 -204.92974)
		(stroke
			(width 0.2)
			(type default)
		)
		(layer "In6.Cu")
	)
	(gr_line
		(start 109.288072 -204.3684)
		(end 109.288072 -204.724)
		(stroke
			(width 0.2)
			(type default)
		)
		(layer "In6.Cu")
	)
	(gr_line
		(start 109.366812 -223.70034)
		(end 109.722412 -223.70034)
		(stroke
			(width 0.2)
			(type default)
		)
		(layer "In6.Cu")
	)
	(gr_arc
		(start 109.366812 -222.93326)
		(mid 109.221332 -222.99352)
		(end 109.161072 -223.139)
		(stroke
			(width 0.2)
			(type default)
		)
		(layer "In6.Cu")
	)
	(gr_line
		(start 109.366812 -222.81134)
		(end 109.722412 -222.81134)
		(stroke
			(width 0.2)
			(type default)
		)
		(layer "In6.Cu")
	)
	(gr_arc
		(start 109.366812 -222.04426)
		(mid 109.221332 -222.10452)
		(end 109.161072 -222.25)
		(stroke
			(width 0.2)
			(type default)
		)
		(layer "In6.Cu")
	)
	(gr_line
		(start 109.366812 -221.94774)
		(end 109.722412 -221.94774)
		(stroke
			(width 0.2)
			(type default)
		)
		(layer "In6.Cu")
	)
	(gr_arc
		(start 109.366812 -221.18066)
		(mid 109.221332 -221.24092)
		(end 109.161072 -221.3864)
		(stroke
			(width 0.2)
			(type default)
		)
		(layer "In6.Cu")
	)
	(gr_arc
		(start 109.491526 -103.849932)
		(mid 109.849539 -104.208326)
		(end 110.207806 -103.850186)
		(stroke
			(width 0.2)
			(type default)
		)
		(layer "In6.Cu")
	)
	(gr_line
		(start 109.491526 -102.850188)
		(end 109.491526 -103.849932)
		(stroke
			(width 0.2)
			(type default)
		)
		(layer "In6.Cu")
	)
	(gr_line
		(start 109.493812 -206.68234)
		(end 109.849412 -206.68234)
		(stroke
			(width 0.2)
			(type default)
		)
		(layer "In6.Cu")
	)
	(gr_arc
		(start 109.493812 -205.91526)
		(mid 109.348332 -205.97552)
		(end 109.288072 -206.121)
		(stroke
			(width 0.2)
			(type default)
		)
		(layer "In6.Cu")
	)
	(gr_line
		(start 109.493812 -205.81874)
		(end 109.849412 -205.81874)
		(stroke
			(width 0.2)
			(type default)
		)
		(layer "In6.Cu")
	)
	(gr_arc
		(start 109.493812 -205.05166)
		(mid 109.348332 -205.11192)
		(end 109.288072 -205.2574)
		(stroke
			(width 0.2)
			(type default)
		)
		(layer "In6.Cu")
	)
	(gr_line
		(start 109.493812 -204.92974)
		(end 109.849412 -204.92974)
		(stroke
			(width 0.2)
			(type default)
		)
		(layer "In6.Cu")
	)
	(gr_arc
		(start 109.493812 -204.16266)
		(mid 109.348332 -204.22292)
		(end 109.288072 -204.3684)
		(stroke
			(width 0.2)
			(type default)
		)
		(layer "In6.Cu")
	)
	(gr_arc
		(start 109.722412 -223.70034)
		(mid 109.867892 -223.64008)
		(end 109.928152 -223.4946)
		(stroke
			(width 0.2)
			(type default)
		)
		(layer "In6.Cu")
	)
	(gr_line
		(start 109.722412 -222.93326)
		(end 109.366812 -222.93326)
		(stroke
			(width 0.2)
			(type default)
		)
		(layer "In6.Cu")
	)
	(gr_arc
		(start 109.722412 -222.81134)
		(mid 109.867892 -222.75108)
		(end 109.928152 -222.6056)
		(stroke
			(width 0.2)
			(type default)
		)
		(layer "In6.Cu")
	)
	(gr_line
		(start 109.722412 -222.04426)
		(end 109.366812 -222.04426)
		(stroke
			(width 0.2)
			(type default)
		)
		(layer "In6.Cu")
	)
	(gr_arc
		(start 109.722412 -221.94774)
		(mid 109.867892 -221.88748)
		(end 109.928152 -221.742)
		(stroke
			(width 0.2)
			(type default)
		)
		(layer "In6.Cu")
	)
	(gr_line
		(start 109.722412 -221.18066)
		(end 109.366812 -221.18066)
		(stroke
			(width 0.2)
			(type default)
		)
		(layer "In6.Cu")
	)
	(gr_arc
		(start 109.849412 -206.68234)
		(mid 109.994892 -206.62208)
		(end 110.055152 -206.4766)
		(stroke
			(width 0.2)
			(type default)
		)
		(layer "In6.Cu")
	)
	(gr_line
		(start 109.849412 -205.91526)
		(end 109.493812 -205.91526)
		(stroke
			(width 0.2)
			(type default)
		)
		(layer "In6.Cu")
	)
	(gr_arc
		(start 109.849412 -205.81874)
		(mid 109.994892 -205.75848)
		(end 110.055152 -205.613)
		(stroke
			(width 0.2)
			(type default)
		)
		(layer "In6.Cu")
	)
	(gr_line
		(start 109.849412 -205.05166)
		(end 109.493812 -205.05166)
		(stroke
			(width 0.2)
			(type default)
		)
		(layer "In6.Cu")
	)
	(gr_arc
		(start 109.849412 -204.92974)
		(mid 109.994892 -204.86948)
		(end 110.055152 -204.724)
		(stroke
			(width 0.2)
			(type default)
		)
		(layer "In6.Cu")
	)
	(gr_line
		(start 109.849412 -204.16266)
		(end 109.493812 -204.16266)
		(stroke
			(width 0.2)
			(type default)
		)
		(layer "In6.Cu")
	)
	(gr_line
		(start 109.928152 -223.4946)
		(end 109.928152 -223.139)
		(stroke
			(width 0.2)
			(type default)
		)
		(layer "In6.Cu")
	)
	(gr_arc
		(start 109.928152 -223.139)
		(mid 109.867892 -222.99352)
		(end 109.722412 -222.93326)
		(stroke
			(width 0.2)
			(type default)
		)
		(layer "In6.Cu")
	)
	(gr_line
		(start 109.928152 -222.6056)
		(end 109.928152 -222.25)
		(stroke
			(width 0.2)
			(type default)
		)
		(layer "In6.Cu")
	)
	(gr_arc
		(start 109.928152 -222.25)
		(mid 109.867892 -222.10452)
		(end 109.722412 -222.04426)
		(stroke
			(width 0.2)
			(type default)
		)
		(layer "In6.Cu")
	)
	(gr_line
		(start 109.928152 -221.742)
		(end 109.928152 -221.3864)
		(stroke
			(width 0.2)
			(type default)
		)
		(layer "In6.Cu")
	)
	(gr_arc
		(start 109.928152 -221.3864)
		(mid 109.867892 -221.24092)
		(end 109.722412 -221.18066)
		(stroke
			(width 0.2)
			(type default)
		)
		(layer "In6.Cu")
	)
	(gr_line
		(start 110.055152 -206.4766)
		(end 110.055152 -206.121)
		(stroke
			(width 0.2)
			(type default)
		)
		(layer "In6.Cu")
	)
	(gr_arc
		(start 110.055152 -206.121)
		(mid 109.994892 -205.97552)
		(end 109.849412 -205.91526)
		(stroke
			(width 0.2)
			(type default)
		)
		(layer "In6.Cu")
	)
	(gr_line
		(start 110.055152 -205.613)
		(end 110.055152 -205.2574)
		(stroke
			(width 0.2)
			(type default)
		)
		(layer "In6.Cu")
	)
	(gr_arc
		(start 110.055152 -205.2574)
		(mid 109.994892 -205.11192)
		(end 109.849412 -205.05166)
		(stroke
			(width 0.2)
			(type default)
		)
		(layer "In6.Cu")
	)
	(gr_line
		(start 110.055152 -204.724)
		(end 110.055152 -204.3684)
		(stroke
			(width 0.2)
			(type default)
		)
		(layer "In6.Cu")
	)
	(gr_arc
		(start 110.055152 -204.3684)
		(mid 109.994892 -204.22292)
		(end 109.849412 -204.16266)
		(stroke
			(width 0.2)
			(type default)
		)
		(layer "In6.Cu")
	)
	(gr_line
		(start 110.207806 -103.850186)
		(end 110.207806 -102.850188)
		(stroke
			(width 0.2)
			(type default)
		)
		(layer "In6.Cu")
	)
	(gr_arc
		(start 110.207806 -102.850188)
		(mid 109.849666 -102.492048)
		(end 109.491526 -102.850188)
		(stroke
			(width 0.2)
			(type default)
		)
		(layer "In6.Cu")
	)
	(gr_arc
		(start 110.491524 -103.850186)
		(mid 110.849664 -104.208326)
		(end 111.207804 -103.850186)
		(stroke
			(width 0.2)
			(type default)
		)
		(layer "In6.Cu")
	)
	(gr_line
		(start 110.491524 -102.850188)
		(end 110.491524 -103.850186)
		(stroke
			(width 0.2)
			(type default)
		)
		(layer "In6.Cu")
	)
	(gr_arc
		(start 110.812072 -223.4946)
		(mid 110.872332 -223.64008)
		(end 111.017812 -223.70034)
		(stroke
			(width 0.2)
			(type default)
		)
		(layer "In6.Cu")
	)
	(gr_line
		(start 110.812072 -223.139)
		(end 110.812072 -223.4946)
		(stroke
			(width 0.2)
			(type default)
		)
		(layer "In6.Cu")
	)
	(gr_arc
		(start 110.812072 -222.631)
		(mid 110.872332 -222.77648)
		(end 111.017812 -222.83674)
		(stroke
			(width 0.2)
			(type default)
		)
		(layer "In6.Cu")
	)
	(gr_line
		(start 110.812072 -222.2754)
		(end 110.812072 -222.631)
		(stroke
			(width 0.2)
			(type default)
		)
		(layer "In6.Cu")
	)
	(gr_arc
		(start 110.812072 -221.742)
		(mid 110.872332 -221.88748)
		(end 111.017812 -221.94774)
		(stroke
			(width 0.2)
			(type default)
		)
		(layer "In6.Cu")
	)
	(gr_line
		(start 110.812072 -221.3864)
		(end 110.812072 -221.742)
		(stroke
			(width 0.2)
			(type default)
		)
		(layer "In6.Cu")
	)
	(gr_line
		(start 111.017812 -223.70034)
		(end 111.373412 -223.70034)
		(stroke
			(width 0.2)
			(type default)
		)
		(layer "In6.Cu")
	)
	(gr_arc
		(start 111.017812 -222.93326)
		(mid 110.872332 -222.99352)
		(end 110.812072 -223.139)
		(stroke
			(width 0.2)
			(type default)
		)
		(layer "In6.Cu")
	)
	(gr_line
		(start 111.017812 -222.83674)
		(end 111.373412 -222.83674)
		(stroke
			(width 0.2)
			(type default)
		)
		(layer "In6.Cu")
	)
	(gr_arc
		(start 111.017812 -222.06966)
		(mid 110.872332 -222.12992)
		(end 110.812072 -222.2754)
		(stroke
			(width 0.2)
			(type default)
		)
		(layer "In6.Cu")
	)
	(gr_line
		(start 111.017812 -221.94774)
		(end 111.373412 -221.94774)
		(stroke
			(width 0.2)
			(type default)
		)
		(layer "In6.Cu")
	)
	(gr_arc
		(start 111.017812 -221.18066)
		(mid 110.872332 -221.24092)
		(end 110.812072 -221.3864)
		(stroke
			(width 0.2)
			(type default)
		)
		(layer "In6.Cu")
	)
	(gr_line
		(start 111.207804 -103.850186)
		(end 111.207804 -102.850442)
		(stroke
			(width 0.2)
			(type default)
		)
		(layer "In6.Cu")
	)
	(gr_arc
		(start 111.207804 -102.850442)
		(mid 110.849791 -102.492048)
		(end 110.491524 -102.850188)
		(stroke
			(width 0.2)
			(type default)
		)
		(layer "In6.Cu")
	)
	(gr_arc
		(start 111.373412 -223.70034)
		(mid 111.518892 -223.64008)
		(end 111.579152 -223.4946)
		(stroke
			(width 0.2)
			(type default)
		)
		(layer "In6.Cu")
	)
	(gr_line
		(start 111.373412 -222.93326)
		(end 111.017812 -222.93326)
		(stroke
			(width 0.2)
			(type default)
		)
		(layer "In6.Cu")
	)
	(gr_arc
		(start 111.373412 -222.83674)
		(mid 111.518892 -222.77648)
		(end 111.579152 -222.631)
		(stroke
			(width 0.2)
			(type default)
		)
		(layer "In6.Cu")
	)
	(gr_line
		(start 111.373412 -222.06966)
		(end 111.017812 -222.06966)
		(stroke
			(width 0.2)
			(type default)
		)
		(layer "In6.Cu")
	)
	(gr_arc
		(start 111.373412 -221.94774)
		(mid 111.518892 -221.88748)
		(end 111.579152 -221.742)
		(stroke
			(width 0.2)
			(type default)
		)
		(layer "In6.Cu")
	)
	(gr_line
		(start 111.373412 -221.18066)
		(end 111.017812 -221.18066)
		(stroke
			(width 0.2)
			(type default)
		)
		(layer "In6.Cu")
	)
	(gr_arc
		(start 111.491522 -103.849932)
		(mid 111.849535 -104.208326)
		(end 112.207802 -103.850186)
		(stroke
			(width 0.2)
			(type default)
		)
		(layer "In6.Cu")
	)
	(gr_line
		(start 111.491522 -102.850188)
		(end 111.491522 -103.849932)
		(stroke
			(width 0.2)
			(type default)
		)
		(layer "In6.Cu")
	)
	(gr_line
		(start 111.579152 -223.4946)
		(end 111.579152 -223.139)
		(stroke
			(width 0.2)
			(type default)
		)
		(layer "In6.Cu")
	)
	(gr_arc
		(start 111.579152 -223.139)
		(mid 111.518892 -222.99352)
		(end 111.373412 -222.93326)
		(stroke
			(width 0.2)
			(type default)
		)
		(layer "In6.Cu")
	)
	(gr_line
		(start 111.579152 -222.631)
		(end 111.579152 -222.2754)
		(stroke
			(width 0.2)
			(type default)
		)
		(layer "In6.Cu")
	)
	(gr_arc
		(start 111.579152 -222.2754)
		(mid 111.518892 -222.12992)
		(end 111.373412 -222.06966)
		(stroke
			(width 0.2)
			(type default)
		)
		(layer "In6.Cu")
	)
	(gr_line
		(start 111.579152 -221.742)
		(end 111.579152 -221.3864)
		(stroke
			(width 0.2)
			(type default)
		)
		(layer "In6.Cu")
	)
	(gr_arc
		(start 111.579152 -221.3864)
		(mid 111.518892 -221.24092)
		(end 111.373412 -221.18066)
		(stroke
			(width 0.2)
			(type default)
		)
		(layer "In6.Cu")
	)
	(gr_line
		(start 112.207802 -103.850186)
		(end 112.207802 -102.850188)
		(stroke
			(width 0.2)
			(type default)
		)
		(layer "In6.Cu")
	)
	(gr_arc
		(start 112.207802 -102.850188)
		(mid 111.849662 -102.492048)
		(end 111.491522 -102.850188)
		(stroke
			(width 0.2)
			(type default)
		)
		(layer "In6.Cu")
	)
	(gr_arc
		(start 112.49152 -103.850186)
		(mid 112.84966 -104.208326)
		(end 113.2078 -103.850186)
		(stroke
			(width 0.2)
			(type default)
		)
		(layer "In6.Cu")
	)
	(gr_line
		(start 112.49152 -102.850188)
		(end 112.49152 -103.850186)
		(stroke
			(width 0.2)
			(type default)
		)
		(layer "In6.Cu")
	)
	(gr_line
		(start 113.2078 -103.850186)
		(end 113.2078 -102.850442)
		(stroke
			(width 0.2)
			(type default)
		)
		(layer "In6.Cu")
	)
	(gr_arc
		(start 113.2078 -102.850442)
		(mid 112.849787 -102.492048)
		(end 112.49152 -102.850188)
		(stroke
			(width 0.2)
			(type default)
		)
		(layer "In6.Cu")
	)
	(gr_arc
		(start 113.491518 -103.849932)
		(mid 113.849531 -104.208326)
		(end 114.207798 -103.850186)
		(stroke
			(width 0.2)
			(type default)
		)
		(layer "In6.Cu")
	)
	(gr_line
		(start 113.491518 -102.850188)
		(end 113.491518 -103.849932)
		(stroke
			(width 0.2)
			(type default)
		)
		(layer "In6.Cu")
	)
	(gr_line
		(start 114.207798 -103.850186)
		(end 114.207798 -102.850188)
		(stroke
			(width 0.2)
			(type default)
		)
		(layer "In6.Cu")
	)
	(gr_arc
		(start 114.207798 -102.850188)
		(mid 113.849658 -102.492048)
		(end 113.491518 -102.850188)
		(stroke
			(width 0.2)
			(type default)
		)
		(layer "In6.Cu")
	)
	(gr_arc
		(start 114.506502 -103.830882)
		(mid 114.864642 -104.189022)
		(end 115.222782 -103.830882)
		(stroke
			(width 0.2)
			(type default)
		)
		(layer "In6.Cu")
	)
	(gr_line
		(start 114.506502 -102.840282)
		(end 114.506502 -103.830882)
		(stroke
			(width 0.2)
			(type default)
		)
		(layer "In6.Cu")
	)
	(gr_line
		(start 115.222782 -103.830882)
		(end 115.222782 -102.840536)
		(stroke
			(width 0.2)
			(type default)
		)
		(layer "In6.Cu")
	)
	(gr_arc
		(start 115.222782 -102.840536)
		(mid 114.864769 -102.482142)
		(end 114.506502 -102.840282)
		(stroke
			(width 0.2)
			(type default)
		)
		(layer "In6.Cu")
	)
	(gr_arc
		(start 115.511072 -206.4766)
		(mid 115.571332 -206.62208)
		(end 115.716812 -206.68234)
		(stroke
			(width 0.2)
			(type default)
		)
		(layer "In6.Cu")
	)
	(gr_line
		(start 115.511072 -206.121)
		(end 115.511072 -206.4766)
		(stroke
			(width 0.2)
			(type default)
		)
		(layer "In6.Cu")
	)
	(gr_arc
		(start 115.511072 -205.613)
		(mid 115.571332 -205.75848)
		(end 115.716812 -205.81874)
		(stroke
			(width 0.2)
			(type default)
		)
		(layer "In6.Cu")
	)
	(gr_line
		(start 115.511072 -205.2574)
		(end 115.511072 -205.613)
		(stroke
			(width 0.2)
			(type default)
		)
		(layer "In6.Cu")
	)
	(gr_arc
		(start 115.511072 -204.724)
		(mid 115.571332 -204.86948)
		(end 115.716812 -204.92974)
		(stroke
			(width 0.2)
			(type default)
		)
		(layer "In6.Cu")
	)
	(gr_line
		(start 115.511072 -204.3684)
		(end 115.511072 -204.724)
		(stroke
			(width 0.2)
			(type default)
		)
		(layer "In6.Cu")
	)
	(gr_arc
		(start 115.522502 -103.830882)
		(mid 115.880642 -104.189022)
		(end 116.238782 -103.830882)
		(stroke
			(width 0.2)
			(type default)
		)
		(layer "In6.Cu")
	)
	(gr_line
		(start 115.522502 -102.840282)
		(end 115.522502 -103.830882)
		(stroke
			(width 0.2)
			(type default)
		)
		(layer "In6.Cu")
	)
	(gr_line
		(start 115.716812 -206.68234)
		(end 116.072412 -206.68234)
		(stroke
			(width 0.2)
			(type default)
		)
		(layer "In6.Cu")
	)
	(gr_arc
		(start 115.716812 -205.91526)
		(mid 115.571332 -205.97552)
		(end 115.511072 -206.121)
		(stroke
			(width 0.2)
			(type default)
		)
		(layer "In6.Cu")
	)
	(gr_line
		(start 115.716812 -205.81874)
		(end 116.072412 -205.81874)
		(stroke
			(width 0.2)
			(type default)
		)
		(layer "In6.Cu")
	)
	(gr_arc
		(start 115.716812 -205.05166)
		(mid 115.571332 -205.11192)
		(end 115.511072 -205.2574)
		(stroke
			(width 0.2)
			(type default)
		)
		(layer "In6.Cu")
	)
	(gr_line
		(start 115.716812 -204.92974)
		(end 116.072412 -204.92974)
		(stroke
			(width 0.2)
			(type default)
		)
		(layer "In6.Cu")
	)
	(gr_arc
		(start 115.716812 -204.16266)
		(mid 115.571332 -204.22292)
		(end 115.511072 -204.3684)
		(stroke
			(width 0.2)
			(type default)
		)
		(layer "In6.Cu")
	)
	(gr_arc
		(start 116.072412 -206.68234)
		(mid 116.217892 -206.62208)
		(end 116.278152 -206.4766)
		(stroke
			(width 0.2)
			(type default)
		)
		(layer "In6.Cu")
	)
	(gr_line
		(start 116.072412 -205.91526)
		(end 115.716812 -205.91526)
		(stroke
			(width 0.2)
			(type default)
		)
		(layer "In6.Cu")
	)
	(gr_arc
		(start 116.072412 -205.81874)
		(mid 116.217892 -205.75848)
		(end 116.278152 -205.613)
		(stroke
			(width 0.2)
			(type default)
		)
		(layer "In6.Cu")
	)
	(gr_line
		(start 116.072412 -205.05166)
		(end 115.716812 -205.05166)
		(stroke
			(width 0.2)
			(type default)
		)
		(layer "In6.Cu")
	)
	(gr_arc
		(start 116.072412 -204.92974)
		(mid 116.217892 -204.86948)
		(end 116.278152 -204.724)
		(stroke
			(width 0.2)
			(type default)
		)
		(layer "In6.Cu")
	)
	(gr_line
		(start 116.072412 -204.16266)
		(end 115.716812 -204.16266)
		(stroke
			(width 0.2)
			(type default)
		)
		(layer "In6.Cu")
	)
	(gr_line
		(start 116.238782 -103.830882)
		(end 116.238782 -102.840536)
		(stroke
			(width 0.2)
			(type default)
		)
		(layer "In6.Cu")
	)
	(gr_arc
		(start 116.238782 -102.840536)
		(mid 115.880769 -102.482142)
		(end 115.522502 -102.840282)
		(stroke
			(width 0.2)
			(type default)
		)
		(layer "In6.Cu")
	)
	(gr_line
		(start 116.278152 -206.4766)
		(end 116.278152 -206.121)
		(stroke
			(width 0.2)
			(type default)
		)
		(layer "In6.Cu")
	)
	(gr_arc
		(start 116.278152 -206.121)
		(mid 116.217892 -205.97552)
		(end 116.072412 -205.91526)
		(stroke
			(width 0.2)
			(type default)
		)
		(layer "In6.Cu")
	)
	(gr_line
		(start 116.278152 -205.613)
		(end 116.278152 -205.2574)
		(stroke
			(width 0.2)
			(type default)
		)
		(layer "In6.Cu")
	)
	(gr_arc
		(start 116.278152 -205.2574)
		(mid 116.217892 -205.11192)
		(end 116.072412 -205.05166)
		(stroke
			(width 0.2)
			(type default)
		)
		(layer "In6.Cu")
	)
	(gr_line
		(start 116.278152 -204.724)
		(end 116.278152 -204.3684)
		(stroke
			(width 0.2)
			(type default)
		)
		(layer "In6.Cu")
	)
	(gr_arc
		(start 116.278152 -204.3684)
		(mid 116.217892 -204.22292)
		(end 116.072412 -204.16266)
		(stroke
			(width 0.2)
			(type default)
		)
		(layer "In6.Cu")
	)
	(gr_arc
		(start 116.654072 -223.4946)
		(mid 116.714332 -223.64008)
		(end 116.859812 -223.70034)
		(stroke
			(width 0.2)
			(type default)
		)
		(layer "In6.Cu")
	)
	(gr_line
		(start 116.654072 -223.139)
		(end 116.654072 -223.4946)
		(stroke
			(width 0.2)
			(type default)
		)
		(layer "In6.Cu")
	)
	(gr_arc
		(start 116.654072 -222.6056)
		(mid 116.714332 -222.75108)
		(end 116.859812 -222.81134)
		(stroke
			(width 0.2)
			(type default)
		)
		(layer "In6.Cu")
	)
	(gr_line
		(start 116.654072 -222.25)
		(end 116.654072 -222.6056)
		(stroke
			(width 0.2)
			(type default)
		)
		(layer "In6.Cu")
	)
	(gr_arc
		(start 116.654072 -221.742)
		(mid 116.714332 -221.88748)
		(end 116.859812 -221.94774)
		(stroke
			(width 0.2)
			(type default)
		)
		(layer "In6.Cu")
	)
	(gr_line
		(start 116.654072 -221.3864)
		(end 116.654072 -221.742)
		(stroke
			(width 0.2)
			(type default)
		)
		(layer "In6.Cu")
	)
	(gr_line
		(start 116.859812 -223.70034)
		(end 117.215412 -223.70034)
		(stroke
			(width 0.2)
			(type default)
		)
		(layer "In6.Cu")
	)
	(gr_arc
		(start 116.859812 -222.93326)
		(mid 116.714332 -222.99352)
		(end 116.654072 -223.139)
		(stroke
			(width 0.2)
			(type default)
		)
		(layer "In6.Cu")
	)
	(gr_line
		(start 116.859812 -222.81134)
		(end 117.215412 -222.81134)
		(stroke
			(width 0.2)
			(type default)
		)
		(layer "In6.Cu")
	)
	(gr_arc
		(start 116.859812 -222.04426)
		(mid 116.714332 -222.10452)
		(end 116.654072 -222.25)
		(stroke
			(width 0.2)
			(type default)
		)
		(layer "In6.Cu")
	)
	(gr_line
		(start 116.859812 -221.94774)
		(end 117.215412 -221.94774)
		(stroke
			(width 0.2)
			(type default)
		)
		(layer "In6.Cu")
	)
	(gr_arc
		(start 116.859812 -221.18066)
		(mid 116.714332 -221.24092)
		(end 116.654072 -221.3864)
		(stroke
			(width 0.2)
			(type default)
		)
		(layer "In6.Cu")
	)
	(gr_arc
		(start 117.162072 -206.4766)
		(mid 117.222332 -206.62208)
		(end 117.367812 -206.68234)
		(stroke
			(width 0.2)
			(type default)
		)
		(layer "In6.Cu")
	)
	(gr_line
		(start 117.162072 -206.121)
		(end 117.162072 -206.4766)
		(stroke
			(width 0.2)
			(type default)
		)
		(layer "In6.Cu")
	)
	(gr_arc
		(start 117.162072 -205.613)
		(mid 117.222332 -205.75848)
		(end 117.367812 -205.81874)
		(stroke
			(width 0.2)
			(type default)
		)
		(layer "In6.Cu")
	)
	(gr_line
		(start 117.162072 -205.2574)
		(end 117.162072 -205.613)
		(stroke
			(width 0.2)
			(type default)
		)
		(layer "In6.Cu")
	)
	(gr_arc
		(start 117.162072 -204.724)
		(mid 117.222332 -204.86948)
		(end 117.367812 -204.92974)
		(stroke
			(width 0.2)
			(type default)
		)
		(layer "In6.Cu")
	)
	(gr_line
		(start 117.162072 -204.3684)
		(end 117.162072 -204.724)
		(stroke
			(width 0.2)
			(type default)
		)
		(layer "In6.Cu")
	)
	(gr_arc
		(start 117.215412 -223.70034)
		(mid 117.360892 -223.64008)
		(end 117.421152 -223.4946)
		(stroke
			(width 0.2)
			(type default)
		)
		(layer "In6.Cu")
	)
	(gr_line
		(start 117.215412 -222.93326)
		(end 116.859812 -222.93326)
		(stroke
			(width 0.2)
			(type default)
		)
		(layer "In6.Cu")
	)
	(gr_arc
		(start 117.215412 -222.81134)
		(mid 117.360892 -222.75108)
		(end 117.421152 -222.6056)
		(stroke
			(width 0.2)
			(type default)
		)
		(layer "In6.Cu")
	)
	(gr_line
		(start 117.215412 -222.04426)
		(end 116.859812 -222.04426)
		(stroke
			(width 0.2)
			(type default)
		)
		(layer "In6.Cu")
	)
	(gr_arc
		(start 117.215412 -221.94774)
		(mid 117.360892 -221.88748)
		(end 117.421152 -221.742)
		(stroke
			(width 0.2)
			(type default)
		)
		(layer "In6.Cu")
	)
	(gr_line
		(start 117.215412 -221.18066)
		(end 116.859812 -221.18066)
		(stroke
			(width 0.2)
			(type default)
		)
		(layer "In6.Cu")
	)
	(gr_line
		(start 117.367812 -206.68234)
		(end 117.723412 -206.68234)
		(stroke
			(width 0.2)
			(type default)
		)
		(layer "In6.Cu")
	)
	(gr_arc
		(start 117.367812 -205.91526)
		(mid 117.222332 -205.97552)
		(end 117.162072 -206.121)
		(stroke
			(width 0.2)
			(type default)
		)
		(layer "In6.Cu")
	)
	(gr_line
		(start 117.367812 -205.81874)
		(end 117.723412 -205.81874)
		(stroke
			(width 0.2)
			(type default)
		)
		(layer "In6.Cu")
	)
	(gr_arc
		(start 117.367812 -205.05166)
		(mid 117.222332 -205.11192)
		(end 117.162072 -205.2574)
		(stroke
			(width 0.2)
			(type default)
		)
		(layer "In6.Cu")
	)
	(gr_line
		(start 117.367812 -204.92974)
		(end 117.723412 -204.92974)
		(stroke
			(width 0.2)
			(type default)
		)
		(layer "In6.Cu")
	)
	(gr_arc
		(start 117.367812 -204.16266)
		(mid 117.222332 -204.22292)
		(end 117.162072 -204.3684)
		(stroke
			(width 0.2)
			(type default)
		)
		(layer "In6.Cu")
	)
	(gr_line
		(start 117.421152 -223.4946)
		(end 117.421152 -223.139)
		(stroke
			(width 0.2)
			(type default)
		)
		(layer "In6.Cu")
	)
	(gr_arc
		(start 117.421152 -223.139)
		(mid 117.360892 -222.99352)
		(end 117.215412 -222.93326)
		(stroke
			(width 0.2)
			(type default)
		)
		(layer "In6.Cu")
	)
	(gr_line
		(start 117.421152 -222.6056)
		(end 117.421152 -222.25)
		(stroke
			(width 0.2)
			(type default)
		)
		(layer "In6.Cu")
	)
	(gr_arc
		(start 117.421152 -222.25)
		(mid 117.360892 -222.10452)
		(end 117.215412 -222.04426)
		(stroke
			(width 0.2)
			(type default)
		)
		(layer "In6.Cu")
	)
	(gr_line
		(start 117.421152 -221.742)
		(end 117.421152 -221.3864)
		(stroke
			(width 0.2)
			(type default)
		)
		(layer "In6.Cu")
	)
	(gr_arc
		(start 117.421152 -221.3864)
		(mid 117.360892 -221.24092)
		(end 117.215412 -221.18066)
		(stroke
			(width 0.2)
			(type default)
		)
		(layer "In6.Cu")
	)
	(gr_arc
		(start 117.492018 -103.849932)
		(mid 117.850031 -104.208326)
		(end 118.208298 -103.850186)
		(stroke
			(width 0.2)
			(type default)
		)
		(layer "In6.Cu")
	)
	(gr_line
		(start 117.492018 -102.850188)
		(end 117.492018 -103.849932)
		(stroke
			(width 0.2)
			(type default)
		)
		(layer "In6.Cu")
	)
	(gr_arc
		(start 117.723412 -206.68234)
		(mid 117.868892 -206.62208)
		(end 117.929152 -206.4766)
		(stroke
			(width 0.2)
			(type default)
		)
		(layer "In6.Cu")
	)
	(gr_line
		(start 117.723412 -205.91526)
		(end 117.367812 -205.91526)
		(stroke
			(width 0.2)
			(type default)
		)
		(layer "In6.Cu")
	)
	(gr_arc
		(start 117.723412 -205.81874)
		(mid 117.868892 -205.75848)
		(end 117.929152 -205.613)
		(stroke
			(width 0.2)
			(type default)
		)
		(layer "In6.Cu")
	)
	(gr_line
		(start 117.723412 -205.05166)
		(end 117.367812 -205.05166)
		(stroke
			(width 0.2)
			(type default)
		)
		(layer "In6.Cu")
	)
	(gr_arc
		(start 117.723412 -204.92974)
		(mid 117.868892 -204.86948)
		(end 117.929152 -204.724)
		(stroke
			(width 0.2)
			(type default)
		)
		(layer "In6.Cu")
	)
	(gr_line
		(start 117.723412 -204.16266)
		(end 117.367812 -204.16266)
		(stroke
			(width 0.2)
			(type default)
		)
		(layer "In6.Cu")
	)
	(gr_line
		(start 117.929152 -206.4766)
		(end 117.929152 -206.121)
		(stroke
			(width 0.2)
			(type default)
		)
		(layer "In6.Cu")
	)
	(gr_arc
		(start 117.929152 -206.121)
		(mid 117.868892 -205.97552)
		(end 117.723412 -205.91526)
		(stroke
			(width 0.2)
			(type default)
		)
		(layer "In6.Cu")
	)
	(gr_line
		(start 117.929152 -205.613)
		(end 117.929152 -205.2574)
		(stroke
			(width 0.2)
			(type default)
		)
		(layer "In6.Cu")
	)
	(gr_arc
		(start 117.929152 -205.2574)
		(mid 117.868892 -205.11192)
		(end 117.723412 -205.05166)
		(stroke
			(width 0.2)
			(type default)
		)
		(layer "In6.Cu")
	)
	(gr_line
		(start 117.929152 -204.724)
		(end 117.929152 -204.3684)
		(stroke
			(width 0.2)
			(type default)
		)
		(layer "In6.Cu")
	)
	(gr_arc
		(start 117.929152 -204.3684)
		(mid 117.868892 -204.22292)
		(end 117.723412 -204.16266)
		(stroke
			(width 0.2)
			(type default)
		)
		(layer "In6.Cu")
	)
	(gr_line
		(start 118.208298 -103.850186)
		(end 118.208298 -102.850188)
		(stroke
			(width 0.2)
			(type default)
		)
		(layer "In6.Cu")
	)
	(gr_arc
		(start 118.208298 -102.850188)
		(mid 117.850158 -102.492048)
		(end 117.492018 -102.850188)
		(stroke
			(width 0.2)
			(type default)
		)
		(layer "In6.Cu")
	)
	(gr_arc
		(start 118.305072 -223.4946)
		(mid 118.365332 -223.64008)
		(end 118.510812 -223.70034)
		(stroke
			(width 0.2)
			(type default)
		)
		(layer "In6.Cu")
	)
	(gr_line
		(start 118.305072 -223.139)
		(end 118.305072 -223.4946)
		(stroke
			(width 0.2)
			(type default)
		)
		(layer "In6.Cu")
	)
	(gr_arc
		(start 118.305072 -222.6056)
		(mid 118.365332 -222.75108)
		(end 118.510812 -222.81134)
		(stroke
			(width 0.2)
			(type default)
		)
		(layer "In6.Cu")
	)
	(gr_line
		(start 118.305072 -222.25)
		(end 118.305072 -222.6056)
		(stroke
			(width 0.2)
			(type default)
		)
		(layer "In6.Cu")
	)
	(gr_arc
		(start 118.305072 -221.742)
		(mid 118.365332 -221.88748)
		(end 118.510812 -221.94774)
		(stroke
			(width 0.2)
			(type default)
		)
		(layer "In6.Cu")
	)
	(gr_line
		(start 118.305072 -221.3864)
		(end 118.305072 -221.742)
		(stroke
			(width 0.2)
			(type default)
		)
		(layer "In6.Cu")
	)
	(gr_arc
		(start 118.492016 -103.849932)
		(mid 118.850029 -104.208326)
		(end 119.208296 -103.850186)
		(stroke
			(width 0.2)
			(type default)
		)
		(layer "In6.Cu")
	)
	(gr_line
		(start 118.492016 -102.850188)
		(end 118.492016 -103.849932)
		(stroke
			(width 0.2)
			(type default)
		)
		(layer "In6.Cu")
	)
	(gr_line
		(start 118.510812 -223.70034)
		(end 118.866412 -223.70034)
		(stroke
			(width 0.2)
			(type default)
		)
		(layer "In6.Cu")
	)
	(gr_arc
		(start 118.510812 -222.93326)
		(mid 118.365332 -222.99352)
		(end 118.305072 -223.139)
		(stroke
			(width 0.2)
			(type default)
		)
		(layer "In6.Cu")
	)
	(gr_line
		(start 118.510812 -222.81134)
		(end 118.866412 -222.81134)
		(stroke
			(width 0.2)
			(type default)
		)
		(layer "In6.Cu")
	)
	(gr_arc
		(start 118.510812 -222.04426)
		(mid 118.365332 -222.10452)
		(end 118.305072 -222.25)
		(stroke
			(width 0.2)
			(type default)
		)
		(layer "In6.Cu")
	)
	(gr_line
		(start 118.510812 -221.94774)
		(end 118.866412 -221.94774)
		(stroke
			(width 0.2)
			(type default)
		)
		(layer "In6.Cu")
	)
	(gr_arc
		(start 118.510812 -221.18066)
		(mid 118.365332 -221.24092)
		(end 118.305072 -221.3864)
		(stroke
			(width 0.2)
			(type default)
		)
		(layer "In6.Cu")
	)
	(gr_arc
		(start 118.866412 -223.70034)
		(mid 119.011892 -223.64008)
		(end 119.072152 -223.4946)
		(stroke
			(width 0.2)
			(type default)
		)
		(layer "In6.Cu")
	)
	(gr_line
		(start 118.866412 -222.93326)
		(end 118.510812 -222.93326)
		(stroke
			(width 0.2)
			(type default)
		)
		(layer "In6.Cu")
	)
	(gr_arc
		(start 118.866412 -222.81134)
		(mid 119.011892 -222.75108)
		(end 119.072152 -222.6056)
		(stroke
			(width 0.2)
			(type default)
		)
		(layer "In6.Cu")
	)
	(gr_line
		(start 118.866412 -222.04426)
		(end 118.510812 -222.04426)
		(stroke
			(width 0.2)
			(type default)
		)
		(layer "In6.Cu")
	)
	(gr_arc
		(start 118.866412 -221.94774)
		(mid 119.011892 -221.88748)
		(end 119.072152 -221.742)
		(stroke
			(width 0.2)
			(type default)
		)
		(layer "In6.Cu")
	)
	(gr_line
		(start 118.866412 -221.18066)
		(end 118.510812 -221.18066)
		(stroke
			(width 0.2)
			(type default)
		)
		(layer "In6.Cu")
	)
	(gr_line
		(start 119.072152 -223.4946)
		(end 119.072152 -223.139)
		(stroke
			(width 0.2)
			(type default)
		)
		(layer "In6.Cu")
	)
	(gr_arc
		(start 119.072152 -223.139)
		(mid 119.011892 -222.99352)
		(end 118.866412 -222.93326)
		(stroke
			(width 0.2)
			(type default)
		)
		(layer "In6.Cu")
	)
	(gr_line
		(start 119.072152 -222.6056)
		(end 119.072152 -222.25)
		(stroke
			(width 0.2)
			(type default)
		)
		(layer "In6.Cu")
	)
	(gr_arc
		(start 119.072152 -222.25)
		(mid 119.011892 -222.10452)
		(end 118.866412 -222.04426)
		(stroke
			(width 0.2)
			(type default)
		)
		(layer "In6.Cu")
	)
	(gr_line
		(start 119.072152 -221.742)
		(end 119.072152 -221.3864)
		(stroke
			(width 0.2)
			(type default)
		)
		(layer "In6.Cu")
	)
	(gr_arc
		(start 119.072152 -221.3864)
		(mid 119.011892 -221.24092)
		(end 118.866412 -221.18066)
		(stroke
			(width 0.2)
			(type default)
		)
		(layer "In6.Cu")
	)
	(gr_line
		(start 119.208296 -103.850186)
		(end 119.208296 -102.850188)
		(stroke
			(width 0.2)
			(type default)
		)
		(layer "In6.Cu")
	)
	(gr_arc
		(start 119.208296 -102.850188)
		(mid 118.850156 -102.492048)
		(end 118.492016 -102.850188)
		(stroke
			(width 0.2)
			(type default)
		)
		(layer "In6.Cu")
	)
	(gr_line
		(start 122.492008 -91.849956)
		(end 122.492262 -92.827348)
		(stroke
			(width 0.2)
			(type default)
		)
		(layer "In6.Cu")
	)
	(gr_arc
		(start 122.492262 -92.827348)
		(mid 122.850402 -93.185742)
		(end 123.208542 -92.827348)
		(stroke
			(width 0.2)
			(type default)
		)
		(layer "In6.Cu")
	)
	(gr_arc
		(start 122.829574 -84.492084)
		(mid 122.492516 -84.87029)
		(end 122.870722 -85.207348)
		(stroke
			(width 0.2)
			(type default)
		)
		(layer "In6.Cu")
	)
	(gr_line
		(start 122.848116 -94.186502)
		(end 123.843542 -94.206822)
		(stroke
			(width 0.2)
			(type default)
		)
		(layer "In6.Cu")
	)
	(gr_line
		(start 122.850148 -91.207844)
		(end 123.850146 -91.207844)
		(stroke
			(width 0.2)
			(type default)
		)
		(layer "In6.Cu")
	)
	(gr_line
		(start 122.850148 -90.207846)
		(end 123.850146 -90.207846)
		(stroke
			(width 0.2)
			(type default)
		)
		(layer "In6.Cu")
	)
	(gr_line
		(start 122.850148 -84.207858)
		(end 123.849892 -84.207858)
		(stroke
			(width 0.2)
			(type default)
		)
		(layer "In6.Cu")
	)
	(gr_arc
		(start 122.850148 -83.491578)
		(mid 122.492008 -83.849718)
		(end 122.850148 -84.207858)
		(stroke
			(width 0.2)
			(type default)
		)
		(layer "In6.Cu")
	)
	(gr_line
		(start 122.850148 -83.20786)
		(end 123.850146 -83.20786)
		(stroke
			(width 0.2)
			(type default)
		)
		(layer "In6.Cu")
	)
	(gr_arc
		(start 122.850402 -90.491564)
		(mid 122.492008 -90.849577)
		(end 122.850148 -91.207844)
		(stroke
			(width 0.2)
			(type default)
		)
		(layer "In6.Cu")
	)
	(gr_arc
		(start 122.850402 -89.491566)
		(mid 122.492008 -89.849579)
		(end 122.850148 -90.207846)
		(stroke
			(width 0.2)
			(type default)
		)
		(layer "In6.Cu")
	)
	(gr_arc
		(start 122.850402 -82.49158)
		(mid 122.492008 -82.849593)
		(end 122.850148 -83.20786)
		(stroke
			(width 0.2)
			(type default)
		)
		(layer "In6.Cu")
	)
	(gr_arc
		(start 122.862848 -93.470222)
		(mid 122.497342 -93.820996)
		(end 122.848116 -94.186502)
		(stroke
			(width 0.2)
			(type default)
		)
		(layer "In6.Cu")
	)
	(gr_line
		(start 122.870722 -85.207348)
		(end 123.84532 -85.151214)
		(stroke
			(width 0.2)
			(type default)
		)
		(layer "In6.Cu")
	)
	(gr_line
		(start 122.924062 -81.28254)
		(end 123.831858 -81.308956)
		(stroke
			(width 0.2)
			(type default)
		)
		(layer "In6.Cu")
	)
	(gr_arc
		(start 122.92457 -81.430114)
		(mid 122.578114 -81.79943)
		(end 122.94743 -82.145886)
		(stroke
			(width 0.2)
			(type default)
		)
		(layer "In6.Cu")
	)
	(gr_line
		(start 122.92457 -81.427828)
		(end 122.92457 -81.430114)
		(stroke
			(width 0.2)
			(type default)
		)
		(layer "In6.Cu")
	)
	(gr_line
		(start 122.924824 -81.427574)
		(end 122.92457 -81.427828)
		(stroke
			(width 0.2)
			(type default)
		)
		(layer "In6.Cu")
	)
	(gr_arc
		(start 122.925332 -80.56626)
		(mid 122.566684 -80.923765)
		(end 122.924062 -81.28254)
		(stroke
			(width 0.2)
			(type default)
		)
		(layer "In6.Cu")
	)
	(gr_line
		(start 122.94743 -82.148426)
		(end 123.7488 -82.123026)
		(stroke
			(width 0.2)
			(type default)
		)
		(layer "In6.Cu")
	)
	(gr_line
		(start 122.94743 -82.145886)
		(end 122.94743 -82.148426)
		(stroke
			(width 0.2)
			(type default)
		)
		(layer "In6.Cu")
	)
	(gr_line
		(start 123.208288 -91.849956)
		(end 123.208288 -91.849702)
		(stroke
			(width 0.2)
			(type default)
		)
		(layer "In6.Cu")
	)
	(gr_arc
		(start 123.208288 -91.849702)
		(mid 122.850021 -91.491562)
		(end 122.492008 -91.849956)
		(stroke
			(width 0.2)
			(type default)
		)
		(layer "In6.Cu")
	)
	(gr_line
		(start 123.208542 -92.827348)
		(end 123.208288 -91.849956)
		(stroke
			(width 0.2)
			(type default)
		)
		(layer "In6.Cu")
	)
	(gr_line
		(start 123.72594 -81.404714)
		(end 123.72594 -81.402174)
		(stroke
			(width 0.2)
			(type default)
		)
		(layer "In6.Cu")
	)
	(gr_line
		(start 123.72594 -81.402174)
		(end 122.924824 -81.427574)
		(stroke
			(width 0.2)
			(type default)
		)
		(layer "In6.Cu")
	)
	(gr_line
		(start 123.7488 -82.123026)
		(end 123.7488 -82.12074)
		(stroke
			(width 0.2)
			(type default)
		)
		(layer "In6.Cu")
	)
	(gr_line
		(start 123.7488 -82.12074)
		(end 123.7488 -82.120486)
		(stroke
			(width 0.2)
			(type default)
		)
		(layer "In6.Cu")
	)
	(gr_arc
		(start 123.7488 -82.120486)
		(mid 124.095256 -81.75117)
		(end 123.72594 -81.404714)
		(stroke
			(width 0.2)
			(type default)
		)
		(layer "In6.Cu")
	)
	(gr_line
		(start 123.804426 -84.43595)
		(end 122.829574 -84.492084)
		(stroke
			(width 0.2)
			(type default)
		)
		(layer "In6.Cu")
	)
	(gr_arc
		(start 123.831858 -81.308956)
		(mid 123.842395 -81.309356)
		(end 123.85294 -81.309464)
		(stroke
			(width 0.2)
			(type default)
		)
		(layer "In6.Cu")
	)
	(gr_line
		(start 123.833128 -80.542892)
		(end 122.925332 -80.56626)
		(stroke
			(width 0.2)
			(type default)
		)
		(layer "In6.Cu")
	)
	(gr_arc
		(start 123.843542 -94.206822)
		(mid 124.209305 -93.856175)
		(end 123.858528 -93.490542)
		(stroke
			(width 0.2)
			(type default)
		)
		(layer "In6.Cu")
	)
	(gr_arc
		(start 123.84532 -85.151214)
		(mid 124.182625 -84.773135)
		(end 123.804426 -84.43595)
		(stroke
			(width 0.2)
			(type default)
		)
		(layer "In6.Cu")
	)
	(gr_arc
		(start 123.849892 -84.207858)
		(mid 124.208286 -83.849845)
		(end 123.850146 -83.491578)
		(stroke
			(width 0.2)
			(type default)
		)
		(layer "In6.Cu")
	)
	(gr_arc
		(start 123.850146 -91.207844)
		(mid 124.208286 -90.849704)
		(end 123.850146 -90.491564)
		(stroke
			(width 0.2)
			(type default)
		)
		(layer "In6.Cu")
	)
	(gr_line
		(start 123.850146 -90.491564)
		(end 122.850402 -90.491564)
		(stroke
			(width 0.2)
			(type default)
		)
		(layer "In6.Cu")
	)
	(gr_arc
		(start 123.850146 -90.207846)
		(mid 124.208286 -89.849706)
		(end 123.850146 -89.491566)
		(stroke
			(width 0.2)
			(type default)
		)
		(layer "In6.Cu")
	)
	(gr_line
		(start 123.850146 -89.491566)
		(end 122.850402 -89.491566)
		(stroke
			(width 0.2)
			(type default)
		)
		(layer "In6.Cu")
	)
	(gr_line
		(start 123.850146 -83.491578)
		(end 122.850148 -83.491578)
		(stroke
			(width 0.2)
			(type default)
		)
		(layer "In6.Cu")
	)
	(gr_arc
		(start 123.850146 -83.20786)
		(mid 124.208286 -82.84972)
		(end 123.850146 -82.49158)
		(stroke
			(width 0.2)
			(type default)
		)
		(layer "In6.Cu")
	)
	(gr_line
		(start 123.850146 -82.49158)
		(end 122.850402 -82.49158)
		(stroke
			(width 0.2)
			(type default)
		)
		(layer "In6.Cu")
	)
	(gr_arc
		(start 123.85294 -81.309464)
		(mid 124.236988 -80.926432)
		(end 123.853956 -80.542384)
		(stroke
			(width 0.2)
			(type default)
		)
		(layer "In6.Cu")
	)
	(gr_arc
		(start 123.853956 -80.542384)
		(mid 123.843539 -80.542498)
		(end 123.833128 -80.542892)
		(stroke
			(width 0.2)
			(type default)
		)
		(layer "In6.Cu")
	)
	(gr_line
		(start 123.858528 -93.490542)
		(end 122.862848 -93.470222)
		(stroke
			(width 0.2)
			(type default)
		)
		(layer "In6.Cu")
	)
	(gr_line
		(start 124.779278 -80.635348)
		(end 125.756162 -80.635348)
		(stroke
			(width 0.2)
			(type default)
		)
		(layer "In6.Cu")
	)
	(gr_arc
		(start 124.779532 -79.868268)
		(mid 124.395738 -80.251681)
		(end 124.779278 -80.635348)
		(stroke
			(width 0.2)
			(type default)
		)
		(layer "In6.Cu")
	)
	(gr_arc
		(start 125.756162 -80.635348)
		(mid 126.139702 -80.251808)
		(end 125.756162 -79.868268)
		(stroke
			(width 0.2)
			(type default)
		)
		(layer "In6.Cu")
	)
	(gr_line
		(start 125.756162 -79.868268)
		(end 124.779532 -79.868268)
		(stroke
			(width 0.2)
			(type default)
		)
		(layer "In6.Cu")
	)
	(gr_line
		(start 127.154178 -80.19034)
		(end 128.130808 -80.19034)
		(stroke
			(width 0.2)
			(type default)
		)
		(layer "In6.Cu")
	)
	(gr_arc
		(start 127.154178 -79.42326)
		(mid 126.770638 -79.8068)
		(end 127.154178 -80.19034)
		(stroke
			(width 0.2)
			(type default)
		)
		(layer "In6.Cu")
	)
	(gr_arc
		(start 128.130808 -80.19034)
		(mid 128.514602 -79.806927)
		(end 128.131062 -79.42326)
		(stroke
			(width 0.2)
			(type default)
		)
		(layer "In6.Cu")
	)
	(gr_line
		(start 128.131062 -79.42326)
		(end 127.154178 -79.42326)
		(stroke
			(width 0.2)
			(type default)
		)
		(layer "In6.Cu")
	)
	(gr_line
		(start 129.159 -81.66354)
		(end 130.047746 -81.66354)
		(stroke
			(width 0.2)
			(type default)
		)
		(layer "In6.Cu")
	)
	(gr_arc
		(start 129.159 -80.89646)
		(mid 128.77546 -81.28)
		(end 129.159 -81.66354)
		(stroke
			(width 0.2)
			(type default)
		)
		(layer "In6.Cu")
	)
	(gr_arc
		(start 130.047746 -81.66354)
		(mid 130.43154 -81.280127)
		(end 130.048 -80.89646)
		(stroke
			(width 0.2)
			(type default)
		)
		(layer "In6.Cu")
	)
	(gr_line
		(start 130.048 -80.89646)
		(end 129.159 -80.89646)
		(stroke
			(width 0.2)
			(type default)
		)
		(layer "In6.Cu")
	)
	(gr_line
		(start 131.02844 -80.13954)
		(end 132.00507 -80.13954)
		(stroke
			(width 0.2)
			(type default)
		)
		(layer "In6.Cu")
	)
	(gr_arc
		(start 131.02844 -79.37246)
		(mid 130.6449 -79.756)
		(end 131.02844 -80.13954)
		(stroke
			(width 0.2)
			(type default)
		)
		(layer "In6.Cu")
	)
	(gr_arc
		(start 131.82346 -92.075)
		(mid 132.207 -92.45854)
		(end 132.59054 -92.075)
		(stroke
			(width 0.2)
			(type default)
		)
		(layer "In6.Cu")
	)
	(gr_line
		(start 131.82346 -91.169998)
		(end 131.82346 -92.075)
		(stroke
			(width 0.2)
			(type default)
		)
		(layer "In6.Cu")
	)
	(gr_arc
		(start 131.82346 -89.281)
		(mid 132.207 -89.66454)
		(end 132.59054 -89.281)
		(stroke
			(width 0.2)
			(type default)
		)
		(layer "In6.Cu")
	)
	(gr_line
		(start 131.82346 -88.375998)
		(end 131.82346 -89.281)
		(stroke
			(width 0.2)
			(type default)
		)
		(layer "In6.Cu")
	)
	(gr_arc
		(start 132.00507 -80.13954)
		(mid 132.388864 -79.756127)
		(end 132.005324 -79.37246)
		(stroke
			(width 0.2)
			(type default)
		)
		(layer "In6.Cu")
	)
	(gr_line
		(start 132.005324 -79.37246)
		(end 131.02844 -79.37246)
		(stroke
			(width 0.2)
			(type default)
		)
		(layer "In6.Cu")
	)
	(gr_line
		(start 132.59054 -92.075)
		(end 132.59054 -91.170252)
		(stroke
			(width 0.2)
			(type default)
		)
		(layer "In6.Cu")
	)
	(gr_arc
		(start 132.59054 -91.170252)
		(mid 132.207127 -90.786458)
		(end 131.82346 -91.169998)
		(stroke
			(width 0.2)
			(type default)
		)
		(layer "In6.Cu")
	)
	(gr_line
		(start 132.59054 -89.281)
		(end 132.59054 -88.376252)
		(stroke
			(width 0.2)
			(type default)
		)
		(layer "In6.Cu")
	)
	(gr_arc
		(start 132.59054 -88.376252)
		(mid 132.207127 -87.992458)
		(end 131.82346 -88.375998)
		(stroke
			(width 0.2)
			(type default)
		)
		(layer "In6.Cu")
	)
	(gr_line
		(start 132.930392 -81.500726)
		(end 133.858254 -81.500726)
		(stroke
			(width 0.2)
			(type default)
		)
		(layer "In6.Cu")
	)
	(gr_arc
		(start 132.930392 -80.733646)
		(mid 132.546852 -81.117186)
		(end 132.930392 -81.500726)
		(stroke
			(width 0.2)
			(type default)
		)
		(layer "In6.Cu")
	)
	(gr_arc
		(start 133.34746 -90.558874)
		(mid 133.730873 -90.942668)
		(end 134.11454 -90.559128)
		(stroke
			(width 0.2)
			(type default)
		)
		(layer "In6.Cu")
	)
	(gr_line
		(start 133.34746 -89.654126)
		(end 133.34746 -90.558874)
		(stroke
			(width 0.2)
			(type default)
		)
		(layer "In6.Cu")
	)
	(gr_arc
		(start 133.34746 -88.019128)
		(mid 133.731 -88.402668)
		(end 134.11454 -88.019128)
		(stroke
			(width 0.2)
			(type default)
		)
		(layer "In6.Cu")
	)
	(gr_line
		(start 133.34746 -87.114126)
		(end 133.34746 -88.019128)
		(stroke
			(width 0.2)
			(type default)
		)
		(layer "In6.Cu")
	)
	(gr_arc
		(start 133.858254 -81.500726)
		(mid 134.242048 -81.117313)
		(end 133.858508 -80.733646)
		(stroke
			(width 0.2)
			(type default)
		)
		(layer "In6.Cu")
	)
	(gr_line
		(start 133.858508 -80.733646)
		(end 132.930392 -80.733646)
		(stroke
			(width 0.2)
			(type default)
		)
		(layer "In6.Cu")
	)
	(gr_line
		(start 134.11454 -90.559128)
		(end 134.11454 -89.654126)
		(stroke
			(width 0.2)
			(type default)
		)
		(layer "In6.Cu")
	)
	(gr_arc
		(start 134.11454 -89.654126)
		(mid 133.731 -89.270586)
		(end 133.34746 -89.654126)
		(stroke
			(width 0.2)
			(type default)
		)
		(layer "In6.Cu")
	)
	(gr_line
		(start 134.11454 -88.019128)
		(end 134.11454 -87.11438)
		(stroke
			(width 0.2)
			(type default)
		)
		(layer "In6.Cu")
	)
	(gr_arc
		(start 134.11454 -87.11438)
		(mid 133.731127 -86.730586)
		(end 133.34746 -87.114126)
		(stroke
			(width 0.2)
			(type default)
		)
		(layer "In6.Cu")
	)
	(gr_line
		(start 134.581392 -83.06054)
		(end 135.509508 -83.06054)
		(stroke
			(width 0.2)
			(type default)
		)
		(layer "In6.Cu")
	)
	(gr_arc
		(start 134.581646 -82.29346)
		(mid 134.197852 -82.676873)
		(end 134.581392 -83.06054)
		(stroke
			(width 0.2)
			(type default)
		)
		(layer "In6.Cu")
	)
	(gr_arc
		(start 135.509508 -83.06054)
		(mid 135.893048 -82.677)
		(end 135.509508 -82.29346)
		(stroke
			(width 0.2)
			(type default)
		)
		(layer "In6.Cu")
	)
	(gr_line
		(start 135.509508 -82.29346)
		(end 134.581646 -82.29346)
		(stroke
			(width 0.2)
			(type default)
		)
		(layer "In6.Cu")
	)
	(gr_line
		(start 135.87984 -81.91754)
		(end 136.807956 -81.91754)
		(stroke
			(width 0.2)
			(type default)
		)
		(layer "In6.Cu")
	)
	(gr_arc
		(start 135.880094 -81.15046)
		(mid 135.4963 -81.533873)
		(end 135.87984 -81.91754)
		(stroke
			(width 0.2)
			(type default)
		)
		(layer "In6.Cu")
	)
	(gr_arc
		(start 136.807956 -81.91754)
		(mid 137.191496 -81.534)
		(end 136.807956 -81.15046)
		(stroke
			(width 0.2)
			(type default)
		)
		(layer "In6.Cu")
	)
	(gr_line
		(start 136.807956 -81.15046)
		(end 135.880094 -81.15046)
		(stroke
			(width 0.2)
			(type default)
		)
		(layer "In6.Cu")
	)
	(gr_line
		(start 138.549888 -258.59994)
		(end 67.349878 -258.59994)
		(stroke
			(width 5.08)
			(type default)
		)
		(layer "In6.Cu")
	)
	(gr_line
		(start 138.549888 -252.549914)
		(end 138.549888 -258.59994)
		(stroke
			(width 1.524)
			(type default)
		)
		(layer "In6.Cu")
	)
	(gr_line
		(start 140.450062 -258.59994)
		(end 140.450062 -252.549914)
		(stroke
			(width 1.524)
			(type default)
		)
		(layer "In6.Cu")
	)
	(gr_arc
		(start 140.450062 -252.549914)
		(mid 139.500102 -251.599954)
		(end 138.549888 -252.549914)
		(stroke
			(width 1.524)
			(type default)
		)
		(layer "In6.Cu")
	)
	(gr_line
		(start 151.649938 -258.59994)
		(end 140.450062 -258.59994)
		(stroke
			(width 5.08)
			(type default)
		)
		(layer "In6.Cu")
	)
	(gr_line
		(start 151.649938 -252.000004)
		(end 151.649938 -258.59994)
		(stroke
			(width 1.524)
			(type default)
		)
		(layer "In6.Cu")
	)
	(gr_arc
		(start 152.649936 -251.000006)
		(mid 151.942831 -251.292899)
		(end 151.649938 -252.000004)
		(stroke
			(width 1.524)
			(type default)
		)
		(layer "In6.Cu")
	)
	(gr_line
		(start 155.866084 -79.95793)
		(end 155.86837 -79.958946)
		(stroke
			(width 0.2)
			(type default)
		)
		(layer "In6.Cu")
	)
	(gr_arc
		(start 155.86837 -79.958946)
		(mid 156.158692 -80.831436)
		(end 157.031182 -80.541114)
		(stroke
			(width 0.2)
			(type default)
		)
		(layer "In6.Cu")
	)
	(gr_line
		(start 155.946348 -77.40904)
		(end 156.928312 -77.40904)
		(stroke
			(width 0.2)
			(type default)
		)
		(layer "In6.Cu")
	)
	(gr_arc
		(start 155.946602 -76.64196)
		(mid 155.562808 -77.025373)
		(end 155.946348 -77.40904)
		(stroke
			(width 0.2)
			(type default)
		)
		(layer "In6.Cu")
	)
	(gr_line
		(start 156.866844 -77.95768)
		(end 155.866084 -79.95793)
		(stroke
			(width 0.2)
			(type default)
		)
		(layer "In6.Cu")
	)
	(gr_line
		(start 156.86913 -77.958696)
		(end 156.866844 -77.95768)
		(stroke
			(width 0.2)
			(type default)
		)
		(layer "In6.Cu")
	)
	(gr_arc
		(start 156.928312 -77.40904)
		(mid 157.311852 -77.0255)
		(end 156.928312 -76.64196)
		(stroke
			(width 0.2)
			(type default)
		)
		(layer "In6.Cu")
	)
	(gr_line
		(start 156.928312 -76.64196)
		(end 155.946602 -76.64196)
		(stroke
			(width 0.2)
			(type default)
		)
		(layer "In6.Cu")
	)
	(gr_line
		(start 157.031182 -80.541114)
		(end 157.033468 -80.54213)
		(stroke
			(width 0.2)
			(type default)
		)
		(layer "In6.Cu")
	)
	(gr_line
		(start 157.033468 -80.54213)
		(end 158.034228 -78.542134)
		(stroke
			(width 0.2)
			(type default)
		)
		(layer "In6.Cu")
	)
	(gr_line
		(start 157.86608 -74.042016)
		(end 158.86557 -76.042266)
		(stroke
			(width 0.2)
			(type default)
		)
		(layer "In6.Cu")
	)
	(gr_line
		(start 157.868366 -74.040746)
		(end 157.86608 -74.042016)
		(stroke
			(width 0.2)
			(type default)
		)
		(layer "In6.Cu")
	)
	(gr_arc
		(start 158.032196 -78.54061)
		(mid 157.741671 -77.668399)
		(end 156.86913 -77.958696)
		(stroke
			(width 0.2)
			(type default)
		)
		(layer "In6.Cu")
	)
	(gr_line
		(start 158.033974 -78.541626)
		(end 158.032196 -78.54061)
		(stroke
			(width 0.2)
			(type default)
		)
		(layer "In6.Cu")
	)
	(gr_line
		(start 158.034228 -78.542134)
		(end 158.033974 -78.541626)
		(stroke
			(width 0.2)
			(type default)
		)
		(layer "In6.Cu")
	)
	(gr_line
		(start 158.86557 -76.042266)
		(end 158.867856 -76.040996)
		(stroke
			(width 0.2)
			(type default)
		)
		(layer "In6.Cu")
	)
	(gr_arc
		(start 158.867856 -76.040996)
		(mid 159.740092 -76.33208)
		(end 160.031176 -75.459844)
		(stroke
			(width 0.2)
			(type default)
		)
		(layer "In6.Cu")
	)
	(gr_arc
		(start 159.031686 -73.459594)
		(mid 158.15945 -73.16851)
		(end 157.868366 -74.040746)
		(stroke
			(width 0.2)
			(type default)
		)
		(layer "In6.Cu")
	)
	(gr_line
		(start 159.033718 -73.458578)
		(end 159.031686 -73.459594)
		(stroke
			(width 0.2)
			(type default)
		)
		(layer "In6.Cu")
	)
	(gr_line
		(start 159.033972 -73.458578)
		(end 159.033718 -73.458578)
		(stroke
			(width 0.2)
			(type default)
		)
		(layer "In6.Cu")
	)
	(gr_line
		(start 159.86633 -79.958184)
		(end 159.868616 -79.959454)
		(stroke
			(width 0.2)
			(type default)
		)
		(layer "In6.Cu")
	)
	(gr_arc
		(start 159.868616 -79.959454)
		(mid 160.1597 -80.83169)
		(end 161.031936 -80.540606)
		(stroke
			(width 0.2)
			(type default)
		)
		(layer "In6.Cu")
	)
	(gr_line
		(start 159.946848 -77.40904)
		(end 160.928812 -77.40904)
		(stroke
			(width 0.2)
			(type default)
		)
		(layer "In6.Cu")
	)
	(gr_arc
		(start 159.947102 -76.64196)
		(mid 159.563308 -77.025373)
		(end 159.946848 -77.40904)
		(stroke
			(width 0.2)
			(type default)
		)
		(layer "In6.Cu")
	)
	(gr_line
		(start 160.031176 -75.459844)
		(end 160.033462 -75.458574)
		(stroke
			(width 0.2)
			(type default)
		)
		(layer "In6.Cu")
	)
	(gr_line
		(start 160.033462 -75.458574)
		(end 159.033972 -73.458578)
		(stroke
			(width 0.2)
			(type default)
		)
		(layer "In6.Cu")
	)
	(gr_line
		(start 160.86582 -77.957934)
		(end 159.86633 -79.958184)
		(stroke
			(width 0.2)
			(type default)
		)
		(layer "In6.Cu")
	)
	(gr_line
		(start 160.868106 -77.959204)
		(end 160.86582 -77.957934)
		(stroke
			(width 0.2)
			(type default)
		)
		(layer "In6.Cu")
	)
	(gr_arc
		(start 160.928812 -77.40904)
		(mid 161.312352 -77.0255)
		(end 160.928812 -76.64196)
		(stroke
			(width 0.2)
			(type default)
		)
		(layer "In6.Cu")
	)
	(gr_line
		(start 160.928812 -76.64196)
		(end 159.947102 -76.64196)
		(stroke
			(width 0.2)
			(type default)
		)
		(layer "In6.Cu")
	)
	(gr_line
		(start 161.031936 -80.540606)
		(end 161.034222 -80.541876)
		(stroke
			(width 0.2)
			(type default)
		)
		(layer "In6.Cu")
	)
	(gr_line
		(start 161.034222 -80.541876)
		(end 162.033712 -78.54188)
		(stroke
			(width 0.2)
			(type default)
		)
		(layer "In6.Cu")
	)
	(gr_line
		(start 161.86658 -74.042016)
		(end 162.86607 -76.042266)
		(stroke
			(width 0.2)
			(type default)
		)
		(layer "In6.Cu")
	)
	(gr_line
		(start 161.868866 -74.040746)
		(end 161.86658 -74.042016)
		(stroke
			(width 0.2)
			(type default)
		)
		(layer "In6.Cu")
	)
	(gr_arc
		(start 162.031426 -78.540356)
		(mid 161.740342 -77.66812)
		(end 160.868106 -77.959204)
		(stroke
			(width 0.2)
			(type default)
		)
		(layer "In6.Cu")
	)
	(gr_line
		(start 162.033458 -78.541372)
		(end 162.031426 -78.540356)
		(stroke
			(width 0.2)
			(type default)
		)
		(layer "In6.Cu")
	)
	(gr_line
		(start 162.033712 -78.54188)
		(end 162.033458 -78.541372)
		(stroke
			(width 0.2)
			(type default)
		)
		(layer "In6.Cu")
	)
	(gr_line
		(start 162.86607 -76.042266)
		(end 162.868356 -76.040996)
		(stroke
			(width 0.2)
			(type default)
		)
		(layer "In6.Cu")
	)
	(gr_arc
		(start 162.868356 -76.040996)
		(mid 163.740592 -76.33208)
		(end 164.031676 -75.459844)
		(stroke
			(width 0.2)
			(type default)
		)
		(layer "In6.Cu")
	)
	(gr_arc
		(start 163.032186 -73.459594)
		(mid 162.15995 -73.16851)
		(end 161.868866 -74.040746)
		(stroke
			(width 0.2)
			(type default)
		)
		(layer "In6.Cu")
	)
	(gr_line
		(start 163.034218 -73.458578)
		(end 163.032186 -73.459594)
		(stroke
			(width 0.2)
			(type default)
		)
		(layer "In6.Cu")
	)
	(gr_line
		(start 163.034472 -73.458578)
		(end 163.034218 -73.458578)
		(stroke
			(width 0.2)
			(type default)
		)
		(layer "In6.Cu")
	)
	(gr_line
		(start 163.865814 -79.95793)
		(end 163.8681 -79.958946)
		(stroke
			(width 0.2)
			(type default)
		)
		(layer "In6.Cu")
	)
	(gr_arc
		(start 163.8681 -79.958946)
		(mid 164.158422 -80.831436)
		(end 165.030912 -80.541114)
		(stroke
			(width 0.2)
			(type default)
		)
		(layer "In6.Cu")
	)
	(gr_line
		(start 163.946078 -77.40904)
		(end 164.928042 -77.40904)
		(stroke
			(width 0.2)
			(type default)
		)
		(layer "In6.Cu")
	)
	(gr_arc
		(start 163.946332 -76.64196)
		(mid 163.562538 -77.025373)
		(end 163.946078 -77.40904)
		(stroke
			(width 0.2)
			(type default)
		)
		(layer "In6.Cu")
	)
	(gr_line
		(start 164.031676 -75.459844)
		(end 164.033962 -75.458574)
		(stroke
			(width 0.2)
			(type default)
		)
		(layer "In6.Cu")
	)
	(gr_line
		(start 164.033962 -75.458574)
		(end 163.034472 -73.458578)
		(stroke
			(width 0.2)
			(type default)
		)
		(layer "In6.Cu")
	)
	(gr_line
		(start 164.866574 -77.95768)
		(end 163.865814 -79.95793)
		(stroke
			(width 0.2)
			(type default)
		)
		(layer "In6.Cu")
	)
	(gr_line
		(start 164.86886 -77.958696)
		(end 164.866574 -77.95768)
		(stroke
			(width 0.2)
			(type default)
		)
		(layer "In6.Cu")
	)
	(gr_arc
		(start 164.928042 -77.40904)
		(mid 165.311582 -77.0255)
		(end 164.928042 -76.64196)
		(stroke
			(width 0.2)
			(type default)
		)
		(layer "In6.Cu")
	)
	(gr_line
		(start 164.928042 -76.64196)
		(end 163.946332 -76.64196)
		(stroke
			(width 0.2)
			(type default)
		)
		(layer "In6.Cu")
	)
	(gr_line
		(start 165.030912 -80.541114)
		(end 165.033198 -80.54213)
		(stroke
			(width 0.2)
			(type default)
		)
		(layer "In6.Cu")
	)
	(gr_line
		(start 165.033198 -80.54213)
		(end 166.033958 -78.542134)
		(stroke
			(width 0.2)
			(type default)
		)
		(layer "In6.Cu")
	)
	(gr_line
		(start 165.866064 -74.04227)
		(end 166.866824 -76.04252)
		(stroke
			(width 0.2)
			(type default)
		)
		(layer "In6.Cu")
	)
	(gr_line
		(start 165.86835 -74.041254)
		(end 165.866064 -74.04227)
		(stroke
			(width 0.2)
			(type default)
		)
		(layer "In6.Cu")
	)
	(gr_arc
		(start 166.031926 -78.54061)
		(mid 165.741401 -77.668399)
		(end 164.86886 -77.958696)
		(stroke
			(width 0.2)
			(type default)
		)
		(layer "In6.Cu")
	)
	(gr_line
		(start 166.033704 -78.541626)
		(end 166.031926 -78.54061)
		(stroke
			(width 0.2)
			(type default)
		)
		(layer "In6.Cu")
	)
	(gr_line
		(start 166.033958 -78.542134)
		(end 166.033704 -78.541626)
		(stroke
			(width 0.2)
			(type default)
		)
		(layer "In6.Cu")
	)
	(gr_line
		(start 166.866824 -76.04252)
		(end 166.86911 -76.041504)
		(stroke
			(width 0.2)
			(type default)
		)
		(layer "In6.Cu")
	)
	(gr_arc
		(start 166.86911 -76.041504)
		(mid 167.7416 -76.331826)
		(end 168.031922 -75.459336)
		(stroke
			(width 0.2)
			(type default)
		)
		(layer "In6.Cu")
	)
	(gr_arc
		(start 167.031416 -73.45934)
		(mid 166.159078 -73.168942)
		(end 165.86835 -74.041254)
		(stroke
			(width 0.2)
			(type default)
		)
		(layer "In6.Cu")
	)
	(gr_line
		(start 167.033194 -73.458324)
		(end 167.031416 -73.45934)
		(stroke
			(width 0.2)
			(type default)
		)
		(layer "In6.Cu")
	)
	(gr_line
		(start 167.033702 -73.458324)
		(end 167.033194 -73.458324)
		(stroke
			(width 0.2)
			(type default)
		)
		(layer "In6.Cu")
	)
	(gr_line
		(start 167.86606 -79.958184)
		(end 167.868346 -79.959454)
		(stroke
			(width 0.2)
			(type default)
		)
		(layer "In6.Cu")
	)
	(gr_arc
		(start 167.868346 -79.959454)
		(mid 168.15943 -80.83169)
		(end 169.031666 -80.540606)
		(stroke
			(width 0.2)
			(type default)
		)
		(layer "In6.Cu")
	)
	(gr_line
		(start 167.946578 -77.40904)
		(end 168.928542 -77.40904)
		(stroke
			(width 0.2)
			(type default)
		)
		(layer "In6.Cu")
	)
	(gr_arc
		(start 167.946832 -76.64196)
		(mid 167.563038 -77.025373)
		(end 167.946578 -77.40904)
		(stroke
			(width 0.2)
			(type default)
		)
		(layer "In6.Cu")
	)
	(gr_line
		(start 168.031922 -75.459336)
		(end 168.034208 -75.45832)
		(stroke
			(width 0.2)
			(type default)
		)
		(layer "In6.Cu")
	)
	(gr_line
		(start 168.034208 -75.45832)
		(end 167.033702 -73.458324)
		(stroke
			(width 0.2)
			(type default)
		)
		(layer "In6.Cu")
	)
	(gr_line
		(start 168.86555 -77.957934)
		(end 167.86606 -79.958184)
		(stroke
			(width 0.2)
			(type default)
		)
		(layer "In6.Cu")
	)
	(gr_line
		(start 168.867836 -77.959204)
		(end 168.86555 -77.957934)
		(stroke
			(width 0.2)
			(type default)
		)
		(layer "In6.Cu")
	)
	(gr_arc
		(start 168.928542 -77.40904)
		(mid 169.312082 -77.0255)
		(end 168.928542 -76.64196)
		(stroke
			(width 0.2)
			(type default)
		)
		(layer "In6.Cu")
	)
	(gr_line
		(start 168.928542 -76.64196)
		(end 167.946832 -76.64196)
		(stroke
			(width 0.2)
			(type default)
		)
		(layer "In6.Cu")
	)
	(gr_line
		(start 169.031666 -80.540606)
		(end 169.033952 -80.541876)
		(stroke
			(width 0.2)
			(type default)
		)
		(layer "In6.Cu")
	)
	(gr_line
		(start 169.033952 -80.541876)
		(end 170.033442 -78.54188)
		(stroke
			(width 0.2)
			(type default)
		)
		(layer "In6.Cu")
	)
	(gr_line
		(start 169.86631 -74.042016)
		(end 170.8658 -76.042266)
		(stroke
			(width 0.2)
			(type default)
		)
		(layer "In6.Cu")
	)
	(gr_line
		(start 169.868596 -74.040746)
		(end 169.86631 -74.042016)
		(stroke
			(width 0.2)
			(type default)
		)
		(layer "In6.Cu")
	)
	(gr_arc
		(start 170.031156 -78.540356)
		(mid 169.740072 -77.66812)
		(end 168.867836 -77.959204)
		(stroke
			(width 0.2)
			(type default)
		)
		(layer "In6.Cu")
	)
	(gr_line
		(start 170.033188 -78.541372)
		(end 170.031156 -78.540356)
		(stroke
			(width 0.2)
			(type default)
		)
		(layer "In6.Cu")
	)
	(gr_line
		(start 170.033442 -78.54188)
		(end 170.033188 -78.541372)
		(stroke
			(width 0.2)
			(type default)
		)
		(layer "In6.Cu")
	)
	(gr_line
		(start 170.8658 -76.042266)
		(end 170.868086 -76.040996)
		(stroke
			(width 0.2)
			(type default)
		)
		(layer "In6.Cu")
	)
	(gr_arc
		(start 170.868086 -76.040996)
		(mid 171.740322 -76.33208)
		(end 172.031406 -75.459844)
		(stroke
			(width 0.2)
			(type default)
		)
		(layer "In6.Cu")
	)
	(gr_arc
		(start 171.031916 -73.459594)
		(mid 170.15968 -73.16851)
		(end 169.868596 -74.040746)
		(stroke
			(width 0.2)
			(type default)
		)
		(layer "In6.Cu")
	)
	(gr_line
		(start 171.033948 -73.458578)
		(end 171.031916 -73.459594)
		(stroke
			(width 0.2)
			(type default)
		)
		(layer "In6.Cu")
	)
	(gr_line
		(start 171.034202 -73.458578)
		(end 171.033948 -73.458578)
		(stroke
			(width 0.2)
			(type default)
		)
		(layer "In6.Cu")
	)
	(gr_line
		(start 172.031406 -75.459844)
		(end 172.033692 -75.458574)
		(stroke
			(width 0.2)
			(type default)
		)
		(layer "In6.Cu")
	)
	(gr_line
		(start 172.033692 -75.458574)
		(end 171.034202 -73.458578)
		(stroke
			(width 0.2)
			(type default)
		)
		(layer "In6.Cu")
	)
	(gr_line
		(start 181.150006 -251.000006)
		(end 152.649936 -251.000006)
		(stroke
			(width 1.524)
			(type default)
		)
		(layer "In6.Cu")
	)
	(gr_line
		(start 182.150004 -258.59994)
		(end 182.150004 -252.000004)
		(stroke
			(width 1.524)
			(type default)
		)
		(layer "In6.Cu")
	)
	(gr_arc
		(start 182.150004 -252.000004)
		(mid 181.857111 -251.292899)
		(end 181.150006 -251.000006)
		(stroke
			(width 1.524)
			(type default)
		)
		(layer "In6.Cu")
	)
	(gr_line
		(start 189.349888 -258.59994)
		(end 182.150004 -258.59994)
		(stroke
			(width 5.08)
			(type default)
		)
		(layer "In6.Cu")
	)
	(gr_line
		(start 189.349888 -252.549914)
		(end 189.349888 -258.59994)
		(stroke
			(width 1.524)
			(type default)
		)
		(layer "In6.Cu")
	)
	(gr_line
		(start 189.86627 -74.042016)
		(end 190.86576 -76.042266)
		(stroke
			(width 0.2)
			(type default)
		)
		(layer "In6.Cu")
	)
	(gr_line
		(start 189.868556 -74.040746)
		(end 189.86627 -74.042016)
		(stroke
			(width 0.2)
			(type default)
		)
		(layer "In6.Cu")
	)
	(gr_line
		(start 190.86576 -76.042266)
		(end 190.868046 -76.040996)
		(stroke
			(width 0.2)
			(type default)
		)
		(layer "In6.Cu")
	)
	(gr_arc
		(start 190.868046 -76.040996)
		(mid 191.740282 -76.33208)
		(end 192.031366 -75.459844)
		(stroke
			(width 0.2)
			(type default)
		)
		(layer "In6.Cu")
	)
	(gr_arc
		(start 191.031876 -73.459594)
		(mid 190.15964 -73.16851)
		(end 189.868556 -74.040746)
		(stroke
			(width 0.2)
			(type default)
		)
		(layer "In6.Cu")
	)
	(gr_line
		(start 191.033908 -73.458578)
		(end 191.031876 -73.459594)
		(stroke
			(width 0.2)
			(type default)
		)
		(layer "In6.Cu")
	)
	(gr_line
		(start 191.034162 -73.458578)
		(end 191.033908 -73.458578)
		(stroke
			(width 0.2)
			(type default)
		)
		(layer "In6.Cu")
	)
	(gr_line
		(start 191.250062 -258.59994)
		(end 191.250062 -252.549914)
		(stroke
			(width 1.524)
			(type default)
		)
		(layer "In6.Cu")
	)
	(gr_arc
		(start 191.250062 -252.549914)
		(mid 190.300102 -251.599954)
		(end 189.349888 -252.549914)
		(stroke
			(width 1.524)
			(type default)
		)
		(layer "In6.Cu")
	)
	(gr_line
		(start 191.86652 -79.958184)
		(end 191.868806 -79.959454)
		(stroke
			(width 0.2)
			(type default)
		)
		(layer "In6.Cu")
	)
	(gr_arc
		(start 191.868806 -79.959454)
		(mid 192.15989 -80.83169)
		(end 193.032126 -80.540606)
		(stroke
			(width 0.2)
			(type default)
		)
		(layer "In6.Cu")
	)
	(gr_line
		(start 191.947038 -77.40904)
		(end 192.928748 -77.40904)
		(stroke
			(width 0.2)
			(type default)
		)
		(layer "In6.Cu")
	)
	(gr_arc
		(start 191.947038 -76.64196)
		(mid 191.563498 -77.0255)
		(end 191.947038 -77.40904)
		(stroke
			(width 0.2)
			(type default)
		)
		(layer "In6.Cu")
	)
	(gr_line
		(start 192.031366 -75.459844)
		(end 192.033652 -75.458574)
		(stroke
			(width 0.2)
			(type default)
		)
		(layer "In6.Cu")
	)
	(gr_line
		(start 192.033652 -75.458574)
		(end 191.034162 -73.458578)
		(stroke
			(width 0.2)
			(type default)
		)
		(layer "In6.Cu")
	)
	(gr_line
		(start 192.86601 -77.957934)
		(end 191.86652 -79.958184)
		(stroke
			(width 0.2)
			(type default)
		)
		(layer "In6.Cu")
	)
	(gr_line
		(start 192.868296 -77.959204)
		(end 192.86601 -77.957934)
		(stroke
			(width 0.2)
			(type default)
		)
		(layer "In6.Cu")
	)
	(gr_arc
		(start 192.928748 -77.40904)
		(mid 193.312542 -77.025627)
		(end 192.929002 -76.64196)
		(stroke
			(width 0.2)
			(type default)
		)
		(layer "In6.Cu")
	)
	(gr_line
		(start 192.929002 -76.64196)
		(end 191.947038 -76.64196)
		(stroke
			(width 0.2)
			(type default)
		)
		(layer "In6.Cu")
	)
	(gr_line
		(start 193.032126 -80.540606)
		(end 193.034412 -80.541876)
		(stroke
			(width 0.2)
			(type default)
		)
		(layer "In6.Cu")
	)
	(gr_line
		(start 193.034412 -80.541876)
		(end 194.033902 -78.54188)
		(stroke
			(width 0.2)
			(type default)
		)
		(layer "In6.Cu")
	)
	(gr_line
		(start 193.865754 -74.04227)
		(end 194.866514 -76.04252)
		(stroke
			(width 0.2)
			(type default)
		)
		(layer "In6.Cu")
	)
	(gr_line
		(start 193.86804 -74.041254)
		(end 193.865754 -74.04227)
		(stroke
			(width 0.2)
			(type default)
		)
		(layer "In6.Cu")
	)
	(gr_arc
		(start 194.031616 -78.540356)
		(mid 193.740532 -77.66812)
		(end 192.868296 -77.959204)
		(stroke
			(width 0.2)
			(type default)
		)
		(layer "In6.Cu")
	)
	(gr_line
		(start 194.033648 -78.541372)
		(end 194.031616 -78.540356)
		(stroke
			(width 0.2)
			(type default)
		)
		(layer "In6.Cu")
	)
	(gr_line
		(start 194.033902 -78.54188)
		(end 194.033648 -78.541372)
		(stroke
			(width 0.2)
			(type default)
		)
		(layer "In6.Cu")
	)
	(gr_line
		(start 194.866514 -76.04252)
		(end 194.8688 -76.041504)
		(stroke
			(width 0.2)
			(type default)
		)
		(layer "In6.Cu")
	)
	(gr_arc
		(start 194.8688 -76.041504)
		(mid 195.74129 -76.331826)
		(end 196.031612 -75.459336)
		(stroke
			(width 0.2)
			(type default)
		)
		(layer "In6.Cu")
	)
	(gr_arc
		(start 195.031106 -73.45934)
		(mid 194.158768 -73.168942)
		(end 193.86804 -74.041254)
		(stroke
			(width 0.2)
			(type default)
		)
		(layer "In6.Cu")
	)
	(gr_line
		(start 195.032884 -73.458324)
		(end 195.031106 -73.45934)
		(stroke
			(width 0.2)
			(type default)
		)
		(layer "In6.Cu")
	)
	(gr_line
		(start 195.033392 -73.458324)
		(end 195.032884 -73.458324)
		(stroke
			(width 0.2)
			(type default)
		)
		(layer "In6.Cu")
	)
	(gr_line
		(start 195.866004 -79.95793)
		(end 195.86829 -79.958946)
		(stroke
			(width 0.2)
			(type default)
		)
		(layer "In6.Cu")
	)
	(gr_arc
		(start 195.86829 -79.958946)
		(mid 196.158612 -80.831436)
		(end 197.031102 -80.541114)
		(stroke
			(width 0.2)
			(type default)
		)
		(layer "In6.Cu")
	)
	(gr_line
		(start 195.947538 -77.40904)
		(end 196.929502 -77.40904)
		(stroke
			(width 0.2)
			(type default)
		)
		(layer "In6.Cu")
	)
	(gr_arc
		(start 195.947792 -76.64196)
		(mid 195.563998 -77.025373)
		(end 195.947538 -77.40904)
		(stroke
			(width 0.2)
			(type default)
		)
		(layer "In6.Cu")
	)
	(gr_line
		(start 196.031612 -75.459336)
		(end 196.033898 -75.45832)
		(stroke
			(width 0.2)
			(type default)
		)
		(layer "In6.Cu")
	)
	(gr_line
		(start 196.033898 -75.45832)
		(end 195.033392 -73.458324)
		(stroke
			(width 0.2)
			(type default)
		)
		(layer "In6.Cu")
	)
	(gr_line
		(start 196.866764 -77.95768)
		(end 195.866004 -79.95793)
		(stroke
			(width 0.2)
			(type default)
		)
		(layer "In6.Cu")
	)
	(gr_line
		(start 196.86905 -77.958696)
		(end 196.866764 -77.95768)
		(stroke
			(width 0.2)
			(type default)
		)
		(layer "In6.Cu")
	)
	(gr_arc
		(start 196.929502 -77.40904)
		(mid 197.313042 -77.0255)
		(end 196.929502 -76.64196)
		(stroke
			(width 0.2)
			(type default)
		)
		(layer "In6.Cu")
	)
	(gr_line
		(start 196.929502 -76.64196)
		(end 195.947792 -76.64196)
		(stroke
			(width 0.2)
			(type default)
		)
		(layer "In6.Cu")
	)
	(gr_line
		(start 197.031102 -80.541114)
		(end 197.033388 -80.54213)
		(stroke
			(width 0.2)
			(type default)
		)
		(layer "In6.Cu")
	)
	(gr_line
		(start 197.033388 -80.54213)
		(end 198.034148 -78.542134)
		(stroke
			(width 0.2)
			(type default)
		)
		(layer "In6.Cu")
	)
	(gr_line
		(start 197.866 -74.042016)
		(end 198.86549 -76.042266)
		(stroke
			(width 0.2)
			(type default)
		)
		(layer "In6.Cu")
	)
	(gr_line
		(start 197.868286 -74.040746)
		(end 197.866 -74.042016)
		(stroke
			(width 0.2)
			(type default)
		)
		(layer "In6.Cu")
	)
	(gr_arc
		(start 198.032116 -78.54061)
		(mid 197.741591 -77.668399)
		(end 196.86905 -77.958696)
		(stroke
			(width 0.2)
			(type default)
		)
		(layer "In6.Cu")
	)
	(gr_line
		(start 198.033894 -78.541626)
		(end 198.032116 -78.54061)
		(stroke
			(width 0.2)
			(type default)
		)
		(layer "In6.Cu")
	)
	(gr_line
		(start 198.034148 -78.542134)
		(end 198.033894 -78.541626)
		(stroke
			(width 0.2)
			(type default)
		)
		(layer "In6.Cu")
	)
	(gr_line
		(start 198.86549 -76.042266)
		(end 198.867776 -76.040996)
		(stroke
			(width 0.2)
			(type default)
		)
		(layer "In6.Cu")
	)
	(gr_arc
		(start 198.867776 -76.040996)
		(mid 199.740012 -76.33208)
		(end 200.031096 -75.459844)
		(stroke
			(width 0.2)
			(type default)
		)
		(layer "In6.Cu")
	)
	(gr_arc
		(start 199.031606 -73.459594)
		(mid 198.15937 -73.16851)
		(end 197.868286 -74.040746)
		(stroke
			(width 0.2)
			(type default)
		)
		(layer "In6.Cu")
	)
	(gr_line
		(start 199.033638 -73.458578)
		(end 199.031606 -73.459594)
		(stroke
			(width 0.2)
			(type default)
		)
		(layer "In6.Cu")
	)
	(gr_line
		(start 199.033892 -73.458578)
		(end 199.033638 -73.458578)
		(stroke
			(width 0.2)
			(type default)
		)
		(layer "In6.Cu")
	)
	(gr_line
		(start 199.86625 -79.958184)
		(end 199.868536 -79.959454)
		(stroke
			(width 0.2)
			(type default)
		)
		(layer "In6.Cu")
	)
	(gr_arc
		(start 199.868536 -79.959454)
		(mid 200.15962 -80.83169)
		(end 201.031856 -80.540606)
		(stroke
			(width 0.2)
			(type default)
		)
		(layer "In6.Cu")
	)
	(gr_line
		(start 199.946768 -77.40904)
		(end 200.928478 -77.40904)
		(stroke
			(width 0.2)
			(type default)
		)
		(layer "In6.Cu")
	)
	(gr_arc
		(start 199.946768 -76.64196)
		(mid 199.563228 -77.0255)
		(end 199.946768 -77.40904)
		(stroke
			(width 0.2)
			(type default)
		)
		(layer "In6.Cu")
	)
	(gr_line
		(start 200.031096 -75.459844)
		(end 200.033382 -75.458574)
		(stroke
			(width 0.2)
			(type default)
		)
		(layer "In6.Cu")
	)
	(gr_line
		(start 200.033382 -75.458574)
		(end 199.033892 -73.458578)
		(stroke
			(width 0.2)
			(type default)
		)
		(layer "In6.Cu")
	)
	(gr_line
		(start 200.86574 -77.957934)
		(end 199.86625 -79.958184)
		(stroke
			(width 0.2)
			(type default)
		)
		(layer "In6.Cu")
	)
	(gr_line
		(start 200.868026 -77.959204)
		(end 200.86574 -77.957934)
		(stroke
			(width 0.2)
			(type default)
		)
		(layer "In6.Cu")
	)
	(gr_arc
		(start 200.928478 -77.40904)
		(mid 201.312272 -77.025627)
		(end 200.928732 -76.64196)
		(stroke
			(width 0.2)
			(type default)
		)
		(layer "In6.Cu")
	)
	(gr_line
		(start 200.928732 -76.64196)
		(end 199.946768 -76.64196)
		(stroke
			(width 0.2)
			(type default)
		)
		(layer "In6.Cu")
	)
	(gr_line
		(start 201.031856 -80.540606)
		(end 201.034142 -80.541876)
		(stroke
			(width 0.2)
			(type default)
		)
		(layer "In6.Cu")
	)
	(gr_line
		(start 201.034142 -80.541876)
		(end 202.033632 -78.54188)
		(stroke
			(width 0.2)
			(type default)
		)
		(layer "In6.Cu")
	)
	(gr_line
		(start 201.8665 -74.042016)
		(end 202.86599 -76.042266)
		(stroke
			(width 0.2)
			(type default)
		)
		(layer "In6.Cu")
	)
	(gr_line
		(start 201.868786 -74.040746)
		(end 201.8665 -74.042016)
		(stroke
			(width 0.2)
			(type default)
		)
		(layer "In6.Cu")
	)
	(gr_arc
		(start 202.031346 -78.540356)
		(mid 201.740262 -77.66812)
		(end 200.868026 -77.959204)
		(stroke
			(width 0.2)
			(type default)
		)
		(layer "In6.Cu")
	)
	(gr_line
		(start 202.033378 -78.541372)
		(end 202.031346 -78.540356)
		(stroke
			(width 0.2)
			(type default)
		)
		(layer "In6.Cu")
	)
	(gr_line
		(start 202.033632 -78.54188)
		(end 202.033378 -78.541372)
		(stroke
			(width 0.2)
			(type default)
		)
		(layer "In6.Cu")
	)
	(gr_line
		(start 202.449938 -258.59994)
		(end 191.250062 -258.59994)
		(stroke
			(width 5.08)
			(type default)
		)
		(layer "In6.Cu")
	)
	(gr_line
		(start 202.449938 -252.000004)
		(end 202.449938 -258.59994)
		(stroke
			(width 1.524)
			(type default)
		)
		(layer "In6.Cu")
	)
	(gr_line
		(start 202.86599 -76.042266)
		(end 202.868276 -76.040996)
		(stroke
			(width 0.2)
			(type default)
		)
		(layer "In6.Cu")
	)
	(gr_arc
		(start 202.868276 -76.040996)
		(mid 203.740512 -76.33208)
		(end 204.031596 -75.459844)
		(stroke
			(width 0.2)
			(type default)
		)
		(layer "In6.Cu")
	)
	(gr_arc
		(start 203.032106 -73.459594)
		(mid 202.15987 -73.16851)
		(end 201.868786 -74.040746)
		(stroke
			(width 0.2)
			(type default)
		)
		(layer "In6.Cu")
	)
	(gr_line
		(start 203.034138 -73.458578)
		(end 203.032106 -73.459594)
		(stroke
			(width 0.2)
			(type default)
		)
		(layer "In6.Cu")
	)
	(gr_line
		(start 203.034392 -73.458578)
		(end 203.034138 -73.458578)
		(stroke
			(width 0.2)
			(type default)
		)
		(layer "In6.Cu")
	)
	(gr_arc
		(start 203.449936 -251.000006)
		(mid 202.742831 -251.292899)
		(end 202.449938 -252.000004)
		(stroke
			(width 1.524)
			(type default)
		)
		(layer "In6.Cu")
	)
	(gr_line
		(start 203.865734 -79.95793)
		(end 203.86802 -79.958946)
		(stroke
			(width 0.2)
			(type default)
		)
		(layer "In6.Cu")
	)
	(gr_arc
		(start 203.86802 -79.958946)
		(mid 204.158342 -80.831436)
		(end 205.030832 -80.541114)
		(stroke
			(width 0.2)
			(type default)
		)
		(layer "In6.Cu")
	)
	(gr_line
		(start 203.947268 -77.40904)
		(end 204.929232 -77.40904)
		(stroke
			(width 0.2)
			(type default)
		)
		(layer "In6.Cu")
	)
	(gr_arc
		(start 203.947522 -76.64196)
		(mid 203.563728 -77.025373)
		(end 203.947268 -77.40904)
		(stroke
			(width 0.2)
			(type default)
		)
		(layer "In6.Cu")
	)
	(gr_line
		(start 204.031596 -75.459844)
		(end 204.033882 -75.458574)
		(stroke
			(width 0.2)
			(type default)
		)
		(layer "In6.Cu")
	)
	(gr_line
		(start 204.033882 -75.458574)
		(end 203.034392 -73.458578)
		(stroke
			(width 0.2)
			(type default)
		)
		(layer "In6.Cu")
	)
	(gr_line
		(start 204.866494 -77.95768)
		(end 203.865734 -79.95793)
		(stroke
			(width 0.2)
			(type default)
		)
		(layer "In6.Cu")
	)
	(gr_line
		(start 204.86878 -77.958696)
		(end 204.866494 -77.95768)
		(stroke
			(width 0.2)
			(type default)
		)
		(layer "In6.Cu")
	)
	(gr_arc
		(start 204.929232 -77.40904)
		(mid 205.312772 -77.0255)
		(end 204.929232 -76.64196)
		(stroke
			(width 0.2)
			(type default)
		)
		(layer "In6.Cu")
	)
	(gr_line
		(start 204.929232 -76.64196)
		(end 203.947522 -76.64196)
		(stroke
			(width 0.2)
			(type default)
		)
		(layer "In6.Cu")
	)
	(gr_line
		(start 205.030832 -80.541114)
		(end 205.033118 -80.54213)
		(stroke
			(width 0.2)
			(type default)
		)
		(layer "In6.Cu")
	)
	(gr_line
		(start 205.033118 -80.54213)
		(end 206.033878 -78.542134)
		(stroke
			(width 0.2)
			(type default)
		)
		(layer "In6.Cu")
	)
	(gr_line
		(start 205.865984 -74.04227)
		(end 206.866744 -76.04252)
		(stroke
			(width 0.2)
			(type default)
		)
		(layer "In6.Cu")
	)
	(gr_line
		(start 205.86827 -74.041254)
		(end 205.865984 -74.04227)
		(stroke
			(width 0.2)
			(type default)
		)
		(layer "In6.Cu")
	)
	(gr_arc
		(start 206.031846 -78.54061)
		(mid 205.741321 -77.668399)
		(end 204.86878 -77.958696)
		(stroke
			(width 0.2)
			(type default)
		)
		(layer "In6.Cu")
	)
	(gr_line
		(start 206.033624 -78.541626)
		(end 206.031846 -78.54061)
		(stroke
			(width 0.2)
			(type default)
		)
		(layer "In6.Cu")
	)
	(gr_line
		(start 206.033878 -78.542134)
		(end 206.033624 -78.541626)
		(stroke
			(width 0.2)
			(type default)
		)
		(layer "In6.Cu")
	)
	(gr_line
		(start 206.866744 -76.04252)
		(end 206.86903 -76.041504)
		(stroke
			(width 0.2)
			(type default)
		)
		(layer "In6.Cu")
	)
	(gr_arc
		(start 206.86903 -76.041504)
		(mid 207.74152 -76.331826)
		(end 208.031842 -75.459336)
		(stroke
			(width 0.2)
			(type default)
		)
		(layer "In6.Cu")
	)
	(gr_arc
		(start 207.031336 -73.45934)
		(mid 206.158998 -73.168942)
		(end 205.86827 -74.041254)
		(stroke
			(width 0.2)
			(type default)
		)
		(layer "In6.Cu")
	)
	(gr_line
		(start 207.033114 -73.458324)
		(end 207.031336 -73.45934)
		(stroke
			(width 0.2)
			(type default)
		)
		(layer "In6.Cu")
	)
	(gr_line
		(start 207.033622 -73.458324)
		(end 207.033114 -73.458324)
		(stroke
			(width 0.2)
			(type default)
		)
		(layer "In6.Cu")
	)
	(gr_line
		(start 208.031842 -75.459336)
		(end 208.034128 -75.45832)
		(stroke
			(width 0.2)
			(type default)
		)
		(layer "In6.Cu")
	)
	(gr_line
		(start 208.034128 -75.45832)
		(end 207.033622 -73.458324)
		(stroke
			(width 0.2)
			(type default)
		)
		(layer "In6.Cu")
	)
	(gr_line
		(start 211.86648 -79.958184)
		(end 211.868766 -79.959454)
		(stroke
			(width 0.2)
			(type default)
		)
		(layer "In6.Cu")
	)
	(gr_arc
		(start 211.868766 -79.959454)
		(mid 212.15985 -80.83169)
		(end 213.032086 -80.540606)
		(stroke
			(width 0.2)
			(type default)
		)
		(layer "In6.Cu")
	)
	(gr_line
		(start 212.86597 -77.957934)
		(end 211.86648 -79.958184)
		(stroke
			(width 0.2)
			(type default)
		)
		(layer "In6.Cu")
	)
	(gr_line
		(start 212.868256 -77.959204)
		(end 212.86597 -77.957934)
		(stroke
			(width 0.2)
			(type default)
		)
		(layer "In6.Cu")
	)
	(gr_line
		(start 213.032086 -80.540606)
		(end 213.034372 -80.541876)
		(stroke
			(width 0.2)
			(type default)
		)
		(layer "In6.Cu")
	)
	(gr_line
		(start 213.034372 -80.541876)
		(end 214.033862 -78.54188)
		(stroke
			(width 0.2)
			(type default)
		)
		(layer "In6.Cu")
	)
	(gr_arc
		(start 214.031576 -78.540356)
		(mid 213.740492 -77.66812)
		(end 212.868256 -77.959204)
		(stroke
			(width 0.2)
			(type default)
		)
		(layer "In6.Cu")
	)
	(gr_line
		(start 214.033608 -78.541372)
		(end 214.031576 -78.540356)
		(stroke
			(width 0.2)
			(type default)
		)
		(layer "In6.Cu")
	)
	(gr_line
		(start 214.033862 -78.54188)
		(end 214.033608 -78.541372)
		(stroke
			(width 0.2)
			(type default)
		)
		(layer "In6.Cu")
	)
	(gr_line
		(start 229.14991 -251.000006)
		(end 203.449936 -251.000006)
		(stroke
			(width 1.524)
			(type default)
		)
		(layer "In6.Cu")
	)
	(gr_arc
		(start 229.14991 -251.000006)
		(mid 232.685436 -249.53554)
		(end 234.1499 -246.000016)
		(stroke
			(width 1.524)
			(type default)
		)
		(layer "In6.Cu")
	)
	(gr_line
		(start 234.1499 -197.000114)
		(end 234.1499 -246.000016)
		(stroke
			(width 1.524)
			(type default)
		)
		(layer "In6.Cu")
	)
	(gr_arc
		(start 235.149898 -196.000116)
		(mid 234.442793 -196.293009)
		(end 234.1499 -197.000114)
		(stroke
			(width 1.524)
			(type default)
		)
		(layer "In6.Cu")
	)
	(gr_line
		(start 250.150122 -196.000116)
		(end 235.149898 -196.000116)
		(stroke
			(width 1.524)
			(type default)
		)
		(layer "In6.Cu")
	)
	(gr_line
		(start 251.15012 -246.000016)
		(end 251.15012 -197.000114)
		(stroke
			(width 1.524)
			(type default)
		)
		(layer "In6.Cu")
	)
	(gr_arc
		(start 251.15012 -246.000016)
		(mid 252.614589 -249.535529)
		(end 256.15011 -251.000006)
		(stroke
			(width 1.524)
			(type default)
		)
		(layer "In6.Cu")
	)
	(gr_arc
		(start 251.15012 -197.000114)
		(mid 250.857227 -196.293009)
		(end 250.150122 -196.000116)
		(stroke
			(width 1.524)
			(type default)
		)
		(layer "In6.Cu")
	)
	(gr_line
		(start 270.999966 -11.779758)
		(end 272.999962 -11.779758)
		(stroke
			(width 0.2)
			(type default)
		)
		(layer "In6.Cu")
	)
	(gr_arc
		(start 270.999966 -10.199878)
		(mid 270.210026 -10.989818)
		(end 270.999966 -11.779758)
		(stroke
			(width 0.2)
			(type default)
		)
		(layer "In6.Cu")
	)
	(gr_arc
		(start 272.999962 -11.779758)
		(mid 273.789902 -10.989818)
		(end 272.999962 -10.199878)
		(stroke
			(width 0.2)
			(type default)
		)
		(layer "In6.Cu")
	)
	(gr_line
		(start 272.999962 -10.199878)
		(end 270.999966 -10.199878)
		(stroke
			(width 0.2)
			(type default)
		)
		(layer "In6.Cu")
	)
	(gr_line
		(start 276.867112 -32.51454)
		(end 277.848822 -32.51454)
		(stroke
			(width 0.2)
			(type default)
		)
		(layer "In6.Cu")
	)
	(gr_arc
		(start 276.867112 -31.74746)
		(mid 276.483572 -32.131)
		(end 276.867112 -32.51454)
		(stroke
			(width 0.2)
			(type default)
		)
		(layer "In6.Cu")
	)
	(gr_arc
		(start 277.848822 -32.51454)
		(mid 278.232616 -32.131127)
		(end 277.849076 -31.74746)
		(stroke
			(width 0.2)
			(type default)
		)
		(layer "In6.Cu")
	)
	(gr_line
		(start 277.849076 -31.74746)
		(end 276.867112 -31.74746)
		(stroke
			(width 0.2)
			(type default)
		)
		(layer "In6.Cu")
	)
	(gr_arc
		(start 282.485084 -53.50002)
		(mid 282.777977 -54.207125)
		(end 283.485082 -54.500018)
		(stroke
			(width 1.524)
			(type default)
		)
		(layer "In6.Cu")
	)
	(gr_arc
		(start 282.485084 -0.999998)
		(mid 282.19219 -0.292899)
		(end 281.485086 0)
		(stroke
			(width 1.524)
			(type default)
		)
		(layer "In6.Cu")
	)
	(gr_line
		(start 282.485084 -0.999998)
		(end 282.485084 -53.50002)
		(stroke
			(width 1.524)
			(type default)
		)
		(layer "In6.Cu")
	)
	(gr_line
		(start 283.485082 -54.500018)
		(end 303.485042 -54.500018)
		(stroke
			(width 1.524)
			(type default)
		)
		(layer "In6.Cu")
	)
	(gr_arc
		(start 284.552898 -184.91327)
		(mid 284.227506 -185.347232)
		(end 284.661356 -185.67273)
		(stroke
			(width 0.2)
			(type default)
		)
		(layer "In6.Cu")
	)
	(gr_line
		(start 284.661356 -185.67273)
		(end 285.550356 -185.54573)
		(stroke
			(width 0.2)
			(type default)
		)
		(layer "In6.Cu")
	)
	(gr_line
		(start 285.441644 -184.78627)
		(end 284.552898 -184.91327)
		(stroke
			(width 0.2)
			(type default)
		)
		(layer "In6.Cu")
	)
	(gr_arc
		(start 285.550356 -185.54573)
		(mid 285.87573 -185.111644)
		(end 285.441644 -184.78627)
		(stroke
			(width 0.2)
			(type default)
		)
		(layer "In6.Cu")
	)
	(gr_arc
		(start 293.26586 -80.366616)
		(mid 293.649273 -80.75041)
		(end 294.03294 -80.36687)
		(stroke
			(width 0.2)
			(type default)
		)
		(layer "In6.Cu")
	)
	(gr_line
		(start 293.26586 -79.44993)
		(end 293.26586 -80.366616)
		(stroke
			(width 0.2)
			(type default)
		)
		(layer "In6.Cu")
	)
	(gr_line
		(start 294.03294 -80.36687)
		(end 294.03294 -79.44993)
		(stroke
			(width 0.2)
			(type default)
		)
		(layer "In6.Cu")
	)
	(gr_arc
		(start 294.03294 -79.44993)
		(mid 293.6494 -79.06639)
		(end 293.26586 -79.44993)
		(stroke
			(width 0.2)
			(type default)
		)
		(layer "In6.Cu")
	)
	(gr_arc
		(start 295.52646 -78.276196)
		(mid 295.909873 -78.65999)
		(end 296.29354 -78.27645)
		(stroke
			(width 0.2)
			(type default)
		)
		(layer "In6.Cu")
	)
	(gr_line
		(start 295.52646 -77.35951)
		(end 295.52646 -78.276196)
		(stroke
			(width 0.2)
			(type default)
		)
		(layer "In6.Cu")
	)
	(gr_line
		(start 296.29354 -78.27645)
		(end 296.29354 -77.35951)
		(stroke
			(width 0.2)
			(type default)
		)
		(layer "In6.Cu")
	)
	(gr_arc
		(start 296.29354 -77.35951)
		(mid 295.91 -76.97597)
		(end 295.52646 -77.35951)
		(stroke
			(width 0.2)
			(type default)
		)
		(layer "In6.Cu")
	)
	(gr_line
		(start 297.05681 -82.607404)
		(end 297.973496 -82.607404)
		(stroke
			(width 0.2)
			(type default)
		)
		(layer "In6.Cu")
	)
	(gr_arc
		(start 297.05681 -81.840324)
		(mid 296.67327 -82.223864)
		(end 297.05681 -82.607404)
		(stroke
			(width 0.2)
			(type default)
		)
		(layer "In6.Cu")
	)
	(gr_line
		(start 297.123358 -74.07529)
		(end 298.139104 -74.07529)
		(stroke
			(width 0.2)
			(type default)
		)
		(layer "In6.Cu")
	)
	(gr_arc
		(start 297.123358 -73.30821)
		(mid 296.739818 -73.69175)
		(end 297.123358 -74.07529)
		(stroke
			(width 0.2)
			(type default)
		)
		(layer "In6.Cu")
	)
	(gr_arc
		(start 297.973496 -82.607404)
		(mid 298.35729 -82.223991)
		(end 297.97375 -81.840324)
		(stroke
			(width 0.2)
			(type default)
		)
		(layer "In6.Cu")
	)
	(gr_line
		(start 297.97375 -81.840324)
		(end 297.05681 -81.840324)
		(stroke
			(width 0.2)
			(type default)
		)
		(layer "In6.Cu")
	)
	(gr_arc
		(start 298.139104 -74.07529)
		(mid 298.522898 -73.691877)
		(end 298.139358 -73.30821)
		(stroke
			(width 0.2)
			(type default)
		)
		(layer "In6.Cu")
	)
	(gr_line
		(start 298.139358 -73.30821)
		(end 297.123358 -73.30821)
		(stroke
			(width 0.2)
			(type default)
		)
		(layer "In6.Cu")
	)
	(gr_line
		(start 299.633132 -175.392334)
		(end 300.430438 -175.40351)
		(stroke
			(width 0.2)
			(type default)
		)
		(layer "In6.Cu")
	)
	(gr_arc
		(start 299.643546 -174.676054)
		(mid 299.280328 -175.028987)
		(end 299.633132 -175.392334)
		(stroke
			(width 0.2)
			(type default)
		)
		(layer "In6.Cu")
	)
	(gr_arc
		(start 300.430438 -175.40351)
		(mid 300.793658 -175.05045)
		(end 300.440598 -174.68723)
		(stroke
			(width 0.2)
			(type default)
		)
		(layer "In6.Cu")
	)
	(gr_line
		(start 300.440598 -174.68723)
		(end 299.643546 -174.676054)
		(stroke
			(width 0.2)
			(type default)
		)
		(layer "In6.Cu")
	)
	(gr_line
		(start 301.974758 -73.99274)
		(end 302.956722 -73.99274)
		(stroke
			(width 0.2)
			(type default)
		)
		(layer "In6.Cu")
	)
	(gr_arc
		(start 301.975012 -73.22566)
		(mid 301.591218 -73.609073)
		(end 301.974758 -73.99274)
		(stroke
			(width 0.2)
			(type default)
		)
		(layer "In6.Cu")
	)
	(gr_arc
		(start 302.214026 -173.36643)
		(mid 301.849028 -173.767496)
		(end 302.250094 -174.132494)
		(stroke
			(width 0.2)
			(type default)
		)
		(layer "In6.Cu")
	)
	(gr_line
		(start 302.214026 -173.364144)
		(end 302.214026 -173.36643)
		(stroke
			(width 0.2)
			(type default)
		)
		(layer "In6.Cu")
	)
	(gr_line
		(start 302.21428 -173.36389)
		(end 302.214026 -173.364144)
		(stroke
			(width 0.2)
			(type default)
		)
		(layer "In6.Cu")
	)
	(gr_line
		(start 302.250094 -174.135034)
		(end 303.024032 -174.098966)
		(stroke
			(width 0.2)
			(type default)
		)
		(layer "In6.Cu")
	)
	(gr_line
		(start 302.250094 -174.132494)
		(end 302.250094 -174.135034)
		(stroke
			(width 0.2)
			(type default)
		)
		(layer "In6.Cu")
	)
	(gr_arc
		(start 302.956722 -73.99274)
		(mid 303.340262 -73.6092)
		(end 302.956722 -73.22566)
		(stroke
			(width 0.2)
			(type default)
		)
		(layer "In6.Cu")
	)
	(gr_line
		(start 302.956722 -73.22566)
		(end 301.975012 -73.22566)
		(stroke
			(width 0.2)
			(type default)
		)
		(layer "In6.Cu")
	)
	(gr_line
		(start 302.987964 -173.330362)
		(end 302.987964 -173.327822)
		(stroke
			(width 0.2)
			(type default)
		)
		(layer "In6.Cu")
	)
	(gr_line
		(start 302.987964 -173.327822)
		(end 302.21428 -173.36389)
		(stroke
			(width 0.2)
			(type default)
		)
		(layer "In6.Cu")
	)
	(gr_line
		(start 303.024032 -174.098966)
		(end 303.024032 -174.096934)
		(stroke
			(width 0.2)
			(type default)
		)
		(layer "In6.Cu")
	)
	(gr_line
		(start 303.024032 -174.096934)
		(end 303.024032 -174.096426)
		(stroke
			(width 0.2)
			(type default)
		)
		(layer "In6.Cu")
	)
	(gr_arc
		(start 303.024032 -174.096426)
		(mid 303.38903 -173.69536)
		(end 302.987964 -173.330362)
		(stroke
			(width 0.2)
			(type default)
		)
		(layer "In6.Cu")
	)
	(gr_arc
		(start 303.485042 -54.500018)
		(mid 304.192147 -54.207125)
		(end 304.48504 -53.50002)
		(stroke
			(width 1.524)
			(type default)
		)
		(layer "In6.Cu")
	)
	(gr_line
		(start 303.80305 -87.908892)
		(end 304.719736 -87.908892)
		(stroke
			(width 0.2)
			(type default)
		)
		(layer "In6.Cu")
	)
	(gr_arc
		(start 303.80305 -87.141812)
		(mid 303.41951 -87.525352)
		(end 303.80305 -87.908892)
		(stroke
			(width 0.2)
			(type default)
		)
		(layer "In6.Cu")
	)
	(gr_line
		(start 304.48504 -53.50002)
		(end 304.48504 -45.500036)
		(stroke
			(width 1.524)
			(type default)
		)
		(layer "In6.Cu")
	)
	(gr_arc
		(start 304.719736 -87.908892)
		(mid 305.10353 -87.525479)
		(end 304.71999 -87.141812)
		(stroke
			(width 0.2)
			(type default)
		)
		(layer "In6.Cu")
	)
	(gr_line
		(start 304.71999 -87.141812)
		(end 303.80305 -87.141812)
		(stroke
			(width 0.2)
			(type default)
		)
		(layer "In6.Cu")
	)
	(gr_arc
		(start 305.485038 -44.500038)
		(mid 304.777921 -44.792919)
		(end 304.48504 -45.500036)
		(stroke
			(width 1.524)
			(type default)
		)
		(layer "In6.Cu")
	)
	(gr_arc
		(start 305.485038 -44.500038)
		(mid 306.192143 -44.207145)
		(end 306.485036 -43.50004)
		(stroke
			(width 1.524)
			(type default)
		)
		(layer "In6.Cu")
	)
	(gr_line
		(start 306.485036 -43.50004)
		(end 306.485036 -0.999998)
		(stroke
			(width 1.524)
			(type default)
		)
		(layer "In6.Cu")
	)
	(gr_arc
		(start 307.485034 0)
		(mid 306.777906 -0.29288)
		(end 306.485036 -0.999998)
		(stroke
			(width 1.524)
			(type default)
		)
		(layer "In6.Cu")
	)
	(gr_line
		(start 307.485034 0)
		(end 354.600002 0)
		(stroke
			(width 1.524)
			(type default)
		)
		(layer "In6.Cu")
	)
	(gr_arc
		(start 317.263018 -73.024746)
		(mid 317.671831 -73.43394)
		(end 318.080898 -73.025)
		(stroke
			(width 0.2)
			(type default)
		)
		(layer "In6.Cu")
	)
	(gr_line
		(start 317.263018 -72.009)
		(end 317.263018 -73.024746)
		(stroke
			(width 0.2)
			(type default)
		)
		(layer "In6.Cu")
	)
	(gr_arc
		(start 317.898018 -82.422746)
		(mid 318.306831 -82.83194)
		(end 318.715898 -82.423)
		(stroke
			(width 0.2)
			(type default)
		)
		(layer "In6.Cu")
	)
	(gr_line
		(start 317.898018 -81.407)
		(end 317.898018 -82.422746)
		(stroke
			(width 0.2)
			(type default)
		)
		(layer "In6.Cu")
	)
	(gr_line
		(start 317.971932 -79.440786)
		(end 317.972186 -79.44104)
		(stroke
			(width 0.2)
			(type default)
		)
		(layer "In6.Cu")
	)
	(gr_line
		(start 317.972186 -79.44104)
		(end 317.974218 -79.44104)
		(stroke
			(width 0.2)
			(type default)
		)
		(layer "In6.Cu")
	)
	(gr_arc
		(start 317.974218 -79.44104)
		(mid 318.372998 -79.86014)
		(end 318.792098 -79.46136)
		(stroke
			(width 0.2)
			(type default)
		)
		(layer "In6.Cu")
	)
	(gr_line
		(start 317.997332 -78.42504)
		(end 317.971932 -79.440786)
		(stroke
			(width 0.2)
			(type default)
		)
		(layer "In6.Cu")
	)
	(gr_line
		(start 317.999618 -78.42504)
		(end 317.997332 -78.42504)
		(stroke
			(width 0.2)
			(type default)
		)
		(layer "In6.Cu")
	)
	(gr_line
		(start 318.080898 -73.025)
		(end 318.080898 -72.009)
		(stroke
			(width 0.2)
			(type default)
		)
		(layer "In6.Cu")
	)
	(gr_arc
		(start 318.080898 -72.009)
		(mid 317.671958 -71.60006)
		(end 317.263018 -72.009)
		(stroke
			(width 0.2)
			(type default)
		)
		(layer "In6.Cu")
	)
	(gr_arc
		(start 318.372236 -69.197982)
		(mid 318.755776 -69.581522)
		(end 319.139316 -69.197982)
		(stroke
			(width 0.2)
			(type default)
		)
		(layer "In6.Cu")
	)
	(gr_line
		(start 318.372236 -68.216018)
		(end 318.372236 -69.197982)
		(stroke
			(width 0.2)
			(type default)
		)
		(layer "In6.Cu")
	)
	(gr_line
		(start 318.715898 -82.423)
		(end 318.715898 -81.407)
		(stroke
			(width 0.2)
			(type default)
		)
		(layer "In6.Cu")
	)
	(gr_arc
		(start 318.715898 -81.407)
		(mid 318.306958 -80.99806)
		(end 317.898018 -81.407)
		(stroke
			(width 0.2)
			(type default)
		)
		(layer "In6.Cu")
	)
	(gr_line
		(start 318.792098 -79.46136)
		(end 318.794384 -79.46136)
		(stroke
			(width 0.2)
			(type default)
		)
		(layer "In6.Cu")
	)
	(gr_line
		(start 318.794384 -79.46136)
		(end 318.819784 -78.44536)
		(stroke
			(width 0.2)
			(type default)
		)
		(layer "In6.Cu")
	)
	(gr_arc
		(start 318.817498 -78.44536)
		(mid 318.418718 -78.02626)
		(end 317.999618 -78.42504)
		(stroke
			(width 0.2)
			(type default)
		)
		(layer "In6.Cu")
	)
	(gr_line
		(start 318.819784 -78.44536)
		(end 318.817498 -78.44536)
		(stroke
			(width 0.2)
			(type default)
		)
		(layer "In6.Cu")
	)
	(gr_line
		(start 319.139316 -69.197982)
		(end 319.139316 -68.216272)
		(stroke
			(width 0.2)
			(type default)
		)
		(layer "In6.Cu")
	)
	(gr_arc
		(start 319.139316 -68.216272)
		(mid 318.755903 -67.832478)
		(end 318.372236 -68.216018)
		(stroke
			(width 0.2)
			(type default)
		)
		(layer "In6.Cu")
	)
	(gr_arc
		(start 319.777618 -76.191618)
		(mid 320.186431 -76.600812)
		(end 320.595498 -76.191872)
		(stroke
			(width 0.2)
			(type default)
		)
		(layer "In6.Cu")
	)
	(gr_line
		(start 319.777618 -75.209908)
		(end 319.777618 -76.191618)
		(stroke
			(width 0.2)
			(type default)
		)
		(layer "In6.Cu")
	)
	(gr_line
		(start 320.595498 -76.191872)
		(end 320.595498 -75.209908)
		(stroke
			(width 0.2)
			(type default)
		)
		(layer "In6.Cu")
	)
	(gr_arc
		(start 320.595498 -75.209908)
		(mid 320.186558 -74.800968)
		(end 319.777618 -75.209908)
		(stroke
			(width 0.2)
			(type default)
		)
		(layer "In6.Cu")
	)
	(gr_arc
		(start 337.466178 -135.715248)
		(mid 337.526438 -135.860728)
		(end 337.671918 -135.920988)
		(stroke
			(width 0.2)
			(type default)
		)
		(layer "In6.Cu")
	)
	(gr_line
		(start 337.466178 -135.054848)
		(end 337.466178 -135.715248)
		(stroke
			(width 0.2)
			(type default)
		)
		(layer "In6.Cu")
	)
	(gr_arc
		(start 337.466178 -133.683248)
		(mid 337.526438 -133.828728)
		(end 337.671918 -133.888988)
		(stroke
			(width 0.2)
			(type default)
		)
		(layer "In6.Cu")
	)
	(gr_line
		(start 337.466178 -133.022848)
		(end 337.466178 -133.683248)
		(stroke
			(width 0.2)
			(type default)
		)
		(layer "In6.Cu")
	)
	(gr_line
		(start 337.671918 -135.920988)
		(end 338.332318 -135.920988)
		(stroke
			(width 0.2)
			(type default)
		)
		(layer "In6.Cu")
	)
	(gr_arc
		(start 337.671918 -134.849108)
		(mid 337.526438 -134.909368)
		(end 337.466178 -135.054848)
		(stroke
			(width 0.2)
			(type default)
		)
		(layer "In6.Cu")
	)
	(gr_line
		(start 337.671918 -133.888988)
		(end 338.332318 -133.888988)
		(stroke
			(width 0.2)
			(type default)
		)
		(layer "In6.Cu")
	)
	(gr_arc
		(start 337.671918 -132.817108)
		(mid 337.526438 -132.877368)
		(end 337.466178 -133.022848)
		(stroke
			(width 0.2)
			(type default)
		)
		(layer "In6.Cu")
	)
	(gr_arc
		(start 338.332318 -135.920988)
		(mid 338.477798 -135.860728)
		(end 338.538058 -135.715248)
		(stroke
			(width 0.2)
			(type default)
		)
		(layer "In6.Cu")
	)
	(gr_line
		(start 338.332318 -134.849108)
		(end 337.671918 -134.849108)
		(stroke
			(width 0.2)
			(type default)
		)
		(layer "In6.Cu")
	)
	(gr_arc
		(start 338.332318 -133.888988)
		(mid 338.477798 -133.828728)
		(end 338.538058 -133.683248)
		(stroke
			(width 0.2)
			(type default)
		)
		(layer "In6.Cu")
	)
	(gr_line
		(start 338.332318 -132.817108)
		(end 337.671918 -132.817108)
		(stroke
			(width 0.2)
			(type default)
		)
		(layer "In6.Cu")
	)
	(gr_line
		(start 338.538058 -135.715248)
		(end 338.538058 -135.054848)
		(stroke
			(width 0.2)
			(type default)
		)
		(layer "In6.Cu")
	)
	(gr_arc
		(start 338.538058 -135.054848)
		(mid 338.477798 -134.909368)
		(end 338.332318 -134.849108)
		(stroke
			(width 0.2)
			(type default)
		)
		(layer "In6.Cu")
	)
	(gr_line
		(start 338.538058 -133.683248)
		(end 338.538058 -133.022848)
		(stroke
			(width 0.2)
			(type default)
		)
		(layer "In6.Cu")
	)
	(gr_arc
		(start 338.538058 -133.022848)
		(mid 338.477798 -132.877368)
		(end 338.332318 -132.817108)
		(stroke
			(width 0.2)
			(type default)
		)
		(layer "In6.Cu")
	)
	(gr_arc
		(start 338.863178 -135.715248)
		(mid 338.923438 -135.860728)
		(end 339.068918 -135.920988)
		(stroke
			(width 0.2)
			(type default)
		)
		(layer "In6.Cu")
	)
	(gr_line
		(start 338.863178 -135.054848)
		(end 338.863178 -135.715248)
		(stroke
			(width 0.2)
			(type default)
		)
		(layer "In6.Cu")
	)
	(gr_arc
		(start 338.863178 -133.683248)
		(mid 338.923438 -133.828728)
		(end 339.068918 -133.888988)
		(stroke
			(width 0.2)
			(type default)
		)
		(layer "In6.Cu")
	)
	(gr_line
		(start 338.863178 -133.022848)
		(end 338.863178 -133.683248)
		(stroke
			(width 0.2)
			(type default)
		)
		(layer "In6.Cu")
	)
	(gr_arc
		(start 338.888578 -135.715248)
		(mid 338.948838 -135.860728)
		(end 339.094318 -135.920988)
		(stroke
			(width 0.2)
			(type default)
		)
		(layer "In6.Cu")
	)
	(gr_line
		(start 338.888578 -135.054848)
		(end 338.888578 -135.715248)
		(stroke
			(width 0.2)
			(type default)
		)
		(layer "In6.Cu")
	)
	(gr_arc
		(start 338.888578 -133.683248)
		(mid 338.948838 -133.828728)
		(end 339.094318 -133.888988)
		(stroke
			(width 0.2)
			(type default)
		)
		(layer "In6.Cu")
	)
	(gr_line
		(start 338.888578 -133.022848)
		(end 338.888578 -133.683248)
		(stroke
			(width 0.2)
			(type default)
		)
		(layer "In6.Cu")
	)
	(gr_line
		(start 339.068918 -135.920988)
		(end 339.729318 -135.920988)
		(stroke
			(width 0.2)
			(type default)
		)
		(layer "In6.Cu")
	)
	(gr_arc
		(start 339.068918 -134.849108)
		(mid 338.923438 -134.909368)
		(end 338.863178 -135.054848)
		(stroke
			(width 0.2)
			(type default)
		)
		(layer "In6.Cu")
	)
	(gr_line
		(start 339.068918 -133.888988)
		(end 339.729318 -133.888988)
		(stroke
			(width 0.2)
			(type default)
		)
		(layer "In6.Cu")
	)
	(gr_arc
		(start 339.068918 -132.817108)
		(mid 338.923438 -132.877368)
		(end 338.863178 -133.022848)
		(stroke
			(width 0.2)
			(type default)
		)
		(layer "In6.Cu")
	)
	(gr_line
		(start 339.094318 -135.920988)
		(end 339.754718 -135.920988)
		(stroke
			(width 0.2)
			(type default)
		)
		(layer "In6.Cu")
	)
	(gr_arc
		(start 339.094318 -134.849108)
		(mid 338.948838 -134.909368)
		(end 338.888578 -135.054848)
		(stroke
			(width 0.2)
			(type default)
		)
		(layer "In6.Cu")
	)
	(gr_line
		(start 339.094318 -133.888988)
		(end 339.754718 -133.888988)
		(stroke
			(width 0.2)
			(type default)
		)
		(layer "In6.Cu")
	)
	(gr_arc
		(start 339.094318 -132.817108)
		(mid 338.948838 -132.877368)
		(end 338.888578 -133.022848)
		(stroke
			(width 0.2)
			(type default)
		)
		(layer "In6.Cu")
	)
	(gr_arc
		(start 339.729318 -135.920988)
		(mid 339.874798 -135.860728)
		(end 339.935058 -135.715248)
		(stroke
			(width 0.2)
			(type default)
		)
		(layer "In6.Cu")
	)
	(gr_line
		(start 339.729318 -134.849108)
		(end 339.068918 -134.849108)
		(stroke
			(width 0.2)
			(type default)
		)
		(layer "In6.Cu")
	)
	(gr_arc
		(start 339.729318 -133.888988)
		(mid 339.874798 -133.828728)
		(end 339.935058 -133.683248)
		(stroke
			(width 0.2)
			(type default)
		)
		(layer "In6.Cu")
	)
	(gr_line
		(start 339.729318 -132.817108)
		(end 339.068918 -132.817108)
		(stroke
			(width 0.2)
			(type default)
		)
		(layer "In6.Cu")
	)
	(gr_arc
		(start 339.754718 -135.920988)
		(mid 339.900198 -135.860728)
		(end 339.960458 -135.715248)
		(stroke
			(width 0.2)
			(type default)
		)
		(layer "In6.Cu")
	)
	(gr_line
		(start 339.754718 -134.849108)
		(end 339.094318 -134.849108)
		(stroke
			(width 0.2)
			(type default)
		)
		(layer "In6.Cu")
	)
	(gr_arc
		(start 339.754718 -133.888988)
		(mid 339.900198 -133.828728)
		(end 339.960458 -133.683248)
		(stroke
			(width 0.2)
			(type default)
		)
		(layer "In6.Cu")
	)
	(gr_line
		(start 339.754718 -132.817108)
		(end 339.094318 -132.817108)
		(stroke
			(width 0.2)
			(type default)
		)
		(layer "In6.Cu")
	)
	(gr_line
		(start 339.935058 -135.715248)
		(end 339.935058 -135.054848)
		(stroke
			(width 0.2)
			(type default)
		)
		(layer "In6.Cu")
	)
	(gr_arc
		(start 339.935058 -135.054848)
		(mid 339.874798 -134.909368)
		(end 339.729318 -134.849108)
		(stroke
			(width 0.2)
			(type default)
		)
		(layer "In6.Cu")
	)
	(gr_line
		(start 339.935058 -133.683248)
		(end 339.935058 -133.022848)
		(stroke
			(width 0.2)
			(type default)
		)
		(layer "In6.Cu")
	)
	(gr_arc
		(start 339.935058 -133.022848)
		(mid 339.874798 -132.877368)
		(end 339.729318 -132.817108)
		(stroke
			(width 0.2)
			(type default)
		)
		(layer "In6.Cu")
	)
	(gr_line
		(start 339.960458 -135.715248)
		(end 339.960458 -135.054848)
		(stroke
			(width 0.2)
			(type default)
		)
		(layer "In6.Cu")
	)
	(gr_arc
		(start 339.960458 -135.054848)
		(mid 339.900198 -134.909368)
		(end 339.754718 -134.849108)
		(stroke
			(width 0.2)
			(type default)
		)
		(layer "In6.Cu")
	)
	(gr_line
		(start 339.960458 -133.683248)
		(end 339.960458 -133.022848)
		(stroke
			(width 0.2)
			(type default)
		)
		(layer "In6.Cu")
	)
	(gr_arc
		(start 339.960458 -133.022848)
		(mid 339.900198 -132.877368)
		(end 339.754718 -132.817108)
		(stroke
			(width 0.2)
			(type default)
		)
		(layer "In6.Cu")
	)
	(gr_arc
		(start 340.260178 -135.715248)
		(mid 340.320438 -135.860728)
		(end 340.465918 -135.920988)
		(stroke
			(width 0.2)
			(type default)
		)
		(layer "In6.Cu")
	)
	(gr_line
		(start 340.260178 -135.054848)
		(end 340.260178 -135.715248)
		(stroke
			(width 0.2)
			(type default)
		)
		(layer "In6.Cu")
	)
	(gr_arc
		(start 340.260178 -133.683248)
		(mid 340.320438 -133.828728)
		(end 340.465918 -133.888988)
		(stroke
			(width 0.2)
			(type default)
		)
		(layer "In6.Cu")
	)
	(gr_line
		(start 340.260178 -133.022848)
		(end 340.260178 -133.683248)
		(stroke
			(width 0.2)
			(type default)
		)
		(layer "In6.Cu")
	)
	(gr_arc
		(start 340.285578 -135.715248)
		(mid 340.345838 -135.860728)
		(end 340.491318 -135.920988)
		(stroke
			(width 0.2)
			(type default)
		)
		(layer "In6.Cu")
	)
	(gr_line
		(start 340.285578 -135.054848)
		(end 340.285578 -135.715248)
		(stroke
			(width 0.2)
			(type default)
		)
		(layer "In6.Cu")
	)
	(gr_arc
		(start 340.285578 -133.683248)
		(mid 340.345838 -133.828728)
		(end 340.491318 -133.888988)
		(stroke
			(width 0.2)
			(type default)
		)
		(layer "In6.Cu")
	)
	(gr_line
		(start 340.285578 -133.022848)
		(end 340.285578 -133.683248)
		(stroke
			(width 0.2)
			(type default)
		)
		(layer "In6.Cu")
	)
	(gr_line
		(start 340.465918 -135.920988)
		(end 341.126318 -135.920988)
		(stroke
			(width 0.2)
			(type default)
		)
		(layer "In6.Cu")
	)
	(gr_arc
		(start 340.465918 -134.849108)
		(mid 340.320438 -134.909368)
		(end 340.260178 -135.054848)
		(stroke
			(width 0.2)
			(type default)
		)
		(layer "In6.Cu")
	)
	(gr_line
		(start 340.465918 -133.888988)
		(end 341.126318 -133.888988)
		(stroke
			(width 0.2)
			(type default)
		)
		(layer "In6.Cu")
	)
	(gr_arc
		(start 340.465918 -132.817108)
		(mid 340.320438 -132.877368)
		(end 340.260178 -133.022848)
		(stroke
			(width 0.2)
			(type default)
		)
		(layer "In6.Cu")
	)
	(gr_line
		(start 340.491318 -135.920988)
		(end 341.151718 -135.920988)
		(stroke
			(width 0.2)
			(type default)
		)
		(layer "In6.Cu")
	)
	(gr_arc
		(start 340.491318 -134.849108)
		(mid 340.345838 -134.909368)
		(end 340.285578 -135.054848)
		(stroke
			(width 0.2)
			(type default)
		)
		(layer "In6.Cu")
	)
	(gr_line
		(start 340.491318 -133.888988)
		(end 341.151718 -133.888988)
		(stroke
			(width 0.2)
			(type default)
		)
		(layer "In6.Cu")
	)
	(gr_arc
		(start 340.491318 -132.817108)
		(mid 340.345838 -132.877368)
		(end 340.285578 -133.022848)
		(stroke
			(width 0.2)
			(type default)
		)
		(layer "In6.Cu")
	)
	(gr_arc
		(start 341.126318 -135.920988)
		(mid 341.271798 -135.860728)
		(end 341.332058 -135.715248)
		(stroke
			(width 0.2)
			(type default)
		)
		(layer "In6.Cu")
	)
	(gr_line
		(start 341.126318 -134.849108)
		(end 340.465918 -134.849108)
		(stroke
			(width 0.2)
			(type default)
		)
		(layer "In6.Cu")
	)
	(gr_arc
		(start 341.126318 -133.888988)
		(mid 341.271798 -133.828728)
		(end 341.332058 -133.683248)
		(stroke
			(width 0.2)
			(type default)
		)
		(layer "In6.Cu")
	)
	(gr_line
		(start 341.126318 -132.817108)
		(end 340.465918 -132.817108)
		(stroke
			(width 0.2)
			(type default)
		)
		(layer "In6.Cu")
	)
	(gr_arc
		(start 341.151718 -135.920988)
		(mid 341.297198 -135.860728)
		(end 341.357458 -135.715248)
		(stroke
			(width 0.2)
			(type default)
		)
		(layer "In6.Cu")
	)
	(gr_line
		(start 341.151718 -134.849108)
		(end 340.491318 -134.849108)
		(stroke
			(width 0.2)
			(type default)
		)
		(layer "In6.Cu")
	)
	(gr_arc
		(start 341.151718 -133.888988)
		(mid 341.297198 -133.828728)
		(end 341.357458 -133.683248)
		(stroke
			(width 0.2)
			(type default)
		)
		(layer "In6.Cu")
	)
	(gr_line
		(start 341.151718 -132.817108)
		(end 340.491318 -132.817108)
		(stroke
			(width 0.2)
			(type default)
		)
		(layer "In6.Cu")
	)
	(gr_line
		(start 341.332058 -135.715248)
		(end 341.332058 -135.054848)
		(stroke
			(width 0.2)
			(type default)
		)
		(layer "In6.Cu")
	)
	(gr_arc
		(start 341.332058 -135.054848)
		(mid 341.271798 -134.909368)
		(end 341.126318 -134.849108)
		(stroke
			(width 0.2)
			(type default)
		)
		(layer "In6.Cu")
	)
	(gr_line
		(start 341.332058 -133.683248)
		(end 341.332058 -133.022848)
		(stroke
			(width 0.2)
			(type default)
		)
		(layer "In6.Cu")
	)
	(gr_arc
		(start 341.332058 -133.022848)
		(mid 341.271798 -132.877368)
		(end 341.126318 -132.817108)
		(stroke
			(width 0.2)
			(type default)
		)
		(layer "In6.Cu")
	)
	(gr_line
		(start 341.357458 -135.715248)
		(end 341.357458 -135.054848)
		(stroke
			(width 0.2)
			(type default)
		)
		(layer "In6.Cu")
	)
	(gr_arc
		(start 341.357458 -135.054848)
		(mid 341.297198 -134.909368)
		(end 341.151718 -134.849108)
		(stroke
			(width 0.2)
			(type default)
		)
		(layer "In6.Cu")
	)
	(gr_line
		(start 341.357458 -133.683248)
		(end 341.357458 -133.022848)
		(stroke
			(width 0.2)
			(type default)
		)
		(layer "In6.Cu")
	)
	(gr_arc
		(start 341.357458 -133.022848)
		(mid 341.297198 -132.877368)
		(end 341.151718 -132.817108)
		(stroke
			(width 0.2)
			(type default)
		)
		(layer "In6.Cu")
	)
	(gr_arc
		(start 341.682578 -135.715248)
		(mid 341.742838 -135.860728)
		(end 341.888318 -135.920988)
		(stroke
			(width 0.2)
			(type default)
		)
		(layer "In6.Cu")
	)
	(gr_line
		(start 341.682578 -135.054848)
		(end 341.682578 -135.715248)
		(stroke
			(width 0.2)
			(type default)
		)
		(layer "In6.Cu")
	)
	(gr_arc
		(start 341.682578 -133.683248)
		(mid 341.742838 -133.828728)
		(end 341.888318 -133.888988)
		(stroke
			(width 0.2)
			(type default)
		)
		(layer "In6.Cu")
	)
	(gr_line
		(start 341.682578 -133.022848)
		(end 341.682578 -133.683248)
		(stroke
			(width 0.2)
			(type default)
		)
		(layer "In6.Cu")
	)
	(gr_line
		(start 341.888318 -135.920988)
		(end 342.548718 -135.920988)
		(stroke
			(width 0.2)
			(type default)
		)
		(layer "In6.Cu")
	)
	(gr_arc
		(start 341.888318 -134.849108)
		(mid 341.742838 -134.909368)
		(end 341.682578 -135.054848)
		(stroke
			(width 0.2)
			(type default)
		)
		(layer "In6.Cu")
	)
	(gr_line
		(start 341.888318 -133.888988)
		(end 342.548718 -133.888988)
		(stroke
			(width 0.2)
			(type default)
		)
		(layer "In6.Cu")
	)
	(gr_arc
		(start 341.888318 -132.817108)
		(mid 341.742838 -132.877368)
		(end 341.682578 -133.022848)
		(stroke
			(width 0.2)
			(type default)
		)
		(layer "In6.Cu")
	)
	(gr_arc
		(start 342.548718 -135.920988)
		(mid 342.694198 -135.860728)
		(end 342.754458 -135.715248)
		(stroke
			(width 0.2)
			(type default)
		)
		(layer "In6.Cu")
	)
	(gr_line
		(start 342.548718 -134.849108)
		(end 341.888318 -134.849108)
		(stroke
			(width 0.2)
			(type default)
		)
		(layer "In6.Cu")
	)
	(gr_arc
		(start 342.548718 -133.888988)
		(mid 342.694198 -133.828728)
		(end 342.754458 -133.683248)
		(stroke
			(width 0.2)
			(type default)
		)
		(layer "In6.Cu")
	)
	(gr_line
		(start 342.548718 -132.817108)
		(end 341.888318 -132.817108)
		(stroke
			(width 0.2)
			(type default)
		)
		(layer "In6.Cu")
	)
	(gr_line
		(start 342.754458 -135.715248)
		(end 342.754458 -135.054848)
		(stroke
			(width 0.2)
			(type default)
		)
		(layer "In6.Cu")
	)
	(gr_arc
		(start 342.754458 -135.054848)
		(mid 342.694198 -134.909368)
		(end 342.548718 -134.849108)
		(stroke
			(width 0.2)
			(type default)
		)
		(layer "In6.Cu")
	)
	(gr_line
		(start 342.754458 -133.683248)
		(end 342.754458 -133.022848)
		(stroke
			(width 0.2)
			(type default)
		)
		(layer "In6.Cu")
	)
	(gr_arc
		(start 342.754458 -133.022848)
		(mid 342.694198 -132.877368)
		(end 342.548718 -132.817108)
		(stroke
			(width 0.2)
			(type default)
		)
		(layer "In6.Cu")
	)
	(gr_arc
		(start 349.652844 -155.154884)
		(mid 350.010857 -155.513278)
		(end 350.369124 -155.155138)
		(stroke
			(width 0.2)
			(type default)
		)
		(layer "In6.Cu")
	)
	(gr_line
		(start 349.652844 -154.275028)
		(end 349.652844 -155.154884)
		(stroke
			(width 0.2)
			(type default)
		)
		(layer "In6.Cu")
	)
	(gr_line
		(start 350.369124 -155.155138)
		(end 350.369124 -154.275028)
		(stroke
			(width 0.2)
			(type default)
		)
		(layer "In6.Cu")
	)
	(gr_arc
		(start 350.369124 -154.275028)
		(mid 350.010984 -153.916888)
		(end 349.652844 -154.275028)
		(stroke
			(width 0.2)
			(type default)
		)
		(layer "In6.Cu")
	)
	(gr_arc
		(start 350.39681 -152.916636)
		(mid 350.754823 -153.27503)
		(end 351.11309 -152.91689)
		(stroke
			(width 0.2)
			(type default)
		)
		(layer "In6.Cu")
	)
	(gr_line
		(start 350.39681 -151.97201)
		(end 350.39681 -152.916636)
		(stroke
			(width 0.2)
			(type default)
		)
		(layer "In6.Cu")
	)
	(gr_line
		(start 350.60001 -251.000006)
		(end 256.15011 -251.000006)
		(stroke
			(width 1.524)
			(type default)
		)
		(layer "In6.Cu")
	)
	(gr_arc
		(start 350.60001 -251.000006)
		(mid 354.135536 -249.53554)
		(end 355.6 -246.000016)
		(stroke
			(width 1.524)
			(type default)
		)
		(layer "In6.Cu")
	)
	(gr_line
		(start 350.87941 -147.98167)
		(end 351.824036 -147.98167)
		(stroke
			(width 0.2)
			(type default)
		)
		(layer "In6.Cu")
	)
	(gr_arc
		(start 350.87941 -147.26539)
		(mid 350.52127 -147.62353)
		(end 350.87941 -147.98167)
		(stroke
			(width 0.2)
			(type default)
		)
		(layer "In6.Cu")
	)
	(gr_line
		(start 351.11309 -152.91689)
		(end 351.11309 -151.97201)
		(stroke
			(width 0.2)
			(type default)
		)
		(layer "In6.Cu")
	)
	(gr_arc
		(start 351.11309 -151.97201)
		(mid 350.75495 -151.61387)
		(end 350.39681 -151.97201)
		(stroke
			(width 0.2)
			(type default)
		)
		(layer "In6.Cu")
	)
	(gr_arc
		(start 351.824036 -147.98167)
		(mid 352.18243 -147.623657)
		(end 351.82429 -147.26539)
		(stroke
			(width 0.2)
			(type default)
		)
		(layer "In6.Cu")
	)
	(gr_line
		(start 351.82429 -147.26539)
		(end 350.87941 -147.26539)
		(stroke
			(width 0.2)
			(type default)
		)
		(layer "In6.Cu")
	)
	(gr_arc
		(start 355.6 -0.999998)
		(mid 355.307107 -0.292893)
		(end 354.600002 0)
		(stroke
			(width 1.524)
			(type default)
		)
		(layer "In6.Cu")
	)
	(gr_line
		(start 355.6 -0.999998)
		(end 355.6 -246.000016)
		(stroke
			(width 1.524)
			(type default)
		)
		(layer "In6.Cu")
	)
	(gr_line
		(start 0 -246.000016)
		(end 0 -81.009998)
		(stroke
			(width 0.05)
			(type default)
		)
		(layer "Edge.Cuts")
	)
	(gr_arc
		(start 0 -246.000016)
		(mid 1.464462 -249.535545)
		(end 4.99999 -251.000006)
		(stroke
			(width 0.05)
			(type default)
		)
		(layer "Edge.Cuts")
	)
	(gr_arc
		(start 2.999994 -78.010004)
		(mid 0.878678 -78.888682)
		(end 0 -81.009998)
		(stroke
			(width 0.05)
			(type default)
		)
		(layer "Edge.Cuts")
	)
	(gr_line
		(start 2.999994 -78.010004)
		(end 25.500076 -78.010004)
		(stroke
			(width 0.05)
			(type default)
		)
		(layer "Edge.Cuts")
	)
	(gr_arc
		(start 25.500076 -78.010004)
		(mid 26.914287 -77.424219)
		(end 27.500072 -76.010008)
		(stroke
			(width 0.05)
			(type default)
		)
		(layer "Edge.Cuts")
	)
	(gr_line
		(start 26.34996 -251.000006)
		(end 4.99999 -251.000006)
		(stroke
			(width 0.05)
			(type default)
		)
		(layer "Edge.Cuts")
	)
	(gr_line
		(start 27.349958 -258.59994)
		(end 27.349958 -252.000004)
		(stroke
			(width 0.05)
			(type default)
		)
		(layer "Edge.Cuts")
	)
	(gr_arc
		(start 27.349958 -252.000004)
		(mid 27.057065 -251.292899)
		(end 26.34996 -251.000006)
		(stroke
			(width 0.05)
			(type default)
		)
		(layer "Edge.Cuts")
	)
	(gr_line
		(start 27.500072 -76.010008)
		(end 27.500072 -60.01004)
		(stroke
			(width 0.05)
			(type default)
		)
		(layer "Edge.Cuts")
	)
	(gr_arc
		(start 29.500068 -58.010044)
		(mid 28.085859 -58.59583)
		(end 27.500072 -60.01004)
		(stroke
			(width 0.05)
			(type default)
		)
		(layer "Edge.Cuts")
	)
	(gr_line
		(start 29.500068 -58.010044)
		(end 60.950094 -58.010044)
		(stroke
			(width 0.05)
			(type default)
		)
		(layer "Edge.Cuts")
	)
	(gr_line
		(start 34.550096 -258.59994)
		(end 27.349958 -258.59994)
		(stroke
			(width 0.05)
			(type default)
		)
		(layer "Edge.Cuts")
	)
	(gr_line
		(start 34.550096 -252.549914)
		(end 34.550096 -258.59994)
		(stroke
			(width 0.05)
			(type default)
		)
		(layer "Edge.Cuts")
	)
	(gr_line
		(start 36.450016 -258.59994)
		(end 36.450016 -252.549914)
		(stroke
			(width 0.05)
			(type default)
		)
		(layer "Edge.Cuts")
	)
	(gr_arc
		(start 36.450016 -252.549914)
		(mid 35.500056 -251.599954)
		(end 34.550096 -252.549914)
		(stroke
			(width 0.05)
			(type default)
		)
		(layer "Edge.Cuts")
	)
	(gr_line
		(start 47.649892 -258.59994)
		(end 36.450016 -258.59994)
		(stroke
			(width 0.05)
			(type default)
		)
		(layer "Edge.Cuts")
	)
	(gr_line
		(start 47.649892 -252.000004)
		(end 47.649892 -258.59994)
		(stroke
			(width 0.05)
			(type default)
		)
		(layer "Edge.Cuts")
	)
	(gr_arc
		(start 48.64989 -251.000006)
		(mid 47.942785 -251.292899)
		(end 47.649892 -252.000004)
		(stroke
			(width 0.05)
			(type default)
		)
		(layer "Edge.Cuts")
	)
	(gr_arc
		(start 60.950094 -58.010044)
		(mid 61.657199 -57.717151)
		(end 61.950092 -57.010046)
		(stroke
			(width 0.05)
			(type default)
		)
		(layer "Edge.Cuts")
	)
	(gr_line
		(start 61.950092 -57.010046)
		(end 61.950092 -17.999964)
		(stroke
			(width 0.05)
			(type default)
		)
		(layer "Edge.Cuts")
	)
	(gr_arc
		(start 62.95009 -16.999966)
		(mid 62.242978 -17.29286)
		(end 61.950092 -17.999964)
		(stroke
			(width 0.05)
			(type default)
		)
		(layer "Edge.Cuts")
	)
	(gr_line
		(start 62.95009 -16.999966)
		(end 73.449942 -16.999966)
		(stroke
			(width 0.05)
			(type default)
		)
		(layer "Edge.Cuts")
	)
	(gr_line
		(start 66.34988 -251.000006)
		(end 48.64989 -251.000006)
		(stroke
			(width 0.05)
			(type default)
		)
		(layer "Edge.Cuts")
	)
	(gr_line
		(start 67.349878 -258.59994)
		(end 67.349878 -252.000004)
		(stroke
			(width 0.05)
			(type default)
		)
		(layer "Edge.Cuts")
	)
	(gr_arc
		(start 67.349878 -252.000004)
		(mid 67.056985 -251.292899)
		(end 66.34988 -251.000006)
		(stroke
			(width 0.05)
			(type default)
		)
		(layer "Edge.Cuts")
	)
	(gr_arc
		(start 73.449942 -16.999966)
		(mid 74.157047 -16.707073)
		(end 74.44994 -15.999968)
		(stroke
			(width 0.05)
			(type default)
		)
		(layer "Edge.Cuts")
	)
	(gr_line
		(start 74.44994 -15.999968)
		(end 74.44994 -0.999998)
		(stroke
			(width 0.05)
			(type default)
		)
		(layer "Edge.Cuts")
	)
	(gr_arc
		(start 75.449938 0)
		(mid 74.742807 -0.292879)
		(end 74.44994 -0.999998)
		(stroke
			(width 0.05)
			(type default)
		)
		(layer "Edge.Cuts")
	)
	(gr_line
		(start 75.449938 0)
		(end 281.485086 0)
		(stroke
			(width 0.05)
			(type default)
		)
		(layer "Edge.Cuts")
	)
	(gr_line
		(start 138.549888 -258.59994)
		(end 67.349878 -258.59994)
		(stroke
			(width 0.05)
			(type default)
		)
		(layer "Edge.Cuts")
	)
	(gr_line
		(start 138.549888 -252.549914)
		(end 138.549888 -258.59994)
		(stroke
			(width 0.05)
			(type default)
		)
		(layer "Edge.Cuts")
	)
	(gr_line
		(start 140.450062 -258.59994)
		(end 140.450062 -252.549914)
		(stroke
			(width 0.05)
			(type default)
		)
		(layer "Edge.Cuts")
	)
	(gr_arc
		(start 140.450062 -252.549914)
		(mid 139.500102 -251.599954)
		(end 138.549888 -252.549914)
		(stroke
			(width 0.05)
			(type default)
		)
		(layer "Edge.Cuts")
	)
	(gr_line
		(start 151.649938 -258.59994)
		(end 140.450062 -258.59994)
		(stroke
			(width 0.05)
			(type default)
		)
		(layer "Edge.Cuts")
	)
	(gr_line
		(start 151.649938 -252.000004)
		(end 151.649938 -258.59994)
		(stroke
			(width 0.05)
			(type default)
		)
		(layer "Edge.Cuts")
	)
	(gr_arc
		(start 152.649936 -251.000006)
		(mid 151.942831 -251.292899)
		(end 151.649938 -252.000004)
		(stroke
			(width 0.05)
			(type default)
		)
		(layer "Edge.Cuts")
	)
	(gr_line
		(start 181.150006 -251.000006)
		(end 152.649936 -251.000006)
		(stroke
			(width 0.05)
			(type default)
		)
		(layer "Edge.Cuts")
	)
	(gr_line
		(start 182.150004 -258.59994)
		(end 182.150004 -252.000004)
		(stroke
			(width 0.05)
			(type default)
		)
		(layer "Edge.Cuts")
	)
	(gr_arc
		(start 182.150004 -252.000004)
		(mid 181.857111 -251.292899)
		(end 181.150006 -251.000006)
		(stroke
			(width 0.05)
			(type default)
		)
		(layer "Edge.Cuts")
	)
	(gr_line
		(start 189.349888 -258.59994)
		(end 182.150004 -258.59994)
		(stroke
			(width 0.05)
			(type default)
		)
		(layer "Edge.Cuts")
	)
	(gr_line
		(start 189.349888 -252.549914)
		(end 189.349888 -258.59994)
		(stroke
			(width 0.05)
			(type default)
		)
		(layer "Edge.Cuts")
	)
	(gr_line
		(start 191.250062 -258.59994)
		(end 191.250062 -252.549914)
		(stroke
			(width 0.05)
			(type default)
		)
		(layer "Edge.Cuts")
	)
	(gr_arc
		(start 191.250062 -252.549914)
		(mid 190.300102 -251.599954)
		(end 189.349888 -252.549914)
		(stroke
			(width 0.05)
			(type default)
		)
		(layer "Edge.Cuts")
	)
	(gr_line
		(start 202.449938 -258.59994)
		(end 191.250062 -258.59994)
		(stroke
			(width 0.05)
			(type default)
		)
		(layer "Edge.Cuts")
	)
	(gr_line
		(start 202.449938 -252.000004)
		(end 202.449938 -258.59994)
		(stroke
			(width 0.05)
			(type default)
		)
		(layer "Edge.Cuts")
	)
	(gr_arc
		(start 203.449936 -251.000006)
		(mid 202.742831 -251.292899)
		(end 202.449938 -252.000004)
		(stroke
			(width 0.05)
			(type default)
		)
		(layer "Edge.Cuts")
	)
	(gr_line
		(start 229.14991 -251.000006)
		(end 203.449936 -251.000006)
		(stroke
			(width 0.05)
			(type default)
		)
		(layer "Edge.Cuts")
	)
	(gr_arc
		(start 229.14991 -251.000006)
		(mid 232.685436 -249.53554)
		(end 234.1499 -246.000016)
		(stroke
			(width 0.05)
			(type default)
		)
		(layer "Edge.Cuts")
	)
	(gr_line
		(start 234.1499 -197.000114)
		(end 234.1499 -246.000016)
		(stroke
			(width 0.05)
			(type default)
		)
		(layer "Edge.Cuts")
	)
	(gr_arc
		(start 235.149898 -196.000116)
		(mid 234.442793 -196.293009)
		(end 234.1499 -197.000114)
		(stroke
			(width 0.05)
			(type default)
		)
		(layer "Edge.Cuts")
	)
	(gr_line
		(start 250.150122 -196.000116)
		(end 235.149898 -196.000116)
		(stroke
			(width 0.05)
			(type default)
		)
		(layer "Edge.Cuts")
	)
	(gr_line
		(start 251.15012 -246.000016)
		(end 251.15012 -197.000114)
		(stroke
			(width 0.05)
			(type default)
		)
		(layer "Edge.Cuts")
	)
	(gr_arc
		(start 251.15012 -246.000016)
		(mid 252.614589 -249.535529)
		(end 256.15011 -251.000006)
		(stroke
			(width 0.05)
			(type default)
		)
		(layer "Edge.Cuts")
	)
	(gr_arc
		(start 251.15012 -197.000114)
		(mid 250.857227 -196.293009)
		(end 250.150122 -196.000116)
		(stroke
			(width 0.05)
			(type default)
		)
		(layer "Edge.Cuts")
	)
	(gr_line
		(start 255.299972 -106.100118)
		(end 256.899918 -106.100118)
		(stroke
			(width 0.05)
			(type default)
		)
		(layer "Edge.Cuts")
	)
	(gr_arc
		(start 255.299972 -102.899972)
		(mid 253.699772 -104.500172)
		(end 255.299972 -106.100118)
		(stroke
			(width 0.05)
			(type default)
		)
		(layer "Edge.Cuts")
	)
	(gr_line
		(start 255.299972 -63.600076)
		(end 256.899918 -63.600076)
		(stroke
			(width 0.05)
			(type default)
		)
		(layer "Edge.Cuts")
	)
	(gr_arc
		(start 255.299972 -60.39993)
		(mid 253.699772 -62.00013)
		(end 255.299972 -63.600076)
		(stroke
			(width 0.05)
			(type default)
		)
		(layer "Edge.Cuts")
	)
	(gr_arc
		(start 256.899918 -106.100118)
		(mid 258.499864 -104.500172)
		(end 256.899918 -102.899972)
		(stroke
			(width 0.05)
			(type default)
		)
		(layer "Edge.Cuts")
	)
	(gr_line
		(start 256.899918 -102.899972)
		(end 255.299972 -102.899972)
		(stroke
			(width 0.05)
			(type default)
		)
		(layer "Edge.Cuts")
	)
	(gr_arc
		(start 256.899918 -63.600076)
		(mid 258.499864 -62.00013)
		(end 256.899918 -60.39993)
		(stroke
			(width 0.05)
			(type default)
		)
		(layer "Edge.Cuts")
	)
	(gr_line
		(start 256.899918 -60.39993)
		(end 255.299972 -60.39993)
		(stroke
			(width 0.05)
			(type default)
		)
		(layer "Edge.Cuts")
	)
	(gr_arc
		(start 282.485084 -53.50002)
		(mid 282.777977 -54.207125)
		(end 283.485082 -54.500018)
		(stroke
			(width 0.05)
			(type default)
		)
		(layer "Edge.Cuts")
	)
	(gr_arc
		(start 282.485084 -0.999998)
		(mid 282.19219 -0.292899)
		(end 281.485086 0)
		(stroke
			(width 0.05)
			(type default)
		)
		(layer "Edge.Cuts")
	)
	(gr_line
		(start 282.485084 -0.999998)
		(end 282.485084 -53.50002)
		(stroke
			(width 0.05)
			(type default)
		)
		(layer "Edge.Cuts")
	)
	(gr_line
		(start 283.485082 -54.500018)
		(end 303.485042 -54.500018)
		(stroke
			(width 0.05)
			(type default)
		)
		(layer "Edge.Cuts")
	)
	(gr_arc
		(start 303.485042 -54.500018)
		(mid 304.192147 -54.207125)
		(end 304.48504 -53.50002)
		(stroke
			(width 0.05)
			(type default)
		)
		(layer "Edge.Cuts")
	)
	(gr_line
		(start 304.48504 -53.50002)
		(end 304.48504 -45.500036)
		(stroke
			(width 0.05)
			(type default)
		)
		(layer "Edge.Cuts")
	)
	(gr_arc
		(start 305.485038 -44.500038)
		(mid 304.777921 -44.792919)
		(end 304.48504 -45.500036)
		(stroke
			(width 0.05)
			(type default)
		)
		(layer "Edge.Cuts")
	)
	(gr_arc
		(start 305.485038 -44.500038)
		(mid 306.192143 -44.207145)
		(end 306.485036 -43.50004)
		(stroke
			(width 0.05)
			(type default)
		)
		(layer "Edge.Cuts")
	)
	(gr_line
		(start 306.485036 -43.50004)
		(end 306.485036 -0.999998)
		(stroke
			(width 0.05)
			(type default)
		)
		(layer "Edge.Cuts")
	)
	(gr_arc
		(start 307.485034 0)
		(mid 306.777906 -0.29288)
		(end 306.485036 -0.999998)
		(stroke
			(width 0.05)
			(type default)
		)
		(layer "Edge.Cuts")
	)
	(gr_line
		(start 307.485034 0)
		(end 354.600002 0)
		(stroke
			(width 0.05)
			(type default)
		)
		(layer "Edge.Cuts")
	)
	(gr_line
		(start 310.900064 -106.100118)
		(end 312.50001 -106.100118)
		(stroke
			(width 0.05)
			(type default)
		)
		(layer "Edge.Cuts")
	)
	(gr_arc
		(start 310.900064 -102.899972)
		(mid 309.299864 -104.500172)
		(end 310.900064 -106.100118)
		(stroke
			(width 0.05)
			(type default)
		)
		(layer "Edge.Cuts")
	)
	(gr_line
		(start 310.900064 -41.099994)
		(end 312.50001 -41.099994)
		(stroke
			(width 0.05)
			(type default)
		)
		(layer "Edge.Cuts")
	)
	(gr_arc
		(start 310.900064 -37.900102)
		(mid 309.300118 -39.500048)
		(end 310.900064 -41.099994)
		(stroke
			(width 0.05)
			(type default)
		)
		(layer "Edge.Cuts")
	)
	(gr_arc
		(start 312.50001 -106.100118)
		(mid 314.099956 -104.500172)
		(end 312.50001 -102.899972)
		(stroke
			(width 0.05)
			(type default)
		)
		(layer "Edge.Cuts")
	)
	(gr_line
		(start 312.50001 -102.899972)
		(end 310.900064 -102.899972)
		(stroke
			(width 0.05)
			(type default)
		)
		(layer "Edge.Cuts")
	)
	(gr_arc
		(start 312.50001 -41.099994)
		(mid 314.099956 -39.500048)
		(end 312.50001 -37.900102)
		(stroke
			(width 0.05)
			(type default)
		)
		(layer "Edge.Cuts")
	)
	(gr_line
		(start 312.50001 -37.900102)
		(end 310.900064 -37.900102)
		(stroke
			(width 0.05)
			(type default)
		)
		(layer "Edge.Cuts")
	)
	(gr_line
		(start 350.60001 -251.000006)
		(end 256.15011 -251.000006)
		(stroke
			(width 0.05)
			(type default)
		)
		(layer "Edge.Cuts")
	)
	(gr_arc
		(start 350.60001 -251.000006)
		(mid 354.135536 -249.53554)
		(end 355.6 -246.000016)
		(stroke
			(width 0.05)
			(type default)
		)
		(layer "Edge.Cuts")
	)
	(gr_arc
		(start 355.6 -0.999998)
		(mid 355.307107 -0.292893)
		(end 354.600002 0)
		(stroke
			(width 0.05)
			(type default)
		)
		(layer "Edge.Cuts")
	)
	(gr_line
		(start 355.6 -0.999998)
		(end 355.6 -246.000016)
		(stroke
			(width 0.05)
			(type default)
		)
		(layer "Edge.Cuts")
	)
	(segment
		(start 256.6035 -117.96776)
		(end 256.6035 -116.673884)
		(width 0.1143)
		(layer "F.Cu")
		(net "CPU_RXD_R")
	)
	(segment
		(start 256.6035 -115.697)
		(end 256.667 -115.6335)
		(width 0.1143)
		(layer "F.Cu")
		(net "CPU_RXD_R")
	)
	(segment
		(start 256.6035 -116.673884)
		(end 256.6035 -115.697)
		(width 0.1143)
		(layer "F.Cu")
		(net "CPU_RXD_R")
	)
	(via
		(at 256.6035 -116.673884)
		(size 0.7112)
		(drill 0.3556)
		(layers "F.Cu" "B.Cu")
		(net "CPU_RXD_R")
	)
	(segment
		(start 253.492 -119.507)
		(end 253.492 -119.126)
		(width 0.1143)
		(layer "F.Cu")
		(net "CPU_U193_PIN3_RX_R")
	)
	(segment
		(start 254 -118.618)
		(end 254.9525 -118.618)
		(width 0.1143)
		(layer "F.Cu")
		(net "CPU_U193_PIN3_RX_R")
	)
	(segment
		(start 253.492 -122.1105)
		(end 253.492 -119.507)
		(width 0.1143)
		(layer "F.Cu")
		(net "CPU_U193_PIN3_RX_R")
	)
	(segment
		(start 253.492 -119.126)
		(end 254 -118.618)
		(width 0.1143)
		(layer "F.Cu")
		(net "CPU_U193_PIN3_RX_R")
	)
	(via
		(at 253.492 -119.507)
		(size 0.7112)
		(drill 0.3556)
		(layers "F.Cu" "B.Cu")
		(net "CPU_U193_PIN3_RX_R")
	)
	(segment
		(start 254.9525 -121.92)
		(end 254.762 -122.1105)
		(width 0.1143)
		(layer "F.Cu")
		(net "CPU_U192_PIN3_RX_R")
	)
	(segment
		(start 254.9525 -120.871742)
		(end 254.9525 -121.92)
		(width 0.1143)
		(layer "F.Cu")
		(net "CPU_U192_PIN3_RX_R")
	)
	(segment
		(start 254.9525 -119.26824)
		(end 254.9525 -120.871742)
		(width 0.1143)
		(layer "F.Cu")
		(net "CPU_U192_PIN3_RX_R")
	)
	(via
		(at 254.9525 -120.871742)
		(size 0.7112)
		(drill 0.3556)
		(layers "F.Cu" "B.Cu")
		(net "CPU_U192_PIN3_RX_R")
	)
	(segment
		(start 254.127 -127.9398)
		(end 254.5588 -128.3716)
		(width 0.1143)
		(layer "F.Cu")
		(net "CPU_U193_PIN3_RX")
	)
	(segment
		(start 253.492 -125.0315)
		(end 254.127 -125.6665)
		(width 0.1143)
		(layer "F.Cu")
		(net "CPU_U193_PIN3_RX")
	)
	(segment
		(start 253.492 -122.9995)
		(end 253.492 -125.0315)
		(width 0.1143)
		(layer "F.Cu")
		(net "CPU_U193_PIN3_RX")
	)
	(segment
		(start 253.94412 -129.31648)
		(end 254.5588 -128.7018)
		(width 0.1143)
		(layer "F.Cu")
		(net "CPU_U193_PIN3_RX")
	)
	(segment
		(start 253.94412 -130.4544)
		(end 253.94412 -129.31648)
		(width 0.1143)
		(layer "F.Cu")
		(net "CPU_U193_PIN3_RX")
	)
	(segment
		(start 254.5588 -128.3716)
		(end 254.5588 -128.7018)
		(width 0.1143)
		(layer "F.Cu")
		(net "CPU_U193_PIN3_RX")
	)
	(segment
		(start 254.127 -125.6665)
		(end 254.127 -127.9398)
		(width 0.1143)
		(layer "F.Cu")
		(net "CPU_U193_PIN3_RX")
	)
	(via
		(at 254.5588 -128.7018)
		(size 0.7112)
		(drill 0.3556)
		(layers "F.Cu" "B.Cu")
		(net "CPU_U193_PIN3_RX")
	)
	(segment
		(start 253.4666 -126.1491)
		(end 253.4285 -126.111)
		(width 0.1143)
		(layer "F.Cu")
		(net "CPU_U193_PIN2_TX")
	)
	(segment
		(start 253.29388 -128.11252)
		(end 253.4666 -127.9398)
		(width 0.1143)
		(layer "F.Cu")
		(net "CPU_U193_PIN2_TX")
	)
	(segment
		(start 253.4666 -127.9398)
		(end 253.4666 -126.1491)
		(width 0.1143)
		(layer "F.Cu")
		(net "CPU_U193_PIN2_TX")
	)
	(segment
		(start 253.29388 -130.4544)
		(end 253.29388 -128.11252)
		(width 0.1143)
		(layer "F.Cu")
		(net "CPU_U193_PIN2_TX")
	)
	(via
		(at 253.4666 -127.9398)
		(size 0.7112)
		(drill 0.3556)
		(layers "F.Cu" "B.Cu")
		(net "CPU_U193_PIN2_TX")
	)
	(segment
		(start 254.59436 -134.6708)
		(end 255.1176 -135.19404)
		(width 0.1143)
		(layer "F.Cu")
		(net "CPU_U193_PIN5_TX")
	)
	(segment
		(start 254.762 -136.3345)
		(end 254.762 -135.5852)
		(width 0.1143)
		(layer "F.Cu")
		(net "CPU_U193_PIN5_TX")
	)
	(segment
		(start 255.1176 -135.19404)
		(end 255.1176 -135.2296)
		(width 0.1143)
		(layer "F.Cu")
		(net "CPU_U193_PIN5_TX")
	)
	(segment
		(start 254.59436 -133.7056)
		(end 254.59436 -134.6708)
		(width 0.1143)
		(layer "F.Cu")
		(net "CPU_U193_PIN5_TX")
	)
	(segment
		(start 254.762 -135.5852)
		(end 255.1176 -135.2296)
		(width 0.1143)
		(layer "F.Cu")
		(net "CPU_U193_PIN5_TX")
	)
	(via
		(at 255.1176 -135.2296)
		(size 0.7112)
		(drill 0.3556)
		(layers "F.Cu" "B.Cu")
		(net "CPU_U193_PIN5_TX")
	)
	(segment
		(start 253.94412 -134.80288)
		(end 253.5428 -135.2042)
		(width 0.1143)
		(layer "F.Cu")
		(net "CPU_U193_PIN6_RX")
	)
	(segment
		(start 253.746 -135.4074)
		(end 253.5428 -135.2042)
		(width 0.1143)
		(layer "F.Cu")
		(net "CPU_U193_PIN6_RX")
	)
	(segment
		(start 253.746 -136.3345)
		(end 253.746 -135.4074)
		(width 0.1143)
		(layer "F.Cu")
		(net "CPU_U193_PIN6_RX")
	)
	(segment
		(start 253.94412 -133.7056)
		(end 253.94412 -134.80288)
		(width 0.1143)
		(layer "F.Cu")
		(net "CPU_U193_PIN6_RX")
	)
	(via
		(at 253.5428 -135.2042)
		(size 0.7112)
		(drill 0.3556)
		(layers "F.Cu" "B.Cu")
		(net "CPU_U193_PIN6_RX")
	)
	(segment
		(start 257.937 -128.143)
		(end 257.937 -128.778)
		(width 0.1143)
		(layer "F.Cu")
		(net "CPU_U192_PIN3_RX")
	)
	(segment
		(start 256.032 -124.968)
		(end 256.395982 -124.968)
		(width 0.1143)
		(layer "F.Cu")
		(net "CPU_U192_PIN3_RX")
	)
	(segment
		(start 257.3655 -127.5715)
		(end 257.937 -128.143)
		(width 0.1143)
		(layer "F.Cu")
		(net "CPU_U192_PIN3_RX")
	)
	(segment
		(start 256.032 -124.961396)
		(end 256.032 -124.968)
		(width 0.1143)
		(layer "F.Cu")
		(net "CPU_U192_PIN3_RX")
	)
	(segment
		(start 257.937 -128.778)
		(end 257.50012 -129.21488)
		(width 0.1143)
		(layer "F.Cu")
		(net "CPU_U192_PIN3_RX")
	)
	(segment
		(start 257.3655 -125.937518)
		(end 257.3655 -127.5715)
		(width 0.1143)
		(layer "F.Cu")
		(net "CPU_U192_PIN3_RX")
	)
	(segment
		(start 254.762 -122.9995)
		(end 254.762 -123.691396)
		(width 0.1143)
		(layer "F.Cu")
		(net "CPU_U192_PIN3_RX")
	)
	(segment
		(start 257.50012 -129.21488)
		(end 257.50012 -130.4544)
		(width 0.1143)
		(layer "F.Cu")
		(net "CPU_U192_PIN3_RX")
	)
	(segment
		(start 256.395982 -124.968)
		(end 257.3655 -125.937518)
		(width 0.1143)
		(layer "F.Cu")
		(net "CPU_U192_PIN3_RX")
	)
	(segment
		(start 254.762 -123.691396)
		(end 256.032 -124.961396)
		(width 0.1143)
		(layer "F.Cu")
		(net "CPU_U192_PIN3_RX")
	)
	(via
		(at 256.032 -124.968)
		(size 0.7112)
		(drill 0.3556)
		(layers "F.Cu" "B.Cu")
		(net "CPU_U192_PIN3_RX")
	)
	(segment
		(start 256.84988 -130.4544)
		(end 256.84988 -128.97612)
		(width 0.1143)
		(layer "F.Cu")
		(net "CPU_U192_PIN2_TX")
	)
	(segment
		(start 256.794 -127.0635)
		(end 256.794 -128.27)
		(width 0.1143)
		(layer "F.Cu")
		(net "CPU_U192_PIN2_TX")
	)
	(segment
		(start 256.794 -128.27)
		(end 257.175 -128.651)
		(width 0.1143)
		(layer "F.Cu")
		(net "CPU_U192_PIN2_TX")
	)
	(segment
		(start 256.84988 -128.97612)
		(end 257.175 -128.651)
		(width 0.1143)
		(layer "F.Cu")
		(net "CPU_U192_PIN2_TX")
	)
	(via
		(at 257.175 -128.651)
		(size 0.7112)
		(drill 0.3556)
		(layers "F.Cu" "B.Cu")
		(net "CPU_U192_PIN2_TX")
	)
	(segment
		(start 258.6228 -135.0518)
		(end 258.6228 -135.2296)
		(width 0.1143)
		(layer "F.Cu")
		(net "CPU_U192_PIN5_RX")
	)
	(segment
		(start 258.15036 -134.57936)
		(end 258.6228 -135.0518)
		(width 0.1143)
		(layer "F.Cu")
		(net "CPU_U192_PIN5_RX")
	)
	(segment
		(start 258.953 -127.762)
		(end 258.699 -127.508)
		(width 0.1143)
		(layer "F.Cu")
		(net "CPU_U192_PIN5_RX")
	)
	(segment
		(start 258.15036 -133.26364)
		(end 258.953 -132.461)
		(width 0.1143)
		(layer "F.Cu")
		(net "CPU_U192_PIN5_RX")
	)
	(segment
		(start 258.953 -132.461)
		(end 258.953 -127.762)
		(width 0.1143)
		(layer "F.Cu")
		(net "CPU_U192_PIN5_RX")
	)
	(segment
		(start 258.15036 -133.7056)
		(end 258.15036 -134.57936)
		(width 0.1143)
		(layer "F.Cu")
		(net "CPU_U192_PIN5_RX")
	)
	(segment
		(start 258.15036 -133.7056)
		(end 258.15036 -133.26364)
		(width 0.1143)
		(layer "F.Cu")
		(net "CPU_U192_PIN5_RX")
	)
	(segment
		(start 258.318 -136.3345)
		(end 258.318 -135.5344)
		(width 0.1143)
		(layer "F.Cu")
		(net "CPU_U192_PIN5_RX")
	)
	(segment
		(start 258.318 -135.5344)
		(end 258.6228 -135.2296)
		(width 0.1143)
		(layer "F.Cu")
		(net "CPU_U192_PIN5_RX")
	)
	(via
		(at 258.6228 -135.2296)
		(size 0.7112)
		(drill 0.3556)
		(layers "F.Cu" "B.Cu")
		(net "CPU_U192_PIN5_RX")
	)
	(segment
		(start 257.50012 -135.03148)
		(end 257.175 -135.3566)
		(width 0.1143)
		(layer "F.Cu")
		(net "CPU_U192_PIN6_TX")
	)
	(segment
		(start 257.302 -136.3345)
		(end 257.302 -135.4836)
		(width 0.1143)
		(layer "F.Cu")
		(net "CPU_U192_PIN6_TX")
	)
	(segment
		(start 257.302 -135.4836)
		(end 257.175 -135.3566)
		(width 0.1143)
		(layer "F.Cu")
		(net "CPU_U192_PIN6_TX")
	)
	(segment
		(start 257.50012 -133.7056)
		(end 257.50012 -135.03148)
		(width 0.1143)
		(layer "F.Cu")
		(net "CPU_U192_PIN6_TX")
	)
	(via
		(at 257.175 -135.3566)
		(size 0.7112)
		(drill 0.3556)
		(layers "F.Cu" "B.Cu")
		(net "CPU_U192_PIN6_TX")
	)
	(segment
		(start 185.65876 -53.05044)
		(end 185.3692 -53.34)
		(width 0.1143)
		(layer "F.Cu")
		(net "MSB_PRSNT_AND_3")
	)
	(segment
		(start 185.3692 -53.34)
		(end 184.5183 -53.34)
		(width 0.1143)
		(layer "F.Cu")
		(net "MSB_PRSNT_AND_3")
	)
	(segment
		(start 184.5183 -53.34)
		(end 184.2643 -53.086)
		(width 0.1143)
		(layer "F.Cu")
		(net "MSB_PRSNT_AND_3")
	)
	(segment
		(start 185.65876 -52.07889)
		(end 185.65876 -53.05044)
		(width 0.1143)
		(layer "F.Cu")
		(net "MSB_PRSNT_AND_3")
	)
	(via
		(at 185.3692 -53.34)
		(size 0.7112)
		(drill 0.3556)
		(layers "F.Cu" "B.Cu")
		(net "MSB_PRSNT_AND_3")
	)
	(segment
		(start 287.62833 -170.23715)
		(end 288.031428 -170.640248)
		(width 0.127)
		(layer "F.Cu")
		(net "TP_BMC_GPIOB7")
	)
	(segment
		(start 288.031428 -170.640248)
		(end 288.034984 -170.640248)
		(width 0.127)
		(layer "F.Cu")
		(net "TP_BMC_GPIOB7")
	)
	(via
		(at 287.62833 -170.23715)
		(size 0.508)
		(drill 0.254)
		(layers "F.Cu" "B.Cu")
		(net "TP_BMC_GPIOB7")
	)
	(segment
		(start 285.60268 -169.7482)
		(end 287.00984 -169.7482)
		(width 0.127)
		(layer "B.Cu")
		(net "TP_BMC_GPIOB7")
	)
	(segment
		(start 284.92704 -169.07256)
		(end 285.60268 -169.7482)
		(width 0.127)
		(layer "B.Cu")
		(net "TP_BMC_GPIOB7")
	)
	(segment
		(start 287.49879 -170.23715)
		(end 287.62833 -170.23715)
		(width 0.127)
		(layer "B.Cu")
		(net "TP_BMC_GPIOB7")
	)
	(segment
		(start 287.00984 -169.7482)
		(end 287.49879 -170.23715)
		(width 0.127)
		(layer "B.Cu")
		(net "TP_BMC_GPIOB7")
	)
	(segment
		(start 57.637934 -214.482934)
		(end 57.637934 -215.5825)
		(width 0.1143)
		(layer "F.Cu")
		(net "HSW_SDA_2")
	)
	(segment
		(start 56.896 -213.741)
		(end 57.637934 -214.482934)
		(width 0.1143)
		(layer "F.Cu")
		(net "HSW_SDA_2")
	)
	(segment
		(start 56.896 -211.5185)
		(end 56.896 -212.979)
		(width 0.1143)
		(layer "F.Cu")
		(net "HSW_SDA_2")
	)
	(segment
		(start 56.896 -212.979)
		(end 56.896 -213.741)
		(width 0.1143)
		(layer "F.Cu")
		(net "HSW_SDA_2")
	)
	(segment
		(start 55.88 -211.5185)
		(end 56.896 -211.5185)
		(width 0.1143)
		(layer "F.Cu")
		(net "HSW_SDA_2")
	)
	(via
		(at 56.896 -212.979)
		(size 0.7112)
		(drill 0.3556)
		(layers "F.Cu" "B.Cu")
		(net "HSW_SDA_2")
	)
	(segment
		(start 57.912 -211.5185)
		(end 58.13806 -211.74456)
		(width 0.1143)
		(layer "F.Cu")
		(net "HSW_SCL_2")
	)
	(segment
		(start 58.13806 -213.07806)
		(end 58.13806 -215.5063)
		(width 0.1143)
		(layer "F.Cu")
		(net "HSW_SCL_2")
	)
	(segment
		(start 58.13806 -211.74456)
		(end 58.13806 -213.07806)
		(width 0.1143)
		(layer "F.Cu")
		(net "HSW_SCL_2")
	)
	(segment
		(start 58.928 -211.5185)
		(end 57.912 -211.5185)
		(width 0.1143)
		(layer "F.Cu")
		(net "HSW_SCL_2")
	)
	(via
		(at 58.13806 -213.07806)
		(size 0.7112)
		(drill 0.3556)
		(layers "F.Cu" "B.Cu")
		(net "HSW_SCL_2")
	)
	(segment
		(start 56.007 -224.536)
		(end 55.9435 -224.4725)
		(width 0.508)
		(layer "F.Cu")
		(net "MB0_VCC")
	)
	(segment
		(start 55.637938 -220.5355)
		(end 55.637938 -221.996)
		(width 0.3048)
		(layer "F.Cu")
		(net "MB0_VCC")
	)
	(segment
		(start 54.864 -222.769938)
		(end 54.864 -223.393)
		(width 0.508)
		(layer "F.Cu")
		(net "MB0_VCC")
	)
	(segment
		(start 55.499 -222.134938)
		(end 54.864 -222.769938)
		(width 0.508)
		(layer "F.Cu")
		(net "MB0_VCC")
	)
	(segment
		(start 54.864 -223.393)
		(end 54.864 -224.4725)
		(width 0.508)
		(layer "F.Cu")
		(net "MB0_VCC")
	)
	(segment
		(start 55.637938 -221.996)
		(end 55.499 -222.134938)
		(width 0.3048)
		(layer "F.Cu")
		(net "MB0_VCC")
	)
	(segment
		(start 55.9435 -224.4725)
		(end 54.864 -224.4725)
		(width 0.508)
		(layer "F.Cu")
		(net "MB0_VCC")
	)
	(via
		(at 54.864 -223.393)
		(size 0.7112)
		(drill 0.3556)
		(layers "F.Cu" "B.Cu")
		(net "MB0_VCC")
	)
	(segment
		(start 58.42 -221.869)
		(end 58.42 -223.393)
		(width 0.254)
		(layer "F.Cu")
		(net "MB0_CM_SENSE_N")
	)
	(segment
		(start 58.42 -224.0915)
		(end 58.1025 -224.409)
		(width 0.254)
		(layer "F.Cu")
		(net "MB0_CM_SENSE_N")
	)
	(segment
		(start 58.42 -223.393)
		(end 58.42 -224.0915)
		(width 0.254)
		(layer "F.Cu")
		(net "MB0_CM_SENSE_N")
	)
	(segment
		(start 57.637934 -220.5355)
		(end 57.637934 -221.086934)
		(width 0.254)
		(layer "F.Cu")
		(net "MB0_CM_SENSE_N")
	)
	(segment
		(start 58.293 -225.3615)
		(end 58.293 -224.5995)
		(width 0.254)
		(layer "F.Cu")
		(net "MB0_CM_SENSE_N")
	)
	(segment
		(start 57.637934 -221.086934)
		(end 58.42 -221.869)
		(width 0.254)
		(layer "F.Cu")
		(net "MB0_CM_SENSE_N")
	)
	(segment
		(start 58.293 -224.5995)
		(end 58.1025 -224.409)
		(width 0.254)
		(layer "F.Cu")
		(net "MB0_CM_SENSE_N")
	)
	(via
		(at 58.42 -223.393)
		(size 0.7112)
		(drill 0.3556)
		(layers "F.Cu" "B.Cu")
		(net "MB0_CM_SENSE_N")
	)
	(segment
		(start 51.362356 -217.424)
		(end 49.330356 -215.392)
		(width 0.254)
		(layer "F.Cu")
		(net "MB0_TIME_R")
	)
	(segment
		(start 49.330356 -215.392)
		(end 49.2125 -215.392)
		(width 0.254)
		(layer "F.Cu")
		(net "MB0_TIME_R")
	)
	(segment
		(start 52.455064 -217.809064)
		(end 53.9115 -217.809064)
		(width 0.254)
		(layer "F.Cu")
		(net "MB0_TIME_R")
	)
	(segment
		(start 52.07 -217.424)
		(end 52.455064 -217.809064)
		(width 0.254)
		(layer "F.Cu")
		(net "MB0_TIME_R")
	)
	(segment
		(start 52.07 -217.424)
		(end 51.362356 -217.424)
		(width 0.254)
		(layer "F.Cu")
		(net "MB0_TIME_R")
	)
	(via
		(at 52.07 -217.424)
		(size 0.7112)
		(drill 0.3556)
		(layers "F.Cu" "B.Cu")
		(net "MB0_TIME_R")
	)
	(segment
		(start 70.485 -229.3112)
		(end 70.4088 -229.235)
		(width 0.508)
		(layer "F.Cu")
		(net "MB0_CM_GATE_R")
	)
	(segment
		(start 68.6435 -228.9175)
		(end 68.961 -229.235)
		(width 0.508)
		(layer "F.Cu")
		(net "MB0_CM_GATE_R")
	)
	(segment
		(start 67.437 -228.9175)
		(end 68.6435 -228.9175)
		(width 0.508)
		(layer "F.Cu")
		(net "MB0_CM_GATE_R")
	)
	(segment
		(start 70.4088 -229.235)
		(end 68.961 -229.235)
		(width 0.508)
		(layer "F.Cu")
		(net "MB0_CM_GATE_R")
	)
	(segment
		(start 68.961 -229.997)
		(end 68.326 -230.632)
		(width 0.508)
		(layer "F.Cu")
		(net "MB0_CM_GATE_R")
	)
	(segment
		(start 70.485 -228.4095)
		(end 70.485 -229.3112)
		(width 0.508)
		(layer "F.Cu")
		(net "MB0_CM_GATE_R")
	)
	(segment
		(start 68.326 -230.632)
		(end 68.326 -231.14)
		(width 0.508)
		(layer "F.Cu")
		(net "MB0_CM_GATE_R")
	)
	(segment
		(start 68.961 -229.235)
		(end 68.961 -229.997)
		(width 0.508)
		(layer "F.Cu")
		(net "MB0_CM_GATE_R")
	)
	(segment
		(start 68.326 -231.14)
		(end 69.596 -231.14)
		(width 0.508)
		(layer "F.Cu")
		(net "MB0_CM_GATE_R")
	)
	(via
		(at 70.485 -229.3112)
		(size 0.7112)
		(drill 0.3556)
		(layers "F.Cu" "B.Cu")
		(net "MB0_CM_GATE_R")
	)
	(segment
		(start 57.785 -221.996)
		(end 57.785 -222.885)
		(width 0.254)
		(layer "F.Cu")
		(net "MB0_P12V_MAIN_R")
	)
	(segment
		(start 57.138062 -221.349062)
		(end 57.785 -221.996)
		(width 0.254)
		(layer "F.Cu")
		(net "MB0_P12V_MAIN_R")
	)
	(segment
		(start 57.138062 -220.5355)
		(end 57.138062 -221.349062)
		(width 0.254)
		(layer "F.Cu")
		(net "MB0_P12V_MAIN_R")
	)
	(segment
		(start 57.785 -222.885)
		(end 57.277 -223.393)
		(width 0.254)
		(layer "F.Cu")
		(net "MB0_P12V_MAIN_R")
	)
	(via
		(at 57.277 -223.393)
		(size 0.7112)
		(drill 0.4064)
		(layers "F.Cu" "B.Cu")
		(net "MB0_P12V_MAIN_R")
	)
	(via
		(at 60.198 -233.6546)
		(size 0.7112)
		(drill 0.3556)
		(layers "F.Cu" "B.Cu")
		(net "MB0_P12V_MAIN_R")
	)
	(via
		(at 58.928 -233.934)
		(size 0.7112)
		(drill 0.4064)
		(layers "F.Cu" "B.Cu")
		(net "MB0_P12V_MAIN_R")
	)
	(segment
		(start 58.928 -233.934)
		(end 58.166 -233.172)
		(width 0.381)
		(layer "B.Cu")
		(net "MB0_P12V_MAIN_R")
	)
	(segment
		(start 58.166 -224.917)
		(end 57.277 -224.028)
		(width 0.381)
		(layer "B.Cu")
		(net "MB0_P12V_MAIN_R")
	)
	(segment
		(start 57.277 -224.028)
		(end 57.277 -223.393)
		(width 0.381)
		(layer "B.Cu")
		(net "MB0_P12V_MAIN_R")
	)
	(segment
		(start 58.166 -233.172)
		(end 58.166 -224.917)
		(width 0.381)
		(layer "B.Cu")
		(net "MB0_P12V_MAIN_R")
	)
	(segment
		(start 62.1538 -213.0298)
		(end 62.1538 -213.741)
		(width 0.254)
		(layer "F.Cu")
		(net "MB0_P12V_PWRGOOD")
	)
	(segment
		(start 60.833 -215.265)
		(end 60.833 -215.519)
		(width 0.254)
		(layer "F.Cu")
		(net "MB0_P12V_PWRGOOD")
	)
	(segment
		(start 62.611 -210.693)
		(end 61.7855 -211.5185)
		(width 0.254)
		(layer "F.Cu")
		(net "MB0_P12V_PWRGOOD")
	)
	(segment
		(start 61.7855 -211.5185)
		(end 61.7855 -212.217)
		(width 0.254)
		(layer "F.Cu")
		(net "MB0_P12V_PWRGOOD")
	)
	(segment
		(start 334.899 -115.824)
		(end 332.994 -117.729)
		(width 0.254)
		(layer "F.Cu")
		(net "MB0_P12V_PWRGOOD")
	)
	(segment
		(start 61.7855 -212.6615)
		(end 62.1538 -213.0298)
		(width 0.254)
		(layer "F.Cu")
		(net "MB0_P12V_PWRGOOD")
	)
	(segment
		(start 61.9125 -213.9823)
		(end 61.9125 -215.265)
		(width 0.254)
		(layer "F.Cu")
		(net "MB0_P12V_PWRGOOD")
	)
	(segment
		(start 60.833 -215.519)
		(end 59.542934 -216.809066)
		(width 0.254)
		(layer "F.Cu")
		(net "MB0_P12V_PWRGOOD")
	)
	(segment
		(start 62.1538 -213.741)
		(end 61.9125 -213.9823)
		(width 0.254)
		(layer "F.Cu")
		(net "MB0_P12V_PWRGOOD")
	)
	(segment
		(start 61.9125 -215.265)
		(end 60.833 -215.265)
		(width 0.254)
		(layer "F.Cu")
		(net "MB0_P12V_PWRGOOD")
	)
	(segment
		(start 62.865 -210.693)
		(end 62.611 -210.693)
		(width 0.254)
		(layer "F.Cu")
		(net "MB0_P12V_PWRGOOD")
	)
	(segment
		(start 61.7855 -212.217)
		(end 61.7855 -212.6615)
		(width 0.254)
		(layer "F.Cu")
		(net "MB0_P12V_PWRGOOD")
	)
	(segment
		(start 334.899 -113.9825)
		(end 334.899 -115.824)
		(width 0.254)
		(layer "F.Cu")
		(net "MB0_P12V_PWRGOOD")
	)
	(segment
		(start 59.542934 -216.809066)
		(end 58.8645 -216.809066)
		(width 0.254)
		(layer "F.Cu")
		(net "MB0_P12V_PWRGOOD")
	)
	(via
		(at 62.865 -210.693)
		(size 0.5588)
		(drill 0.3048)
		(layers "F.Cu" "B.Cu")
		(net "MB0_P12V_PWRGOOD")
	)
	(via
		(at 60.833 -215.265)
		(size 0.7112)
		(drill 0.3556)
		(layers "F.Cu" "B.Cu")
		(net "MB0_P12V_PWRGOOD")
	)
	(via
		(at 279.019 -118.11)
		(size 0.5588)
		(drill 0.3048)
		(layers "F.Cu" "B.Cu")
		(net "MB0_P12V_PWRGOOD")
	)
	(via
		(at 332.994 -117.729)
		(size 0.5588)
		(drill 0.3048)
		(layers "F.Cu" "B.Cu")
		(net "MB0_P12V_PWRGOOD")
	)
	(via
		(at 328.8284 -133.1468)
		(size 0.5588)
		(drill 0.3048)
		(layers "F.Cu" "B.Cu")
		(net "MB0_P12V_PWRGOOD")
	)
	(via
		(at 232.918 -191.135)
		(size 0.5588)
		(drill 0.3048)
		(layers "F.Cu" "B.Cu")
		(net "MB0_P12V_PWRGOOD")
	)
	(segment
		(start 328.8284 -133.1468)
		(end 328.1172 -133.1468)
		(width 0.254)
		(layer "B.Cu")
		(net "MB0_P12V_PWRGOOD")
	)
	(segment
		(start 286.361886 -118.768114)
		(end 279.677114 -118.768114)
		(width 0.254)
		(layer "B.Cu")
		(net "MB0_P12V_PWRGOOD")
	)
	(segment
		(start 286.575754 -118.554246)
		(end 286.361886 -118.768114)
		(width 0.254)
		(layer "B.Cu")
		(net "MB0_P12V_PWRGOOD")
	)
	(segment
		(start 323.526404 -128.556004)
		(end 316.810898 -128.556004)
		(width 0.254)
		(layer "B.Cu")
		(net "MB0_P12V_PWRGOOD")
	)
	(segment
		(start 306.80914 -118.554246)
		(end 286.575754 -118.554246)
		(width 0.254)
		(layer "B.Cu")
		(net "MB0_P12V_PWRGOOD")
	)
	(segment
		(start 316.810898 -128.556004)
		(end 306.80914 -118.554246)
		(width 0.254)
		(layer "B.Cu")
		(net "MB0_P12V_PWRGOOD")
	)
	(segment
		(start 328.1172 -133.1468)
		(end 323.526404 -128.556004)
		(width 0.254)
		(layer "B.Cu")
		(net "MB0_P12V_PWRGOOD")
	)
	(segment
		(start 279.677114 -118.768114)
		(end 279.019 -118.11)
		(width 0.254)
		(layer "B.Cu")
		(net "MB0_P12V_PWRGOOD")
	)
	(segment
		(start 63.119 -210.312)
		(end 64.77 -210.312)
		(width 0.254)
		(layer "In2.Cu")
		(net "MB0_P12V_PWRGOOD")
	)
	(segment
		(start 68.834 -214.376)
		(end 101.219 -214.376)
		(width 0.254)
		(layer "In2.Cu")
		(net "MB0_P12V_PWRGOOD")
	)
	(segment
		(start 216.535 -207.899)
		(end 216.535 -207.518)
		(width 0.254)
		(layer "In2.Cu")
		(net "MB0_P12V_PWRGOOD")
	)
	(segment
		(start 64.77 -210.312)
		(end 68.834 -214.376)
		(width 0.254)
		(layer "In2.Cu")
		(net "MB0_P12V_PWRGOOD")
	)
	(segment
		(start 168.148 -218.059)
		(end 169.926 -216.281)
		(width 0.254)
		(layer "In2.Cu")
		(net "MB0_P12V_PWRGOOD")
	)
	(segment
		(start 101.219 -214.376)
		(end 105.41 -218.567)
		(width 0.254)
		(layer "In2.Cu")
		(net "MB0_P12V_PWRGOOD")
	)
	(segment
		(start 181.102 -216.281)
		(end 182.499 -217.678)
		(width 0.254)
		(layer "In2.Cu")
		(net "MB0_P12V_PWRGOOD")
	)
	(segment
		(start 206.756 -217.678)
		(end 216.535 -207.899)
		(width 0.254)
		(layer "In2.Cu")
		(net "MB0_P12V_PWRGOOD")
	)
	(segment
		(start 216.535 -207.518)
		(end 232.918 -191.135)
		(width 0.254)
		(layer "In2.Cu")
		(net "MB0_P12V_PWRGOOD")
	)
	(segment
		(start 105.41 -218.567)
		(end 125.73 -218.567)
		(width 0.254)
		(layer "In2.Cu")
		(net "MB0_P12V_PWRGOOD")
	)
	(segment
		(start 62.865 -210.693)
		(end 62.865 -210.566)
		(width 0.254)
		(layer "In2.Cu")
		(net "MB0_P12V_PWRGOOD")
	)
	(segment
		(start 125.73 -218.567)
		(end 126.238 -218.059)
		(width 0.254)
		(layer "In2.Cu")
		(net "MB0_P12V_PWRGOOD")
	)
	(segment
		(start 126.238 -218.059)
		(end 168.148 -218.059)
		(width 0.254)
		(layer "In2.Cu")
		(net "MB0_P12V_PWRGOOD")
	)
	(segment
		(start 182.499 -217.678)
		(end 206.756 -217.678)
		(width 0.254)
		(layer "In2.Cu")
		(net "MB0_P12V_PWRGOOD")
	)
	(segment
		(start 169.926 -216.281)
		(end 181.102 -216.281)
		(width 0.254)
		(layer "In2.Cu")
		(net "MB0_P12V_PWRGOOD")
	)
	(segment
		(start 62.865 -210.566)
		(end 63.119 -210.312)
		(width 0.254)
		(layer "In2.Cu")
		(net "MB0_P12V_PWRGOOD")
	)
	(segment
		(start 258.43992 -178.30292)
		(end 250.1138 -169.9768)
		(width 0.254)
		(layer "In5.Cu")
		(net "MB0_P12V_PWRGOOD")
	)
	(segment
		(start 278.0538 -116.989352)
		(end 278.0538 -117.1448)
		(width 0.254)
		(layer "In5.Cu")
		(net "MB0_P12V_PWRGOOD")
	)
	(segment
		(start 278.0538 -117.1448)
		(end 279.019 -118.11)
		(width 0.254)
		(layer "In5.Cu")
		(net "MB0_P12V_PWRGOOD")
	)
	(segment
		(start 258.43992 -186.563)
		(end 258.43992 -178.30292)
		(width 0.254)
		(layer "In5.Cu")
		(net "MB0_P12V_PWRGOOD")
	)
	(segment
		(start 232.918 -191.135)
		(end 233.045 -191.008)
		(width 0.254)
		(layer "In5.Cu")
		(net "MB0_P12V_PWRGOOD")
	)
	(segment
		(start 329.692 -121.031)
		(end 330.1492 -120.5738)
		(width 0.254)
		(layer "In5.Cu")
		(net "MB0_P12V_PWRGOOD")
	)
	(segment
		(start 277.625048 -116.5606)
		(end 278.0538 -116.989352)
		(width 0.254)
		(layer "In5.Cu")
		(net "MB0_P12V_PWRGOOD")
	)
	(segment
		(start 233.045 -191.008)
		(end 253.99492 -191.008)
		(width 0.254)
		(layer "In5.Cu")
		(net "MB0_P12V_PWRGOOD")
	)
	(segment
		(start 259.08762 -125.73)
		(end 259.36702 -126.0094)
		(width 0.254)
		(layer "In5.Cu")
		(net "MB0_P12V_PWRGOOD")
	)
	(segment
		(start 260.08838 -125.73)
		(end 264.16 -125.73)
		(width 0.254)
		(layer "In5.Cu")
		(net "MB0_P12V_PWRGOOD")
	)
	(segment
		(start 329.692 -121.12371)
		(end 329.692 -121.031)
		(width 0.254)
		(layer "In5.Cu")
		(net "MB0_P12V_PWRGOOD")
	)
	(segment
		(start 250.1138 -139.2428)
		(end 250.1011 -139.2301)
		(width 0.254)
		(layer "In5.Cu")
		(net "MB0_P12V_PWRGOOD")
	)
	(segment
		(start 330.476352 -120.0912)
		(end 330.6318 -120.0912)
		(width 0.254)
		(layer "In5.Cu")
		(net "MB0_P12V_PWRGOOD")
	)
	(segment
		(start 250.1138 -169.9768)
		(end 250.1138 -139.2428)
		(width 0.254)
		(layer "In5.Cu")
		(net "MB0_P12V_PWRGOOD")
	)
	(segment
		(start 259.36702 -126.0094)
		(end 259.80898 -126.0094)
		(width 0.254)
		(layer "In5.Cu")
		(net "MB0_P12V_PWRGOOD")
	)
	(segment
		(start 264.16 -125.73)
		(end 273.3294 -116.5606)
		(width 0.254)
		(layer "In5.Cu")
		(net "MB0_P12V_PWRGOOD")
	)
	(segment
		(start 250.1011 -127.749046)
		(end 252.120146 -125.73)
		(width 0.254)
		(layer "In5.Cu")
		(net "MB0_P12V_PWRGOOD")
	)
	(segment
		(start 328.8284 -121.98731)
		(end 329.692 -121.12371)
		(width 0.254)
		(layer "In5.Cu")
		(net "MB0_P12V_PWRGOOD")
	)
	(segment
		(start 253.99492 -191.008)
		(end 258.43992 -186.563)
		(width 0.254)
		(layer "In5.Cu")
		(net "MB0_P12V_PWRGOOD")
	)
	(segment
		(start 259.80898 -126.0094)
		(end 260.08838 -125.73)
		(width 0.254)
		(layer "In5.Cu")
		(net "MB0_P12V_PWRGOOD")
	)
	(segment
		(start 250.1011 -139.2301)
		(end 250.1011 -127.749046)
		(width 0.254)
		(layer "In5.Cu")
		(net "MB0_P12V_PWRGOOD")
	)
	(segment
		(start 330.1492 -120.5738)
		(end 330.1492 -120.418352)
		(width 0.254)
		(layer "In5.Cu")
		(net "MB0_P12V_PWRGOOD")
	)
	(segment
		(start 328.8284 -133.1468)
		(end 328.8284 -121.98731)
		(width 0.254)
		(layer "In5.Cu")
		(net "MB0_P12V_PWRGOOD")
	)
	(segment
		(start 330.1492 -120.418352)
		(end 330.476352 -120.0912)
		(width 0.254)
		(layer "In5.Cu")
		(net "MB0_P12V_PWRGOOD")
	)
	(segment
		(start 330.6318 -120.0912)
		(end 332.994 -117.729)
		(width 0.254)
		(layer "In5.Cu")
		(net "MB0_P12V_PWRGOOD")
	)
	(segment
		(start 252.120146 -125.73)
		(end 259.08762 -125.73)
		(width 0.254)
		(layer "In5.Cu")
		(net "MB0_P12V_PWRGOOD")
	)
	(segment
		(start 273.3294 -116.5606)
		(end 277.625048 -116.5606)
		(width 0.254)
		(layer "In5.Cu")
		(net "MB0_P12V_PWRGOOD")
	)
	(segment
		(start 56.138064 -220.5355)
		(end 56.138064 -222.753936)
		(width 0.254)
		(layer "F.Cu")
		(net "MB0_CM_SENSE_P")
	)
	(segment
		(start 57.15 -225.3615)
		(end 57.15 -224.4725)
		(width 0.254)
		(layer "F.Cu")
		(net "MB0_CM_SENSE_P")
	)
	(segment
		(start 56.138064 -223.524064)
		(end 57.023 -224.409)
		(width 0.254)
		(layer "F.Cu")
		(net "MB0_CM_SENSE_P")
	)
	(segment
		(start 57.023 -224.409)
		(end 57.2135 -224.409)
		(width 0.254)
		(layer "F.Cu")
		(net "MB0_CM_SENSE_P")
	)
	(segment
		(start 56.138064 -222.753936)
		(end 56.138064 -223.524064)
		(width 0.254)
		(layer "F.Cu")
		(net "MB0_CM_SENSE_P")
	)
	(segment
		(start 57.15 -224.4725)
		(end 57.2135 -224.409)
		(width 0.254)
		(layer "F.Cu")
		(net "MB0_CM_SENSE_P")
	)
	(via
		(at 56.138064 -222.753936)
		(size 0.7112)
		(drill 0.3556)
		(layers "F.Cu" "B.Cu")
		(net "MB0_CM_SENSE_P")
	)
	(segment
		(start 48.3235 -218.7575)
		(end 48.26 -218.694)
		(width 0.508)
		(layer "F.Cu")
		(net "MB0_VCAP_R")
	)
	(segment
		(start 48.26 -219.9005)
		(end 48.3235 -219.837)
		(width 0.508)
		(layer "F.Cu")
		(net "MB0_VCAP_R")
	)
	(segment
		(start 48.3235 -219.837)
		(end 48.3235 -218.7575)
		(width 0.508)
		(layer "F.Cu")
		(net "MB0_VCAP_R")
	)
	(segment
		(start 48.4505 -219.71)
		(end 49.3395 -219.71)
		(width 0.508)
		(layer "F.Cu")
		(net "MB0_VCAP_R")
	)
	(segment
		(start 52.1335 -219.6465)
		(end 52.6415 -219.6465)
		(width 0.3048)
		(layer "F.Cu")
		(net "MB0_VCAP_R")
	)
	(segment
		(start 52.6415 -219.6465)
		(end 52.979066 -219.308934)
		(width 0.3048)
		(layer "F.Cu")
		(net "MB0_VCAP_R")
	)
	(segment
		(start 48.3235 -219.837)
		(end 48.4505 -219.71)
		(width 0.508)
		(layer "F.Cu")
		(net "MB0_VCAP_R")
	)
	(segment
		(start 48.4505 -220.853)
		(end 48.26 -220.6625)
		(width 0.508)
		(layer "F.Cu")
		(net "MB0_VCAP_R")
	)
	(segment
		(start 48.26 -220.6625)
		(end 48.26 -219.9005)
		(width 0.508)
		(layer "F.Cu")
		(net "MB0_VCAP_R")
	)
	(segment
		(start 49.3395 -219.71)
		(end 49.403 -219.6465)
		(width 0.508)
		(layer "F.Cu")
		(net "MB0_VCAP_R")
	)
	(segment
		(start 49.403 -219.6465)
		(end 50.7365 -219.6465)
		(width 0.508)
		(layer "F.Cu")
		(net "MB0_VCAP_R")
	)
	(segment
		(start 52.979066 -219.308934)
		(end 53.9115 -219.308934)
		(width 0.3048)
		(layer "F.Cu")
		(net "MB0_VCAP_R")
	)
	(segment
		(start 50.7365 -219.6465)
		(end 52.1335 -219.6465)
		(width 0.508)
		(layer "F.Cu")
		(net "MB0_VCAP_R")
	)
	(via
		(at 50.7365 -219.6465)
		(size 0.7112)
		(drill 0.3556)
		(layers "F.Cu" "B.Cu")
		(net "MB0_VCAP_R")
	)
	(segment
		(start 53.8353 -216.30894)
		(end 53.8353 -215.8873)
		(width 0.254)
		(layer "F.Cu")
		(net "MB0_CM_ADR2_R")
	)
	(segment
		(start 51.308 -213.36)
		(end 49.2125 -213.36)
		(width 0.254)
		(layer "F.Cu")
		(net "MB0_CM_ADR2_R")
	)
	(segment
		(start 51.943 -213.995)
		(end 51.308 -213.36)
		(width 0.254)
		(layer "F.Cu")
		(net "MB0_CM_ADR2_R")
	)
	(segment
		(start 53.8353 -215.8873)
		(end 51.943 -213.995)
		(width 0.254)
		(layer "F.Cu")
		(net "MB0_CM_ADR2_R")
	)
	(via
		(at 51.943 -213.995)
		(size 0.7112)
		(drill 0.3556)
		(layers "F.Cu" "B.Cu")
		(net "MB0_CM_ADR2_R")
	)
	(segment
		(start 49.2125 -217.551)
		(end 49.403 -217.7415)
		(width 0.254)
		(layer "F.Cu")
		(net "MB0_ISTART_R")
	)
	(segment
		(start 50.804064 -218.308936)
		(end 49.851564 -218.308936)
		(width 0.254)
		(layer "F.Cu")
		(net "MB0_ISTART_R")
	)
	(segment
		(start 49.149 -216.408)
		(end 49.2125 -216.4715)
		(width 0.254)
		(layer "F.Cu")
		(net "MB0_ISTART_R")
	)
	(segment
		(start 49.2125 -216.4715)
		(end 49.2125 -217.551)
		(width 0.254)
		(layer "F.Cu")
		(net "MB0_ISTART_R")
	)
	(segment
		(start 49.403 -217.7415)
		(end 49.403 -218.7575)
		(width 0.254)
		(layer "F.Cu")
		(net "MB0_ISTART_R")
	)
	(segment
		(start 49.851564 -218.308936)
		(end 49.403 -218.7575)
		(width 0.254)
		(layer "F.Cu")
		(net "MB0_ISTART_R")
	)
	(segment
		(start 53.9115 -218.308936)
		(end 50.804064 -218.308936)
		(width 0.254)
		(layer "F.Cu")
		(net "MB0_ISTART_R")
	)
	(via
		(at 50.804064 -218.308936)
		(size 0.7112)
		(drill 0.3556)
		(layers "F.Cu" "B.Cu")
		(net "MB0_ISTART_R")
	)
	(segment
		(start 60.579 -221.742)
		(end 70.358 -221.742)
		(width 0.508)
		(layer "F.Cu")
		(net "MB0_CM_GATE")
	)
	(segment
		(start 71.374 -222.758)
		(end 71.374 -224.155)
		(width 0.508)
		(layer "F.Cu")
		(net "MB0_CM_GATE")
	)
	(segment
		(start 71.374 -226.6315)
		(end 70.485 -227.5205)
		(width 0.508)
		(layer "F.Cu")
		(net "MB0_CM_GATE")
	)
	(segment
		(start 58.9407 -219.80906)
		(end 59.182 -220.05036)
		(width 0.254)
		(layer "F.Cu")
		(net "MB0_CM_GATE")
	)
	(segment
		(start 71.374 -224.155)
		(end 71.374 -226.6315)
		(width 0.508)
		(layer "F.Cu")
		(net "MB0_CM_GATE")
	)
	(segment
		(start 59.182 -220.05036)
		(end 59.182 -220.345)
		(width 0.254)
		(layer "F.Cu")
		(net "MB0_CM_GATE")
	)
	(segment
		(start 59.182 -220.345)
		(end 60.579 -221.742)
		(width 0.508)
		(layer "F.Cu")
		(net "MB0_CM_GATE")
	)
	(segment
		(start 70.358 -221.742)
		(end 71.374 -222.758)
		(width 0.508)
		(layer "F.Cu")
		(net "MB0_CM_GATE")
	)
	(via
		(at 71.374 -224.155)
		(size 0.7112)
		(drill 0.3556)
		(layers "F.Cu" "B.Cu")
		(net "MB0_CM_GATE")
	)
	(segment
		(start 53.721 -213.868)
		(end 54.63794 -214.78494)
		(width 0.254)
		(layer "F.Cu")
		(net "MB0_SPISS_PD")
	)
	(segment
		(start 53.34 -211.5185)
		(end 53.34 -213.487)
		(width 0.254)
		(layer "F.Cu")
		(net "MB0_SPISS_PD")
	)
	(segment
		(start 53.34 -213.487)
		(end 53.721 -213.868)
		(width 0.254)
		(layer "F.Cu")
		(net "MB0_SPISS_PD")
	)
	(segment
		(start 54.63794 -214.78494)
		(end 54.63794 -215.5063)
		(width 0.254)
		(layer "F.Cu")
		(net "MB0_SPISS_PD")
	)
	(via
		(at 53.721 -213.868)
		(size 0.7112)
		(drill 0.3556)
		(layers "F.Cu" "B.Cu")
		(net "MB0_SPISS_PD")
	)
	(segment
		(start 69.2785 -225.3615)
		(end 69.2785 -224.663)
		(width 0.508)
		(layer "F.Cu")
		(net "MB0_P12V_R")
	)
	(segment
		(start 68.961 -225.679)
		(end 69.2785 -225.3615)
		(width 0.508)
		(layer "F.Cu")
		(net "MB0_P12V_R")
	)
	(segment
		(start 68.961 -226.949)
		(end 68.961 -225.679)
		(width 0.508)
		(layer "F.Cu")
		(net "MB0_P12V_R")
	)
	(via
		(at 68.961 -225.679)
		(size 0.7112)
		(drill 0.3556)
		(layers "F.Cu" "B.Cu")
		(net "MB0_P12V_R")
	)
	(segment
		(start 55.499 -213.233)
		(end 56.138064 -213.872064)
		(width 0.254)
		(layer "F.Cu")
		(net "MB0_HS_ENABLE")
	)
	(segment
		(start 54.8005 -207.3275)
		(end 54.737 -207.391)
		(width 0.254)
		(layer "F.Cu")
		(net "MB0_HS_ENABLE")
	)
	(segment
		(start 54.61 -212.344)
		(end 55.499 -213.233)
		(width 0.254)
		(layer "F.Cu")
		(net "MB0_HS_ENABLE")
	)
	(segment
		(start 54.737 -207.391)
		(end 54.737 -208.8642)
		(width 0.254)
		(layer "F.Cu")
		(net "MB0_HS_ENABLE")
	)
	(segment
		(start 54.737 -208.8642)
		(end 54.5592 -209.042)
		(width 0.254)
		(layer "F.Cu")
		(net "MB0_HS_ENABLE")
	)
	(segment
		(start 56.138064 -213.872064)
		(end 56.138064 -215.5825)
		(width 0.254)
		(layer "F.Cu")
		(net "MB0_HS_ENABLE")
	)
	(segment
		(start 54.102 -212.09)
		(end 54.356 -212.344)
		(width 0.254)
		(layer "F.Cu")
		(net "MB0_HS_ENABLE")
	)
	(segment
		(start 54.102 -209.4992)
		(end 54.102 -212.09)
		(width 0.254)
		(layer "F.Cu")
		(net "MB0_HS_ENABLE")
	)
	(segment
		(start 54.5592 -209.042)
		(end 54.102 -209.4992)
		(width 0.254)
		(layer "F.Cu")
		(net "MB0_HS_ENABLE")
	)
	(segment
		(start 54.356 -212.344)
		(end 54.61 -212.344)
		(width 0.254)
		(layer "F.Cu")
		(net "MB0_HS_ENABLE")
	)
	(segment
		(start 54.8005 -206.248)
		(end 54.8005 -207.3275)
		(width 0.254)
		(layer "F.Cu")
		(net "MB0_HS_ENABLE")
	)
	(via
		(at 55.499 -213.233)
		(size 0.7112)
		(drill 0.3556)
		(layers "F.Cu" "B.Cu")
		(net "MB0_HS_ENABLE")
	)
	(segment
		(start 59.817 -218.308936)
		(end 60.193936 -217.932)
		(width 0.254)
		(layer "F.Cu")
		(net "MB0_P12V_PWGIN_R")
	)
	(segment
		(start 58.8645 -218.308936)
		(end 59.817 -218.308936)
		(width 0.254)
		(layer "F.Cu")
		(net "MB0_P12V_PWGIN_R")
	)
	(segment
		(start 61.214 -218.313)
		(end 60.96 -218.059)
		(width 0.254)
		(layer "F.Cu")
		(net "MB0_P12V_PWGIN_R")
	)
	(segment
		(start 61.9125 -218.313)
		(end 61.214 -218.313)
		(width 0.254)
		(layer "F.Cu")
		(net "MB0_P12V_PWGIN_R")
	)
	(segment
		(start 60.193936 -217.932)
		(end 60.833 -217.932)
		(width 0.254)
		(layer "F.Cu")
		(net "MB0_P12V_PWGIN_R")
	)
	(segment
		(start 60.833 -217.932)
		(end 60.96 -218.059)
		(width 0.254)
		(layer "F.Cu")
		(net "MB0_P12V_PWGIN_R")
	)
	(segment
		(start 61.9125 -218.313)
		(end 61.9125 -219.329)
		(width 0.254)
		(layer "F.Cu")
		(net "MB0_P12V_PWGIN_R")
	)
	(via
		(at 60.96 -218.059)
		(size 0.7112)
		(drill 0.3556)
		(layers "F.Cu" "B.Cu")
		(net "MB0_P12V_PWGIN_R")
	)
	(segment
		(start 53.36794 -219.80906)
		(end 53.8353 -219.80906)
		(width 0.254)
		(layer "F.Cu")
		(net "MB0_PSET_R")
	)
	(segment
		(start 51.943 -220.599)
		(end 49.5935 -220.599)
		(width 0.254)
		(layer "F.Cu")
		(net "MB0_PSET_R")
	)
	(segment
		(start 49.5935 -220.599)
		(end 49.3395 -220.853)
		(width 0.254)
		(layer "F.Cu")
		(net "MB0_PSET_R")
	)
	(segment
		(start 51.943 -220.599)
		(end 52.578 -220.599)
		(width 0.254)
		(layer "F.Cu")
		(net "MB0_PSET_R")
	)
	(segment
		(start 49.276 -223.012)
		(end 49.276 -221.996)
		(width 0.254)
		(layer "F.Cu")
		(net "MB0_PSET_R")
	)
	(segment
		(start 52.578 -220.599)
		(end 53.36794 -219.80906)
		(width 0.254)
		(layer "F.Cu")
		(net "MB0_PSET_R")
	)
	(segment
		(start 49.3395 -223.139)
		(end 49.282096 -223.081596)
		(width 0.254)
		(layer "F.Cu")
		(net "MB0_PSET_R")
	)
	(segment
		(start 49.282096 -223.081596)
		(end 49.276 -223.012)
		(width 0.254)
		(layer "F.Cu")
		(net "MB0_PSET_R")
	)
	(segment
		(start 49.3395 -221.9325)
		(end 49.276 -221.996)
		(width 0.254)
		(layer "F.Cu")
		(net "MB0_PSET_R")
	)
	(segment
		(start 49.3395 -220.853)
		(end 49.3395 -221.9325)
		(width 0.254)
		(layer "F.Cu")
		(net "MB0_PSET_R")
	)
	(via
		(at 51.943 -220.599)
		(size 0.7112)
		(drill 0.3556)
		(layers "F.Cu" "B.Cu")
		(net "MB0_PSET_R")
	)
	(segment
		(start 53.848 -222.631)
		(end 53.975 -222.504)
		(width 0.254)
		(layer "F.Cu")
		(net "MB0_CM_UV_R")
	)
	(segment
		(start 55.138066 -220.5355)
		(end 55.138066 -221.340934)
		(width 0.254)
		(layer "F.Cu")
		(net "MB0_CM_UV_R")
	)
	(segment
		(start 51.689 -224.536)
		(end 51.7525 -224.4725)
		(width 0.254)
		(layer "F.Cu")
		(net "MB0_CM_UV_R")
	)
	(segment
		(start 53.848 -224.4725)
		(end 53.848 -222.631)
		(width 0.254)
		(layer "F.Cu")
		(net "MB0_CM_UV_R")
	)
	(segment
		(start 55.138066 -221.340934)
		(end 53.975 -222.504)
		(width 0.254)
		(layer "F.Cu")
		(net "MB0_CM_UV_R")
	)
	(segment
		(start 51.7525 -224.4725)
		(end 52.832 -224.4725)
		(width 0.254)
		(layer "F.Cu")
		(net "MB0_CM_UV_R")
	)
	(segment
		(start 53.848 -224.4725)
		(end 52.832 -224.4725)
		(width 0.254)
		(layer "F.Cu")
		(net "MB0_CM_UV_R")
	)
	(via
		(at 53.975 -222.504)
		(size 0.7112)
		(drill 0.3556)
		(layers "F.Cu" "B.Cu")
		(net "MB0_CM_UV_R")
	)
	(segment
		(start 67.056 -227.076)
		(end 67.31 -226.822)
		(width 0.508)
		(layer "F.Cu")
		(net "MB0_12V_CTRL_GATE1")
	)
	(segment
		(start 65.786 -227.076)
		(end 67.056 -227.076)
		(width 0.508)
		(layer "F.Cu")
		(net "MB0_12V_CTRL_GATE1")
	)
	(segment
		(start 67.437 -228.0285)
		(end 67.437 -226.949)
		(width 0.508)
		(layer "F.Cu")
		(net "MB0_12V_CTRL_GATE1")
	)
	(segment
		(start 67.437 -226.949)
		(end 67.31 -226.822)
		(width 0.508)
		(layer "F.Cu")
		(net "MB0_12V_CTRL_GATE1")
	)
	(via
		(at 67.31 -226.822)
		(size 0.7112)
		(drill 0.3556)
		(layers "F.Cu" "B.Cu")
		(net "MB0_12V_CTRL_GATE1")
	)
	(segment
		(start 48.387 -224.536)
		(end 48.4505 -224.4725)
		(width 0.254)
		(layer "F.Cu")
		(net "MB0_CM_OV_R")
	)
	(segment
		(start 54.2163 -220.6117)
		(end 51.689 -223.139)
		(width 0.254)
		(layer "F.Cu")
		(net "MB0_CM_OV_R")
	)
	(segment
		(start 50.546 -224.282)
		(end 51.689 -223.139)
		(width 0.254)
		(layer "F.Cu")
		(net "MB0_CM_OV_R")
	)
	(segment
		(start 54.63794 -220.6117)
		(end 54.2163 -220.6117)
		(width 0.254)
		(layer "F.Cu")
		(net "MB0_CM_OV_R")
	)
	(segment
		(start 50.546 -224.4725)
		(end 50.546 -224.282)
		(width 0.254)
		(layer "F.Cu")
		(net "MB0_CM_OV_R")
	)
	(segment
		(start 50.546 -224.4725)
		(end 49.53 -224.4725)
		(width 0.254)
		(layer "F.Cu")
		(net "MB0_CM_OV_R")
	)
	(segment
		(start 48.4505 -224.4725)
		(end 49.53 -224.4725)
		(width 0.254)
		(layer "F.Cu")
		(net "MB0_CM_OV_R")
	)
	(via
		(at 51.689 -223.139)
		(size 0.7112)
		(drill 0.3556)
		(layers "F.Cu" "B.Cu")
		(net "MB0_CM_OV_R")
	)
	(segment
		(start 50.292 -214.376)
		(end 51.816 -215.9)
		(width 0.254)
		(layer "F.Cu")
		(net "MB0_CM_ADR1_R")
	)
	(segment
		(start 52.725066 -216.809066)
		(end 53.9115 -216.809066)
		(width 0.254)
		(layer "F.Cu")
		(net "MB0_CM_ADR1_R")
	)
	(segment
		(start 49.2125 -214.376)
		(end 50.292 -214.376)
		(width 0.254)
		(layer "F.Cu")
		(net "MB0_CM_ADR1_R")
	)
	(segment
		(start 51.816 -215.9)
		(end 52.725066 -216.809066)
		(width 0.254)
		(layer "F.Cu")
		(net "MB0_CM_ADR1_R")
	)
	(via
		(at 51.816 -215.9)
		(size 0.7112)
		(drill 0.3556)
		(layers "F.Cu" "B.Cu")
		(net "MB0_CM_ADR1_R")
	)
	(segment
		(start 58.039 -227.33)
		(end 58.039 -226.5045)
		(width 0.254)
		(layer "F.Cu")
		(net "MB0_CM_SENSE_R1_N")
	)
	(segment
		(start 58.039 -229.37343)
		(end 58.039 -227.33)
		(width 0.254)
		(layer "F.Cu")
		(net "MB0_CM_SENSE_R1_N")
	)
	(segment
		(start 58.598562 -229.932992)
		(end 58.039 -229.37343)
		(width 0.254)
		(layer "F.Cu")
		(net "MB0_CM_SENSE_R1_N")
	)
	(segment
		(start 58.039 -226.5045)
		(end 58.293 -226.2505)
		(width 0.254)
		(layer "F.Cu")
		(net "MB0_CM_SENSE_R1_N")
	)
	(via
		(at 58.039 -227.33)
		(size 0.7112)
		(drill 0.3556)
		(layers "F.Cu" "B.Cu")
		(net "MB0_CM_SENSE_R1_N")
	)
	(segment
		(start 58.9407 -213.8553)
		(end 58.9407 -216.30894)
		(width 0.254)
		(layer "F.Cu")
		(net "MB0_RETRY_R")
	)
	(segment
		(start 60.071 -212.725)
		(end 59.69 -213.106)
		(width 0.254)
		(layer "F.Cu")
		(net "MB0_RETRY_R")
	)
	(segment
		(start 60.071 -211.5185)
		(end 60.071 -212.725)
		(width 0.254)
		(layer "F.Cu")
		(net "MB0_RETRY_R")
	)
	(segment
		(start 59.69 -213.106)
		(end 58.9407 -213.8553)
		(width 0.254)
		(layer "F.Cu")
		(net "MB0_RETRY_R")
	)
	(via
		(at 59.69 -213.106)
		(size 0.7112)
		(drill 0.3556)
		(layers "F.Cu" "B.Cu")
		(net "MB0_RETRY_R")
	)
	(segment
		(start 61.9125 -216.281)
		(end 61.087 -216.281)
		(width 0.3048)
		(layer "F.Cu")
		(net "MB0_CM_VOUT_R")
	)
	(segment
		(start 60.706 -216.662)
		(end 59.558936 -217.809064)
		(width 0.3048)
		(layer "F.Cu")
		(net "MB0_CM_VOUT_R")
	)
	(segment
		(start 61.9125 -217.297)
		(end 61.9125 -216.281)
		(width 0.508)
		(layer "F.Cu")
		(net "MB0_CM_VOUT_R")
	)
	(segment
		(start 59.558936 -217.809064)
		(end 58.8645 -217.809064)
		(width 0.3048)
		(layer "F.Cu")
		(net "MB0_CM_VOUT_R")
	)
	(segment
		(start 61.087 -216.281)
		(end 60.706 -216.662)
		(width 0.3048)
		(layer "F.Cu")
		(net "MB0_CM_VOUT_R")
	)
	(via
		(at 60.706 -216.662)
		(size 0.7112)
		(drill 0.3556)
		(layers "F.Cu" "B.Cu")
		(net "MB0_CM_VOUT_R")
	)
	(segment
		(start 47.4345 -219.837)
		(end 47.244 -219.9005)
		(width 0.254)
		(layer "F.Cu")
		(net "MB0_ISET_R")
	)
	(segment
		(start 51.954938 -218.809062)
		(end 51.816 -218.948)
		(width 0.254)
		(layer "F.Cu")
		(net "MB0_ISET_R")
	)
	(segment
		(start 45.0215 -219.9005)
		(end 45.593 -219.9005)
		(width 0.254)
		(layer "F.Cu")
		(net "MB0_ISET_R")
	)
	(segment
		(start 44.45 -218.694)
		(end 44.45 -219.329)
		(width 0.254)
		(layer "F.Cu")
		(net "MB0_ISET_R")
	)
	(segment
		(start 44.45 -218.186)
		(end 44.45 -218.694)
		(width 0.254)
		(layer "F.Cu")
		(net "MB0_ISET_R")
	)
	(segment
		(start 45.593 -219.9005)
		(end 46.482 -219.9005)
		(width 0.254)
		(layer "F.Cu")
		(net "MB0_ISET_R")
	)
	(segment
		(start 47.244 -219.9005)
		(end 46.482 -219.9005)
		(width 0.254)
		(layer "F.Cu")
		(net "MB0_ISET_R")
	)
	(segment
		(start 44.831 -217.805)
		(end 44.45 -218.186)
		(width 0.254)
		(layer "F.Cu")
		(net "MB0_ISET_R")
	)
	(segment
		(start 45.466 -217.805)
		(end 44.831 -217.805)
		(width 0.254)
		(layer "F.Cu")
		(net "MB0_ISET_R")
	)
	(segment
		(start 53.9115 -218.809062)
		(end 51.954938 -218.809062)
		(width 0.254)
		(layer "F.Cu")
		(net "MB0_ISET_R")
	)
	(segment
		(start 44.45 -219.329)
		(end 45.0215 -219.9005)
		(width 0.254)
		(layer "F.Cu")
		(net "MB0_ISET_R")
	)
	(via
		(at 46.482 -219.9005)
		(size 0.5588)
		(drill 0.3048)
		(layers "F.Cu" "B.Cu")
		(net "MB0_ISET_R")
	)
	(via
		(at 51.816 -218.948)
		(size 0.5588)
		(drill 0.3048)
		(layers "F.Cu" "B.Cu")
		(net "MB0_ISET_R")
	)
	(via
		(at 44.45 -218.694)
		(size 0.7112)
		(drill 0.3556)
		(layers "F.Cu" "B.Cu")
		(net "MB0_ISET_R")
	)
	(segment
		(start 50.8635 -219.9005)
		(end 51.816 -218.948)
		(width 0.254)
		(layer "In2.Cu")
		(net "MB0_ISET_R")
	)
	(segment
		(start 46.482 -219.9005)
		(end 50.8635 -219.9005)
		(width 0.254)
		(layer "In2.Cu")
		(net "MB0_ISET_R")
	)
	(segment
		(start 57.404 -228.6)
		(end 57.404 -226.5045)
		(width 0.254)
		(layer "F.Cu")
		(net "MB0_CM_SENSE_R1_P")
	)
	(segment
		(start 57.404 -229.50043)
		(end 57.404 -228.6)
		(width 0.254)
		(layer "F.Cu")
		(net "MB0_CM_SENSE_R1_P")
	)
	(segment
		(start 57.404 -226.5045)
		(end 57.15 -226.2505)
		(width 0.254)
		(layer "F.Cu")
		(net "MB0_CM_SENSE_R1_P")
	)
	(segment
		(start 56.971438 -229.932992)
		(end 57.404 -229.50043)
		(width 0.254)
		(layer "F.Cu")
		(net "MB0_CM_SENSE_R1_P")
	)
	(via
		(at 57.404 -228.6)
		(size 0.7112)
		(drill 0.3556)
		(layers "F.Cu" "B.Cu")
		(net "MB0_CM_SENSE_R1_P")
	)
	(segment
		(start 60.042044 -225.863912)
		(end 59.817 -225.638868)
		(width 0.254)
		(layer "F.Cu")
		(net "MB0_TEMP")
	)
	(segment
		(start 59.817 -222.377)
		(end 58.13806 -220.69806)
		(width 0.254)
		(layer "F.Cu")
		(net "MB0_TEMP")
	)
	(segment
		(start 60.042044 -226.383088)
		(end 60.042044 -225.863912)
		(width 0.254)
		(layer "F.Cu")
		(net "MB0_TEMP")
	)
	(segment
		(start 59.817 -225.638868)
		(end 59.817 -225.482912)
		(width 0.254)
		(layer "F.Cu")
		(net "MB0_TEMP")
	)
	(segment
		(start 59.817 -225.482912)
		(end 59.817 -222.377)
		(width 0.254)
		(layer "F.Cu")
		(net "MB0_TEMP")
	)
	(segment
		(start 58.13806 -220.69806)
		(end 58.13806 -220.6117)
		(width 0.254)
		(layer "F.Cu")
		(net "MB0_TEMP")
	)
	(via
		(at 59.817 -222.377)
		(size 0.7112)
		(drill 0.3556)
		(layers "F.Cu" "B.Cu")
		(net "MB0_TEMP")
	)
	(segment
		(start 64.0842 -213.741)
		(end 64.0842 -214.9348)
		(width 0.508)
		(layer "F.Cu")
		(net "AGND_CURRENT_MON")
	)
	(segment
		(start 47.879 -214.376)
		(end 47.244 -213.741)
		(width 0.508)
		(layer "F.Cu")
		(net "AGND_CURRENT_MON")
	)
	(segment
		(start 52.3875 -210.6295)
		(end 52.197 -210.82)
		(width 0.508)
		(layer "F.Cu")
		(net "AGND_CURRENT_MON")
	)
	(segment
		(start 58.8645 -218.809062)
		(end 60.440062 -218.809062)
		(width 0.3048)
		(layer "F.Cu")
		(net "AGND_CURRENT_MON")
	)
	(segment
		(start 46.736 -217.678)
		(end 46.736 -218.694)
		(width 0.508)
		(layer "F.Cu")
		(net "AGND_CURRENT_MON")
	)
	(segment
		(start 47.117 -217.551)
		(end 46.99 -217.424)
		(width 0.508)
		(layer "F.Cu")
		(net "AGND_CURRENT_MON")
	)
	(segment
		(start 53.34 -210.6295)
		(end 52.3875 -210.6295)
		(width 0.508)
		(layer "F.Cu")
		(net "AGND_CURRENT_MON")
	)
	(segment
		(start 64.389 -219.287598)
		(end 64.41694 -219.315538)
		(width 0.508)
		(layer "F.Cu")
		(net "AGND_CURRENT_MON")
	)
	(segment
		(start 63.754 -215.265)
		(end 64.008 -215.011)
		(width 0.508)
		(layer "F.Cu")
		(net "AGND_CURRENT_MON")
	)
	(segment
		(start 56.388 -226.949)
		(end 56.388 -226.9744)
		(width 0.508)
		(layer "F.Cu")
		(net "AGND_CURRENT_MON")
	)
	(segment
		(start 47.18304 -215.392)
		(end 47.117 -215.45804)
		(width 0.508)
		(layer "F.Cu")
		(net "AGND_CURRENT_MON")
	)
	(segment
		(start 45.593 -214.249)
		(end 45.593 -215.138)
		(width 0.508)
		(layer "F.Cu")
		(net "AGND_CURRENT_MON")
	)
	(segment
		(start 45.466 -216.281)
		(end 45.593 -216.154)
		(width 0.508)
		(layer "F.Cu")
		(net "AGND_CURRENT_MON")
	)
	(segment
		(start 64.0842 -214.9348)
		(end 64.008 -215.011)
		(width 0.508)
		(layer "F.Cu")
		(net "AGND_CURRENT_MON")
	)
	(segment
		(start 48.4505 -223.139)
		(end 47.625 -223.139)
		(width 0.508)
		(layer "F.Cu")
		(net "AGND_CURRENT_MON")
	)
	(segment
		(start 48.3235 -213.36)
		(end 47.625 -213.36)
		(width 0.508)
		(layer "F.Cu")
		(net "AGND_CURRENT_MON")
	)
	(segment
		(start 47.117 -215.9)
		(end 47.117 -215.45804)
		(width 0.508)
		(layer "F.Cu")
		(net "AGND_CURRENT_MON")
	)
	(segment
		(start 56.007 -226.568)
		(end 56.388 -226.949)
		(width 0.508)
		(layer "F.Cu")
		(net "AGND_CURRENT_MON")
	)
	(segment
		(start 64.008 -218.821)
		(end 64.389 -219.202)
		(width 0.508)
		(layer "F.Cu")
		(net "AGND_CURRENT_MON")
	)
	(segment
		(start 52.832 -225.3615)
		(end 52.832 -226.568)
		(width 0.508)
		(layer "F.Cu")
		(net "AGND_CURRENT_MON")
	)
	(segment
		(start 64.008 -218.313)
		(end 64.008 -218.821)
		(width 0.508)
		(layer "F.Cu")
		(net "AGND_CURRENT_MON")
	)
	(segment
		(start 64.008 -218.313)
		(end 62.8015 -218.313)
		(width 0.508)
		(layer "F.Cu")
		(net "AGND_CURRENT_MON")
	)
	(segment
		(start 46.736 -218.694)
		(end 45.9105 -218.694)
		(width 0.508)
		(layer "F.Cu")
		(net "AGND_CURRENT_MON")
	)
	(segment
		(start 47.498 -222.25)
		(end 47.498 -223.012)
		(width 0.508)
		(layer "F.Cu")
		(net "AGND_CURRENT_MON")
	)
	(segment
		(start 45.9105 -218.694)
		(end 45.593 -219.0115)
		(width 0.508)
		(layer "F.Cu")
		(net "AGND_CURRENT_MON")
	)
	(segment
		(start 48.3235 -217.551)
		(end 47.117 -217.551)
		(width 0.508)
		(layer "F.Cu")
		(net "AGND_CURRENT_MON")
	)
	(segment
		(start 48.3235 -214.376)
		(end 47.879 -214.376)
		(width 0.508)
		(layer "F.Cu")
		(net "AGND_CURRENT_MON")
	)
	(segment
		(start 47.752 -221.996)
		(end 47.498 -222.25)
		(width 0.508)
		(layer "F.Cu")
		(net "AGND_CURRENT_MON")
	)
	(segment
		(start 62.8015 -216.281)
		(end 64.135 -216.281)
		(width 0.508)
		(layer "F.Cu")
		(net "AGND_CURRENT_MON")
	)
	(segment
		(start 62.8015 -215.265)
		(end 63.754 -215.265)
		(width 0.508)
		(layer "F.Cu")
		(net "AGND_CURRENT_MON")
	)
	(segment
		(start 46.99 -217.424)
		(end 46.736 -217.678)
		(width 0.508)
		(layer "F.Cu")
		(net "AGND_CURRENT_MON")
	)
	(segment
		(start 48.387 -226.06)
		(end 48.387 -227.076)
		(width 0.508)
		(layer "F.Cu")
		(net "AGND_CURRENT_MON")
	)
	(segment
		(start 47.625 -216.408)
		(end 47.117 -215.9)
		(width 0.508)
		(layer "F.Cu")
		(net "AGND_CURRENT_MON")
	)
	(segment
		(start 47.625 -223.139)
		(end 47.498 -223.012)
		(width 0.508)
		(layer "F.Cu")
		(net "AGND_CURRENT_MON")
	)
	(segment
		(start 56.007 -226.06)
		(end 56.007 -226.568)
		(width 0.508)
		(layer "F.Cu")
		(net "AGND_CURRENT_MON")
	)
	(segment
		(start 51.689 -226.06)
		(end 51.689 -227.076)
		(width 0.508)
		(layer "F.Cu")
		(net "AGND_CURRENT_MON")
	)
	(segment
		(start 45.593 -216.154)
		(end 45.593 -215.138)
		(width 0.508)
		(layer "F.Cu")
		(net "AGND_CURRENT_MON")
	)
	(segment
		(start 49.53 -225.3615)
		(end 49.53 -226.441)
		(width 0.508)
		(layer "F.Cu")
		(net "AGND_CURRENT_MON")
	)
	(segment
		(start 64.389 -219.202)
		(end 64.389 -219.287598)
		(width 0.508)
		(layer "F.Cu")
		(net "AGND_CURRENT_MON")
	)
	(segment
		(start 48.3235 -215.392)
		(end 47.18304 -215.392)
		(width 0.508)
		(layer "F.Cu")
		(net "AGND_CURRENT_MON")
	)
	(segment
		(start 47.625 -213.36)
		(end 47.244 -213.741)
		(width 0.508)
		(layer "F.Cu")
		(net "AGND_CURRENT_MON")
	)
	(via
		(at 47.244 -213.741)
		(size 0.5588)
		(drill 0.3048)
		(layers "F.Cu" "B.Cu")
		(net "AGND_CURRENT_MON")
	)
	(via
		(at 52.832 -226.568)
		(size 0.5588)
		(drill 0.3048)
		(layers "F.Cu" "B.Cu")
		(net "AGND_CURRENT_MON")
	)
	(via
		(at 52.197 -210.82)
		(size 0.5588)
		(drill 0.3048)
		(layers "F.Cu" "B.Cu")
		(net "AGND_CURRENT_MON")
	)
	(via
		(at 48.387 -227.076)
		(size 0.5588)
		(drill 0.3048)
		(layers "F.Cu" "B.Cu")
		(net "AGND_CURRENT_MON")
	)
	(via
		(at 46.99 -217.424)
		(size 0.5588)
		(drill 0.3048)
		(layers "F.Cu" "B.Cu")
		(net "AGND_CURRENT_MON")
	)
	(via
		(at 45.593 -215.138)
		(size 0.5588)
		(drill 0.3048)
		(layers "F.Cu" "B.Cu")
		(net "AGND_CURRENT_MON")
	)
	(via
		(at 45.593 -214.249)
		(size 0.7112)
		(drill 0.3556)
		(layers "F.Cu" "B.Cu")
		(net "AGND_CURRENT_MON")
	)
	(via
		(at 64.41694 -219.315538)
		(size 0.5588)
		(drill 0.3048)
		(layers "F.Cu" "B.Cu")
		(net "AGND_CURRENT_MON")
	)
	(via
		(at 56.388 -226.9744)
		(size 0.5588)
		(drill 0.3048)
		(layers "F.Cu" "B.Cu")
		(net "AGND_CURRENT_MON")
	)
	(via
		(at 60.440062 -218.809062)
		(size 0.5588)
		(drill 0.3048)
		(layers "F.Cu" "B.Cu")
		(net "AGND_CURRENT_MON")
	)
	(via
		(at 57.658 -217.932)
		(size 0.5588)
		(drill 0.3048)
		(layers "F.Cu" "B.Cu")
		(net "AGND_CURRENT_MON")
	)
	(via
		(at 64.008 -215.011)
		(size 0.5588)
		(drill 0.3048)
		(layers "F.Cu" "B.Cu")
		(net "AGND_CURRENT_MON")
	)
	(via
		(at 47.498 -223.012)
		(size 0.5588)
		(drill 0.3048)
		(layers "F.Cu" "B.Cu")
		(net "AGND_CURRENT_MON")
	)
	(via
		(at 55.118 -218.059)
		(size 0.5588)
		(drill 0.3048)
		(layers "F.Cu" "B.Cu")
		(net "AGND_CURRENT_MON")
	)
	(via
		(at 49.53 -226.441)
		(size 0.5588)
		(drill 0.3048)
		(layers "F.Cu" "B.Cu")
		(net "AGND_CURRENT_MON")
	)
	(via
		(at 51.689 -227.076)
		(size 0.5588)
		(drill 0.3048)
		(layers "F.Cu" "B.Cu")
		(net "AGND_CURRENT_MON")
	)
	(via
		(at 64.135 -216.281)
		(size 0.5588)
		(drill 0.3048)
		(layers "F.Cu" "B.Cu")
		(net "AGND_CURRENT_MON")
	)
	(via
		(at 56.388 -216.789)
		(size 0.5588)
		(drill 0.3048)
		(layers "F.Cu" "B.Cu")
		(net "AGND_CURRENT_MON")
	)
	(via
		(at 47.117 -215.45804)
		(size 0.5588)
		(drill 0.3048)
		(layers "F.Cu" "B.Cu")
		(net "AGND_CURRENT_MON")
	)
	(via
		(at 56.388 -219.329)
		(size 0.5588)
		(drill 0.3048)
		(layers "F.Cu" "B.Cu")
		(net "AGND_CURRENT_MON")
	)
	(via
		(at 56.388 -218.059)
		(size 0.5588)
		(drill 0.3048)
		(layers "F.Cu" "B.Cu")
		(net "AGND_CURRENT_MON")
	)
	(segment
		(start 209.6135 -221.869)
		(end 210.55076 -221.869)
		(width 0.1143)
		(layer "F.Cu")
		(net "OE_BMC_RSET")
	)
	(segment
		(start 211.3915 -220.61424)
		(end 211.3915 -221.1705)
		(width 0.1143)
		(layer "F.Cu")
		(net "OE_BMC_RSET")
	)
	(segment
		(start 210.693 -221.869)
		(end 210.55076 -221.869)
		(width 0.1143)
		(layer "F.Cu")
		(net "OE_BMC_RSET")
	)
	(segment
		(start 211.3915 -221.1705)
		(end 210.693 -221.869)
		(width 0.1143)
		(layer "F.Cu")
		(net "OE_BMC_RSET")
	)
	(segment
		(start 209.4865 -221.742)
		(end 209.6135 -221.869)
		(width 0.1143)
		(layer "F.Cu")
		(net "OE_BMC_RSET")
	)
	(via
		(at 210.55076 -221.869)
		(size 0.7112)
		(drill 0.3556)
		(layers "F.Cu" "B.Cu")
		(net "OE_BMC_RSET")
	)
	(segment
		(start 299.23486 -184.31129)
		(end 303.77257 -188.849)
		(width 0.1143)
		(layer "F.Cu")
		(net "BMC_EN_CPU_RESET_CONTROL")
	)
	(segment
		(start 303.77257 -188.849)
		(end 304.673 -188.849)
		(width 0.1143)
		(layer "F.Cu")
		(net "BMC_EN_CPU_RESET_CONTROL")
	)
	(segment
		(start 208.5975 -221.742)
		(end 208.5975 -221.1705)
		(width 0.1143)
		(layer "F.Cu")
		(net "BMC_EN_CPU_RESET_CONTROL")
	)
	(segment
		(start 299.23486 -184.24017)
		(end 299.23486 -184.31129)
		(width 0.1143)
		(layer "F.Cu")
		(net "BMC_EN_CPU_RESET_CONTROL")
	)
	(segment
		(start 208.5975 -221.1705)
		(end 208.026 -220.599)
		(width 0.1143)
		(layer "F.Cu")
		(net "BMC_EN_CPU_RESET_CONTROL")
	)
	(via
		(at 304.673 -188.849)
		(size 0.5588)
		(drill 0.254)
		(layers "F.Cu" "B.Cu")
		(net "BMC_EN_CPU_RESET_CONTROL")
	)
	(via
		(at 208.026 -220.599)
		(size 0.5588)
		(drill 0.3048)
		(layers "F.Cu" "B.Cu")
		(net "BMC_EN_CPU_RESET_CONTROL")
	)
	(via
		(at 305.3588 -188.3664)
		(size 0.7112)
		(drill 0.3556)
		(layers "F.Cu" "B.Cu")
		(net "BMC_EN_CPU_RESET_CONTROL")
	)
	(via
		(at 259.969 -184.658)
		(size 0.5588)
		(drill 0.3048)
		(layers "F.Cu" "B.Cu")
		(net "BMC_EN_CPU_RESET_CONTROL")
	)
	(segment
		(start 305.3588 -188.3664)
		(end 305.1556 -188.3664)
		(width 0.1143)
		(layer "B.Cu")
		(net "BMC_EN_CPU_RESET_CONTROL")
	)
	(segment
		(start 305.1556 -188.3664)
		(end 304.673 -188.849)
		(width 0.1143)
		(layer "B.Cu")
		(net "BMC_EN_CPU_RESET_CONTROL")
	)
	(segment
		(start 266.446 -196.719698)
		(end 266.446 -190.767716)
		(width 0.127)
		(layer "In2.Cu")
		(net "BMC_EN_CPU_RESET_CONTROL")
	)
	(segment
		(start 286.026098 -193.421)
		(end 279.180798 -200.2663)
		(width 0.127)
		(layer "In2.Cu")
		(net "BMC_EN_CPU_RESET_CONTROL")
	)
	(segment
		(start 300.355 -188.849)
		(end 295.783 -193.421)
		(width 0.127)
		(layer "In2.Cu")
		(net "BMC_EN_CPU_RESET_CONTROL")
	)
	(segment
		(start 260.844284 -185.166)
		(end 260.477 -185.166)
		(width 0.127)
		(layer "In2.Cu")
		(net "BMC_EN_CPU_RESET_CONTROL")
	)
	(segment
		(start 279.180798 -200.2663)
		(end 269.992602 -200.2663)
		(width 0.127)
		(layer "In2.Cu")
		(net "BMC_EN_CPU_RESET_CONTROL")
	)
	(segment
		(start 304.673 -188.849)
		(end 300.355 -188.849)
		(width 0.127)
		(layer "In2.Cu")
		(net "BMC_EN_CPU_RESET_CONTROL")
	)
	(segment
		(start 260.477 -185.166)
		(end 259.969 -184.658)
		(width 0.127)
		(layer "In2.Cu")
		(net "BMC_EN_CPU_RESET_CONTROL")
	)
	(segment
		(start 269.992602 -200.2663)
		(end 266.446 -196.719698)
		(width 0.127)
		(layer "In2.Cu")
		(net "BMC_EN_CPU_RESET_CONTROL")
	)
	(segment
		(start 266.446 -190.767716)
		(end 260.844284 -185.166)
		(width 0.127)
		(layer "In2.Cu")
		(net "BMC_EN_CPU_RESET_CONTROL")
	)
	(segment
		(start 295.783 -193.421)
		(end 286.026098 -193.421)
		(width 0.127)
		(layer "In2.Cu")
		(net "BMC_EN_CPU_RESET_CONTROL")
	)
	(segment
		(start 210.566 -213.456012)
		(end 210.566 -219.463874)
		(width 0.127)
		(layer "In5.Cu")
		(net "BMC_EN_CPU_RESET_CONTROL")
	)
	(segment
		(start 210.065874 -219.964)
		(end 208.915 -219.964)
		(width 0.127)
		(layer "In5.Cu")
		(net "BMC_EN_CPU_RESET_CONTROL")
	)
	(segment
		(start 259.08 -186.736228)
		(end 253.995428 -191.8208)
		(width 0.127)
		(layer "In5.Cu")
		(net "BMC_EN_CPU_RESET_CONTROL")
	)
	(segment
		(start 208.28 -220.599)
		(end 208.026 -220.599)
		(width 0.127)
		(layer "In5.Cu")
		(net "BMC_EN_CPU_RESET_CONTROL")
	)
	(segment
		(start 210.566 -219.463874)
		(end 210.065874 -219.964)
		(width 0.127)
		(layer "In5.Cu")
		(net "BMC_EN_CPU_RESET_CONTROL")
	)
	(segment
		(start 232.201212 -191.8208)
		(end 210.566 -213.456012)
		(width 0.127)
		(layer "In5.Cu")
		(net "BMC_EN_CPU_RESET_CONTROL")
	)
	(segment
		(start 259.08 -185.547)
		(end 259.08 -186.736228)
		(width 0.127)
		(layer "In5.Cu")
		(net "BMC_EN_CPU_RESET_CONTROL")
	)
	(segment
		(start 208.915 -219.964)
		(end 208.28 -220.599)
		(width 0.127)
		(layer "In5.Cu")
		(net "BMC_EN_CPU_RESET_CONTROL")
	)
	(segment
		(start 253.995428 -191.8208)
		(end 232.201212 -191.8208)
		(width 0.127)
		(layer "In5.Cu")
		(net "BMC_EN_CPU_RESET_CONTROL")
	)
	(segment
		(start 259.969 -184.658)
		(end 259.08 -185.547)
		(width 0.127)
		(layer "In5.Cu")
		(net "BMC_EN_CPU_RESET_CONTROL")
	)
	(segment
		(start 296.834814 -181.040024)
		(end 296.834814 -181.01183)
		(width 0.127)
		(layer "F.Cu")
		(net "TP_BMC_GPIOO7")
	)
	(segment
		(start 296.834814 -181.01183)
		(end 296.444162 -180.621178)
		(width 0.127)
		(layer "F.Cu")
		(net "TP_BMC_GPIOO7")
	)
	(via
		(at 296.444162 -180.621178)
		(size 0.508)
		(drill 0.254)
		(layers "F.Cu" "B.Cu")
		(net "TP_BMC_GPIOO7")
	)
	(segment
		(start 295.5798 -181.4576)
		(end 296.36466 -180.67274)
		(width 0.127)
		(layer "B.Cu")
		(net "TP_BMC_GPIOO7")
	)
	(segment
		(start 296.3926 -180.67274)
		(end 296.444162 -180.621178)
		(width 0.127)
		(layer "B.Cu")
		(net "TP_BMC_GPIOO7")
	)
	(segment
		(start 296.36466 -180.67274)
		(end 296.3926 -180.67274)
		(width 0.127)
		(layer "B.Cu")
		(net "TP_BMC_GPIOO7")
	)
	(segment
		(start 107.349798 -96.350074)
		(end 106.849672 -96.8502)
		(width 0.1143)
		(layer "F.Cu")
		(net "EXP_FW_DET_BOARD_VER_1")
	)
	(via
		(at 106.849672 -96.8502)
		(size 0.508)
		(drill 0.254)
		(layers "F.Cu" "B.Cu")
		(net "EXP_FW_DET_BOARD_VER_1")
	)
	(via
		(at 96.393 -95.758)
		(size 0.7112)
		(drill 0.3556)
		(layers "F.Cu" "B.Cu")
		(net "EXP_FW_DET_BOARD_VER_1")
	)
	(segment
		(start 101.399848 -95.196152)
		(end 105.77957 -95.196152)
		(width 0.1143)
		(layer "B.Cu")
		(net "EXP_FW_DET_BOARD_VER_1")
	)
	(segment
		(start 96.393 -95.758)
		(end 94.615 -95.758)
		(width 0.1143)
		(layer "B.Cu")
		(net "EXP_FW_DET_BOARD_VER_1")
	)
	(segment
		(start 88.0745 -100.584)
		(end 88.138 -100.6475)
		(width 0.1143)
		(layer "B.Cu")
		(net "EXP_FW_DET_BOARD_VER_1")
	)
	(segment
		(start 105.77957 -95.196152)
		(end 106.411522 -95.828104)
		(width 0.1143)
		(layer "B.Cu")
		(net "EXP_FW_DET_BOARD_VER_1")
	)
	(segment
		(start 94.234 -96.139)
		(end 90.17 -96.139)
		(width 0.1143)
		(layer "B.Cu")
		(net "EXP_FW_DET_BOARD_VER_1")
	)
	(segment
		(start 88.3285 -97.9805)
		(end 88.3285 -99.7585)
		(width 0.1143)
		(layer "B.Cu")
		(net "EXP_FW_DET_BOARD_VER_1")
	)
	(segment
		(start 94.615 -95.758)
		(end 94.234 -96.139)
		(width 0.1143)
		(layer "B.Cu")
		(net "EXP_FW_DET_BOARD_VER_1")
	)
	(segment
		(start 106.411522 -95.995998)
		(end 106.553762 -96.138238)
		(width 0.1143)
		(layer "B.Cu")
		(net "EXP_FW_DET_BOARD_VER_1")
	)
	(segment
		(start 96.393 -95.758)
		(end 100.838 -95.758)
		(width 0.1143)
		(layer "B.Cu")
		(net "EXP_FW_DET_BOARD_VER_1")
	)
	(segment
		(start 106.553762 -96.55429)
		(end 106.849672 -96.8502)
		(width 0.1143)
		(layer "B.Cu")
		(net "EXP_FW_DET_BOARD_VER_1")
	)
	(segment
		(start 100.838 -95.758)
		(end 101.399848 -95.196152)
		(width 0.1143)
		(layer "B.Cu")
		(net "EXP_FW_DET_BOARD_VER_1")
	)
	(segment
		(start 90.17 -96.139)
		(end 88.3285 -97.9805)
		(width 0.1143)
		(layer "B.Cu")
		(net "EXP_FW_DET_BOARD_VER_1")
	)
	(segment
		(start 89.154 -100.584)
		(end 89.154 -100.6475)
		(width 0.1143)
		(layer "B.Cu")
		(net "EXP_FW_DET_BOARD_VER_1")
	)
	(segment
		(start 106.553762 -96.138238)
		(end 106.553762 -96.55429)
		(width 0.1143)
		(layer "B.Cu")
		(net "EXP_FW_DET_BOARD_VER_1")
	)
	(segment
		(start 106.411522 -95.828104)
		(end 106.411522 -95.995998)
		(width 0.1143)
		(layer "B.Cu")
		(net "EXP_FW_DET_BOARD_VER_1")
	)
	(segment
		(start 88.3285 -99.7585)
		(end 89.154 -100.584)
		(width 0.1143)
		(layer "B.Cu")
		(net "EXP_FW_DET_BOARD_VER_1")
	)
	(segment
		(start 88.138 -100.6475)
		(end 89.154 -100.6475)
		(width 0.1143)
		(layer "B.Cu")
		(net "EXP_FW_DET_BOARD_VER_1")
	)
	(segment
		(start 62.23 -108.458)
		(end 61.1505 -108.458)
		(width 0.1143)
		(layer "F.Cu")
		(net "EXP_FW_DET_BOARD_VER_0")
	)
	(segment
		(start 100.576126 -101.12375)
		(end 102.349808 -99.350068)
		(width 0.1143)
		(layer "F.Cu")
		(net "EXP_FW_DET_BOARD_VER_0")
	)
	(segment
		(start 92.305124 -101.12375)
		(end 100.576126 -101.12375)
		(width 0.1143)
		(layer "F.Cu")
		(net "EXP_FW_DET_BOARD_VER_0")
	)
	(segment
		(start 61.1505 -108.458)
		(end 61.1505 -109.474)
		(width 0.1143)
		(layer "F.Cu")
		(net "EXP_FW_DET_BOARD_VER_0")
	)
	(segment
		(start 65.718182 -105.626662)
		(end 76.775818 -105.626662)
		(width 0.1143)
		(layer "F.Cu")
		(net "EXP_FW_DET_BOARD_VER_0")
	)
	(segment
		(start 92.281248 -101.099874)
		(end 92.305124 -101.12375)
		(width 0.1143)
		(layer "F.Cu")
		(net "EXP_FW_DET_BOARD_VER_0")
	)
	(segment
		(start 77.481938 -106.332782)
		(end 86.082124 -106.332782)
		(width 0.1143)
		(layer "F.Cu")
		(net "EXP_FW_DET_BOARD_VER_0")
	)
	(segment
		(start 86.082124 -106.332782)
		(end 91.315032 -101.099874)
		(width 0.1143)
		(layer "F.Cu")
		(net "EXP_FW_DET_BOARD_VER_0")
	)
	(segment
		(start 62.886844 -108.458)
		(end 65.718182 -105.626662)
		(width 0.1143)
		(layer "F.Cu")
		(net "EXP_FW_DET_BOARD_VER_0")
	)
	(segment
		(start 91.315032 -101.099874)
		(end 92.281248 -101.099874)
		(width 0.1143)
		(layer "F.Cu")
		(net "EXP_FW_DET_BOARD_VER_0")
	)
	(segment
		(start 62.23 -108.458)
		(end 62.886844 -108.458)
		(width 0.1143)
		(layer "F.Cu")
		(net "EXP_FW_DET_BOARD_VER_0")
	)
	(segment
		(start 76.775818 -105.626662)
		(end 77.481938 -106.332782)
		(width 0.1143)
		(layer "F.Cu")
		(net "EXP_FW_DET_BOARD_VER_0")
	)
	(via
		(at 62.23 -108.458)
		(size 0.7112)
		(drill 0.3556)
		(layers "F.Cu" "B.Cu")
		(net "EXP_FW_DET_BOARD_VER_0")
	)
	(segment
		(start 300.834806 -184.452768)
		(end 300.834806 -184.24017)
		(width 0.1143)
		(layer "F.Cu")
		(net "BMC_FW_DET_BOARD_VER_2")
	)
	(segment
		(start 305.329844 -187.071)
		(end 304.688494 -186.42965)
		(width 0.1143)
		(layer "F.Cu")
		(net "BMC_FW_DET_BOARD_VER_2")
	)
	(segment
		(start 305.828954 -187.579)
		(end 305.329844 -187.07989)
		(width 0.1143)
		(layer "F.Cu")
		(net "BMC_FW_DET_BOARD_VER_2")
	)
	(segment
		(start 302.999902 -186.2201)
		(end 302.5521 -186.2201)
		(width 0.1143)
		(layer "F.Cu")
		(net "BMC_FW_DET_BOARD_VER_2")
	)
	(segment
		(start 308.6735 -187.579)
		(end 309.4355 -186.817)
		(width 0.1143)
		(layer "F.Cu")
		(net "BMC_FW_DET_BOARD_VER_2")
	)
	(segment
		(start 302.5521 -186.2201)
		(end 301.472854 -185.140854)
		(width 0.1143)
		(layer "F.Cu")
		(net "BMC_FW_DET_BOARD_VER_2")
	)
	(segment
		(start 304.688494 -186.42965)
		(end 304.65776 -186.42965)
		(width 0.1143)
		(layer "F.Cu")
		(net "BMC_FW_DET_BOARD_VER_2")
	)
	(segment
		(start 301.472854 -185.090816)
		(end 300.834806 -184.452768)
		(width 0.1143)
		(layer "F.Cu")
		(net "BMC_FW_DET_BOARD_VER_2")
	)
	(segment
		(start 306.832 -187.579)
		(end 308.6735 -187.579)
		(width 0.1143)
		(layer "F.Cu")
		(net "BMC_FW_DET_BOARD_VER_2")
	)
	(segment
		(start 301.472854 -185.140854)
		(end 301.472854 -185.090816)
		(width 0.1143)
		(layer "F.Cu")
		(net "BMC_FW_DET_BOARD_VER_2")
	)
	(segment
		(start 306.832 -187.579)
		(end 305.828954 -187.579)
		(width 0.1143)
		(layer "F.Cu")
		(net "BMC_FW_DET_BOARD_VER_2")
	)
	(segment
		(start 304.65776 -186.42965)
		(end 304.45456 -186.22645)
		(width 0.1143)
		(layer "F.Cu")
		(net "BMC_FW_DET_BOARD_VER_2")
	)
	(segment
		(start 304.45456 -186.22645)
		(end 303.006252 -186.22645)
		(width 0.1143)
		(layer "F.Cu")
		(net "BMC_FW_DET_BOARD_VER_2")
	)
	(segment
		(start 309.4355 -186.817)
		(end 310.4515 -186.817)
		(width 0.1143)
		(layer "F.Cu")
		(net "BMC_FW_DET_BOARD_VER_2")
	)
	(segment
		(start 305.329844 -187.07989)
		(end 305.329844 -187.071)
		(width 0.1143)
		(layer "F.Cu")
		(net "BMC_FW_DET_BOARD_VER_2")
	)
	(segment
		(start 303.006252 -186.22645)
		(end 302.999902 -186.2201)
		(width 0.1143)
		(layer "F.Cu")
		(net "BMC_FW_DET_BOARD_VER_2")
	)
	(via
		(at 306.832 -187.579)
		(size 0.7112)
		(drill 0.3556)
		(layers "F.Cu" "B.Cu")
		(net "BMC_FW_DET_BOARD_VER_2")
	)
	(segment
		(start 300.71822 -183.87822)
		(end 300.28007 -183.44007)
		(width 0.1143)
		(layer "F.Cu")
		(net "BMC_FW_DET_BOARD_VER_1")
	)
	(segment
		(start 300.28007 -183.44007)
		(end 300.03496 -183.44007)
		(width 0.1143)
		(layer "F.Cu")
		(net "BMC_FW_DET_BOARD_VER_1")
	)
	(segment
		(start 306.33416 -186.055)
		(end 306.705 -186.055)
		(width 0.1143)
		(layer "F.Cu")
		(net "BMC_FW_DET_BOARD_VER_1")
	)
	(segment
		(start 306.705 -186.055)
		(end 307.848 -184.912)
		(width 0.1143)
		(layer "F.Cu")
		(net "BMC_FW_DET_BOARD_VER_1")
	)
	(segment
		(start 307.848 -184.912)
		(end 308.6735 -184.912)
		(width 0.1143)
		(layer "F.Cu")
		(net "BMC_FW_DET_BOARD_VER_1")
	)
	(segment
		(start 309.4355 -185.674)
		(end 310.4515 -185.674)
		(width 0.1143)
		(layer "F.Cu")
		(net "BMC_FW_DET_BOARD_VER_1")
	)
	(segment
		(start 301.244 -184.12841)
		(end 301.01159 -183.896)
		(width 0.1143)
		(layer "F.Cu")
		(net "BMC_FW_DET_BOARD_VER_1")
	)
	(segment
		(start 308.6735 -184.912)
		(end 309.4355 -185.674)
		(width 0.1143)
		(layer "F.Cu")
		(net "BMC_FW_DET_BOARD_VER_1")
	)
	(segment
		(start 301.0027 -183.896)
		(end 300.98492 -183.87822)
		(width 0.1143)
		(layer "F.Cu")
		(net "BMC_FW_DET_BOARD_VER_1")
	)
	(segment
		(start 301.01159 -183.896)
		(end 301.0027 -183.896)
		(width 0.1143)
		(layer "F.Cu")
		(net "BMC_FW_DET_BOARD_VER_1")
	)
	(segment
		(start 303.008792 -185.674)
		(end 302.415448 -185.674)
		(width 0.1143)
		(layer "F.Cu")
		(net "BMC_FW_DET_BOARD_VER_1")
	)
	(segment
		(start 300.98492 -183.87822)
		(end 300.71822 -183.87822)
		(width 0.1143)
		(layer "F.Cu")
		(net "BMC_FW_DET_BOARD_VER_1")
	)
	(segment
		(start 301.244 -184.502552)
		(end 301.244 -184.12841)
		(width 0.1143)
		(layer "F.Cu")
		(net "BMC_FW_DET_BOARD_VER_1")
	)
	(segment
		(start 306.33416 -186.055)
		(end 304.804064 -186.055)
		(width 0.1143)
		(layer "F.Cu")
		(net "BMC_FW_DET_BOARD_VER_1")
	)
	(segment
		(start 304.804064 -186.055)
		(end 304.537364 -185.7883)
		(width 0.1143)
		(layer "F.Cu")
		(net "BMC_FW_DET_BOARD_VER_1")
	)
	(segment
		(start 303.123092 -185.7883)
		(end 303.008792 -185.674)
		(width 0.1143)
		(layer "F.Cu")
		(net "BMC_FW_DET_BOARD_VER_1")
	)
	(segment
		(start 302.415448 -185.674)
		(end 301.244 -184.502552)
		(width 0.1143)
		(layer "F.Cu")
		(net "BMC_FW_DET_BOARD_VER_1")
	)
	(segment
		(start 304.537364 -185.7883)
		(end 303.123092 -185.7883)
		(width 0.1143)
		(layer "F.Cu")
		(net "BMC_FW_DET_BOARD_VER_1")
	)
	(via
		(at 306.33416 -186.055)
		(size 0.7112)
		(drill 0.3556)
		(layers "F.Cu" "B.Cu")
		(net "BMC_FW_DET_BOARD_VER_1")
	)
	(segment
		(start 299.631862 -182.237126)
		(end 300.03496 -182.640224)
		(width 0.1143)
		(layer "F.Cu")
		(net "BMC_FW_DET_BOARD_VER_0")
	)
	(segment
		(start 298.828206 -182.237126)
		(end 299.631862 -182.237126)
		(width 0.1143)
		(layer "F.Cu")
		(net "BMC_FW_DET_BOARD_VER_0")
	)
	(via
		(at 307.086 -183.515)
		(size 0.7112)
		(drill 0.3556)
		(layers "F.Cu" "B.Cu")
		(net "BMC_FW_DET_BOARD_VER_0")
	)
	(via
		(at 298.828206 -182.237126)
		(size 0.508)
		(drill 0.254)
		(layers "F.Cu" "B.Cu")
		(net "BMC_FW_DET_BOARD_VER_0")
	)
	(segment
		(start 298.828206 -182.4482)
		(end 298.828206 -182.237126)
		(width 0.1143)
		(layer "B.Cu")
		(net "BMC_FW_DET_BOARD_VER_0")
	)
	(segment
		(start 307.086 -183.515)
		(end 310.4515 -183.515)
		(width 0.1143)
		(layer "B.Cu")
		(net "BMC_FW_DET_BOARD_VER_0")
	)
	(segment
		(start 299.243496 -182.86349)
		(end 298.828206 -182.4482)
		(width 0.1143)
		(layer "B.Cu")
		(net "BMC_FW_DET_BOARD_VER_0")
	)
	(segment
		(start 299.243496 -182.911496)
		(end 299.243496 -182.86349)
		(width 0.1143)
		(layer "B.Cu")
		(net "BMC_FW_DET_BOARD_VER_0")
	)
	(segment
		(start 307.086 -183.515)
		(end 299.847 -183.515)
		(width 0.1143)
		(layer "B.Cu")
		(net "BMC_FW_DET_BOARD_VER_0")
	)
	(segment
		(start 299.847 -183.515)
		(end 299.243496 -182.911496)
		(width 0.1143)
		(layer "B.Cu")
		(net "BMC_FW_DET_BOARD_VER_0")
	)
	(segment
		(start 310.4515 -183.515)
		(end 310.4515 -182.499)
		(width 0.1143)
		(layer "B.Cu")
		(net "BMC_FW_DET_BOARD_VER_0")
	)
	(segment
		(start 63.881 -106.426)
		(end 65.151 -105.156)
		(width 0.1143)
		(layer "F.Cu")
		(net "EXP_FW_DET_BOARD_VER_2")
	)
	(segment
		(start 61.1505 -106.426)
		(end 63.627 -106.426)
		(width 0.1143)
		(layer "F.Cu")
		(net "EXP_FW_DET_BOARD_VER_2")
	)
	(segment
		(start 97.96145 -100.75545)
		(end 100.270564 -100.75545)
		(width 0.1143)
		(layer "F.Cu")
		(net "EXP_FW_DET_BOARD_VER_2")
	)
	(segment
		(start 97.937574 -100.731574)
		(end 97.96145 -100.75545)
		(width 0.1143)
		(layer "F.Cu")
		(net "EXP_FW_DET_BOARD_VER_2")
	)
	(segment
		(start 65.151 -105.156)
		(end 76.835 -105.156)
		(width 0.1143)
		(layer "F.Cu")
		(net "EXP_FW_DET_BOARD_VER_2")
	)
	(segment
		(start 77.643482 -105.964482)
		(end 85.92947 -105.964482)
		(width 0.1143)
		(layer "F.Cu")
		(net "EXP_FW_DET_BOARD_VER_2")
	)
	(segment
		(start 85.92947 -105.964482)
		(end 91.162378 -100.731574)
		(width 0.1143)
		(layer "F.Cu")
		(net "EXP_FW_DET_BOARD_VER_2")
	)
	(segment
		(start 100.270564 -100.75545)
		(end 102.349808 -98.676206)
		(width 0.1143)
		(layer "F.Cu")
		(net "EXP_FW_DET_BOARD_VER_2")
	)
	(segment
		(start 91.162378 -100.731574)
		(end 97.937574 -100.731574)
		(width 0.1143)
		(layer "F.Cu")
		(net "EXP_FW_DET_BOARD_VER_2")
	)
	(segment
		(start 63.627 -106.426)
		(end 63.881 -106.426)
		(width 0.1143)
		(layer "F.Cu")
		(net "EXP_FW_DET_BOARD_VER_2")
	)
	(segment
		(start 102.349808 -98.676206)
		(end 102.349808 -98.35007)
		(width 0.1143)
		(layer "F.Cu")
		(net "EXP_FW_DET_BOARD_VER_2")
	)
	(segment
		(start 76.835 -105.156)
		(end 77.643482 -105.964482)
		(width 0.1143)
		(layer "F.Cu")
		(net "EXP_FW_DET_BOARD_VER_2")
	)
	(segment
		(start 61.1505 -107.442)
		(end 61.1505 -106.426)
		(width 0.1143)
		(layer "F.Cu")
		(net "EXP_FW_DET_BOARD_VER_2")
	)
	(via
		(at 63.627 -106.426)
		(size 0.7112)
		(drill 0.3556)
		(layers "F.Cu" "B.Cu")
		(net "EXP_FW_DET_BOARD_VER_2")
	)
	(segment
		(start 286.434784 -181.040024)
		(end 286.443674 -181.040024)
		(width 0.1143)
		(layer "F.Cu")
		(net "FLA_CS_1_R")
	)
	(segment
		(start 326.263 -82.9945)
		(end 326.263 -84.836)
		(width 0.1143)
		(layer "F.Cu")
		(net "FLA_CS_1_R")
	)
	(segment
		(start 326.263 -84.836)
		(end 325.247 -85.852)
		(width 0.1143)
		(layer "F.Cu")
		(net "FLA_CS_1_R")
	)
	(segment
		(start 286.443674 -181.040024)
		(end 286.836358 -180.64734)
		(width 0.1143)
		(layer "F.Cu")
		(net "FLA_CS_1_R")
	)
	(via
		(at 294.654732 -92.597732)
		(size 0.5588)
		(drill 0.3048)
		(layers "F.Cu" "B.Cu")
		(net "FLA_CS_1_R")
	)
	(via
		(at 325.247 -85.852)
		(size 0.5588)
		(drill 0.3048)
		(layers "F.Cu" "B.Cu")
		(net "FLA_CS_1_R")
	)
	(via
		(at 269.1892 -182.81396)
		(size 0.5588)
		(drill 0.3048)
		(layers "F.Cu" "B.Cu")
		(net "FLA_CS_1_R")
	)
	(via
		(at 286.836358 -180.64734)
		(size 0.508)
		(drill 0.254)
		(layers "F.Cu" "B.Cu")
		(net "FLA_CS_1_R")
	)
	(via
		(at 301.117 -92.075)
		(size 0.7112)
		(drill 0.3556)
		(layers "F.Cu" "B.Cu")
		(net "FLA_CS_1_R")
	)
	(segment
		(start 295.177464 -92.075)
		(end 294.654732 -92.597732)
		(width 0.1143)
		(layer "B.Cu")
		(net "FLA_CS_1_R")
	)
	(segment
		(start 324.98665 -85.59165)
		(end 308.418992 -85.59165)
		(width 0.1143)
		(layer "B.Cu")
		(net "FLA_CS_1_R")
	)
	(segment
		(start 308.418992 -85.59165)
		(end 301.935642 -92.075)
		(width 0.1143)
		(layer "B.Cu")
		(net "FLA_CS_1_R")
	)
	(segment
		(start 325.247 -85.852)
		(end 324.98665 -85.59165)
		(width 0.1143)
		(layer "B.Cu")
		(net "FLA_CS_1_R")
	)
	(segment
		(start 301.935642 -92.075)
		(end 301.117 -92.075)
		(width 0.1143)
		(layer "B.Cu")
		(net "FLA_CS_1_R")
	)
	(segment
		(start 301.117 -92.075)
		(end 295.177464 -92.075)
		(width 0.1143)
		(layer "B.Cu")
		(net "FLA_CS_1_R")
	)
	(segment
		(start 285.24454 -181.049422)
		(end 275.436838 -181.049422)
		(width 0.127)
		(layer "In2.Cu")
		(net "FLA_CS_1_R")
	)
	(segment
		(start 269.37716 -182.626)
		(end 269.1892 -182.81396)
		(width 0.127)
		(layer "In2.Cu")
		(net "FLA_CS_1_R")
	)
	(segment
		(start 275.436838 -181.049422)
		(end 273.86026 -182.626)
		(width 0.127)
		(layer "In2.Cu")
		(net "FLA_CS_1_R")
	)
	(segment
		(start 286.836358 -180.64734)
		(end 286.836358 -180.655722)
		(width 0.0889)
		(layer "In2.Cu")
		(net "FLA_CS_1_R")
	)
	(segment
		(start 286.836358 -180.655722)
		(end 286.442658 -181.049422)
		(width 0.0889)
		(layer "In2.Cu")
		(net "FLA_CS_1_R")
	)
	(segment
		(start 273.86026 -182.626)
		(end 269.37716 -182.626)
		(width 0.127)
		(layer "In2.Cu")
		(net "FLA_CS_1_R")
	)
	(segment
		(start 286.442658 -181.049422)
		(end 285.24454 -181.049422)
		(width 0.0889)
		(layer "In2.Cu")
		(net "FLA_CS_1_R")
	)
	(segment
		(start 277.114 -129.667)
		(end 275.717 -129.667)
		(width 0.127)
		(layer "In5.Cu")
		(net "FLA_CS_1_R")
	)
	(segment
		(start 294.625268 -92.583)
		(end 293.497 -92.583)
		(width 0.127)
		(layer "In5.Cu")
		(net "FLA_CS_1_R")
	)
	(segment
		(start 271.653 -149.86)
		(end 274.32 -152.527)
		(width 0.127)
		(layer "In5.Cu")
		(net "FLA_CS_1_R")
	)
	(segment
		(start 294.64 -92.597732)
		(end 294.625268 -92.583)
		(width 0.127)
		(layer "In5.Cu")
		(net "FLA_CS_1_R")
	)
	(segment
		(start 293.497 -92.583)
		(end 291.719 -94.361)
		(width 0.127)
		(layer "In5.Cu")
		(net "FLA_CS_1_R")
	)
	(segment
		(start 274.32 -152.527)
		(end 274.32 -163.03244)
		(width 0.127)
		(layer "In5.Cu")
		(net "FLA_CS_1_R")
	)
	(segment
		(start 294.654732 -92.597732)
		(end 294.64 -92.597732)
		(width 0.127)
		(layer "In5.Cu")
		(net "FLA_CS_1_R")
	)
	(segment
		(start 291.719 -115.062)
		(end 277.114 -129.667)
		(width 0.127)
		(layer "In5.Cu")
		(net "FLA_CS_1_R")
	)
	(segment
		(start 269.1892 -175.1711)
		(end 269.1892 -182.81396)
		(width 0.127)
		(layer "In5.Cu")
		(net "FLA_CS_1_R")
	)
	(segment
		(start 275.717 -129.667)
		(end 272.161 -133.223)
		(width 0.127)
		(layer "In5.Cu")
		(net "FLA_CS_1_R")
	)
	(segment
		(start 271.98574 -165.78072)
		(end 271.98574 -172.37456)
		(width 0.127)
		(layer "In5.Cu")
		(net "FLA_CS_1_R")
	)
	(segment
		(start 291.719 -94.361)
		(end 291.719 -115.062)
		(width 0.127)
		(layer "In5.Cu")
		(net "FLA_CS_1_R")
	)
	(segment
		(start 274.32 -163.03244)
		(end 272.2753 -165.07714)
		(width 0.127)
		(layer "In5.Cu")
		(net "FLA_CS_1_R")
	)
	(segment
		(start 271.98574 -172.37456)
		(end 269.1892 -175.1711)
		(width 0.127)
		(layer "In5.Cu")
		(net "FLA_CS_1_R")
	)
	(segment
		(start 272.2753 -165.49116)
		(end 271.98574 -165.78072)
		(width 0.127)
		(layer "In5.Cu")
		(net "FLA_CS_1_R")
	)
	(segment
		(start 272.161 -148.844)
		(end 271.653 -149.352)
		(width 0.127)
		(layer "In5.Cu")
		(net "FLA_CS_1_R")
	)
	(segment
		(start 272.161 -133.223)
		(end 272.161 -148.844)
		(width 0.127)
		(layer "In5.Cu")
		(net "FLA_CS_1_R")
	)
	(segment
		(start 272.2753 -165.07714)
		(end 272.2753 -165.49116)
		(width 0.127)
		(layer "In5.Cu")
		(net "FLA_CS_1_R")
	)
	(segment
		(start 271.653 -149.352)
		(end 271.653 -149.86)
		(width 0.127)
		(layer "In5.Cu")
		(net "FLA_CS_1_R")
	)
	(segment
		(start 239.014 -15.113)
		(end 239.9665 -15.113)
		(width 0.1143)
		(layer "F.Cu")
		(net "BMC_ENCLOSURE_LED_R")
	)
	(segment
		(start 236.7915 -15.113)
		(end 239.014 -15.113)
		(width 0.1143)
		(layer "F.Cu")
		(net "BMC_ENCLOSURE_LED_R")
	)
	(via
		(at 239.014 -15.113)
		(size 0.7112)
		(drill 0.3556)
		(layers "F.Cu" "B.Cu")
		(net "BMC_ENCLOSURE_LED_R")
	)
	(segment
		(start 293.634922 -170.640248)
		(end 293.239698 -170.245024)
		(width 0.1143)
		(layer "F.Cu")
		(net "BMC_RXCK_R")
	)
	(segment
		(start 294.513 -158.623)
		(end 293.719758 -159.416242)
		(width 0.1143)
		(layer "F.Cu")
		(net "BMC_RXCK_R")
	)
	(segment
		(start 294.513 -158.4325)
		(end 294.513 -158.623)
		(width 0.1143)
		(layer "F.Cu")
		(net "BMC_RXCK_R")
	)
	(via
		(at 293.719758 -159.416242)
		(size 0.5588)
		(drill 0.3048)
		(layers "F.Cu" "B.Cu")
		(net "BMC_RXCK_R")
	)
	(via
		(at 293.116 -165.735)
		(size 0.7112)
		(drill 0.3556)
		(layers "F.Cu" "B.Cu")
		(net "BMC_RXCK_R")
	)
	(via
		(at 293.239698 -170.245024)
		(size 0.508)
		(drill 0.254)
		(layers "F.Cu" "B.Cu")
		(net "BMC_RXCK_R")
	)
	(segment
		(start 292.891972 -169.11701)
		(end 292.835584 -169.173398)
		(width 0.1016)
		(layer "B.Cu")
		(net "BMC_RXCK_R")
	)
	(segment
		(start 292.94455 -167.381174)
		(end 293.1033 -167.539924)
		(width 0.1143)
		(layer "B.Cu")
		(net "BMC_RXCK_R")
	)
	(segment
		(start 293.116 -165.735)
		(end 292.94455 -165.90645)
		(width 0.1143)
		(layer "B.Cu")
		(net "BMC_RXCK_R")
	)
	(segment
		(start 293.719758 -159.416242)
		(end 293.820088 -159.516572)
		(width 0.1143)
		(layer "B.Cu")
		(net "BMC_RXCK_R")
	)
	(segment
		(start 293.820088 -161.093912)
		(end 293.32555 -161.58845)
		(width 0.1143)
		(layer "B.Cu")
		(net "BMC_RXCK_R")
	)
	(segment
		(start 293.370508 -163.46043)
		(end 293.370508 -164.36721)
		(width 0.1143)
		(layer "B.Cu")
		(net "BMC_RXCK_R")
	)
	(segment
		(start 293.1033 -168.905682)
		(end 292.891972 -169.11701)
		(width 0.1143)
		(layer "B.Cu")
		(net "BMC_RXCK_R")
	)
	(segment
		(start 293.1033 -167.539924)
		(end 293.1033 -168.905682)
		(width 0.1143)
		(layer "B.Cu")
		(net "BMC_RXCK_R")
	)
	(segment
		(start 293.420038 -165.430962)
		(end 293.116 -165.735)
		(width 0.1143)
		(layer "B.Cu")
		(net "BMC_RXCK_R")
	)
	(segment
		(start 292.94455 -165.90645)
		(end 292.94455 -167.381174)
		(width 0.1143)
		(layer "B.Cu")
		(net "BMC_RXCK_R")
	)
	(segment
		(start 293.820088 -159.516572)
		(end 293.820088 -161.093912)
		(width 0.1143)
		(layer "B.Cu")
		(net "BMC_RXCK_R")
	)
	(segment
		(start 293.32555 -161.58845)
		(end 293.32555 -163.3855)
		(width 0.1143)
		(layer "B.Cu")
		(net "BMC_RXCK_R")
	)
	(segment
		(start 293.370508 -164.36721)
		(end 293.4335 -164.438076)
		(width 0.1143)
		(layer "B.Cu")
		(net "BMC_RXCK_R")
	)
	(segment
		(start 293.32555 -163.3855)
		(end 293.370508 -163.46043)
		(width 0.1143)
		(layer "B.Cu")
		(net "BMC_RXCK_R")
	)
	(segment
		(start 292.835584 -169.84091)
		(end 293.239698 -170.245024)
		(width 0.1016)
		(layer "B.Cu")
		(net "BMC_RXCK_R")
	)
	(segment
		(start 293.4335 -164.438076)
		(end 293.4335 -165.202362)
		(width 0.1143)
		(layer "B.Cu")
		(net "BMC_RXCK_R")
	)
	(segment
		(start 293.4335 -165.202362)
		(end 293.420038 -165.430962)
		(width 0.1143)
		(layer "B.Cu")
		(net "BMC_RXCK_R")
	)
	(segment
		(start 292.835584 -169.173398)
		(end 292.835584 -169.84091)
		(width 0.1016)
		(layer "B.Cu")
		(net "BMC_RXCK_R")
	)
	(segment
		(start 326.992488 -76.581)
		(end 330.962 -76.581)
		(width 0.1143)
		(layer "F.Cu")
		(net "ROMD2_R_R")
	)
	(segment
		(start 333.4385 -80.772)
		(end 333.4385 -79.756)
		(width 0.1143)
		(layer "F.Cu")
		(net "ROMD2_R_R")
	)
	(segment
		(start 330.962 -76.581)
		(end 333.4385 -79.0575)
		(width 0.1143)
		(layer "F.Cu")
		(net "ROMD2_R_R")
	)
	(segment
		(start 333.4385 -79.0575)
		(end 333.4385 -79.756)
		(width 0.1143)
		(layer "F.Cu")
		(net "ROMD2_R_R")
	)
	(via
		(at 333.4385 -79.756)
		(size 0.5588)
		(drill 0.3048)
		(layers "F.Cu" "B.Cu")
		(net "ROMD2_R_R")
	)
	(segment
		(start 336.4865 -73.787)
		(end 336.296 -73.787)
		(width 0.1143)
		(layer "F.Cu")
		(net "ROMD0_R_R")
	)
	(segment
		(start 336.042 -74.041)
		(end 336.296 -73.787)
		(width 0.1143)
		(layer "F.Cu")
		(net "ROMD0_R_R")
	)
	(segment
		(start 333.977488 -74.041)
		(end 336.042 -74.041)
		(width 0.1143)
		(layer "F.Cu")
		(net "ROMD0_R_R")
	)
	(segment
		(start 337.1215 -74.422)
		(end 336.4865 -73.787)
		(width 0.1143)
		(layer "F.Cu")
		(net "ROMD0_R_R")
	)
	(via
		(at 336.296 -73.787)
		(size 0.5588)
		(drill 0.3048)
		(layers "F.Cu" "B.Cu")
		(net "ROMD0_R_R")
	)
	(segment
		(start 337.1215 -75.692)
		(end 336.8675 -75.946)
		(width 0.1143)
		(layer "F.Cu")
		(net "ROMD1_R_R")
	)
	(segment
		(start 336.8675 -75.946)
		(end 335.915 -75.946)
		(width 0.1143)
		(layer "F.Cu")
		(net "ROMD1_R_R")
	)
	(segment
		(start 335.28 -75.311)
		(end 335.915 -75.946)
		(width 0.1143)
		(layer "F.Cu")
		(net "ROMD1_R_R")
	)
	(segment
		(start 333.977488 -75.311)
		(end 335.28 -75.311)
		(width 0.1143)
		(layer "F.Cu")
		(net "ROMD1_R_R")
	)
	(via
		(at 335.915 -75.946)
		(size 0.5588)
		(drill 0.3048)
		(layers "F.Cu" "B.Cu")
		(net "ROMD1_R_R")
	)
	(segment
		(start 29.566616 -81.522062)
		(end 30.087062 -82.042508)
		(width 0.1143)
		(layer "F.Cu")
		(net "SAS_ACTIVITY_LED16")
	)
	(segment
		(start 31.345124 -83.173062)
		(end 31.345124 -84.009484)
		(width 0.1143)
		(layer "F.Cu")
		(net "SAS_ACTIVITY_LED16")
	)
	(segment
		(start 30.21457 -82.042508)
		(end 31.345124 -83.173062)
		(width 0.1143)
		(layer "F.Cu")
		(net "SAS_ACTIVITY_LED16")
	)
	(segment
		(start 114.84991 -88.76538)
		(end 114.934492 -88.76538)
		(width 0.1143)
		(layer "F.Cu")
		(net "SAS_ACTIVITY_LED16")
	)
	(segment
		(start 30.087062 -82.042508)
		(end 30.21457 -82.042508)
		(width 0.1143)
		(layer "F.Cu")
		(net "SAS_ACTIVITY_LED16")
	)
	(segment
		(start 114.934492 -88.76538)
		(end 115.350036 -88.349836)
		(width 0.1143)
		(layer "F.Cu")
		(net "SAS_ACTIVITY_LED16")
	)
	(via
		(at 31.345124 -83.173062)
		(size 0.7112)
		(drill 0.3556)
		(layers "F.Cu" "B.Cu")
		(net "SAS_ACTIVITY_LED16")
	)
	(via
		(at 54.991 -131.064)
		(size 0.5588)
		(drill 0.3048)
		(layers "F.Cu" "B.Cu")
		(net "SAS_ACTIVITY_LED16")
	)
	(via
		(at 31.218124 -84.316062)
		(size 0.5588)
		(drill 0.3048)
		(layers "F.Cu" "B.Cu")
		(net "SAS_ACTIVITY_LED16")
	)
	(via
		(at 114.84991 -88.76538)
		(size 0.508)
		(drill 0.254)
		(layers "F.Cu" "B.Cu")
		(net "SAS_ACTIVITY_LED16")
	)
	(arc
		(start 31.345124 -84.009484)
		(mid 31.31212 -84.175407)
		(end 31.218124 -84.316062)
		(width 0.1143)
		(layer "F.Cu")
		(net "SAS_ACTIVITY_LED16")
	)
	(segment
		(start 31.218124 -84.316062)
		(end 30.714696 -84.81949)
		(width 0.127)
		(layer "In2.Cu")
		(net "SAS_ACTIVITY_LED16")
	)
	(segment
		(start 51.2445 -115.2525)
		(end 51.2445 -119.66956)
		(width 0.127)
		(layer "In2.Cu")
		(net "SAS_ACTIVITY_LED16")
	)
	(segment
		(start 54.991 -123.41606)
		(end 54.991 -131.064)
		(width 0.127)
		(layer "In2.Cu")
		(net "SAS_ACTIVITY_LED16")
	)
	(segment
		(start 30.714696 -84.81949)
		(end 30.714696 -94.722696)
		(width 0.127)
		(layer "In2.Cu")
		(net "SAS_ACTIVITY_LED16")
	)
	(segment
		(start 30.714696 -94.722696)
		(end 51.2445 -115.2525)
		(width 0.127)
		(layer "In2.Cu")
		(net "SAS_ACTIVITY_LED16")
	)
	(segment
		(start 51.2445 -119.66956)
		(end 54.991 -123.41606)
		(width 0.127)
		(layer "In2.Cu")
		(net "SAS_ACTIVITY_LED16")
	)
	(segment
		(start 98.171 -94.234)
		(end 99.06 -93.345)
		(width 0.127)
		(layer "In5.Cu")
		(net "SAS_ACTIVITY_LED16")
	)
	(segment
		(start 99.06 -92.964)
		(end 99.822 -92.202)
		(width 0.127)
		(layer "In5.Cu")
		(net "SAS_ACTIVITY_LED16")
	)
	(segment
		(start 67.564 -118.999)
		(end 79.883 -106.68)
		(width 0.127)
		(layer "In5.Cu")
		(net "SAS_ACTIVITY_LED16")
	)
	(segment
		(start 61.722 -125.857)
		(end 67.564 -120.015)
		(width 0.127)
		(layer "In5.Cu")
		(net "SAS_ACTIVITY_LED16")
	)
	(segment
		(start 92.583 -94.234)
		(end 98.171 -94.234)
		(width 0.127)
		(layer "In5.Cu")
		(net "SAS_ACTIVITY_LED16")
	)
	(segment
		(start 100.33 -92.202)
		(end 102.235 -90.297)
		(width 0.127)
		(layer "In5.Cu")
		(net "SAS_ACTIVITY_LED16")
	)
	(segment
		(start 99.06 -93.345)
		(end 99.06 -92.964)
		(width 0.127)
		(layer "In5.Cu")
		(net "SAS_ACTIVITY_LED16")
	)
	(segment
		(start 102.235 -90.297)
		(end 109.22 -90.297)
		(width 0.127)
		(layer "In5.Cu")
		(net "SAS_ACTIVITY_LED16")
	)
	(segment
		(start 60.452 -125.857)
		(end 61.722 -125.857)
		(width 0.127)
		(layer "In5.Cu")
		(net "SAS_ACTIVITY_LED16")
	)
	(segment
		(start 91.821 -99.822)
		(end 91.821 -94.996)
		(width 0.127)
		(layer "In5.Cu")
		(net "SAS_ACTIVITY_LED16")
	)
	(segment
		(start 67.564 -120.015)
		(end 67.564 -118.999)
		(width 0.127)
		(layer "In5.Cu")
		(net "SAS_ACTIVITY_LED16")
	)
	(segment
		(start 91.821 -94.996)
		(end 92.583 -94.234)
		(width 0.127)
		(layer "In5.Cu")
		(net "SAS_ACTIVITY_LED16")
	)
	(segment
		(start 109.22 -90.297)
		(end 110.236 -89.281)
		(width 0.127)
		(layer "In5.Cu")
		(net "SAS_ACTIVITY_LED16")
	)
	(segment
		(start 114.68862 -88.76538)
		(end 114.84991 -88.76538)
		(width 0.127)
		(layer "In5.Cu")
		(net "SAS_ACTIVITY_LED16")
	)
	(segment
		(start 54.991 -131.064)
		(end 55.245 -131.064)
		(width 0.127)
		(layer "In5.Cu")
		(net "SAS_ACTIVITY_LED16")
	)
	(segment
		(start 79.883 -106.68)
		(end 85.598 -106.68)
		(width 0.127)
		(layer "In5.Cu")
		(net "SAS_ACTIVITY_LED16")
	)
	(segment
		(start 55.245 -131.064)
		(end 60.452 -125.857)
		(width 0.127)
		(layer "In5.Cu")
		(net "SAS_ACTIVITY_LED16")
	)
	(segment
		(start 89.789 -101.854)
		(end 91.821 -99.822)
		(width 0.127)
		(layer "In5.Cu")
		(net "SAS_ACTIVITY_LED16")
	)
	(segment
		(start 99.822 -92.202)
		(end 100.33 -92.202)
		(width 0.127)
		(layer "In5.Cu")
		(net "SAS_ACTIVITY_LED16")
	)
	(segment
		(start 85.598 -106.68)
		(end 89.789 -102.489)
		(width 0.127)
		(layer "In5.Cu")
		(net "SAS_ACTIVITY_LED16")
	)
	(segment
		(start 110.236 -89.281)
		(end 114.173 -89.281)
		(width 0.127)
		(layer "In5.Cu")
		(net "SAS_ACTIVITY_LED16")
	)
	(segment
		(start 89.789 -102.489)
		(end 89.789 -101.854)
		(width 0.127)
		(layer "In5.Cu")
		(net "SAS_ACTIVITY_LED16")
	)
	(segment
		(start 114.173 -89.281)
		(end 114.68862 -88.76538)
		(width 0.127)
		(layer "In5.Cu")
		(net "SAS_ACTIVITY_LED16")
	)
	(segment
		(start 111.892842 -82.936842)
		(end 112.305846 -83.349846)
		(width 0.1143)
		(layer "F.Cu")
		(net "SAS_STATUS_LED17")
	)
	(segment
		(start 111.892842 -82.047842)
		(end 111.892842 -82.936842)
		(width 0.1143)
		(layer "F.Cu")
		(net "SAS_STATUS_LED17")
	)
	(segment
		(start 33.401 -82.296)
		(end 33.528 -82.296)
		(width 0.1143)
		(layer "F.Cu")
		(net "SAS_STATUS_LED17")
	)
	(segment
		(start 112.305846 -83.349846)
		(end 112.349788 -83.349846)
		(width 0.1143)
		(layer "F.Cu")
		(net "SAS_STATUS_LED17")
	)
	(segment
		(start 34.6075 -81.2165)
		(end 35.052 -81.2165)
		(width 0.1143)
		(layer "F.Cu")
		(net "SAS_STATUS_LED17")
	)
	(segment
		(start 33.528 -82.296)
		(end 34.6075 -81.2165)
		(width 0.1143)
		(layer "F.Cu")
		(net "SAS_STATUS_LED17")
	)
	(segment
		(start 109.093 -78.994)
		(end 109.22 -78.994)
		(width 0.1143)
		(layer "F.Cu")
		(net "SAS_STATUS_LED17")
	)
	(segment
		(start 111.633 -81.407)
		(end 111.633 -81.788)
		(width 0.1143)
		(layer "F.Cu")
		(net "SAS_STATUS_LED17")
	)
	(segment
		(start 109.22 -78.994)
		(end 111.633 -81.407)
		(width 0.1143)
		(layer "F.Cu")
		(net "SAS_STATUS_LED17")
	)
	(segment
		(start 111.633 -81.788)
		(end 111.892842 -82.047842)
		(width 0.1143)
		(layer "F.Cu")
		(net "SAS_STATUS_LED17")
	)
	(via
		(at 33.401 -82.296)
		(size 0.5588)
		(drill 0.3048)
		(layers "F.Cu" "B.Cu")
		(net "SAS_STATUS_LED17")
	)
	(via
		(at 109.093 -78.105)
		(size 0.7112)
		(drill 0.3556)
		(layers "F.Cu" "B.Cu")
		(net "SAS_STATUS_LED17")
	)
	(via
		(at 109.093 -78.994)
		(size 0.5588)
		(drill 0.3048)
		(layers "F.Cu" "B.Cu")
		(net "SAS_STATUS_LED17")
	)
	(segment
		(start 109.093 -78.105)
		(end 109.093 -78.994)
		(width 0.1143)
		(layer "B.Cu")
		(net "SAS_STATUS_LED17")
	)
	(segment
		(start 88.361266 -84.405978)
		(end 88.361266 -85.694266)
		(width 0.127)
		(layer "In2.Cu")
		(net "SAS_STATUS_LED17")
	)
	(segment
		(start 47.9933 -91.8083)
		(end 42.672 -86.487)
		(width 0.127)
		(layer "In2.Cu")
		(net "SAS_STATUS_LED17")
	)
	(segment
		(start 109.093 -78.994)
		(end 108.966 -79.121)
		(width 0.127)
		(layer "In2.Cu")
		(net "SAS_STATUS_LED17")
	)
	(segment
		(start 108.966 -79.121)
		(end 94.488 -79.121)
		(width 0.127)
		(layer "In2.Cu")
		(net "SAS_STATUS_LED17")
	)
	(segment
		(start 94.488 -79.121)
		(end 89.916 -83.693)
		(width 0.127)
		(layer "In2.Cu")
		(net "SAS_STATUS_LED17")
	)
	(segment
		(start 88.361266 -85.694266)
		(end 87.060532 -86.995)
		(width 0.127)
		(layer "In2.Cu")
		(net "SAS_STATUS_LED17")
	)
	(segment
		(start 89.916 -83.693)
		(end 89.074244 -83.693)
		(width 0.127)
		(layer "In2.Cu")
		(net "SAS_STATUS_LED17")
	)
	(segment
		(start 89.074244 -83.693)
		(end 88.361266 -84.405978)
		(width 0.127)
		(layer "In2.Cu")
		(net "SAS_STATUS_LED17")
	)
	(segment
		(start 37.592 -86.487)
		(end 33.401 -82.296)
		(width 0.127)
		(layer "In2.Cu")
		(net "SAS_STATUS_LED17")
	)
	(segment
		(start 72.3519 -91.8083)
		(end 47.9933 -91.8083)
		(width 0.127)
		(layer "In2.Cu")
		(net "SAS_STATUS_LED17")
	)
	(segment
		(start 42.672 -86.487)
		(end 37.592 -86.487)
		(width 0.127)
		(layer "In2.Cu")
		(net "SAS_STATUS_LED17")
	)
	(segment
		(start 77.1652 -86.995)
		(end 72.3519 -91.8083)
		(width 0.127)
		(layer "In2.Cu")
		(net "SAS_STATUS_LED17")
	)
	(segment
		(start 87.060532 -86.995)
		(end 77.1652 -86.995)
		(width 0.127)
		(layer "In2.Cu")
		(net "SAS_STATUS_LED17")
	)
	(segment
		(start 34.382456 -72.972168)
		(end 34.382456 -73.70826)
		(width 0.1778)
		(layer "F.Cu")
		(net "INTA_LED_BLUE_C")
	)
	(segment
		(start 36.04006 -70.286118)
		(end 36.04006 -68.460112)
		(width 0.1778)
		(layer "F.Cu")
		(net "INTA_LED_BLUE_C")
	)
	(segment
		(start 35.1155 -72.009)
		(end 34.382456 -72.972168)
		(width 0.1778)
		(layer "F.Cu")
		(net "INTA_LED_BLUE_C")
	)
	(segment
		(start 34.382456 -74.844402)
		(end 35.354514 -75.81646)
		(width 0.1778)
		(layer "F.Cu")
		(net "INTA_LED_BLUE_C")
	)
	(segment
		(start 35.1155 -71.210678)
		(end 36.04006 -70.286118)
		(width 0.1778)
		(layer "F.Cu")
		(net "INTA_LED_BLUE_C")
	)
	(segment
		(start 35.354514 -75.81646)
		(end 35.354514 -75.842622)
		(width 0.1778)
		(layer "F.Cu")
		(net "INTA_LED_BLUE_C")
	)
	(segment
		(start 34.382456 -73.70826)
		(end 34.382456 -74.844402)
		(width 0.1778)
		(layer "F.Cu")
		(net "INTA_LED_BLUE_C")
	)
	(segment
		(start 35.1155 -72.009)
		(end 35.1155 -71.210678)
		(width 0.1778)
		(layer "F.Cu")
		(net "INTA_LED_BLUE_C")
	)
	(segment
		(start 29.884116 -74.537062)
		(end 29.884116 -76.632562)
		(width 0.1778)
		(layer "F.Cu")
		(net "INTA_LED_RED_C")
	)
	(segment
		(start 31.217616 -76.632562)
		(end 29.884116 -76.632562)
		(width 0.1778)
		(layer "F.Cu")
		(net "INTA_LED_RED_C")
	)
	(segment
		(start 30.96006 -68.460112)
		(end 30.96006 -73.461118)
		(width 0.1778)
		(layer "F.Cu")
		(net "INTA_LED_RED_C")
	)
	(segment
		(start 30.96006 -73.461118)
		(end 29.884116 -74.537062)
		(width 0.1778)
		(layer "F.Cu")
		(net "INTA_LED_RED_C")
	)
	(segment
		(start 32.424116 -77.204062)
		(end 31.789116 -77.204062)
		(width 0.1778)
		(layer "F.Cu")
		(net "INTA_LED_RED_C")
	)
	(segment
		(start 31.789116 -77.204062)
		(end 31.217616 -76.632562)
		(width 0.1778)
		(layer "F.Cu")
		(net "INTA_LED_RED_C")
	)
	(segment
		(start 33.50006 -68.460112)
		(end 33.186116 -68.774056)
		(width 0.1778)
		(layer "F.Cu")
		(net "INTA_LED_GND")
	)
	(segment
		(start 33.186116 -68.774056)
		(end 33.186116 -77.648562)
		(width 0.1778)
		(layer "F.Cu")
		(net "INTA_LED_GND")
	)
	(segment
		(start 33.186116 -77.648562)
		(end 32.424116 -78.410562)
		(width 0.1778)
		(layer "F.Cu")
		(net "INTA_LED_GND")
	)
	(segment
		(start 30.868366 -79.998062)
		(end 30.868366 -78.537562)
		(width 0.1778)
		(layer "F.Cu")
		(net "INTA_LED_RED_B")
	)
	(segment
		(start 30.455616 -81.522062)
		(end 30.455616 -80.379062)
		(width 0.1778)
		(layer "F.Cu")
		(net "INTA_LED_RED_B")
	)
	(segment
		(start 30.455616 -80.379062)
		(end 30.487366 -80.379062)
		(width 0.1778)
		(layer "F.Cu")
		(net "INTA_LED_RED_B")
	)
	(segment
		(start 30.487366 -80.379062)
		(end 30.868366 -79.998062)
		(width 0.1778)
		(layer "F.Cu")
		(net "INTA_LED_RED_B")
	)
	(segment
		(start 31.408116 -81.522062)
		(end 30.455616 -81.522062)
		(width 0.1778)
		(layer "F.Cu")
		(net "INTA_LED_RED_B")
	)
	(via
		(at 31.408116 -81.522062)
		(size 0.5588)
		(drill 0.3048)
		(layers "F.Cu" "B.Cu")
		(net "INTA_LED_RED_B")
	)
	(segment
		(start 36.338764 -78.088236)
		(end 36.338764 -77.747622)
		(width 0.1778)
		(layer "F.Cu")
		(net "INTA_LED_BLUE_B")
	)
	(segment
		(start 35.4965 -79.248)
		(end 35.4965 -78.9305)
		(width 0.1778)
		(layer "F.Cu")
		(net "INTA_LED_BLUE_B")
	)
	(segment
		(start 35.4965 -78.9305)
		(end 36.338764 -78.088236)
		(width 0.1778)
		(layer "F.Cu")
		(net "INTA_LED_BLUE_B")
	)
	(segment
		(start 35.037776 -80.341724)
		(end 35.052 -80.3275)
		(width 0.1778)
		(layer "F.Cu")
		(net "INTA_LED_BLUE_B")
	)
	(segment
		(start 33.559242 -80.994758)
		(end 34.212276 -80.341724)
		(width 0.1778)
		(layer "F.Cu")
		(net "INTA_LED_BLUE_B")
	)
	(segment
		(start 34.212276 -80.341724)
		(end 35.037776 -80.341724)
		(width 0.1778)
		(layer "F.Cu")
		(net "INTA_LED_BLUE_B")
	)
	(segment
		(start 35.052 -80.3275)
		(end 35.4965 -79.883)
		(width 0.1778)
		(layer "F.Cu")
		(net "INTA_LED_BLUE_B")
	)
	(segment
		(start 35.4965 -79.883)
		(end 35.4965 -79.248)
		(width 0.1778)
		(layer "F.Cu")
		(net "INTA_LED_BLUE_B")
	)
	(via
		(at 33.559242 -80.994758)
		(size 0.5588)
		(drill 0.3048)
		(layers "F.Cu" "B.Cu")
		(net "INTA_LED_BLUE_B")
	)
	(segment
		(start 48.199802 -80.816958)
		(end 48.33493 -80.952086)
		(width 0.1143)
		(layer "F.Cu")
		(net "INT_CONN_A_SB2")
	)
	(segment
		(start 48.199802 -79.590138)
		(end 48.199802 -80.816958)
		(width 0.1143)
		(layer "F.Cu")
		(net "INT_CONN_A_SB2")
	)
	(via
		(at 48.33493 -80.952086)
		(size 0.5588)
		(drill 0.3048)
		(layers "F.Cu" "B.Cu")
		(net "INT_CONN_A_SB2")
	)
	(segment
		(start 48.58893 -78.793086)
		(end 48.58893 -80.698086)
		(width 0.1143)
		(layer "B.Cu")
		(net "INT_CONN_A_SB2")
	)
	(segment
		(start 48.58893 -80.698086)
		(end 48.33493 -80.952086)
		(width 0.1143)
		(layer "B.Cu")
		(net "INT_CONN_A_SB2")
	)
	(segment
		(start 48.20793 -78.412086)
		(end 48.58893 -78.793086)
		(width 0.1143)
		(layer "B.Cu")
		(net "INT_CONN_A_SB2")
	)
	(segment
		(start 47.399956 -79.590138)
		(end 47.399956 -81.033112)
		(width 0.1143)
		(layer "F.Cu")
		(net "INT_CONN_A_SB1")
	)
	(via
		(at 47.399956 -81.033112)
		(size 0.5588)
		(drill 0.3048)
		(layers "F.Cu" "B.Cu")
		(net "INT_CONN_A_SB1")
	)
	(segment
		(start 47.399956 -80.49006)
		(end 47.399956 -81.033112)
		(width 0.1143)
		(layer "B.Cu")
		(net "INT_CONN_A_SB1")
	)
	(segment
		(start 47.82693 -80.063086)
		(end 47.399956 -80.49006)
		(width 0.1143)
		(layer "B.Cu")
		(net "INT_CONN_A_SB1")
	)
	(segment
		(start 48.599852 -77.08011)
		(end 48.599852 -74.994008)
		(width 0.1143)
		(layer "F.Cu")
		(net "INT_CONN_A_SB4")
	)
	(segment
		(start 48.599852 -74.994008)
		(end 48.58893 -74.983086)
		(width 0.1143)
		(layer "F.Cu")
		(net "INT_CONN_A_SB4")
	)
	(via
		(at 48.58893 -74.983086)
		(size 0.5588)
		(drill 0.3048)
		(layers "F.Cu" "B.Cu")
		(net "INT_CONN_A_SB4")
	)
	(segment
		(start 48.71593 -77.269086)
		(end 48.71593 -75.110086)
		(width 0.1143)
		(layer "B.Cu")
		(net "INT_CONN_A_SB4")
	)
	(segment
		(start 49.60493 -78.158086)
		(end 48.71593 -77.269086)
		(width 0.1143)
		(layer "B.Cu")
		(net "INT_CONN_A_SB4")
	)
	(segment
		(start 48.71593 -75.110086)
		(end 48.58893 -74.983086)
		(width 0.1143)
		(layer "B.Cu")
		(net "INT_CONN_A_SB4")
	)
	(segment
		(start 48.999902 -79.590138)
		(end 48.999902 -81.684114)
		(width 0.1143)
		(layer "F.Cu")
		(net "INT_CONN_A_SB6")
	)
	(segment
		(start 48.999902 -81.684114)
		(end 48.96993 -81.714086)
		(width 0.1143)
		(layer "F.Cu")
		(net "INT_CONN_A_SB6")
	)
	(via
		(at 48.96993 -81.714086)
		(size 0.5588)
		(drill 0.3048)
		(layers "F.Cu" "B.Cu")
		(net "INT_CONN_A_SB6")
	)
	(segment
		(start 48.96993 -80.952086)
		(end 48.96993 -81.714086)
		(width 0.1143)
		(layer "B.Cu")
		(net "INT_CONN_A_SB6")
	)
	(segment
		(start 49.73193 -80.190086)
		(end 48.96993 -80.952086)
		(width 0.1143)
		(layer "B.Cu")
		(net "INT_CONN_A_SB6")
	)
	(segment
		(start 49.73193 -79.682086)
		(end 49.73193 -80.190086)
		(width 0.1143)
		(layer "B.Cu")
		(net "INT_CONN_A_SB6")
	)
	(segment
		(start 46.999906 -77.08011)
		(end 46.999906 -74.983086)
		(width 0.1143)
		(layer "F.Cu")
		(net "INT_CONN_A_SB7")
	)
	(via
		(at 46.999906 -74.983086)
		(size 0.5588)
		(drill 0.3048)
		(layers "F.Cu" "B.Cu")
		(net "INT_CONN_A_SB7")
	)
	(segment
		(start 46.999906 -77.46111)
		(end 46.999906 -74.983086)
		(width 0.1143)
		(layer "B.Cu")
		(net "INT_CONN_A_SB7")
	)
	(segment
		(start 46.81093 -77.650086)
		(end 46.999906 -77.46111)
		(width 0.1143)
		(layer "B.Cu")
		(net "INT_CONN_A_SB7")
	)
	(segment
		(start 46.599856 -79.590138)
		(end 46.599856 -81.630012)
		(width 0.1143)
		(layer "F.Cu")
		(net "INT_CONN_A_SB0")
	)
	(segment
		(start 46.599856 -81.630012)
		(end 46.81093 -81.841086)
		(width 0.1143)
		(layer "F.Cu")
		(net "INT_CONN_A_SB0")
	)
	(via
		(at 46.81093 -81.841086)
		(size 0.5588)
		(drill 0.3048)
		(layers "F.Cu" "B.Cu")
		(net "INT_CONN_A_SB0")
	)
	(segment
		(start 46.81093 -79.301086)
		(end 46.81093 -81.841086)
		(width 0.1143)
		(layer "B.Cu")
		(net "INT_CONN_A_SB0")
	)
	(segment
		(start 46.68393 -79.174086)
		(end 46.81093 -79.301086)
		(width 0.1143)
		(layer "B.Cu")
		(net "INT_CONN_A_SB0")
	)
	(segment
		(start 49.399952 -75.794108)
		(end 49.235614 -75.62977)
		(width 0.1143)
		(layer "F.Cu")
		(net "INT_CONN_A_SB5")
	)
	(segment
		(start 49.399952 -77.08011)
		(end 49.399952 -75.794108)
		(width 0.1143)
		(layer "F.Cu")
		(net "INT_CONN_A_SB5")
	)
	(via
		(at 49.235614 -75.62977)
		(size 0.5588)
		(drill 0.3048)
		(layers "F.Cu" "B.Cu")
		(net "INT_CONN_A_SB5")
	)
	(segment
		(start 49.60493 -76.634086)
		(end 49.47793 -75.872086)
		(width 0.1143)
		(layer "B.Cu")
		(net "INT_CONN_A_SB5")
	)
	(segment
		(start 49.47793 -75.872086)
		(end 49.235614 -75.62977)
		(width 0.1143)
		(layer "B.Cu")
		(net "INT_CONN_A_SB5")
	)
	(segment
		(start 47.800006 -77.08011)
		(end 47.800006 -75.51801)
		(width 0.1143)
		(layer "F.Cu")
		(net "INT_CONN_A_SB3")
	)
	(segment
		(start 47.800006 -75.51801)
		(end 47.82693 -75.491086)
		(width 0.1143)
		(layer "F.Cu")
		(net "INT_CONN_A_SB3")
	)
	(via
		(at 47.82693 -75.491086)
		(size 0.5588)
		(drill 0.3048)
		(layers "F.Cu" "B.Cu")
		(net "INT_CONN_A_SB3")
	)
	(segment
		(start 47.82693 -76.507086)
		(end 47.82693 -75.491086)
		(width 0.1143)
		(layer "B.Cu")
		(net "INT_CONN_A_SB3")
	)
	(segment
		(start 298.43476 -175.440086)
		(end 298.039536 -175.83531)
		(width 0.1143)
		(layer "F.Cu")
		(net "ADC0_12V_BMC")
	)
	(via
		(at 313.563 -176.657)
		(size 0.7112)
		(drill 0.3556)
		(layers "F.Cu" "B.Cu")
		(net "ADC0_12V_BMC")
	)
	(via
		(at 298.039536 -175.83531)
		(size 0.508)
		(drill 0.254)
		(layers "F.Cu" "B.Cu")
		(net "ADC0_12V_BMC")
	)
	(segment
		(start 300.257464 -174.634144)
		(end 299.240702 -174.634144)
		(width 0.0889)
		(layer "B.Cu")
		(net "ADC0_12V_BMC")
	)
	(segment
		(start 312.678826 -176.657)
		(end 310.303926 -174.2821)
		(width 0.1143)
		(layer "B.Cu")
		(net "ADC0_12V_BMC")
	)
	(segment
		(start 299.240702 -174.634144)
		(end 298.039536 -175.83531)
		(width 0.0889)
		(layer "B.Cu")
		(net "ADC0_12V_BMC")
	)
	(segment
		(start 300.261528 -174.638208)
		(end 300.257464 -174.634144)
		(width 0.0889)
		(layer "B.Cu")
		(net "ADC0_12V_BMC")
	)
	(segment
		(start 313.563 -176.657)
		(end 312.678826 -176.657)
		(width 0.1143)
		(layer "B.Cu")
		(net "ADC0_12V_BMC")
	)
	(segment
		(start 301.738792 -174.638208)
		(end 300.261528 -174.638208)
		(width 0.0889)
		(layer "B.Cu")
		(net "ADC0_12V_BMC")
	)
	(segment
		(start 310.303926 -174.2821)
		(end 302.0949 -174.2821)
		(width 0.1143)
		(layer "B.Cu")
		(net "ADC0_12V_BMC")
	)
	(segment
		(start 313.563 -176.657)
		(end 317.5635 -176.657)
		(width 0.1143)
		(layer "B.Cu")
		(net "ADC0_12V_BMC")
	)
	(segment
		(start 302.0949 -174.2821)
		(end 301.738792 -174.638208)
		(width 0.1143)
		(layer "B.Cu")
		(net "ADC0_12V_BMC")
	)
	(segment
		(start 331.969872 -229.108508)
		(end 331.969872 -228.219)
		(width 0.127)
		(layer "F.Cu")
		(net "12V_SENSE")
	)
	(segment
		(start 332.096872 -232.037636)
		(end 332.096872 -229.235508)
		(width 0.127)
		(layer "F.Cu")
		(net "12V_SENSE")
	)
	(segment
		(start 331.596492 -227.84562)
		(end 331.969872 -228.219)
		(width 0.127)
		(layer "F.Cu")
		(net "12V_SENSE")
	)
	(segment
		(start 332.096872 -229.235508)
		(end 331.969872 -229.108508)
		(width 0.127)
		(layer "F.Cu")
		(net "12V_SENSE")
	)
	(segment
		(start 331.596492 -226.297236)
		(end 331.596492 -227.84562)
		(width 0.127)
		(layer "F.Cu")
		(net "12V_SENSE")
	)
	(via
		(at 331.969872 -228.219)
		(size 0.7112)
		(drill 0.3556)
		(layers "F.Cu" "B.Cu")
		(net "12V_SENSE")
	)
	(segment
		(start 297.970702 -183.035702)
		(end 298.030392 -183.035702)
		(width 0.1143)
		(layer "F.Cu")
		(net "TP_BMC0_TACH8")
	)
	(segment
		(start 297.634914 -182.699914)
		(end 297.970702 -183.035702)
		(width 0.1143)
		(layer "F.Cu")
		(net "TP_BMC0_TACH8")
	)
	(segment
		(start 297.634914 -182.640224)
		(end 297.634914 -182.699914)
		(width 0.1143)
		(layer "F.Cu")
		(net "TP_BMC0_TACH8")
	)
	(via
		(at 298.030392 -183.035702)
		(size 0.508)
		(drill 0.254)
		(layers "F.Cu" "B.Cu")
		(net "TP_BMC0_TACH8")
	)
	(segment
		(start 300.863 -185.547)
		(end 300.101 -185.547)
		(width 0.1143)
		(layer "B.Cu")
		(net "TP_BMC0_TACH8")
	)
	(segment
		(start 300.101 -185.547)
		(end 298.030392 -183.476392)
		(width 0.1143)
		(layer "B.Cu")
		(net "TP_BMC0_TACH8")
	)
	(segment
		(start 298.030392 -183.476392)
		(end 298.030392 -183.035702)
		(width 0.1143)
		(layer "B.Cu")
		(net "TP_BMC0_TACH8")
	)
	(segment
		(start 334.11795 -177.74285)
		(end 332.0161 -175.641)
		(width 0.1143)
		(layer "F.Cu")
		(net "ADC_12V")
	)
	(segment
		(start 332.72095 -234.54995)
		(end 334.372966 -234.54995)
		(width 0.1143)
		(layer "F.Cu")
		(net "ADC_12V")
	)
	(segment
		(start 334.11795 -190.48095)
		(end 334.11795 -177.74285)
		(width 0.1143)
		(layer "F.Cu")
		(net "ADC_12V")
	)
	(segment
		(start 334.372966 -234.54995)
		(end 337.2993 -231.623616)
		(width 0.1143)
		(layer "F.Cu")
		(net "ADC_12V")
	)
	(segment
		(start 332.096872 -232.926636)
		(end 332.096872 -233.925872)
		(width 0.1143)
		(layer "F.Cu")
		(net "ADC_12V")
	)
	(segment
		(start 337.2993 -193.6623)
		(end 334.11795 -190.48095)
		(width 0.1143)
		(layer "F.Cu")
		(net "ADC_12V")
	)
	(segment
		(start 337.2993 -231.623616)
		(end 337.2993 -193.6623)
		(width 0.1143)
		(layer "F.Cu")
		(net "ADC_12V")
	)
	(segment
		(start 332.096872 -233.925872)
		(end 332.72095 -234.54995)
		(width 0.1143)
		(layer "F.Cu")
		(net "ADC_12V")
	)
	(via
		(at 329.6285 -175.6029)
		(size 0.7112)
		(drill 0.3556)
		(layers "F.Cu" "B.Cu")
		(net "ADC_12V")
	)
	(via
		(at 332.0161 -175.641)
		(size 0.508)
		(drill 0.254)
		(layers "F.Cu" "B.Cu")
		(net "ADC_12V")
	)
	(segment
		(start 325.374 -174.5615)
		(end 325.4375 -174.5615)
		(width 0.1143)
		(layer "B.Cu")
		(net "ADC_12V")
	)
	(segment
		(start 322.547488 -174.530512)
		(end 320.421 -176.657)
		(width 0.1143)
		(layer "B.Cu")
		(net "ADC_12V")
	)
	(segment
		(start 329.6285 -175.6029)
		(end 331.978 -175.6029)
		(width 0.1143)
		(layer "B.Cu")
		(net "ADC_12V")
	)
	(segment
		(start 324.358 -174.5615)
		(end 325.374 -174.5615)
		(width 0.1143)
		(layer "B.Cu")
		(net "ADC_12V")
	)
	(segment
		(start 325.63435 -174.75835)
		(end 325.66102 -174.75835)
		(width 0.1143)
		(layer "B.Cu")
		(net "ADC_12V")
	)
	(segment
		(start 320.421 -176.657)
		(end 318.4525 -176.657)
		(width 0.1143)
		(layer "B.Cu")
		(net "ADC_12V")
	)
	(segment
		(start 323.401944 -174.530512)
		(end 322.547488 -174.530512)
		(width 0.1143)
		(layer "B.Cu")
		(net "ADC_12V")
	)
	(segment
		(start 325.66102 -174.75835)
		(end 326.06615 -175.16348)
		(width 0.1143)
		(layer "B.Cu")
		(net "ADC_12V")
	)
	(segment
		(start 324.358 -174.5615)
		(end 324.327012 -174.530512)
		(width 0.1143)
		(layer "B.Cu")
		(net "ADC_12V")
	)
	(segment
		(start 325.4375 -174.5615)
		(end 325.63435 -174.75835)
		(width 0.1143)
		(layer "B.Cu")
		(net "ADC_12V")
	)
	(segment
		(start 324.327012 -174.530512)
		(end 323.401944 -174.530512)
		(width 0.1143)
		(layer "B.Cu")
		(net "ADC_12V")
	)
	(segment
		(start 326.06615 -175.19015)
		(end 326.4789 -175.6029)
		(width 0.1143)
		(layer "B.Cu")
		(net "ADC_12V")
	)
	(segment
		(start 326.4789 -175.6029)
		(end 329.6285 -175.6029)
		(width 0.1143)
		(layer "B.Cu")
		(net "ADC_12V")
	)
	(segment
		(start 331.978 -175.6029)
		(end 332.0161 -175.641)
		(width 0.1143)
		(layer "B.Cu")
		(net "ADC_12V")
	)
	(segment
		(start 326.06615 -175.16348)
		(end 326.06615 -175.19015)
		(width 0.1143)
		(layer "B.Cu")
		(net "ADC_12V")
	)
	(segment
		(start 85.6742 -241.173)
		(end 86.1822 -241.173)
		(width 0.1143)
		(layer "F.Cu")
		(net "PCIE_MATED#_LED_CD")
	)
	(segment
		(start 87.3125 -239.3442)
		(end 87.3125 -239.965992)
		(width 0.1143)
		(layer "F.Cu")
		(net "PCIE_MATED#_LED_CD")
	)
	(segment
		(start 99.568 -241.7445)
		(end 100.5205 -240.792)
		(width 0.1143)
		(layer "F.Cu")
		(net "PCIE_MATED#_LED_CD")
	)
	(segment
		(start 100.5205 -240.792)
		(end 100.5205 -239.4712)
		(width 0.1143)
		(layer "F.Cu")
		(net "PCIE_MATED#_LED_CD")
	)
	(segment
		(start 98.7425 -241.7445)
		(end 99.568 -241.7445)
		(width 0.1143)
		(layer "F.Cu")
		(net "PCIE_MATED#_LED_CD")
	)
	(segment
		(start 86.4362 -240.842292)
		(end 86.4362 -240.919)
		(width 0.1143)
		(layer "F.Cu")
		(net "PCIE_MATED#_LED_CD")
	)
	(segment
		(start 87.3125 -239.965992)
		(end 86.4362 -240.842292)
		(width 0.1143)
		(layer "F.Cu")
		(net "PCIE_MATED#_LED_CD")
	)
	(segment
		(start 86.1822 -241.173)
		(end 86.4362 -240.919)
		(width 0.1143)
		(layer "F.Cu")
		(net "PCIE_MATED#_LED_CD")
	)
	(via
		(at 85.6742 -241.173)
		(size 0.508)
		(drill 0.254)
		(layers "F.Cu" "B.Cu")
		(net "PCIE_MATED#_LED_CD")
	)
	(via
		(at 98.7425 -241.7445)
		(size 0.508)
		(drill 0.254)
		(layers "F.Cu" "B.Cu")
		(net "PCIE_MATED#_LED_CD")
	)
	(via
		(at 86.4362 -240.919)
		(size 0.7112)
		(drill 0.3556)
		(layers "F.Cu" "B.Cu")
		(net "PCIE_MATED#_LED_CD")
	)
	(segment
		(start 86.3092 -241.808)
		(end 98.679 -241.808)
		(width 0.127)
		(layer "In2.Cu")
		(net "PCIE_MATED#_LED_CD")
	)
	(segment
		(start 85.6742 -241.173)
		(end 86.3092 -241.808)
		(width 0.127)
		(layer "In2.Cu")
		(net "PCIE_MATED#_LED_CD")
	)
	(segment
		(start 98.679 -241.808)
		(end 98.7425 -241.7445)
		(width 0.127)
		(layer "In2.Cu")
		(net "PCIE_MATED#_LED_CD")
	)
	(segment
		(start 314.251848 -69.200014)
		(end 313.125104 -69.200014)
		(width 0.1397)
		(layer "F.Cu")
		(net "PCIE_10G_REFCLK_2_N")
	)
	(segment
		(start 315.45149 -68.971414)
		(end 314.596272 -68.971414)
		(width 0.1397)
		(layer "F.Cu")
		(net "PCIE_10G_REFCLK_2_N")
	)
	(segment
		(start 314.497466 -69.012308)
		(end 314.350654 -69.15912)
		(width 0.1397)
		(layer "F.Cu")
		(net "PCIE_10G_REFCLK_2_N")
	)
	(arc
		(start 316.0395 -69.215)
		(mid 315.769719 -69.034738)
		(end 315.45149 -68.971414)
		(width 0.1397)
		(layer "F.Cu")
		(net "PCIE_10G_REFCLK_2_N")
	)
	(arc
		(start 314.596272 -68.971414)
		(mid 314.542811 -68.982048)
		(end 314.497466 -69.012308)
		(width 0.1397)
		(layer "F.Cu")
		(net "PCIE_10G_REFCLK_2_N")
	)
	(arc
		(start 314.350654 -69.15912)
		(mid 314.305321 -69.18941)
		(end 314.251848 -69.200014)
		(width 0.1397)
		(layer "F.Cu")
		(net "PCIE_10G_REFCLK_2_N")
	)
	(segment
		(start 314.251848 -68.400168)
		(end 313.125104 -68.400168)
		(width 0.1397)
		(layer "F.Cu")
		(net "PCIE_10G_REFCLK_2_P")
	)
	(segment
		(start 314.497212 -68.58762)
		(end 314.350654 -68.441062)
		(width 0.1397)
		(layer "F.Cu")
		(net "PCIE_10G_REFCLK_2_P")
	)
	(segment
		(start 316.0395 -68.199)
		(end 315.704982 -68.533518)
		(width 0.1397)
		(layer "F.Cu")
		(net "PCIE_10G_REFCLK_2_P")
	)
	(segment
		(start 315.47562 -68.628514)
		(end 314.596018 -68.628514)
		(width 0.1397)
		(layer "F.Cu")
		(net "PCIE_10G_REFCLK_2_P")
	)
	(arc
		(start 315.704982 -68.533518)
		(mid 315.59975 -68.603832)
		(end 315.47562 -68.628514)
		(width 0.1397)
		(layer "F.Cu")
		(net "PCIE_10G_REFCLK_2_P")
	)
	(arc
		(start 314.350654 -68.441062)
		(mid 314.305321 -68.410772)
		(end 314.251848 -68.400168)
		(width 0.1397)
		(layer "F.Cu")
		(net "PCIE_10G_REFCLK_2_P")
	)
	(arc
		(start 314.596018 -68.628514)
		(mid 314.542557 -68.61788)
		(end 314.497212 -68.58762)
		(width 0.1397)
		(layer "F.Cu")
		(net "PCIE_10G_REFCLK_2_P")
	)
	(segment
		(start 317.4619 -69.0753)
		(end 317.4619 -69.01815)
		(width 0.1397)
		(layer "F.Cu")
		(net "CLK_100M_CLKBUFF_ENET2_DN")
	)
	(segment
		(start 316.9285 -69.215)
		(end 317.3222 -69.215)
		(width 0.1397)
		(layer "F.Cu")
		(net "CLK_100M_CLKBUFF_ENET2_DN")
	)
	(segment
		(start 318.477138 -68.919344)
		(end 318.755776 -69.197982)
		(width 0.1397)
		(layer "F.Cu")
		(net "CLK_100M_CLKBUFF_ENET2_DN")
	)
	(segment
		(start 317.6016 -68.87845)
		(end 318.378332 -68.87845)
		(width 0.1397)
		(layer "F.Cu")
		(net "CLK_100M_CLKBUFF_ENET2_DN")
	)
	(via
		(at 318.755776 -69.197982)
		(size 0.5588)
		(drill 0.3048)
		(layers "F.Cu" "B.Cu")
		(net "CLK_100M_CLKBUFF_ENET2_DN")
	)
	(via
		(at 295.91 -77.35951)
		(size 0.5588)
		(drill 0.3048)
		(layers "F.Cu" "B.Cu")
		(net "CLK_100M_CLKBUFF_ENET2_DN")
	)
	(arc
		(start 318.378332 -68.87845)
		(mid 318.431793 -68.889084)
		(end 318.477138 -68.919344)
		(width 0.1397)
		(layer "F.Cu")
		(net "CLK_100M_CLKBUFF_ENET2_DN")
	)
	(arc
		(start 317.3222 -69.215)
		(mid 317.420983 -69.174083)
		(end 317.4619 -69.0753)
		(width 0.1397)
		(layer "F.Cu")
		(net "CLK_100M_CLKBUFF_ENET2_DN")
	)
	(arc
		(start 317.4619 -69.01815)
		(mid 317.502817 -68.919367)
		(end 317.6016 -68.87845)
		(width 0.1397)
		(layer "F.Cu")
		(net "CLK_100M_CLKBUFF_ENET2_DN")
	)
	(segment
		(start 319.405254 -69.031104)
		(end 319.405254 -69.6722)
		(width 0.1397)
		(layer "B.Cu")
		(net "CLK_100M_CLKBUFF_ENET2_DN")
	)
	(segment
		(start 300.886622 -77.41285)
		(end 300.467522 -77.41285)
		(width 0.1397)
		(layer "B.Cu")
		(net "CLK_100M_CLKBUFF_ENET2_DN")
	)
	(segment
		(start 313.986418 -72.721724)
		(end 313.69 -73.017888)
		(width 0.1397)
		(layer "B.Cu")
		(net "CLK_100M_CLKBUFF_ENET2_DN")
	)
	(segment
		(start 312.826146 -73.881996)
		(end 312.529982 -74.17816)
		(width 0.1397)
		(layer "B.Cu")
		(net "CLK_100M_CLKBUFF_ENET2_DN")
	)
	(segment
		(start 313.548268 -73.443592)
		(end 313.25185 -73.74001)
		(width 0.1397)
		(layer "B.Cu")
		(net "CLK_100M_CLKBUFF_ENET2_DN")
	)
	(segment
		(start 301.707042 -77.61351)
		(end 301.287942 -77.61351)
		(width 0.1397)
		(layer "B.Cu")
		(net "CLK_100M_CLKBUFF_ENET2_DN")
	)
	(segment
		(start 311.665874 -75.042014)
		(end 311.36971 -75.338432)
		(width 0.1397)
		(layer "B.Cu")
		(net "CLK_100M_CLKBUFF_ENET2_DN")
	)
	(segment
		(start 318.338454 -70.739)
		(end 316.8396 -70.739)
		(width 0.1397)
		(layer "B.Cu")
		(net "CLK_100M_CLKBUFF_ENET2_DN")
	)
	(segment
		(start 302.527462 -77.41285)
		(end 302.108362 -77.41285)
		(width 0.1397)
		(layer "B.Cu")
		(net "CLK_100M_CLKBUFF_ENET2_DN")
	)
	(segment
		(start 305.648614 -77.61351)
		(end 305.229514 -77.61351)
		(width 0.1397)
		(layer "B.Cu")
		(net "CLK_100M_CLKBUFF_ENET2_DN")
	)
	(segment
		(start 300.066202 -77.61351)
		(end 299.647102 -77.61351)
		(width 0.1397)
		(layer "B.Cu")
		(net "CLK_100M_CLKBUFF_ENET2_DN")
	)
	(segment
		(start 310.03113 -76.96073)
		(end 309.939436 -77.05217)
		(width 0.1397)
		(layer "B.Cu")
		(net "CLK_100M_CLKBUFF_ENET2_DN")
	)
	(segment
		(start 315.808614 -71.183246)
		(end 314.412122 -72.579738)
		(width 0.1397)
		(layer "B.Cu")
		(net "CLK_100M_CLKBUFF_ENET2_DN")
	)
	(segment
		(start 315.83757 -71.154036)
		(end 315.808614 -71.183246)
		(width 0.1397)
		(layer "B.Cu")
		(net "CLK_100M_CLKBUFF_ENET2_DN")
	)
	(segment
		(start 316.8396 -70.739)
		(end 316.8396 -70.738746)
		(width 0.1397)
		(layer "B.Cu")
		(net "CLK_100M_CLKBUFF_ENET2_DN")
	)
	(segment
		(start 311.227724 -75.764136)
		(end 310.03113 -76.96073)
		(width 0.1397)
		(layer "B.Cu")
		(net "CLK_100M_CLKBUFF_ENET2_DN")
	)
	(segment
		(start 318.755776 -69.197982)
		(end 319.034414 -68.919344)
		(width 0.1397)
		(layer "B.Cu")
		(net "CLK_100M_CLKBUFF_ENET2_DN")
	)
	(segment
		(start 312.387996 -74.603864)
		(end 312.091578 -74.900282)
		(width 0.1397)
		(layer "B.Cu")
		(net "CLK_100M_CLKBUFF_ENET2_DN")
	)
	(segment
		(start 298.425362 -77.61351)
		(end 296.523156 -77.61351)
		(width 0.1397)
		(layer "B.Cu")
		(net "CLK_100M_CLKBUFF_ENET2_DN")
	)
	(segment
		(start 299.245782 -77.41285)
		(end 298.826682 -77.41285)
		(width 0.1397)
		(layer "B.Cu")
		(net "CLK_100M_CLKBUFF_ENET2_DN")
	)
	(segment
		(start 308.5846 -77.61351)
		(end 306.870354 -77.61351)
		(width 0.1397)
		(layer "B.Cu")
		(net "CLK_100M_CLKBUFF_ENET2_DN")
	)
	(segment
		(start 319.13322 -68.87845)
		(end 319.2526 -68.87845)
		(width 0.1397)
		(layer "B.Cu")
		(net "CLK_100M_CLKBUFF_ENET2_DN")
	)
	(segment
		(start 306.469034 -77.41285)
		(end 306.049934 -77.41285)
		(width 0.1397)
		(layer "B.Cu")
		(net "CLK_100M_CLKBUFF_ENET2_DN")
	)
	(segment
		(start 304.007774 -77.61351)
		(end 302.928782 -77.61351)
		(width 0.1397)
		(layer "B.Cu")
		(net "CLK_100M_CLKBUFF_ENET2_DN")
	)
	(segment
		(start 304.828194 -77.41285)
		(end 304.409094 -77.41285)
		(width 0.1397)
		(layer "B.Cu")
		(net "CLK_100M_CLKBUFF_ENET2_DN")
	)
	(arc
		(start 302.728122 -77.51318)
		(mid 302.639596 -77.43942)
		(end 302.527462 -77.41285)
		(width 0.1397)
		(layer "B.Cu")
		(net "CLK_100M_CLKBUFF_ENET2_DN")
	)
	(arc
		(start 313.038998 -73.810876)
		(mid 312.924215 -73.8214)
		(end 312.826146 -73.881996)
		(width 0.1397)
		(layer "B.Cu")
		(net "CLK_100M_CLKBUFF_ENET2_DN")
	)
	(arc
		(start 301.287942 -77.61351)
		(mid 301.175785 -77.586986)
		(end 301.087282 -77.51318)
		(width 0.1397)
		(layer "B.Cu")
		(net "CLK_100M_CLKBUFF_ENET2_DN")
	)
	(arc
		(start 299.647102 -77.61351)
		(mid 299.534945 -77.586986)
		(end 299.446442 -77.51318)
		(width 0.1397)
		(layer "B.Cu")
		(net "CLK_100M_CLKBUFF_ENET2_DN")
	)
	(arc
		(start 314.19927 -72.650604)
		(mid 314.084487 -72.661128)
		(end 313.986418 -72.721724)
		(width 0.1397)
		(layer "B.Cu")
		(net "CLK_100M_CLKBUFF_ENET2_DN")
	)
	(arc
		(start 311.878726 -74.971148)
		(mid 311.763957 -74.981534)
		(end 311.665874 -75.042014)
		(width 0.1397)
		(layer "B.Cu")
		(net "CLK_100M_CLKBUFF_ENET2_DN")
	)
	(arc
		(start 313.25185 -73.74001)
		(mid 313.153768 -73.800517)
		(end 313.038998 -73.810876)
		(width 0.1397)
		(layer "B.Cu")
		(net "CLK_100M_CLKBUFF_ENET2_DN")
	)
	(arc
		(start 302.108362 -77.41285)
		(mid 301.996205 -77.439374)
		(end 301.907702 -77.51318)
		(width 0.1397)
		(layer "B.Cu")
		(net "CLK_100M_CLKBUFF_ENET2_DN")
	)
	(arc
		(start 314.412122 -72.579738)
		(mid 314.31404 -72.640245)
		(end 314.19927 -72.650604)
		(width 0.1397)
		(layer "B.Cu")
		(net "CLK_100M_CLKBUFF_ENET2_DN")
	)
	(arc
		(start 311.29859 -75.551284)
		(mid 311.288197 -75.666042)
		(end 311.227724 -75.764136)
		(width 0.1397)
		(layer "B.Cu")
		(net "CLK_100M_CLKBUFF_ENET2_DN")
	)
	(arc
		(start 309.939436 -77.05217)
		(mid 309.317847 -77.467596)
		(end 308.5846 -77.61351)
		(width 0.1397)
		(layer "B.Cu")
		(net "CLK_100M_CLKBUFF_ENET2_DN")
	)
	(arc
		(start 301.907702 -77.51318)
		(mid 301.819176 -77.58694)
		(end 301.707042 -77.61351)
		(width 0.1397)
		(layer "B.Cu")
		(net "CLK_100M_CLKBUFF_ENET2_DN")
	)
	(arc
		(start 306.669694 -77.51318)
		(mid 306.581168 -77.43942)
		(end 306.469034 -77.41285)
		(width 0.1397)
		(layer "B.Cu")
		(net "CLK_100M_CLKBUFF_ENET2_DN")
	)
	(arc
		(start 312.458862 -74.391012)
		(mid 312.448469 -74.50577)
		(end 312.387996 -74.603864)
		(width 0.1397)
		(layer "B.Cu")
		(net "CLK_100M_CLKBUFF_ENET2_DN")
	)
	(arc
		(start 304.208434 -77.51318)
		(mid 304.119908 -77.58694)
		(end 304.007774 -77.61351)
		(width 0.1397)
		(layer "B.Cu")
		(net "CLK_100M_CLKBUFF_ENET2_DN")
	)
	(arc
		(start 319.405254 -69.6722)
		(mid 319.092796 -70.426542)
		(end 318.338454 -70.739)
		(width 0.1397)
		(layer "B.Cu")
		(net "CLK_100M_CLKBUFF_ENET2_DN")
	)
	(arc
		(start 305.229514 -77.61351)
		(mid 305.117357 -77.586986)
		(end 305.028854 -77.51318)
		(width 0.1397)
		(layer "B.Cu")
		(net "CLK_100M_CLKBUFF_ENET2_DN")
	)
	(arc
		(start 306.870354 -77.61351)
		(mid 306.758197 -77.586986)
		(end 306.669694 -77.51318)
		(width 0.1397)
		(layer "B.Cu")
		(net "CLK_100M_CLKBUFF_ENET2_DN")
	)
	(arc
		(start 313.619134 -73.23074)
		(mid 313.608741 -73.345498)
		(end 313.548268 -73.443592)
		(width 0.1397)
		(layer "B.Cu")
		(net "CLK_100M_CLKBUFF_ENET2_DN")
	)
	(arc
		(start 316.8396 -70.738746)
		(mid 316.297272 -70.846693)
		(end 315.83757 -71.154036)
		(width 0.1397)
		(layer "B.Cu")
		(net "CLK_100M_CLKBUFF_ENET2_DN")
	)
	(arc
		(start 299.446442 -77.51318)
		(mid 299.357916 -77.43942)
		(end 299.245782 -77.41285)
		(width 0.1397)
		(layer "B.Cu")
		(net "CLK_100M_CLKBUFF_ENET2_DN")
	)
	(arc
		(start 312.091578 -74.900282)
		(mid 311.993496 -74.960789)
		(end 311.878726 -74.971148)
		(width 0.1397)
		(layer "B.Cu")
		(net "CLK_100M_CLKBUFF_ENET2_DN")
	)
	(arc
		(start 300.266862 -77.51318)
		(mid 300.178336 -77.58694)
		(end 300.066202 -77.61351)
		(width 0.1397)
		(layer "B.Cu")
		(net "CLK_100M_CLKBUFF_ENET2_DN")
	)
	(arc
		(start 305.849274 -77.51318)
		(mid 305.760748 -77.58694)
		(end 305.648614 -77.61351)
		(width 0.1397)
		(layer "B.Cu")
		(net "CLK_100M_CLKBUFF_ENET2_DN")
	)
	(arc
		(start 300.467522 -77.41285)
		(mid 300.355365 -77.439374)
		(end 300.266862 -77.51318)
		(width 0.1397)
		(layer "B.Cu")
		(net "CLK_100M_CLKBUFF_ENET2_DN")
	)
	(arc
		(start 305.028854 -77.51318)
		(mid 304.940328 -77.43942)
		(end 304.828194 -77.41285)
		(width 0.1397)
		(layer "B.Cu")
		(net "CLK_100M_CLKBUFF_ENET2_DN")
	)
	(arc
		(start 298.626022 -77.51318)
		(mid 298.537496 -77.58694)
		(end 298.425362 -77.61351)
		(width 0.1397)
		(layer "B.Cu")
		(net "CLK_100M_CLKBUFF_ENET2_DN")
	)
	(arc
		(start 304.409094 -77.41285)
		(mid 304.296937 -77.439374)
		(end 304.208434 -77.51318)
		(width 0.1397)
		(layer "B.Cu")
		(net "CLK_100M_CLKBUFF_ENET2_DN")
	)
	(arc
		(start 319.2526 -68.87845)
		(mid 319.360543 -68.923161)
		(end 319.405254 -69.031104)
		(width 0.1397)
		(layer "B.Cu")
		(net "CLK_100M_CLKBUFF_ENET2_DN")
	)
	(arc
		(start 301.087282 -77.51318)
		(mid 300.998756 -77.43942)
		(end 300.886622 -77.41285)
		(width 0.1397)
		(layer "B.Cu")
		(net "CLK_100M_CLKBUFF_ENET2_DN")
	)
	(arc
		(start 311.36971 -75.338432)
		(mid 311.309046 -75.436479)
		(end 311.29859 -75.551284)
		(width 0.1397)
		(layer "B.Cu")
		(net "CLK_100M_CLKBUFF_ENET2_DN")
	)
	(arc
		(start 298.826682 -77.41285)
		(mid 298.714525 -77.439374)
		(end 298.626022 -77.51318)
		(width 0.1397)
		(layer "B.Cu")
		(net "CLK_100M_CLKBUFF_ENET2_DN")
	)
	(arc
		(start 296.523156 -77.61351)
		(mid 296.19131 -77.547502)
		(end 295.91 -77.35951)
		(width 0.1397)
		(layer "B.Cu")
		(net "CLK_100M_CLKBUFF_ENET2_DN")
	)
	(arc
		(start 312.529982 -74.17816)
		(mid 312.469318 -74.276207)
		(end 312.458862 -74.391012)
		(width 0.1397)
		(layer "B.Cu")
		(net "CLK_100M_CLKBUFF_ENET2_DN")
	)
	(arc
		(start 319.034414 -68.919344)
		(mid 319.079747 -68.889054)
		(end 319.13322 -68.87845)
		(width 0.1397)
		(layer "B.Cu")
		(net "CLK_100M_CLKBUFF_ENET2_DN")
	)
	(arc
		(start 306.049934 -77.41285)
		(mid 305.937777 -77.439374)
		(end 305.849274 -77.51318)
		(width 0.1397)
		(layer "B.Cu")
		(net "CLK_100M_CLKBUFF_ENET2_DN")
	)
	(arc
		(start 302.928782 -77.61351)
		(mid 302.816625 -77.586986)
		(end 302.728122 -77.51318)
		(width 0.1397)
		(layer "B.Cu")
		(net "CLK_100M_CLKBUFF_ENET2_DN")
	)
	(arc
		(start 313.69 -73.017888)
		(mid 313.629554 -73.115982)
		(end 313.619134 -73.23074)
		(width 0.1397)
		(layer "B.Cu")
		(net "CLK_100M_CLKBUFF_ENET2_DN")
	)
	(segment
		(start 183.2864 -74.0156)
		(end 183.2864 -73.25487)
		(width 0.127)
		(layer "In5.Cu")
		(net "CLK_100M_CLKBUFF_ENET2_DN")
	)
	(segment
		(start 295.629076 -77.640434)
		(end 295.91 -77.35951)
		(width 0.127)
		(layer "In5.Cu")
		(net "CLK_100M_CLKBUFF_ENET2_DN")
	)
	(segment
		(start 183.61406 -72.46366)
		(end 184.723278 -71.354442)
		(width 0.127)
		(layer "In5.Cu")
		(net "CLK_100M_CLKBUFF_ENET2_DN")
	)
	(segment
		(start 183.065166 -74.389234)
		(end 183.178704 -74.27595)
		(width 0.127)
		(layer "In5.Cu")
		(net "CLK_100M_CLKBUFF_ENET2_DN")
	)
	(segment
		(start 182.450486 -73.75017)
		(end 182.450232 -74.134472)
		(width 0.127)
		(layer "In5.Cu")
		(net "CLK_100M_CLKBUFF_ENET2_DN")
	)
	(segment
		(start 228.048312 -71.697088)
		(end 233.492548 -77.141324)
		(width 0.127)
		(layer "In5.Cu")
		(net "CLK_100M_CLKBUFF_ENET2_DN")
	)
	(segment
		(start 185.9026 -70.866)
		(end 226.041712 -70.866)
		(width 0.127)
		(layer "In5.Cu")
		(net "CLK_100M_CLKBUFF_ENET2_DN")
	)
	(segment
		(start 234.8992 -77.724)
		(end 295.4274 -77.724)
		(width 0.127)
		(layer "In5.Cu")
		(net "CLK_100M_CLKBUFF_ENET2_DN")
	)
	(arc
		(start 182.450232 -74.134472)
		(mid 182.627042 -74.444222)
		(end 182.983632 -74.44994)
		(width 0.127)
		(layer "In5.Cu")
		(net "CLK_100M_CLKBUFF_ENET2_DN")
	)
	(arc
		(start 233.492548 -77.141324)
		(mid 234.137925 -77.572551)
		(end 234.8992 -77.724)
		(width 0.127)
		(layer "In5.Cu")
		(net "CLK_100M_CLKBUFF_ENET2_DN")
	)
	(arc
		(start 182.983632 -74.44994)
		(mid 183.010143 -74.433894)
		(end 183.035194 -74.41565)
		(width 0.127)
		(layer "In5.Cu")
		(net "CLK_100M_CLKBUFF_ENET2_DN")
	)
	(arc
		(start 183.035194 -74.41565)
		(mid 183.050547 -74.402858)
		(end 183.065166 -74.389234)
		(width 0.127)
		(layer "In5.Cu")
		(net "CLK_100M_CLKBUFF_ENET2_DN")
	)
	(arc
		(start 226.041712 -70.866)
		(mid 227.127648 -71.082006)
		(end 228.048312 -71.697088)
		(width 0.127)
		(layer "In5.Cu")
		(net "CLK_100M_CLKBUFF_ENET2_DN")
	)
	(arc
		(start 295.4274 -77.724)
		(mid 295.536557 -77.702287)
		(end 295.629076 -77.640434)
		(width 0.127)
		(layer "In5.Cu")
		(net "CLK_100M_CLKBUFF_ENET2_DN")
	)
	(arc
		(start 183.178704 -74.27595)
		(mid 183.258435 -74.156485)
		(end 183.2864 -74.0156)
		(width 0.127)
		(layer "In5.Cu")
		(net "CLK_100M_CLKBUFF_ENET2_DN")
	)
	(arc
		(start 183.2864 -73.25487)
		(mid 183.371569 -72.826697)
		(end 183.61406 -72.46366)
		(width 0.127)
		(layer "In5.Cu")
		(net "CLK_100M_CLKBUFF_ENET2_DN")
	)
	(arc
		(start 184.723278 -71.354442)
		(mid 185.26437 -70.992959)
		(end 185.9026 -70.866)
		(width 0.127)
		(layer "In5.Cu")
		(net "CLK_100M_CLKBUFF_ENET2_DN")
	)
	(segment
		(start 317.6016 -68.53555)
		(end 318.378332 -68.53555)
		(width 0.1397)
		(layer "F.Cu")
		(net "CLK_100M_CLKBUFF_ENET2_DP")
	)
	(segment
		(start 316.9285 -68.199)
		(end 317.3222 -68.199)
		(width 0.1397)
		(layer "F.Cu")
		(net "CLK_100M_CLKBUFF_ENET2_DP")
	)
	(segment
		(start 317.4619 -68.3387)
		(end 317.4619 -68.39585)
		(width 0.1397)
		(layer "F.Cu")
		(net "CLK_100M_CLKBUFF_ENET2_DP")
	)
	(segment
		(start 318.477138 -68.494656)
		(end 318.755776 -68.216018)
		(width 0.1397)
		(layer "F.Cu")
		(net "CLK_100M_CLKBUFF_ENET2_DP")
	)
	(via
		(at 318.755776 -68.216018)
		(size 0.5588)
		(drill 0.3048)
		(layers "F.Cu" "B.Cu")
		(net "CLK_100M_CLKBUFF_ENET2_DP")
	)
	(via
		(at 295.91 -78.27645)
		(size 0.5588)
		(drill 0.3048)
		(layers "F.Cu" "B.Cu")
		(net "CLK_100M_CLKBUFF_ENET2_DP")
	)
	(arc
		(start 317.4619 -68.39585)
		(mid 317.502817 -68.494633)
		(end 317.6016 -68.53555)
		(width 0.1397)
		(layer "F.Cu")
		(net "CLK_100M_CLKBUFF_ENET2_DP")
	)
	(arc
		(start 318.378332 -68.53555)
		(mid 318.431793 -68.524916)
		(end 318.477138 -68.494656)
		(width 0.1397)
		(layer "F.Cu")
		(net "CLK_100M_CLKBUFF_ENET2_DP")
	)
	(arc
		(start 317.3222 -68.199)
		(mid 317.420983 -68.239917)
		(end 317.4619 -68.3387)
		(width 0.1397)
		(layer "F.Cu")
		(net "CLK_100M_CLKBUFF_ENET2_DP")
	)
	(segment
		(start 316.0522 -71.4248)
		(end 316.080648 -71.396098)
		(width 0.1397)
		(layer "B.Cu")
		(net "CLK_100M_CLKBUFF_ENET2_DP")
	)
	(segment
		(start 319.748154 -69.6722)
		(end 319.748154 -69.031104)
		(width 0.1397)
		(layer "B.Cu")
		(net "CLK_100M_CLKBUFF_ENET2_DP")
	)
	(segment
		(start 319.2526 -68.53555)
		(end 319.13322 -68.53555)
		(width 0.1397)
		(layer "B.Cu")
		(net "CLK_100M_CLKBUFF_ENET2_DP")
	)
	(segment
		(start 295.91 -78.27645)
		(end 296.007282 -78.179168)
		(width 0.1397)
		(layer "B.Cu")
		(net "CLK_100M_CLKBUFF_ENET2_DP")
	)
	(segment
		(start 310.182006 -77.294994)
		(end 316.0522 -71.4248)
		(width 0.1397)
		(layer "B.Cu")
		(net "CLK_100M_CLKBUFF_ENET2_DP")
	)
	(segment
		(start 316.8396 -71.0819)
		(end 318.338454 -71.0819)
		(width 0.1397)
		(layer "B.Cu")
		(net "CLK_100M_CLKBUFF_ENET2_DP")
	)
	(segment
		(start 296.545 -77.95641)
		(end 308.584854 -77.95641)
		(width 0.1397)
		(layer "B.Cu")
		(net "CLK_100M_CLKBUFF_ENET2_DP")
	)
	(segment
		(start 319.034414 -68.494656)
		(end 318.755776 -68.216018)
		(width 0.1397)
		(layer "B.Cu")
		(net "CLK_100M_CLKBUFF_ENET2_DP")
	)
	(arc
		(start 316.080648 -71.396098)
		(mid 316.428873 -71.163514)
		(end 316.8396 -71.0819)
		(width 0.1397)
		(layer "B.Cu")
		(net "CLK_100M_CLKBUFF_ENET2_DP")
	)
	(arc
		(start 319.748154 -69.031104)
		(mid 319.60301 -68.680694)
		(end 319.2526 -68.53555)
		(width 0.1397)
		(layer "B.Cu")
		(net "CLK_100M_CLKBUFF_ENET2_DP")
	)
	(arc
		(start 308.584854 -77.95641)
		(mid 309.449199 -77.784517)
		(end 310.182006 -77.294994)
		(width 0.1397)
		(layer "B.Cu")
		(net "CLK_100M_CLKBUFF_ENET2_DP")
	)
	(arc
		(start 296.007282 -78.179168)
		(mid 296.253989 -78.014324)
		(end 296.545 -77.95641)
		(width 0.1397)
		(layer "B.Cu")
		(net "CLK_100M_CLKBUFF_ENET2_DP")
	)
	(arc
		(start 318.338454 -71.0819)
		(mid 319.335262 -70.669008)
		(end 319.748154 -69.6722)
		(width 0.1397)
		(layer "B.Cu")
		(net "CLK_100M_CLKBUFF_ENET2_DP")
	)
	(arc
		(start 319.13322 -68.53555)
		(mid 319.079759 -68.524916)
		(end 319.034414 -68.494656)
		(width 0.1397)
		(layer "B.Cu")
		(net "CLK_100M_CLKBUFF_ENET2_DP")
	)
	(segment
		(start 183.811672 -72.661272)
		(end 184.92089 -71.552054)
		(width 0.127)
		(layer "In5.Cu")
		(net "CLK_100M_CLKBUFF_ENET2_DP")
	)
	(segment
		(start 227.8507 -71.8947)
		(end 233.294936 -77.338936)
		(width 0.127)
		(layer "In5.Cu")
		(net "CLK_100M_CLKBUFF_ENET2_DP")
	)
	(segment
		(start 234.8992 -78.0034)
		(end 295.275 -78.0034)
		(width 0.127)
		(layer "In5.Cu")
		(net "CLK_100M_CLKBUFF_ENET2_DP")
	)
	(segment
		(start 185.9026 -71.1454)
		(end 226.041712 -71.1454)
		(width 0.127)
		(layer "In5.Cu")
		(net "CLK_100M_CLKBUFF_ENET2_DP")
	)
	(segment
		(start 183.275478 -75.329034)
		(end 183.275478 -74.867516)
		(width 0.127)
		(layer "In5.Cu")
		(net "CLK_100M_CLKBUFF_ENET2_DP")
	)
	(segment
		(start 295.892728 -78.259432)
		(end 295.91 -78.27645)
		(width 0.127)
		(layer "In5.Cu")
		(net "CLK_100M_CLKBUFF_ENET2_DP")
	)
	(segment
		(start 183.5658 -74.0156)
		(end 183.5658 -73.25487)
		(width 0.127)
		(layer "In5.Cu")
		(net "CLK_100M_CLKBUFF_ENET2_DP")
	)
	(arc
		(start 183.40324 -74.55916)
		(mid 183.524259 -74.299264)
		(end 183.5658 -74.0156)
		(width 0.127)
		(layer "In5.Cu")
		(net "CLK_100M_CLKBUFF_ENET2_DP")
	)
	(arc
		(start 183.275478 -74.867516)
		(mid 183.308676 -74.700621)
		(end 183.40324 -74.55916)
		(width 0.127)
		(layer "In5.Cu")
		(net "CLK_100M_CLKBUFF_ENET2_DP")
	)
	(arc
		(start 295.275 -78.0034)
		(mid 295.60932 -78.069994)
		(end 295.892728 -78.259432)
		(width 0.127)
		(layer "In5.Cu")
		(net "CLK_100M_CLKBUFF_ENET2_DP")
	)
	(arc
		(start 184.92089 -71.552054)
		(mid 185.371302 -71.251098)
		(end 185.9026 -71.1454)
		(width 0.127)
		(layer "In5.Cu")
		(net "CLK_100M_CLKBUFF_ENET2_DP")
	)
	(arc
		(start 183.5658 -73.25487)
		(mid 183.629701 -72.933619)
		(end 183.811672 -72.661272)
		(width 0.127)
		(layer "In5.Cu")
		(net "CLK_100M_CLKBUFF_ENET2_DP")
	)
	(arc
		(start 226.041712 -71.1454)
		(mid 227.020726 -71.340138)
		(end 227.8507 -71.8947)
		(width 0.127)
		(layer "In5.Cu")
		(net "CLK_100M_CLKBUFF_ENET2_DP")
	)
	(arc
		(start 233.294936 -77.338936)
		(mid 234.030993 -77.83069)
		(end 234.8992 -78.0034)
		(width 0.127)
		(layer "In5.Cu")
		(net "CLK_100M_CLKBUFF_ENET2_DP")
	)
	(arc
		(start 183.449976 -75.75042)
		(mid 183.320795 -75.557086)
		(end 183.275478 -75.329034)
		(width 0.127)
		(layer "In5.Cu")
		(net "CLK_100M_CLKBUFF_ENET2_DP")
	)
	(segment
		(start 298.9834 -158.6865)
		(end 298.8945 -158.5976)
		(width 0.1143)
		(layer "F.Cu")
		(net "CLK_50M_BMC_NCSI_R")
	)
	(segment
		(start 295.234868 -169.040048)
		(end 295.24452 -169.040048)
		(width 0.1143)
		(layer "F.Cu")
		(net "CLK_50M_BMC_NCSI_R")
	)
	(segment
		(start 298.8945 -158.5976)
		(end 298.8945 -157.734)
		(width 0.1143)
		(layer "F.Cu")
		(net "CLK_50M_BMC_NCSI_R")
	)
	(segment
		(start 295.24452 -169.040048)
		(end 295.641776 -169.437304)
		(width 0.1143)
		(layer "F.Cu")
		(net "CLK_50M_BMC_NCSI_R")
	)
	(segment
		(start 298.8945 -157.734)
		(end 299.847 -157.734)
		(width 0.1143)
		(layer "F.Cu")
		(net "CLK_50M_BMC_NCSI_R")
	)
	(via
		(at 299.847 -157.734)
		(size 0.7112)
		(drill 0.3556)
		(layers "F.Cu" "B.Cu")
		(net "CLK_50M_BMC_NCSI_R")
	)
	(via
		(at 295.641776 -169.437304)
		(size 0.508)
		(drill 0.254)
		(layers "F.Cu" "B.Cu")
		(net "CLK_50M_BMC_NCSI_R")
	)
	(via
		(at 298.9834 -158.6865)
		(size 0.5588)
		(drill 0.3048)
		(layers "F.Cu" "B.Cu")
		(net "CLK_50M_BMC_NCSI_R")
	)
	(segment
		(start 298.831 -159.004)
		(end 298.831 -162.51682)
		(width 0.127)
		(layer "In2.Cu")
		(net "CLK_50M_BMC_NCSI_R")
	)
	(segment
		(start 296.042334 -167.528494)
		(end 296.042334 -169.036746)
		(width 0.0889)
		(layer "In2.Cu")
		(net "CLK_50M_BMC_NCSI_R")
	)
	(segment
		(start 296.042334 -169.036746)
		(end 295.641776 -169.437304)
		(width 0.0889)
		(layer "In2.Cu")
		(net "CLK_50M_BMC_NCSI_R")
	)
	(segment
		(start 295.99382 -165.354)
		(end 295.99382 -167.47998)
		(width 0.127)
		(layer "In2.Cu")
		(net "CLK_50M_BMC_NCSI_R")
	)
	(segment
		(start 295.99382 -167.47998)
		(end 296.042334 -167.528494)
		(width 0.0889)
		(layer "In2.Cu")
		(net "CLK_50M_BMC_NCSI_R")
	)
	(segment
		(start 298.831 -162.51682)
		(end 295.99382 -165.354)
		(width 0.127)
		(layer "In2.Cu")
		(net "CLK_50M_BMC_NCSI_R")
	)
	(segment
		(start 298.9834 -158.6865)
		(end 298.9834 -158.8516)
		(width 0.127)
		(layer "In2.Cu")
		(net "CLK_50M_BMC_NCSI_R")
	)
	(segment
		(start 298.9834 -158.8516)
		(end 298.831 -159.004)
		(width 0.127)
		(layer "In2.Cu")
		(net "CLK_50M_BMC_NCSI_R")
	)
	(segment
		(start 298.0055 -158.9405)
		(end 297.942 -159.004)
		(width 0.1143)
		(layer "F.Cu")
		(net "CLK_50M_BMC_NCSI")
	)
	(segment
		(start 298.0055 -156.1465)
		(end 298.069 -156.083)
		(width 0.1143)
		(layer "F.Cu")
		(net "CLK_50M_BMC_NCSI")
	)
	(segment
		(start 298.0055 -157.734)
		(end 298.0055 -156.1465)
		(width 0.1143)
		(layer "F.Cu")
		(net "CLK_50M_BMC_NCSI")
	)
	(segment
		(start 298.069 -156.083)
		(end 298.069 -154.051)
		(width 0.1143)
		(layer "F.Cu")
		(net "CLK_50M_BMC_NCSI")
	)
	(segment
		(start 298.069 -154.051)
		(end 298.533312 -153.586688)
		(width 0.1143)
		(layer "F.Cu")
		(net "CLK_50M_BMC_NCSI")
	)
	(segment
		(start 298.533312 -153.586688)
		(end 299.703236 -153.586688)
		(width 0.1143)
		(layer "F.Cu")
		(net "CLK_50M_BMC_NCSI")
	)
	(segment
		(start 298.0055 -157.734)
		(end 298.0055 -158.9405)
		(width 0.1143)
		(layer "F.Cu")
		(net "CLK_50M_BMC_NCSI")
	)
	(via
		(at 297.942 -159.004)
		(size 0.7112)
		(drill 0.3556)
		(layers "F.Cu" "B.Cu")
		(net "CLK_50M_BMC_NCSI")
	)
	(segment
		(start 326.263 -82.1055)
		(end 325.374 -81.2165)
		(width 0.1143)
		(layer "F.Cu")
		(net "FLA_CS_1")
	)
	(segment
		(start 325.8185 -79.9465)
		(end 326.263 -79.9465)
		(width 0.1143)
		(layer "F.Cu")
		(net "FLA_CS_1")
	)
	(segment
		(start 325.374 -80.391)
		(end 325.8185 -79.9465)
		(width 0.1143)
		(layer "F.Cu")
		(net "FLA_CS_1")
	)
	(segment
		(start 326.263 -79.9465)
		(end 326.263 -78.580488)
		(width 0.1143)
		(layer "F.Cu")
		(net "FLA_CS_1")
	)
	(segment
		(start 326.263 -78.580488)
		(end 326.992488 -77.851)
		(width 0.1143)
		(layer "F.Cu")
		(net "FLA_CS_1")
	)
	(segment
		(start 325.374 -81.2165)
		(end 325.374 -80.391)
		(width 0.1143)
		(layer "F.Cu")
		(net "FLA_CS_1")
	)
	(segment
		(start 282.004516 -169.040048)
		(end 276.921468 -163.957)
		(width 0.1143)
		(layer "F.Cu")
		(net "TP_BMC_GPIOI0")
	)
	(segment
		(start 276.921468 -163.957)
		(end 275.971 -163.957)
		(width 0.1143)
		(layer "F.Cu")
		(net "TP_BMC_GPIOI0")
	)
	(segment
		(start 274.6375 -163.576)
		(end 275.59 -163.576)
		(width 0.1143)
		(layer "F.Cu")
		(net "TP_BMC_GPIOI0")
	)
	(segment
		(start 275.59 -163.576)
		(end 275.8186 -163.8046)
		(width 0.1143)
		(layer "F.Cu")
		(net "TP_BMC_GPIOI0")
	)
	(segment
		(start 275.971 -163.957)
		(end 275.8186 -163.8046)
		(width 0.1143)
		(layer "F.Cu")
		(net "TP_BMC_GPIOI0")
	)
	(segment
		(start 284.834838 -169.040048)
		(end 282.004516 -169.040048)
		(width 0.1143)
		(layer "F.Cu")
		(net "TP_BMC_GPIOI0")
	)
	(via
		(at 275.8186 -163.8046)
		(size 0.7112)
		(drill 0.3556)
		(layers "F.Cu" "B.Cu")
		(net "TP_BMC_GPIOI0")
	)
	(segment
		(start 96.90608 -230.63708)
		(end 93.7006 -230.63708)
		(width 0.1143)
		(layer "F.Cu")
		(net "SAS_HDD_LED_9")
	)
	(segment
		(start 105.9688 -232.7783)
		(end 105.9688 -231.177846)
		(width 0.1143)
		(layer "F.Cu")
		(net "SAS_HDD_LED_9")
	)
	(segment
		(start 106.2355 -233.045)
		(end 105.9688 -232.7783)
		(width 0.1143)
		(layer "F.Cu")
		(net "SAS_HDD_LED_9")
	)
	(segment
		(start 94.221046 -232.41)
		(end 93.460316 -231.64927)
		(width 0.1143)
		(layer "F.Cu")
		(net "SAS_HDD_LED_9")
	)
	(segment
		(start 96.52 -233.299)
		(end 95.631 -232.41)
		(width 0.1143)
		(layer "F.Cu")
		(net "SAS_HDD_LED_9")
	)
	(segment
		(start 100.812346 -232.1687)
		(end 98.4377 -232.1687)
		(width 0.1143)
		(layer "F.Cu")
		(net "SAS_HDD_LED_9")
	)
	(segment
		(start 92.75445 -230.96855)
		(end 93.08592 -230.63708)
		(width 0.1143)
		(layer "F.Cu")
		(net "SAS_HDD_LED_9")
	)
	(segment
		(start 93.08592 -230.63708)
		(end 93.7006 -230.63708)
		(width 0.1143)
		(layer "F.Cu")
		(net "SAS_HDD_LED_9")
	)
	(segment
		(start 94.742 -232.41)
		(end 94.221046 -232.41)
		(width 0.1143)
		(layer "F.Cu")
		(net "SAS_HDD_LED_9")
	)
	(segment
		(start 96.52 -233.3625)
		(end 96.52 -233.299)
		(width 0.1143)
		(layer "F.Cu")
		(net "SAS_HDD_LED_9")
	)
	(segment
		(start 105.9688 -231.177846)
		(end 105.918 -231.127046)
		(width 0.1143)
		(layer "F.Cu")
		(net "SAS_HDD_LED_9")
	)
	(segment
		(start 102.488746 -230.4923)
		(end 100.812346 -232.1687)
		(width 0.1143)
		(layer "F.Cu")
		(net "SAS_HDD_LED_9")
	)
	(segment
		(start 95.631 -232.41)
		(end 94.742 -232.41)
		(width 0.1143)
		(layer "F.Cu")
		(net "SAS_HDD_LED_9")
	)
	(segment
		(start 105.2957 -230.4923)
		(end 102.488746 -230.4923)
		(width 0.1143)
		(layer "F.Cu")
		(net "SAS_HDD_LED_9")
	)
	(segment
		(start 92.75445 -231.541574)
		(end 92.75445 -230.96855)
		(width 0.1143)
		(layer "F.Cu")
		(net "SAS_HDD_LED_9")
	)
	(segment
		(start 92.862146 -231.64927)
		(end 92.75445 -231.541574)
		(width 0.1143)
		(layer "F.Cu")
		(net "SAS_HDD_LED_9")
	)
	(segment
		(start 106.2355 -234.2388)
		(end 106.2355 -233.045)
		(width 0.1143)
		(layer "F.Cu")
		(net "SAS_HDD_LED_9")
	)
	(segment
		(start 93.460316 -231.64927)
		(end 92.862146 -231.64927)
		(width 0.1143)
		(layer "F.Cu")
		(net "SAS_HDD_LED_9")
	)
	(segment
		(start 98.4377 -232.1687)
		(end 96.90608 -230.63708)
		(width 0.1143)
		(layer "F.Cu")
		(net "SAS_HDD_LED_9")
	)
	(segment
		(start 105.918 -231.127046)
		(end 105.918 -231.1146)
		(width 0.1143)
		(layer "F.Cu")
		(net "SAS_HDD_LED_9")
	)
	(segment
		(start 105.918 -231.1146)
		(end 105.2957 -230.4923)
		(width 0.1143)
		(layer "F.Cu")
		(net "SAS_HDD_LED_9")
	)
	(via
		(at 94.742 -232.41)
		(size 0.7112)
		(drill 0.3556)
		(layers "F.Cu" "B.Cu")
		(net "SAS_HDD_LED_9")
	)
	(segment
		(start 90.4875 -233.045)
		(end 90.4875 -234.1118)
		(width 0.1143)
		(layer "F.Cu")
		(net "SAS_HDD_LED_15")
	)
	(segment
		(start 90.4875 -234.1118)
		(end 90.4875 -235.2675)
		(width 0.1143)
		(layer "F.Cu")
		(net "SAS_HDD_LED_15")
	)
	(segment
		(start 91.14536 -226.73564)
		(end 90.043 -227.838)
		(width 0.1143)
		(layer "F.Cu")
		(net "SAS_HDD_LED_15")
	)
	(segment
		(start 91.313 -232.2195)
		(end 90.4875 -233.045)
		(width 0.1143)
		(layer "F.Cu")
		(net "SAS_HDD_LED_15")
	)
	(segment
		(start 93.7006 -226.73564)
		(end 91.14536 -226.73564)
		(width 0.1143)
		(layer "F.Cu")
		(net "SAS_HDD_LED_15")
	)
	(segment
		(start 85.344 -237.109)
		(end 84.328 -236.093)
		(width 0.1143)
		(layer "F.Cu")
		(net "SAS_HDD_LED_15")
	)
	(segment
		(start 90.4875 -235.2675)
		(end 88.646 -237.109)
		(width 0.1143)
		(layer "F.Cu")
		(net "SAS_HDD_LED_15")
	)
	(segment
		(start 84.328 -236.093)
		(end 84.328 -229.489)
		(width 0.1143)
		(layer "F.Cu")
		(net "SAS_HDD_LED_15")
	)
	(segment
		(start 85.979 -227.838)
		(end 85.344 -228.473)
		(width 0.1143)
		(layer "F.Cu")
		(net "SAS_HDD_LED_15")
	)
	(segment
		(start 88.646 -237.109)
		(end 85.344 -237.109)
		(width 0.1143)
		(layer "F.Cu")
		(net "SAS_HDD_LED_15")
	)
	(segment
		(start 90.043 -227.838)
		(end 85.979 -227.838)
		(width 0.1143)
		(layer "F.Cu")
		(net "SAS_HDD_LED_15")
	)
	(segment
		(start 84.328 -229.489)
		(end 85.344 -228.473)
		(width 0.1143)
		(layer "F.Cu")
		(net "SAS_HDD_LED_15")
	)
	(via
		(at 85.344 -228.473)
		(size 0.7112)
		(drill 0.3556)
		(layers "F.Cu" "B.Cu")
		(net "SAS_HDD_LED_15")
	)
	(segment
		(start 85.598 -236.728)
		(end 84.6963 -235.8263)
		(width 0.1143)
		(layer "F.Cu")
		(net "SAS_HDD_LED_14")
	)
	(segment
		(start 84.6963 -230.124)
		(end 86.614 -228.2063)
		(width 0.1143)
		(layer "F.Cu")
		(net "SAS_HDD_LED_14")
	)
	(segment
		(start 84.6963 -235.8263)
		(end 84.6963 -230.124)
		(width 0.1143)
		(layer "F.Cu")
		(net "SAS_HDD_LED_14")
	)
	(segment
		(start 89.8525 -235.2675)
		(end 88.392 -236.728)
		(width 0.1143)
		(layer "F.Cu")
		(net "SAS_HDD_LED_14")
	)
	(segment
		(start 89.8525 -234.1118)
		(end 89.8525 -235.2675)
		(width 0.1143)
		(layer "F.Cu")
		(net "SAS_HDD_LED_14")
	)
	(segment
		(start 88.392 -236.728)
		(end 85.598 -236.728)
		(width 0.1143)
		(layer "F.Cu")
		(net "SAS_HDD_LED_14")
	)
	(segment
		(start 86.614 -228.2063)
		(end 90.195654 -228.2063)
		(width 0.1143)
		(layer "F.Cu")
		(net "SAS_HDD_LED_14")
	)
	(segment
		(start 89.8525 -232.664)
		(end 89.8525 -234.1118)
		(width 0.1143)
		(layer "F.Cu")
		(net "SAS_HDD_LED_14")
	)
	(segment
		(start 90.195654 -228.2063)
		(end 91.016074 -227.38588)
		(width 0.1143)
		(layer "F.Cu")
		(net "SAS_HDD_LED_14")
	)
	(segment
		(start 91.016074 -227.38588)
		(end 92.14612 -227.38588)
		(width 0.1143)
		(layer "F.Cu")
		(net "SAS_HDD_LED_14")
	)
	(segment
		(start 90.297 -232.2195)
		(end 89.8525 -232.664)
		(width 0.1143)
		(layer "F.Cu")
		(net "SAS_HDD_LED_14")
	)
	(segment
		(start 93.7006 -227.38588)
		(end 92.14612 -227.38588)
		(width 0.1143)
		(layer "F.Cu")
		(net "SAS_HDD_LED_14")
	)
	(via
		(at 92.14612 -227.38588)
		(size 0.7112)
		(drill 0.3556)
		(layers "F.Cu" "B.Cu")
		(net "SAS_HDD_LED_14")
	)
	(segment
		(start 86.359746 -229.489254)
		(end 86.614 -229.235)
		(width 0.1143)
		(layer "F.Cu")
		(net "SAS_HDD_LED_13")
	)
	(segment
		(start 85.0646 -235.5596)
		(end 85.0646 -230.276654)
		(width 0.1143)
		(layer "F.Cu")
		(net "SAS_HDD_LED_13")
	)
	(segment
		(start 93.7006 -228.03612)
		(end 90.886788 -228.03612)
		(width 0.1143)
		(layer "F.Cu")
		(net "SAS_HDD_LED_13")
	)
	(segment
		(start 87.2744 -228.5746)
		(end 86.614 -229.235)
		(width 0.1143)
		(layer "F.Cu")
		(net "SAS_HDD_LED_13")
	)
	(segment
		(start 89.2175 -235.2675)
		(end 88.138 -236.347)
		(width 0.1143)
		(layer "F.Cu")
		(net "SAS_HDD_LED_13")
	)
	(segment
		(start 90.886788 -228.03612)
		(end 90.348308 -228.5746)
		(width 0.1143)
		(layer "F.Cu")
		(net "SAS_HDD_LED_13")
	)
	(segment
		(start 85.852 -236.347)
		(end 85.0646 -235.5596)
		(width 0.1143)
		(layer "F.Cu")
		(net "SAS_HDD_LED_13")
	)
	(segment
		(start 90.348308 -228.5746)
		(end 87.2744 -228.5746)
		(width 0.1143)
		(layer "F.Cu")
		(net "SAS_HDD_LED_13")
	)
	(segment
		(start 85.852 -229.489254)
		(end 86.359746 -229.489254)
		(width 0.1143)
		(layer "F.Cu")
		(net "SAS_HDD_LED_13")
	)
	(segment
		(start 89.2175 -232.283)
		(end 89.2175 -234.1118)
		(width 0.1143)
		(layer "F.Cu")
		(net "SAS_HDD_LED_13")
	)
	(segment
		(start 89.154 -232.2195)
		(end 89.2175 -232.283)
		(width 0.1143)
		(layer "F.Cu")
		(net "SAS_HDD_LED_13")
	)
	(segment
		(start 85.0646 -230.276654)
		(end 85.852 -229.489254)
		(width 0.1143)
		(layer "F.Cu")
		(net "SAS_HDD_LED_13")
	)
	(segment
		(start 89.2175 -234.1118)
		(end 89.2175 -235.2675)
		(width 0.1143)
		(layer "F.Cu")
		(net "SAS_HDD_LED_13")
	)
	(segment
		(start 88.138 -236.347)
		(end 85.852 -236.347)
		(width 0.1143)
		(layer "F.Cu")
		(net "SAS_HDD_LED_13")
	)
	(via
		(at 86.614 -229.235)
		(size 0.7112)
		(drill 0.3556)
		(layers "F.Cu" "B.Cu")
		(net "SAS_HDD_LED_13")
	)
	(segment
		(start 87.89035 -235.95965)
		(end 86.056216 -235.95965)
		(width 0.1143)
		(layer "F.Cu")
		(net "SAS_HDD_LED_12")
	)
	(segment
		(start 88.5825 -234.1118)
		(end 88.5825 -235.2675)
		(width 0.1143)
		(layer "F.Cu")
		(net "SAS_HDD_LED_12")
	)
	(segment
		(start 92.86494 -228.68636)
		(end 92.583 -228.40442)
		(width 0.1143)
		(layer "F.Cu")
		(net "SAS_HDD_LED_12")
	)
	(segment
		(start 88.011 -232.2195)
		(end 88.5825 -232.791)
		(width 0.1143)
		(layer "F.Cu")
		(net "SAS_HDD_LED_12")
	)
	(segment
		(start 87.757 -228.9429)
		(end 86.3219 -230.378)
		(width 0.1143)
		(layer "F.Cu")
		(net "SAS_HDD_LED_12")
	)
	(segment
		(start 92.583 -228.40442)
		(end 91.039442 -228.40442)
		(width 0.1143)
		(layer "F.Cu")
		(net "SAS_HDD_LED_12")
	)
	(segment
		(start 85.4329 -235.336588)
		(end 85.4329 -230.7971)
		(width 0.1143)
		(layer "F.Cu")
		(net "SAS_HDD_LED_12")
	)
	(segment
		(start 86.056216 -235.95965)
		(end 85.823806 -235.72724)
		(width 0.1143)
		(layer "F.Cu")
		(net "SAS_HDD_LED_12")
	)
	(segment
		(start 85.823806 -235.72724)
		(end 85.823552 -235.72724)
		(width 0.1143)
		(layer "F.Cu")
		(net "SAS_HDD_LED_12")
	)
	(segment
		(start 91.039442 -228.40442)
		(end 90.500962 -228.9429)
		(width 0.1143)
		(layer "F.Cu")
		(net "SAS_HDD_LED_12")
	)
	(segment
		(start 85.4329 -230.7971)
		(end 85.852 -230.378)
		(width 0.1143)
		(layer "F.Cu")
		(net "SAS_HDD_LED_12")
	)
	(segment
		(start 85.823552 -235.72724)
		(end 85.4329 -235.336588)
		(width 0.1143)
		(layer "F.Cu")
		(net "SAS_HDD_LED_12")
	)
	(segment
		(start 88.5825 -235.2675)
		(end 87.89035 -235.95965)
		(width 0.1143)
		(layer "F.Cu")
		(net "SAS_HDD_LED_12")
	)
	(segment
		(start 90.500962 -228.9429)
		(end 87.757 -228.9429)
		(width 0.1143)
		(layer "F.Cu")
		(net "SAS_HDD_LED_12")
	)
	(segment
		(start 88.5825 -232.791)
		(end 88.5825 -234.1118)
		(width 0.1143)
		(layer "F.Cu")
		(net "SAS_HDD_LED_12")
	)
	(segment
		(start 93.7006 -228.68636)
		(end 92.86494 -228.68636)
		(width 0.1143)
		(layer "F.Cu")
		(net "SAS_HDD_LED_12")
	)
	(segment
		(start 86.3219 -230.378)
		(end 85.852 -230.378)
		(width 0.1143)
		(layer "F.Cu")
		(net "SAS_HDD_LED_12")
	)
	(via
		(at 85.852 -230.378)
		(size 0.7112)
		(drill 0.3556)
		(layers "F.Cu" "B.Cu")
		(net "SAS_HDD_LED_12")
	)
	(segment
		(start 93.7006 -229.3366)
		(end 95.0214 -229.3366)
		(width 0.1143)
		(layer "F.Cu")
		(net "SAS_HDD_LED_11")
	)
	(segment
		(start 91.192096 -228.77272)
		(end 92.430346 -228.77272)
		(width 0.1143)
		(layer "F.Cu")
		(net "SAS_HDD_LED_11")
	)
	(segment
		(start 90.653616 -229.3112)
		(end 91.192096 -228.77272)
		(width 0.1143)
		(layer "F.Cu")
		(net "SAS_HDD_LED_11")
	)
	(segment
		(start 87.85225 -235.42625)
		(end 86.270592 -235.42625)
		(width 0.1143)
		(layer "F.Cu")
		(net "SAS_HDD_LED_11")
	)
	(segment
		(start 86.270592 -235.42625)
		(end 85.94725 -235.102908)
		(width 0.1143)
		(layer "F.Cu")
		(net "SAS_HDD_LED_11")
	)
	(segment
		(start 85.94725 -231.285796)
		(end 87.921846 -229.3112)
		(width 0.1143)
		(layer "F.Cu")
		(net "SAS_HDD_LED_11")
	)
	(segment
		(start 87.9475 -234.1118)
		(end 87.9475 -235.331)
		(width 0.1143)
		(layer "F.Cu")
		(net "SAS_HDD_LED_11")
	)
	(segment
		(start 85.94725 -235.102908)
		(end 85.94725 -231.285796)
		(width 0.1143)
		(layer "F.Cu")
		(net "SAS_HDD_LED_11")
	)
	(segment
		(start 87.921846 -229.3112)
		(end 90.653616 -229.3112)
		(width 0.1143)
		(layer "F.Cu")
		(net "SAS_HDD_LED_11")
	)
	(segment
		(start 87.9475 -235.331)
		(end 87.85225 -235.42625)
		(width 0.1143)
		(layer "F.Cu")
		(net "SAS_HDD_LED_11")
	)
	(segment
		(start 92.430346 -228.77272)
		(end 92.994226 -229.3366)
		(width 0.1143)
		(layer "F.Cu")
		(net "SAS_HDD_LED_11")
	)
	(segment
		(start 92.994226 -229.3366)
		(end 93.7006 -229.3366)
		(width 0.1143)
		(layer "F.Cu")
		(net "SAS_HDD_LED_11")
	)
	(segment
		(start 95.0214 -229.3366)
		(end 95.377 -228.981)
		(width 0.1143)
		(layer "F.Cu")
		(net "SAS_HDD_LED_11")
	)
	(via
		(at 95.377 -228.981)
		(size 0.5588)
		(drill 0.3048)
		(layers "F.Cu" "B.Cu")
		(net "SAS_HDD_LED_11")
	)
	(via
		(at 94.4626 -228.9556)
		(size 0.7112)
		(drill 0.3556)
		(layers "F.Cu" "B.Cu")
		(net "SAS_HDD_LED_11")
	)
	(segment
		(start 95.377 -228.981)
		(end 96.4565 -228.981)
		(width 0.1143)
		(layer "B.Cu")
		(net "SAS_HDD_LED_11")
	)
	(segment
		(start 94.4626 -228.9556)
		(end 95.3516 -228.9556)
		(width 0.1143)
		(layer "B.Cu")
		(net "SAS_HDD_LED_11")
	)
	(segment
		(start 95.3516 -228.9556)
		(end 95.377 -228.981)
		(width 0.1143)
		(layer "B.Cu")
		(net "SAS_HDD_LED_11")
	)
	(segment
		(start 92.075 -229.14102)
		(end 92.92082 -229.98684)
		(width 0.1143)
		(layer "F.Cu")
		(net "SAS_HDD_LED_10")
	)
	(segment
		(start 86.423246 -235.05795)
		(end 86.31555 -234.950254)
		(width 0.1143)
		(layer "F.Cu")
		(net "SAS_HDD_LED_10")
	)
	(segment
		(start 86.9569 -235.05795)
		(end 86.423246 -235.05795)
		(width 0.1143)
		(layer "F.Cu")
		(net "SAS_HDD_LED_10")
	)
	(segment
		(start 91.34475 -229.14102)
		(end 92.075 -229.14102)
		(width 0.1143)
		(layer "F.Cu")
		(net "SAS_HDD_LED_10")
	)
	(segment
		(start 90.80627 -229.6795)
		(end 91.34475 -229.14102)
		(width 0.1143)
		(layer "F.Cu")
		(net "SAS_HDD_LED_10")
	)
	(segment
		(start 93.7006 -229.98684)
		(end 95.23984 -229.98684)
		(width 0.1143)
		(layer "F.Cu")
		(net "SAS_HDD_LED_10")
	)
	(segment
		(start 88.0745 -229.6795)
		(end 90.80627 -229.6795)
		(width 0.1143)
		(layer "F.Cu")
		(net "SAS_HDD_LED_10")
	)
	(segment
		(start 92.92082 -229.98684)
		(end 93.7006 -229.98684)
		(width 0.1143)
		(layer "F.Cu")
		(net "SAS_HDD_LED_10")
	)
	(segment
		(start 86.31555 -234.950254)
		(end 86.31555 -231.43845)
		(width 0.1143)
		(layer "F.Cu")
		(net "SAS_HDD_LED_10")
	)
	(segment
		(start 87.3125 -234.1118)
		(end 87.3125 -234.70235)
		(width 0.1143)
		(layer "F.Cu")
		(net "SAS_HDD_LED_10")
	)
	(segment
		(start 95.23984 -229.98684)
		(end 95.377 -230.124)
		(width 0.1143)
		(layer "F.Cu")
		(net "SAS_HDD_LED_10")
	)
	(segment
		(start 86.31555 -231.43845)
		(end 88.0745 -229.6795)
		(width 0.1143)
		(layer "F.Cu")
		(net "SAS_HDD_LED_10")
	)
	(segment
		(start 87.3125 -234.70235)
		(end 86.9569 -235.05795)
		(width 0.1143)
		(layer "F.Cu")
		(net "SAS_HDD_LED_10")
	)
	(via
		(at 95.377 -230.124)
		(size 0.5588)
		(drill 0.3048)
		(layers "F.Cu" "B.Cu")
		(net "SAS_HDD_LED_10")
	)
	(via
		(at 95.4024 -231.0384)
		(size 0.7112)
		(drill 0.3556)
		(layers "F.Cu" "B.Cu")
		(net "SAS_HDD_LED_10")
	)
	(segment
		(start 95.4024 -231.0384)
		(end 95.4024 -230.1494)
		(width 0.1143)
		(layer "B.Cu")
		(net "SAS_HDD_LED_10")
	)
	(segment
		(start 95.377 -230.124)
		(end 96.4565 -230.124)
		(width 0.1143)
		(layer "B.Cu")
		(net "SAS_HDD_LED_10")
	)
	(segment
		(start 95.4024 -230.1494)
		(end 95.377 -230.124)
		(width 0.1143)
		(layer "B.Cu")
		(net "SAS_HDD_LED_10")
	)
	(segment
		(start 97.536 -233.3625)
		(end 97.536 -233.299)
		(width 0.1143)
		(layer "F.Cu")
		(net "SAS_HDD_LED_8")
	)
	(segment
		(start 96.012 -231.775)
		(end 94.107 -231.775)
		(width 0.1143)
		(layer "F.Cu")
		(net "SAS_HDD_LED_8")
	)
	(segment
		(start 100.965 -232.537)
		(end 98.171 -232.537)
		(width 0.1143)
		(layer "F.Cu")
		(net "SAS_HDD_LED_8")
	)
	(segment
		(start 105.6005 -234.2388)
		(end 105.6005 -231.3305)
		(width 0.1143)
		(layer "F.Cu")
		(net "SAS_HDD_LED_8")
	)
	(segment
		(start 96.647 -232.41)
		(end 96.012 -231.775)
		(width 0.1143)
		(layer "F.Cu")
		(net "SAS_HDD_LED_8")
	)
	(segment
		(start 105.1306 -230.8606)
		(end 102.6414 -230.8606)
		(width 0.1143)
		(layer "F.Cu")
		(net "SAS_HDD_LED_8")
	)
	(segment
		(start 94.107 -231.775)
		(end 93.7006 -231.3686)
		(width 0.1143)
		(layer "F.Cu")
		(net "SAS_HDD_LED_8")
	)
	(segment
		(start 97.536 -233.299)
		(end 96.647 -232.41)
		(width 0.1143)
		(layer "F.Cu")
		(net "SAS_HDD_LED_8")
	)
	(segment
		(start 102.6414 -230.8606)
		(end 100.965 -232.537)
		(width 0.1143)
		(layer "F.Cu")
		(net "SAS_HDD_LED_8")
	)
	(segment
		(start 98.171 -232.537)
		(end 96.92132 -231.28732)
		(width 0.1143)
		(layer "F.Cu")
		(net "SAS_HDD_LED_8")
	)
	(segment
		(start 93.7006 -231.3686)
		(end 93.7006 -231.28732)
		(width 0.1143)
		(layer "F.Cu")
		(net "SAS_HDD_LED_8")
	)
	(segment
		(start 105.6005 -231.3305)
		(end 105.1306 -230.8606)
		(width 0.1143)
		(layer "F.Cu")
		(net "SAS_HDD_LED_8")
	)
	(segment
		(start 96.92132 -231.28732)
		(end 93.7006 -231.28732)
		(width 0.1143)
		(layer "F.Cu")
		(net "SAS_HDD_LED_8")
	)
	(via
		(at 96.647 -232.41)
		(size 0.7112)
		(drill 0.3556)
		(layers "F.Cu" "B.Cu")
		(net "SAS_HDD_LED_8")
	)
	(segment
		(start 102.108 -230.124)
		(end 101.675692 -230.556308)
		(width 0.1143)
		(layer "F.Cu")
		(net "SAS_HDD_LED_7")
	)
	(segment
		(start 99.3394 -230.63708)
		(end 101.21392 -230.63708)
		(width 0.1143)
		(layer "F.Cu")
		(net "SAS_HDD_LED_7")
	)
	(segment
		(start 107.48645 -232.162096)
		(end 105.448354 -230.124)
		(width 0.1143)
		(layer "F.Cu")
		(net "SAS_HDD_LED_7")
	)
	(segment
		(start 104.3305 -231.521)
		(end 104.902 -232.0925)
		(width 0.1143)
		(layer "F.Cu")
		(net "SAS_HDD_LED_7")
	)
	(segment
		(start 104.902 -232.0925)
		(end 104.902 -234.1753)
		(width 0.1143)
		(layer "F.Cu")
		(net "SAS_HDD_LED_7")
	)
	(segment
		(start 107.124754 -235.18495)
		(end 107.48645 -234.823254)
		(width 0.1143)
		(layer "F.Cu")
		(net "SAS_HDD_LED_7")
	)
	(segment
		(start 107.48645 -234.823254)
		(end 107.48645 -232.162096)
		(width 0.1143)
		(layer "F.Cu")
		(net "SAS_HDD_LED_7")
	)
	(segment
		(start 105.448354 -230.124)
		(end 102.108 -230.124)
		(width 0.1143)
		(layer "F.Cu")
		(net "SAS_HDD_LED_7")
	)
	(segment
		(start 104.902 -234.1753)
		(end 104.9655 -234.2388)
		(width 0.1143)
		(layer "F.Cu")
		(net "SAS_HDD_LED_7")
	)
	(segment
		(start 104.9655 -234.2388)
		(end 104.9655 -235.0135)
		(width 0.1143)
		(layer "F.Cu")
		(net "SAS_HDD_LED_7")
	)
	(segment
		(start 101.21392 -230.63708)
		(end 101.219 -230.632)
		(width 0.1143)
		(layer "F.Cu")
		(net "SAS_HDD_LED_7")
	)
	(segment
		(start 101.675692 -230.556308)
		(end 101.294692 -230.556308)
		(width 0.1143)
		(layer "F.Cu")
		(net "SAS_HDD_LED_7")
	)
	(segment
		(start 105.13695 -235.18495)
		(end 107.124754 -235.18495)
		(width 0.1143)
		(layer "F.Cu")
		(net "SAS_HDD_LED_7")
	)
	(segment
		(start 104.9655 -235.0135)
		(end 105.13695 -235.18495)
		(width 0.1143)
		(layer "F.Cu")
		(net "SAS_HDD_LED_7")
	)
	(segment
		(start 101.294692 -230.556308)
		(end 101.219 -230.632)
		(width 0.1143)
		(layer "F.Cu")
		(net "SAS_HDD_LED_7")
	)
	(via
		(at 101.219 -230.632)
		(size 0.7112)
		(drill 0.3556)
		(layers "F.Cu" "B.Cu")
		(net "SAS_HDD_LED_7")
	)
	(segment
		(start 105.404158 -229.55885)
		(end 103.505 -229.55885)
		(width 0.1143)
		(layer "F.Cu")
		(net "SAS_HDD_LED_6")
	)
	(segment
		(start 99.3394 -229.98684)
		(end 100.19284 -229.98684)
		(width 0.1143)
		(layer "F.Cu")
		(net "SAS_HDD_LED_6")
	)
	(segment
		(start 107.85475 -234.975908)
		(end 107.85475 -232.009442)
		(width 0.1143)
		(layer "F.Cu")
		(net "SAS_HDD_LED_6")
	)
	(segment
		(start 100.927662 -230.124)
		(end 100.984812 -230.06685)
		(width 0.1143)
		(layer "F.Cu")
		(net "SAS_HDD_LED_6")
	)
	(segment
		(start 104.3305 -235.2548)
		(end 104.62895 -235.55325)
		(width 0.1143)
		(layer "F.Cu")
		(net "SAS_HDD_LED_6")
	)
	(segment
		(start 100.984812 -230.06685)
		(end 101.644196 -230.06685)
		(width 0.1143)
		(layer "F.Cu")
		(net "SAS_HDD_LED_6")
	)
	(segment
		(start 104.3305 -234.2388)
		(end 104.3305 -235.2548)
		(width 0.1143)
		(layer "F.Cu")
		(net "SAS_HDD_LED_6")
	)
	(segment
		(start 104.62895 -235.55325)
		(end 107.277408 -235.55325)
		(width 0.1143)
		(layer "F.Cu")
		(net "SAS_HDD_LED_6")
	)
	(segment
		(start 104.3305 -232.537)
		(end 104.3305 -234.2388)
		(width 0.1143)
		(layer "F.Cu")
		(net "SAS_HDD_LED_6")
	)
	(segment
		(start 107.277408 -235.55325)
		(end 107.85475 -234.975908)
		(width 0.1143)
		(layer "F.Cu")
		(net "SAS_HDD_LED_6")
	)
	(segment
		(start 102.152196 -229.55885)
		(end 103.505 -229.55885)
		(width 0.1143)
		(layer "F.Cu")
		(net "SAS_HDD_LED_6")
	)
	(segment
		(start 100.33 -230.124)
		(end 100.927662 -230.124)
		(width 0.1143)
		(layer "F.Cu")
		(net "SAS_HDD_LED_6")
	)
	(segment
		(start 101.644196 -230.06685)
		(end 102.152196 -229.55885)
		(width 0.1143)
		(layer "F.Cu")
		(net "SAS_HDD_LED_6")
	)
	(segment
		(start 107.85475 -232.009442)
		(end 105.404158 -229.55885)
		(width 0.1143)
		(layer "F.Cu")
		(net "SAS_HDD_LED_6")
	)
	(segment
		(start 100.19284 -229.98684)
		(end 100.33 -230.124)
		(width 0.1143)
		(layer "F.Cu")
		(net "SAS_HDD_LED_6")
	)
	(via
		(at 103.505 -229.55885)
		(size 0.7112)
		(drill 0.3556)
		(layers "F.Cu" "B.Cu")
		(net "SAS_HDD_LED_6")
	)
	(segment
		(start 108.22305 -235.128562)
		(end 108.22305 -231.856534)
		(width 0.1143)
		(layer "F.Cu")
		(net "SAS_HDD_LED_5")
	)
	(segment
		(start 100.457 -229.616)
		(end 100.711 -229.616)
		(width 0.1143)
		(layer "F.Cu")
		(net "SAS_HDD_LED_5")
	)
	(segment
		(start 99.3394 -229.3366)
		(end 100.1776 -229.3366)
		(width 0.1143)
		(layer "F.Cu")
		(net "SAS_HDD_LED_5")
	)
	(segment
		(start 108.22305 -231.856534)
		(end 105.220516 -228.854)
		(width 0.1143)
		(layer "F.Cu")
		(net "SAS_HDD_LED_5")
	)
	(segment
		(start 105.220516 -228.854)
		(end 102.291642 -228.854)
		(width 0.1143)
		(layer "F.Cu")
		(net "SAS_HDD_LED_5")
	)
	(segment
		(start 103.6955 -235.3818)
		(end 104.23525 -235.92155)
		(width 0.1143)
		(layer "F.Cu")
		(net "SAS_HDD_LED_5")
	)
	(segment
		(start 107.430062 -235.92155)
		(end 108.22305 -235.128562)
		(width 0.1143)
		(layer "F.Cu")
		(net "SAS_HDD_LED_5")
	)
	(segment
		(start 101.529642 -229.616)
		(end 100.711 -229.616)
		(width 0.1143)
		(layer "F.Cu")
		(net "SAS_HDD_LED_5")
	)
	(segment
		(start 103.6955 -234.2388)
		(end 103.6955 -235.3818)
		(width 0.1143)
		(layer "F.Cu")
		(net "SAS_HDD_LED_5")
	)
	(segment
		(start 100.1776 -229.3366)
		(end 100.457 -229.616)
		(width 0.1143)
		(layer "F.Cu")
		(net "SAS_HDD_LED_5")
	)
	(segment
		(start 104.23525 -235.92155)
		(end 107.430062 -235.92155)
		(width 0.1143)
		(layer "F.Cu")
		(net "SAS_HDD_LED_5")
	)
	(segment
		(start 102.291642 -228.854)
		(end 101.529642 -229.616)
		(width 0.1143)
		(layer "F.Cu")
		(net "SAS_HDD_LED_5")
	)
	(via
		(at 100.711 -229.616)
		(size 0.5588)
		(drill 0.3048)
		(layers "F.Cu" "B.Cu")
		(net "SAS_HDD_LED_5")
	)
	(via
		(at 101.473 -230.759)
		(size 0.7112)
		(drill 0.3556)
		(layers "F.Cu" "B.Cu")
		(net "SAS_HDD_LED_5")
	)
	(segment
		(start 100.711 -229.997)
		(end 100.711 -229.616)
		(width 0.1143)
		(layer "B.Cu")
		(net "SAS_HDD_LED_5")
	)
	(segment
		(start 102.5525 -231.013)
		(end 101.727 -231.013)
		(width 0.1143)
		(layer "B.Cu")
		(net "SAS_HDD_LED_5")
	)
	(segment
		(start 101.727 -231.013)
		(end 101.473 -230.759)
		(width 0.1143)
		(layer "B.Cu")
		(net "SAS_HDD_LED_5")
	)
	(segment
		(start 101.473 -230.759)
		(end 100.711 -229.997)
		(width 0.1143)
		(layer "B.Cu")
		(net "SAS_HDD_LED_5")
	)
	(segment
		(start 100.137468 -228.68636)
		(end 100.465128 -229.01402)
		(width 0.1143)
		(layer "F.Cu")
		(net "SAS_HDD_LED_4")
	)
	(segment
		(start 102.235 -228.219)
		(end 101.473 -228.981)
		(width 0.1143)
		(layer "F.Cu")
		(net "SAS_HDD_LED_4")
	)
	(segment
		(start 103.0605 -234.2388)
		(end 103.0605 -235.2929)
		(width 0.1143)
		(layer "F.Cu")
		(net "SAS_HDD_LED_4")
	)
	(segment
		(start 108.59135 -235.281216)
		(end 108.59135 -231.296718)
		(width 0.1143)
		(layer "F.Cu")
		(net "SAS_HDD_LED_4")
	)
	(segment
		(start 108.59135 -231.296718)
		(end 105.513632 -228.219)
		(width 0.1143)
		(layer "F.Cu")
		(net "SAS_HDD_LED_4")
	)
	(segment
		(start 100.465128 -229.01402)
		(end 101.43998 -229.01402)
		(width 0.1143)
		(layer "F.Cu")
		(net "SAS_HDD_LED_4")
	)
	(segment
		(start 99.3394 -228.68636)
		(end 100.137468 -228.68636)
		(width 0.1143)
		(layer "F.Cu")
		(net "SAS_HDD_LED_4")
	)
	(segment
		(start 103.0605 -235.2929)
		(end 104.05745 -236.28985)
		(width 0.1143)
		(layer "F.Cu")
		(net "SAS_HDD_LED_4")
	)
	(segment
		(start 105.513632 -228.219)
		(end 104.394 -228.219)
		(width 0.1143)
		(layer "F.Cu")
		(net "SAS_HDD_LED_4")
	)
	(segment
		(start 107.582716 -236.28985)
		(end 108.59135 -235.281216)
		(width 0.1143)
		(layer "F.Cu")
		(net "SAS_HDD_LED_4")
	)
	(segment
		(start 104.05745 -236.28985)
		(end 107.582716 -236.28985)
		(width 0.1143)
		(layer "F.Cu")
		(net "SAS_HDD_LED_4")
	)
	(segment
		(start 101.43998 -229.01402)
		(end 101.473 -228.981)
		(width 0.1143)
		(layer "F.Cu")
		(net "SAS_HDD_LED_4")
	)
	(segment
		(start 104.394 -228.219)
		(end 102.235 -228.219)
		(width 0.1143)
		(layer "F.Cu")
		(net "SAS_HDD_LED_4")
	)
	(via
		(at 104.394 -228.219)
		(size 0.7112)
		(drill 0.3556)
		(layers "F.Cu" "B.Cu")
		(net "SAS_HDD_LED_4")
	)
	(via
		(at 101.473 -228.981)
		(size 0.5588)
		(drill 0.3048)
		(layers "F.Cu" "B.Cu")
		(net "SAS_HDD_LED_4")
	)
	(segment
		(start 102.5525 -229.997)
		(end 102.489 -229.997)
		(width 0.1143)
		(layer "B.Cu")
		(net "SAS_HDD_LED_4")
	)
	(segment
		(start 102.489 -229.997)
		(end 101.473 -228.981)
		(width 0.1143)
		(layer "B.Cu")
		(net "SAS_HDD_LED_4")
	)
	(segment
		(start 102.4255 -234.2388)
		(end 102.4255 -235.178854)
		(width 0.1143)
		(layer "F.Cu")
		(net "SAS_HDD_LED_3")
	)
	(segment
		(start 107.73537 -236.65815)
		(end 108.95965 -235.43387)
		(width 0.1143)
		(layer "F.Cu")
		(net "SAS_HDD_LED_3")
	)
	(segment
		(start 100.17887 -228.03612)
		(end 100.66782 -228.52507)
		(width 0.1143)
		(layer "F.Cu")
		(net "SAS_HDD_LED_3")
	)
	(segment
		(start 101.73589 -227.457)
		(end 103.124 -227.457)
		(width 0.1143)
		(layer "F.Cu")
		(net "SAS_HDD_LED_3")
	)
	(segment
		(start 103.904796 -236.65815)
		(end 107.73537 -236.65815)
		(width 0.1143)
		(layer "F.Cu")
		(net "SAS_HDD_LED_3")
	)
	(segment
		(start 105.272586 -227.457)
		(end 103.124 -227.457)
		(width 0.1143)
		(layer "F.Cu")
		(net "SAS_HDD_LED_3")
	)
	(segment
		(start 108.95965 -235.43387)
		(end 108.95965 -231.144064)
		(width 0.1143)
		(layer "F.Cu")
		(net "SAS_HDD_LED_3")
	)
	(segment
		(start 100.66782 -228.52507)
		(end 101.73589 -227.457)
		(width 0.1143)
		(layer "F.Cu")
		(net "SAS_HDD_LED_3")
	)
	(segment
		(start 108.95965 -231.144064)
		(end 105.272586 -227.457)
		(width 0.1143)
		(layer "F.Cu")
		(net "SAS_HDD_LED_3")
	)
	(segment
		(start 102.4255 -235.178854)
		(end 103.904796 -236.65815)
		(width 0.1143)
		(layer "F.Cu")
		(net "SAS_HDD_LED_3")
	)
	(segment
		(start 99.3394 -228.03612)
		(end 100.17887 -228.03612)
		(width 0.1143)
		(layer "F.Cu")
		(net "SAS_HDD_LED_3")
	)
	(via
		(at 103.124 -227.457)
		(size 0.7112)
		(drill 0.3556)
		(layers "F.Cu" "B.Cu")
		(net "SAS_HDD_LED_3")
	)
	(via
		(at 100.66782 -228.52507)
		(size 0.5588)
		(drill 0.3048)
		(layers "F.Cu" "B.Cu")
		(net "SAS_HDD_LED_3")
	)
	(segment
		(start 102.5525 -228.981)
		(end 102.5525 -228.727)
		(width 0.1143)
		(layer "B.Cu")
		(net "SAS_HDD_LED_3")
	)
	(segment
		(start 101.708712 -228.52507)
		(end 101.675692 -228.49205)
		(width 0.1143)
		(layer "B.Cu")
		(net "SAS_HDD_LED_3")
	)
	(segment
		(start 102.5525 -228.727)
		(end 102.35057 -228.52507)
		(width 0.1143)
		(layer "B.Cu")
		(net "SAS_HDD_LED_3")
	)
	(segment
		(start 101.270308 -228.49205)
		(end 101.237288 -228.52507)
		(width 0.1143)
		(layer "B.Cu")
		(net "SAS_HDD_LED_3")
	)
	(segment
		(start 101.675692 -228.49205)
		(end 101.270308 -228.49205)
		(width 0.1143)
		(layer "B.Cu")
		(net "SAS_HDD_LED_3")
	)
	(segment
		(start 102.35057 -228.52507)
		(end 101.708712 -228.52507)
		(width 0.1143)
		(layer "B.Cu")
		(net "SAS_HDD_LED_3")
	)
	(segment
		(start 101.237288 -228.52507)
		(end 100.66782 -228.52507)
		(width 0.1143)
		(layer "B.Cu")
		(net "SAS_HDD_LED_3")
	)
	(segment
		(start 101.6 -226.822)
		(end 101.03612 -227.38588)
		(width 0.1143)
		(layer "F.Cu")
		(net "SAS_HDD_LED_2")
	)
	(segment
		(start 99.3394 -227.38588)
		(end 100.57511 -227.38588)
		(width 0.1143)
		(layer "F.Cu")
		(net "SAS_HDD_LED_2")
	)
	(segment
		(start 107.888024 -237.02645)
		(end 109.32795 -235.586524)
		(width 0.1143)
		(layer "F.Cu")
		(net "SAS_HDD_LED_2")
	)
	(segment
		(start 104.521 -226.822)
		(end 101.6 -226.822)
		(width 0.1143)
		(layer "F.Cu")
		(net "SAS_HDD_LED_2")
	)
	(segment
		(start 109.32795 -230.99141)
		(end 105.15854 -226.822)
		(width 0.1143)
		(layer "F.Cu")
		(net "SAS_HDD_LED_2")
	)
	(segment
		(start 101.7905 -235.9279)
		(end 102.88905 -237.02645)
		(width 0.1143)
		(layer "F.Cu")
		(net "SAS_HDD_LED_2")
	)
	(segment
		(start 109.32795 -235.586524)
		(end 109.32795 -230.99141)
		(width 0.1143)
		(layer "F.Cu")
		(net "SAS_HDD_LED_2")
	)
	(segment
		(start 101.03612 -227.38588)
		(end 100.89769 -227.38588)
		(width 0.1143)
		(layer "F.Cu")
		(net "SAS_HDD_LED_2")
	)
	(segment
		(start 100.89769 -227.38588)
		(end 100.7364 -227.54717)
		(width 0.1143)
		(layer "F.Cu")
		(net "SAS_HDD_LED_2")
	)
	(segment
		(start 101.7905 -234.2388)
		(end 101.7905 -235.9279)
		(width 0.1143)
		(layer "F.Cu")
		(net "SAS_HDD_LED_2")
	)
	(segment
		(start 100.57511 -227.38588)
		(end 100.7364 -227.54717)
		(width 0.1143)
		(layer "F.Cu")
		(net "SAS_HDD_LED_2")
	)
	(segment
		(start 105.15854 -226.822)
		(end 104.521 -226.822)
		(width 0.1143)
		(layer "F.Cu")
		(net "SAS_HDD_LED_2")
	)
	(segment
		(start 102.88905 -237.02645)
		(end 107.888024 -237.02645)
		(width 0.1143)
		(layer "F.Cu")
		(net "SAS_HDD_LED_2")
	)
	(via
		(at 100.7364 -227.54717)
		(size 0.5588)
		(drill 0.3048)
		(layers "F.Cu" "B.Cu")
		(net "SAS_HDD_LED_2")
	)
	(via
		(at 104.521 -226.822)
		(size 0.7112)
		(drill 0.3556)
		(layers "F.Cu" "B.Cu")
		(net "SAS_HDD_LED_2")
	)
	(segment
		(start 102.5525 -227.965)
		(end 101.15423 -227.965)
		(width 0.1143)
		(layer "B.Cu")
		(net "SAS_HDD_LED_2")
	)
	(segment
		(start 101.15423 -227.965)
		(end 100.7364 -227.54717)
		(width 0.1143)
		(layer "B.Cu")
		(net "SAS_HDD_LED_2")
	)
	(segment
		(start 105.044494 -226.187)
		(end 101.432868 -226.187)
		(width 0.1143)
		(layer "F.Cu")
		(net "SAS_HDD_LED_1")
	)
	(segment
		(start 109.69625 -230.838756)
		(end 105.044494 -226.187)
		(width 0.1143)
		(layer "F.Cu")
		(net "SAS_HDD_LED_1")
	)
	(segment
		(start 101.046534 -226.573334)
		(end 100.995734 -226.573334)
		(width 0.1143)
		(layer "F.Cu")
		(net "SAS_HDD_LED_1")
	)
	(segment
		(start 99.3394 -226.73564)
		(end 100.82276 -226.73564)
		(width 0.1143)
		(layer "F.Cu")
		(net "SAS_HDD_LED_1")
	)
	(segment
		(start 101.1555 -234.2388)
		(end 101.1555 -236.2835)
		(width 0.1143)
		(layer "F.Cu")
		(net "SAS_HDD_LED_1")
	)
	(segment
		(start 100.82276 -226.73564)
		(end 100.9904 -226.568)
		(width 0.1143)
		(layer "F.Cu")
		(net "SAS_HDD_LED_1")
	)
	(segment
		(start 109.69625 -235.739178)
		(end 109.69625 -230.838756)
		(width 0.1143)
		(layer "F.Cu")
		(net "SAS_HDD_LED_1")
	)
	(segment
		(start 101.1555 -236.2835)
		(end 102.26675 -237.39475)
		(width 0.1143)
		(layer "F.Cu")
		(net "SAS_HDD_LED_1")
	)
	(segment
		(start 101.432868 -226.187)
		(end 101.046534 -226.573334)
		(width 0.1143)
		(layer "F.Cu")
		(net "SAS_HDD_LED_1")
	)
	(segment
		(start 108.040678 -237.39475)
		(end 109.69625 -235.739178)
		(width 0.1143)
		(layer "F.Cu")
		(net "SAS_HDD_LED_1")
	)
	(segment
		(start 102.26675 -237.39475)
		(end 108.040678 -237.39475)
		(width 0.1143)
		(layer "F.Cu")
		(net "SAS_HDD_LED_1")
	)
	(segment
		(start 100.995734 -226.573334)
		(end 100.9904 -226.568)
		(width 0.1143)
		(layer "F.Cu")
		(net "SAS_HDD_LED_1")
	)
	(via
		(at 101.6 -225.679)
		(size 0.7112)
		(drill 0.3556)
		(layers "F.Cu" "B.Cu")
		(net "SAS_HDD_LED_1")
	)
	(via
		(at 100.9904 -226.568)
		(size 0.5588)
		(drill 0.3048)
		(layers "F.Cu" "B.Cu")
		(net "SAS_HDD_LED_1")
	)
	(segment
		(start 102.2985 -225.679)
		(end 101.6 -225.679)
		(width 0.1143)
		(layer "B.Cu")
		(net "SAS_HDD_LED_1")
	)
	(segment
		(start 100.9904 -226.2886)
		(end 101.6 -225.679)
		(width 0.1143)
		(layer "B.Cu")
		(net "SAS_HDD_LED_1")
	)
	(segment
		(start 100.9904 -226.568)
		(end 100.9904 -226.2886)
		(width 0.1143)
		(layer "B.Cu")
		(net "SAS_HDD_LED_1")
	)
	(segment
		(start 102.5525 -225.933)
		(end 102.2985 -225.679)
		(width 0.1143)
		(layer "B.Cu")
		(net "SAS_HDD_LED_1")
	)
	(segment
		(start 100.5205 -234.2388)
		(end 100.5205 -236.3343)
		(width 0.1143)
		(layer "F.Cu")
		(net "SAS_HDD_LED_0")
	)
	(segment
		(start 101.94925 -237.76305)
		(end 108.193332 -237.76305)
		(width 0.1143)
		(layer "F.Cu")
		(net "SAS_HDD_LED_0")
	)
	(segment
		(start 105.057448 -225.679)
		(end 100.711 -225.679)
		(width 0.1143)
		(layer "F.Cu")
		(net "SAS_HDD_LED_0")
	)
	(segment
		(start 99.3394 -226.0854)
		(end 100.3046 -226.0854)
		(width 0.1143)
		(layer "F.Cu")
		(net "SAS_HDD_LED_0")
	)
	(segment
		(start 110.06455 -235.891832)
		(end 110.06455 -230.686102)
		(width 0.1143)
		(layer "F.Cu")
		(net "SAS_HDD_LED_0")
	)
	(segment
		(start 100.5205 -236.3343)
		(end 101.94925 -237.76305)
		(width 0.1143)
		(layer "F.Cu")
		(net "SAS_HDD_LED_0")
	)
	(segment
		(start 100.3046 -226.0854)
		(end 100.711 -225.679)
		(width 0.1143)
		(layer "F.Cu")
		(net "SAS_HDD_LED_0")
	)
	(segment
		(start 108.193332 -237.76305)
		(end 110.06455 -235.891832)
		(width 0.1143)
		(layer "F.Cu")
		(net "SAS_HDD_LED_0")
	)
	(segment
		(start 110.06455 -230.686102)
		(end 105.057448 -225.679)
		(width 0.1143)
		(layer "F.Cu")
		(net "SAS_HDD_LED_0")
	)
	(via
		(at 101.6508 -227.05695)
		(size 0.7112)
		(drill 0.3556)
		(layers "F.Cu" "B.Cu")
		(net "SAS_HDD_LED_0")
	)
	(via
		(at 100.711 -225.679)
		(size 0.5588)
		(drill 0.3048)
		(layers "F.Cu" "B.Cu")
		(net "SAS_HDD_LED_0")
	)
	(segment
		(start 102.44455 -227.05695)
		(end 101.6508 -227.05695)
		(width 0.1143)
		(layer "B.Cu")
		(net "SAS_HDD_LED_0")
	)
	(segment
		(start 100.787708 -227.05695)
		(end 100.50145 -226.770692)
		(width 0.1143)
		(layer "B.Cu")
		(net "SAS_HDD_LED_0")
	)
	(segment
		(start 100.50145 -226.770692)
		(end 100.50145 -225.888804)
		(width 0.1143)
		(layer "B.Cu")
		(net "SAS_HDD_LED_0")
	)
	(segment
		(start 101.6508 -227.05695)
		(end 100.787708 -227.05695)
		(width 0.1143)
		(layer "B.Cu")
		(net "SAS_HDD_LED_0")
	)
	(segment
		(start 100.50145 -225.888804)
		(end 100.711 -225.679)
		(width 0.1143)
		(layer "B.Cu")
		(net "SAS_HDD_LED_0")
	)
	(segment
		(start 102.5525 -226.949)
		(end 102.44455 -227.05695)
		(width 0.1143)
		(layer "B.Cu")
		(net "SAS_HDD_LED_0")
	)
	(segment
		(start 337.3628 -12.7)
		(end 336.296 -12.7)
		(width 0.1778)
		(layer "F.Cu")
		(net "EXP_BMC_HB_LED_R")
	)
	(segment
		(start 337.5533 -12.8905)
		(end 337.3628 -12.7)
		(width 0.1778)
		(layer "F.Cu")
		(net "EXP_BMC_HB_LED_R")
	)
	(segment
		(start 338.455 -12.8905)
		(end 337.5533 -12.8905)
		(width 0.1778)
		(layer "F.Cu")
		(net "EXP_BMC_HB_LED_R")
	)
	(via
		(at 337.3628 -12.7)
		(size 0.7112)
		(drill 0.3556)
		(layers "F.Cu" "B.Cu")
		(net "EXP_BMC_HB_LED_R")
	)
	(segment
		(start 335.153 -14.224)
		(end 334.899 -13.97)
		(width 0.1778)
		(layer "F.Cu")
		(net "EXP_BMC_HB_LED_D")
	)
	(segment
		(start 333.31404 -13.903198)
		(end 334.832198 -13.903198)
		(width 0.1778)
		(layer "F.Cu")
		(net "EXP_BMC_HB_LED_D")
	)
	(segment
		(start 334.832198 -13.903198)
		(end 334.899 -13.97)
		(width 0.1778)
		(layer "F.Cu")
		(net "EXP_BMC_HB_LED_D")
	)
	(segment
		(start 336.296 -14.224)
		(end 335.153 -14.224)
		(width 0.1778)
		(layer "F.Cu")
		(net "EXP_BMC_HB_LED_D")
	)
	(via
		(at 334.899 -13.97)
		(size 0.7112)
		(drill 0.3556)
		(layers "F.Cu" "B.Cu")
		(net "EXP_BMC_HB_LED_D")
	)
	(segment
		(start 6.9469 -217.17)
		(end 7.747 -217.17)
		(width 0.1143)
		(layer "F.Cu")
		(net "PRSNT_AND_1")
	)
	(segment
		(start 8.522716 -216.394284)
		(end 7.747 -217.17)
		(width 0.1143)
		(layer "F.Cu")
		(net "PRSNT_AND_1")
	)
	(segment
		(start 8.522716 -215.84412)
		(end 8.522716 -216.394284)
		(width 0.1143)
		(layer "F.Cu")
		(net "PRSNT_AND_1")
	)
	(segment
		(start 6.7437 -216.9668)
		(end 6.9469 -217.17)
		(width 0.1143)
		(layer "F.Cu")
		(net "PRSNT_AND_1")
	)
	(via
		(at 7.747 -217.17)
		(size 0.7112)
		(drill 0.3556)
		(layers "F.Cu" "B.Cu")
		(net "PRSNT_AND_1")
	)
	(segment
		(start 241.261138 -63.908178)
		(end 264.3759 -87.02294)
		(width 0.1143)
		(layer "F.Cu")
		(net "BMC_ENCLOSURE_LED")
	)
	(segment
		(start 297.688 -193.9036)
		(end 297.688 -193.294)
		(width 0.1143)
		(layer "F.Cu")
		(net "BMC_ENCLOSURE_LED")
	)
	(segment
		(start 300.863 -196.286628)
		(end 300.071028 -196.286628)
		(width 0.1143)
		(layer "F.Cu")
		(net "BMC_ENCLOSURE_LED")
	)
	(segment
		(start 270.7386 -122.8344)
		(end 271.2466 -123.3424)
		(width 0.1143)
		(layer "F.Cu")
		(net "BMC_ENCLOSURE_LED")
	)
	(segment
		(start 241.261138 -15.518638)
		(end 241.261138 -63.908178)
		(width 0.1143)
		(layer "F.Cu")
		(net "BMC_ENCLOSURE_LED")
	)
	(segment
		(start 264.3759 -91.816174)
		(end 270.7386 -98.178874)
		(width 0.1143)
		(layer "F.Cu")
		(net "BMC_ENCLOSURE_LED")
	)
	(segment
		(start 271.3482 -123.444)
		(end 271.2466 -123.3424)
		(width 0.1143)
		(layer "F.Cu")
		(net "BMC_ENCLOSURE_LED")
	)
	(segment
		(start 264.3759 -87.02294)
		(end 264.3759 -91.816174)
		(width 0.1143)
		(layer "F.Cu")
		(net "BMC_ENCLOSURE_LED")
	)
	(segment
		(start 240.8555 -15.113)
		(end 241.261138 -15.518638)
		(width 0.1143)
		(layer "F.Cu")
		(net "BMC_ENCLOSURE_LED")
	)
	(segment
		(start 271.3482 -124.1298)
		(end 271.3482 -123.444)
		(width 0.1143)
		(layer "F.Cu")
		(net "BMC_ENCLOSURE_LED")
	)
	(segment
		(start 300.071028 -196.286628)
		(end 297.688 -193.9036)
		(width 0.1143)
		(layer "F.Cu")
		(net "BMC_ENCLOSURE_LED")
	)
	(segment
		(start 297.688 -193.294)
		(end 297.688 -192.3415)
		(width 0.1143)
		(layer "F.Cu")
		(net "BMC_ENCLOSURE_LED")
	)
	(segment
		(start 270.7386 -98.178874)
		(end 270.7386 -122.8344)
		(width 0.1143)
		(layer "F.Cu")
		(net "BMC_ENCLOSURE_LED")
	)
	(via
		(at 271.3482 -124.1298)
		(size 0.5588)
		(drill 0.3048)
		(layers "F.Cu" "B.Cu")
		(net "BMC_ENCLOSURE_LED")
	)
	(via
		(at 271.2466 -123.3424)
		(size 0.7112)
		(drill 0.3556)
		(layers "F.Cu" "B.Cu")
		(net "BMC_ENCLOSURE_LED")
	)
	(via
		(at 297.688 -193.294)
		(size 0.7112)
		(drill 0.3556)
		(layers "F.Cu" "B.Cu")
		(net "BMC_ENCLOSURE_LED")
	)
	(via
		(at 264.212832 -189.23508)
		(size 0.5588)
		(drill 0.3048)
		(layers "F.Cu" "B.Cu")
		(net "BMC_ENCLOSURE_LED")
	)
	(via
		(at 300.863 -196.286628)
		(size 0.5588)
		(drill 0.3048)
		(layers "F.Cu" "B.Cu")
		(net "BMC_ENCLOSURE_LED")
	)
	(segment
		(start 265.684 -190.706248)
		(end 264.212832 -189.23508)
		(width 0.127)
		(layer "In2.Cu")
		(net "BMC_ENCLOSURE_LED")
	)
	(segment
		(start 296.443654 -204.706728)
		(end 273.457162 -204.706728)
		(width 0.127)
		(layer "In2.Cu")
		(net "BMC_ENCLOSURE_LED")
	)
	(segment
		(start 300.228 -196.921628)
		(end 300.228 -200.922382)
		(width 0.127)
		(layer "In2.Cu")
		(net "BMC_ENCLOSURE_LED")
	)
	(segment
		(start 300.228 -200.922382)
		(end 296.443654 -204.706728)
		(width 0.127)
		(layer "In2.Cu")
		(net "BMC_ENCLOSURE_LED")
	)
	(segment
		(start 265.684 -196.933566)
		(end 265.684 -190.706248)
		(width 0.127)
		(layer "In2.Cu")
		(net "BMC_ENCLOSURE_LED")
	)
	(segment
		(start 300.863 -196.286628)
		(end 300.228 -196.921628)
		(width 0.127)
		(layer "In2.Cu")
		(net "BMC_ENCLOSURE_LED")
	)
	(segment
		(start 273.457162 -204.706728)
		(end 265.684 -196.933566)
		(width 0.127)
		(layer "In2.Cu")
		(net "BMC_ENCLOSURE_LED")
	)
	(segment
		(start 271.3482 -125.07595)
		(end 262.3947 -134.02945)
		(width 0.127)
		(layer "In5.Cu")
		(net "BMC_ENCLOSURE_LED")
	)
	(segment
		(start 262.3947 -161.9377)
		(end 263.0932 -162.6362)
		(width 0.127)
		(layer "In5.Cu")
		(net "BMC_ENCLOSURE_LED")
	)
	(segment
		(start 264.033 -189.055248)
		(end 264.212832 -189.23508)
		(width 0.127)
		(layer "In5.Cu")
		(net "BMC_ENCLOSURE_LED")
	)
	(segment
		(start 264.033 -182.626)
		(end 264.033 -189.055248)
		(width 0.127)
		(layer "In5.Cu")
		(net "BMC_ENCLOSURE_LED")
	)
	(segment
		(start 263.0932 -162.6362)
		(end 263.0932 -181.6862)
		(width 0.127)
		(layer "In5.Cu")
		(net "BMC_ENCLOSURE_LED")
	)
	(segment
		(start 271.3482 -124.1298)
		(end 271.3482 -125.07595)
		(width 0.127)
		(layer "In5.Cu")
		(net "BMC_ENCLOSURE_LED")
	)
	(segment
		(start 263.0932 -181.6862)
		(end 264.033 -182.626)
		(width 0.127)
		(layer "In5.Cu")
		(net "BMC_ENCLOSURE_LED")
	)
	(segment
		(start 262.3947 -134.02945)
		(end 262.3947 -161.9377)
		(width 0.127)
		(layer "In5.Cu")
		(net "BMC_ENCLOSURE_LED")
	)
	(segment
		(start 302.641 -208.534)
		(end 302.641 -204.978)
		(width 0.1143)
		(layer "F.Cu")
		(net "BMC0_TACH9")
	)
	(segment
		(start 302.641 -195.326)
		(end 302.26 -194.945)
		(width 0.1143)
		(layer "F.Cu")
		(net "BMC0_TACH9")
	)
	(segment
		(start 299.85208 -186.837828)
		(end 299.85208 -185.78068)
		(width 0.1143)
		(layer "F.Cu")
		(net "BMC0_TACH9")
	)
	(segment
		(start 305.181 -216.3445)
		(end 305.181 -211.074)
		(width 0.1143)
		(layer "F.Cu")
		(net "BMC0_TACH9")
	)
	(segment
		(start 298.43476 -184.36336)
		(end 298.43476 -184.24017)
		(width 0.1143)
		(layer "F.Cu")
		(net "BMC0_TACH9")
	)
	(segment
		(start 305.181 -211.074)
		(end 302.641 -208.534)
		(width 0.1143)
		(layer "F.Cu")
		(net "BMC0_TACH9")
	)
	(segment
		(start 302.641 -204.978)
		(end 302.641 -195.326)
		(width 0.1143)
		(layer "F.Cu")
		(net "BMC0_TACH9")
	)
	(segment
		(start 300.863 -187.848748)
		(end 299.85208 -186.837828)
		(width 0.1143)
		(layer "F.Cu")
		(net "BMC0_TACH9")
	)
	(segment
		(start 299.85208 -185.78068)
		(end 298.43476 -184.36336)
		(width 0.1143)
		(layer "F.Cu")
		(net "BMC0_TACH9")
	)
	(segment
		(start 300.863 -190.373)
		(end 300.863 -187.848748)
		(width 0.1143)
		(layer "F.Cu")
		(net "BMC0_TACH9")
	)
	(via
		(at 302.26 -194.945)
		(size 0.5588)
		(drill 0.3048)
		(layers "F.Cu" "B.Cu")
		(net "BMC0_TACH9")
	)
	(via
		(at 302.641 -204.978)
		(size 0.7112)
		(drill 0.3556)
		(layers "F.Cu" "B.Cu")
		(net "BMC0_TACH9")
	)
	(via
		(at 300.863 -190.373)
		(size 0.5588)
		(drill 0.3048)
		(layers "F.Cu" "B.Cu")
		(net "BMC0_TACH9")
	)
	(segment
		(start 302.26 -194.945)
		(end 300.863 -193.548)
		(width 0.127)
		(layer "In2.Cu")
		(net "BMC0_TACH9")
	)
	(segment
		(start 300.863 -193.548)
		(end 300.863 -190.373)
		(width 0.127)
		(layer "In2.Cu")
		(net "BMC0_TACH9")
	)
	(segment
		(start 52.2605 -204.978)
		(end 52.3875 -205.105)
		(width 0.1143)
		(layer "F.Cu")
		(net "MATED_P12V_EN")
	)
	(segment
		(start 52.2605 -201.422)
		(end 52.2605 -204.978)
		(width 0.1143)
		(layer "F.Cu")
		(net "MATED_P12V_EN")
	)
	(segment
		(start 52.3875 -205.105)
		(end 53.975 -205.105)
		(width 0.1143)
		(layer "F.Cu")
		(net "MATED_P12V_EN")
	)
	(segment
		(start 53.9115 -206.248)
		(end 53.9115 -205.1685)
		(width 0.1143)
		(layer "F.Cu")
		(net "MATED_P12V_EN")
	)
	(segment
		(start 53.9115 -205.1685)
		(end 53.975 -205.105)
		(width 0.1143)
		(layer "F.Cu")
		(net "MATED_P12V_EN")
	)
	(segment
		(start 55.118 -205.105)
		(end 53.975 -205.105)
		(width 0.1143)
		(layer "F.Cu")
		(net "MATED_P12V_EN")
	)
	(via
		(at 55.118 -205.105)
		(size 0.7112)
		(drill 0.3556)
		(layers "F.Cu" "B.Cu")
		(net "MATED_P12V_EN")
	)
	(segment
		(start 285.991808 -157.912308)
		(end 286.614108 -157.912308)
		(width 0.1143)
		(layer "F.Cu")
		(net "BMC_LSI_BOARD")
	)
	(segment
		(start 289.26155 -161.58845)
		(end 289.26155 -160.054036)
		(width 0.1143)
		(layer "F.Cu")
		(net "BMC_LSI_BOARD")
	)
	(segment
		(start 284.988 -156.9085)
		(end 285.991808 -157.912308)
		(width 0.1143)
		(layer "F.Cu")
		(net "BMC_LSI_BOARD")
	)
	(segment
		(start 289.63493 -167.440102)
		(end 289.63493 -164.92093)
		(width 0.1143)
		(layer "F.Cu")
		(net "BMC_LSI_BOARD")
	)
	(segment
		(start 288.89325 -161.95675)
		(end 289.26155 -161.58845)
		(width 0.1143)
		(layer "F.Cu")
		(net "BMC_LSI_BOARD")
	)
	(segment
		(start 289.26155 -160.054036)
		(end 287.576514 -158.369)
		(width 0.1143)
		(layer "F.Cu")
		(net "BMC_LSI_BOARD")
	)
	(segment
		(start 289.63493 -164.92093)
		(end 288.89325 -164.17925)
		(width 0.1143)
		(layer "F.Cu")
		(net "BMC_LSI_BOARD")
	)
	(segment
		(start 288.89325 -164.17925)
		(end 288.89325 -161.95675)
		(width 0.1143)
		(layer "F.Cu")
		(net "BMC_LSI_BOARD")
	)
	(segment
		(start 287.576514 -158.369)
		(end 287.0708 -158.369)
		(width 0.1143)
		(layer "F.Cu")
		(net "BMC_LSI_BOARD")
	)
	(segment
		(start 286.614108 -157.912308)
		(end 286.6898 -157.988)
		(width 0.1143)
		(layer "F.Cu")
		(net "BMC_LSI_BOARD")
	)
	(segment
		(start 287.0708 -158.369)
		(end 286.6898 -157.988)
		(width 0.1143)
		(layer "F.Cu")
		(net "BMC_LSI_BOARD")
	)
	(segment
		(start 283.845 -156.9085)
		(end 284.988 -156.9085)
		(width 0.1143)
		(layer "F.Cu")
		(net "BMC_LSI_BOARD")
	)
	(via
		(at 286.6898 -157.988)
		(size 0.7112)
		(drill 0.3556)
		(layers "F.Cu" "B.Cu")
		(net "BMC_LSI_BOARD")
	)
	(segment
		(start 300.834806 -173.072806)
		(end 300.834806 -173.04004)
		(width 0.1143)
		(layer "F.Cu")
		(net "TP_BMC_GPIOQ6")
	)
	(segment
		(start 302.128428 -173.232572)
		(end 301.97806 -173.38294)
		(width 0.1143)
		(layer "F.Cu")
		(net "TP_BMC_GPIOQ6")
	)
	(segment
		(start 307.848 -173.99)
		(end 307.090572 -173.232572)
		(width 0.1143)
		(layer "F.Cu")
		(net "TP_BMC_GPIOQ6")
	)
	(segment
		(start 307.090572 -173.232572)
		(end 302.128428 -173.232572)
		(width 0.1143)
		(layer "F.Cu")
		(net "TP_BMC_GPIOQ6")
	)
	(segment
		(start 301.97806 -173.38294)
		(end 301.14494 -173.38294)
		(width 0.1143)
		(layer "F.Cu")
		(net "TP_BMC_GPIOQ6")
	)
	(segment
		(start 301.14494 -173.38294)
		(end 300.834806 -173.072806)
		(width 0.1143)
		(layer "F.Cu")
		(net "TP_BMC_GPIOQ6")
	)
	(segment
		(start 344.90025 -27.90825)
		(end 344.17 -27.178)
		(width 0.1143)
		(layer "F.Cu")
		(net "BMC_CONSOLE_LED0_R")
	)
	(segment
		(start 344.17 -27.178)
		(end 344.17 -26.924)
		(width 0.1143)
		(layer "F.Cu")
		(net "BMC_CONSOLE_LED0_R")
	)
	(segment
		(start 344.17 -26.924)
		(end 345.1225 -26.924)
		(width 0.1143)
		(layer "F.Cu")
		(net "BMC_CONSOLE_LED0_R")
	)
	(segment
		(start 344.90025 -30.4165)
		(end 344.90025 -27.90825)
		(width 0.1143)
		(layer "F.Cu")
		(net "BMC_CONSOLE_LED0_R")
	)
	(via
		(at 344.17 -26.924)
		(size 0.7112)
		(drill 0.3556)
		(layers "F.Cu" "B.Cu")
		(net "BMC_CONSOLE_LED0_R")
	)
	(segment
		(start 288.83483 -169.040048)
		(end 288.440622 -168.64584)
		(width 0.1143)
		(layer "F.Cu")
		(net "TP_BMC_GPIOF7")
	)
	(segment
		(start 288.440622 -168.64584)
		(end 288.431224 -168.64584)
		(width 0.1143)
		(layer "F.Cu")
		(net "TP_BMC_GPIOF7")
	)
	(segment
		(start 288.431224 -168.64584)
		(end 288.430462 -168.645078)
		(width 0.1143)
		(layer "F.Cu")
		(net "TP_BMC_GPIOF7")
	)
	(via
		(at 288.430462 -168.645078)
		(size 0.508)
		(drill 0.254)
		(layers "F.Cu" "B.Cu")
		(net "TP_BMC_GPIOF7")
	)
	(segment
		(start 286.4612 -166.675816)
		(end 288.430462 -168.645078)
		(width 0.1143)
		(layer "B.Cu")
		(net "TP_BMC_GPIOF7")
	)
	(segment
		(start 289.41776 -170.9547)
		(end 289.41776 -171.427394)
		(width 0.1143)
		(layer "F.Cu")
		(net "TP_BMC_GPIOF6")
	)
	(segment
		(start 289.41776 -171.427394)
		(end 289.36823 -171.476924)
		(width 0.1143)
		(layer "F.Cu")
		(net "TP_BMC_GPIOF6")
	)
	(segment
		(start 289.63493 -170.640248)
		(end 289.63493 -170.73753)
		(width 0.1143)
		(layer "F.Cu")
		(net "TP_BMC_GPIOF6")
	)
	(segment
		(start 289.63493 -170.73753)
		(end 289.41776 -170.9547)
		(width 0.1143)
		(layer "F.Cu")
		(net "TP_BMC_GPIOF6")
	)
	(via
		(at 289.36823 -171.476924)
		(size 0.508)
		(drill 0.254)
		(layers "F.Cu" "B.Cu")
		(net "TP_BMC_GPIOF6")
	)
	(segment
		(start 289.306 -171.539154)
		(end 289.36823 -171.476924)
		(width 0.1143)
		(layer "B.Cu")
		(net "TP_BMC_GPIOF6")
	)
	(segment
		(start 289.306 -172.3644)
		(end 289.306 -171.539154)
		(width 0.1143)
		(layer "B.Cu")
		(net "TP_BMC_GPIOF6")
	)
	(segment
		(start 307.594 -226.314)
		(end 302.006 -226.314)
		(width 0.127)
		(layer "F.Cu")
		(net "DEBUG_OE_2_N")
	)
	(segment
		(start 309.118 -222.377)
		(end 309.118 -224.79)
		(width 0.127)
		(layer "F.Cu")
		(net "DEBUG_OE_2_N")
	)
	(segment
		(start 252.64364 -130.4544)
		(end 252.64364 -131.99364)
		(width 0.127)
		(layer "F.Cu")
		(net "DEBUG_OE_2_N")
	)
	(segment
		(start 308.37124 -220.6625)
		(end 308.37124 -221.63024)
		(width 0.127)
		(layer "F.Cu")
		(net "DEBUG_OE_2_N")
	)
	(segment
		(start 309.118 -224.79)
		(end 307.594 -226.314)
		(width 0.127)
		(layer "F.Cu")
		(net "DEBUG_OE_2_N")
	)
	(segment
		(start 252.476 -128.9812)
		(end 251.968 -128.4732)
		(width 0.127)
		(layer "F.Cu")
		(net "DEBUG_OE_2_N")
	)
	(segment
		(start 295.91 -218.089988)
		(end 295.91 -217.932)
		(width 0.127)
		(layer "F.Cu")
		(net "DEBUG_OE_2_N")
	)
	(segment
		(start 252.476 -128.9812)
		(end 252.64364 -129.14884)
		(width 0.127)
		(layer "F.Cu")
		(net "DEBUG_OE_2_N")
	)
	(segment
		(start 252.64364 -129.14884)
		(end 252.64364 -130.4544)
		(width 0.127)
		(layer "F.Cu")
		(net "DEBUG_OE_2_N")
	)
	(segment
		(start 253.29388 -132.64388)
		(end 253.29388 -133.7056)
		(width 0.127)
		(layer "F.Cu")
		(net "DEBUG_OE_2_N")
	)
	(segment
		(start 295.91 -217.932)
		(end 295.783 -217.805)
		(width 0.127)
		(layer "F.Cu")
		(net "DEBUG_OE_2_N")
	)
	(segment
		(start 308.37124 -221.63024)
		(end 309.118 -222.377)
		(width 0.127)
		(layer "F.Cu")
		(net "DEBUG_OE_2_N")
	)
	(segment
		(start 252.64364 -131.99364)
		(end 253.29388 -132.64388)
		(width 0.127)
		(layer "F.Cu")
		(net "DEBUG_OE_2_N")
	)
	(segment
		(start 302.006 -226.314)
		(end 297.688 -221.996)
		(width 0.127)
		(layer "F.Cu")
		(net "DEBUG_OE_2_N")
	)
	(segment
		(start 251.968 -128.4732)
		(end 251.968 -128.397)
		(width 0.127)
		(layer "F.Cu")
		(net "DEBUG_OE_2_N")
	)
	(segment
		(start 297.688 -221.996)
		(end 297.688 -219.867988)
		(width 0.127)
		(layer "F.Cu")
		(net "DEBUG_OE_2_N")
	)
	(segment
		(start 297.688 -219.867988)
		(end 295.91 -218.089988)
		(width 0.127)
		(layer "F.Cu")
		(net "DEBUG_OE_2_N")
	)
	(via
		(at 295.783 -217.805)
		(size 0.5588)
		(drill 0.3048)
		(layers "F.Cu" "B.Cu")
		(net "DEBUG_OE_2_N")
	)
	(via
		(at 262.89 -204.343)
		(size 0.5588)
		(drill 0.3048)
		(layers "F.Cu" "B.Cu")
		(net "DEBUG_OE_2_N")
	)
	(via
		(at 252.476 -128.9812)
		(size 0.7112)
		(drill 0.3556)
		(layers "F.Cu" "B.Cu")
		(net "DEBUG_OE_2_N")
	)
	(via
		(at 251.968 -128.397)
		(size 0.5588)
		(drill 0.3048)
		(layers "F.Cu" "B.Cu")
		(net "DEBUG_OE_2_N")
	)
	(segment
		(start 293.847012 -213.36)
		(end 295.958006 -215.470994)
		(width 0.127)
		(layer "In2.Cu")
		(net "DEBUG_OE_2_N")
	)
	(segment
		(start 274.289012 -213.36)
		(end 293.847012 -213.36)
		(width 0.127)
		(layer "In2.Cu")
		(net "DEBUG_OE_2_N")
	)
	(segment
		(start 295.958006 -215.470994)
		(end 295.958006 -217.629994)
		(width 0.127)
		(layer "In2.Cu")
		(net "DEBUG_OE_2_N")
	)
	(segment
		(start 262.89 -204.343)
		(end 265.272012 -204.343)
		(width 0.127)
		(layer "In2.Cu")
		(net "DEBUG_OE_2_N")
	)
	(segment
		(start 265.272012 -204.343)
		(end 274.289012 -213.36)
		(width 0.127)
		(layer "In2.Cu")
		(net "DEBUG_OE_2_N")
	)
	(segment
		(start 295.958006 -217.629994)
		(end 295.783 -217.805)
		(width 0.127)
		(layer "In2.Cu")
		(net "DEBUG_OE_2_N")
	)
	(segment
		(start 251.968 -128.397)
		(end 252.668532 -128.397)
		(width 0.127)
		(layer "In5.Cu")
		(net "DEBUG_OE_2_N")
	)
	(segment
		(start 254.127 -134.366)
		(end 254.127 -155.829)
		(width 0.127)
		(layer "In5.Cu")
		(net "DEBUG_OE_2_N")
	)
	(segment
		(start 258.826 -160.528)
		(end 258.826 -170.688)
		(width 0.127)
		(layer "In5.Cu")
		(net "DEBUG_OE_2_N")
	)
	(segment
		(start 253.873 -134.112)
		(end 254.127 -134.366)
		(width 0.127)
		(layer "In5.Cu")
		(net "DEBUG_OE_2_N")
	)
	(segment
		(start 260.731 -202.184)
		(end 262.89 -204.343)
		(width 0.127)
		(layer "In5.Cu")
		(net "DEBUG_OE_2_N")
	)
	(segment
		(start 254.127 -155.829)
		(end 258.826 -160.528)
		(width 0.127)
		(layer "In5.Cu")
		(net "DEBUG_OE_2_N")
	)
	(segment
		(start 260.731 -172.593)
		(end 260.731 -202.184)
		(width 0.127)
		(layer "In5.Cu")
		(net "DEBUG_OE_2_N")
	)
	(segment
		(start 253.873 -129.601468)
		(end 253.873 -134.112)
		(width 0.127)
		(layer "In5.Cu")
		(net "DEBUG_OE_2_N")
	)
	(segment
		(start 258.826 -170.688)
		(end 260.731 -172.593)
		(width 0.127)
		(layer "In5.Cu")
		(net "DEBUG_OE_2_N")
	)
	(segment
		(start 252.668532 -128.397)
		(end 253.873 -129.601468)
		(width 0.127)
		(layer "In5.Cu")
		(net "DEBUG_OE_2_N")
	)
	(segment
		(start 329.167236 -168.91)
		(end 329.565 -168.91)
		(width 0.1143)
		(layer "F.Cu")
		(net "CPU_S_RXD")
	)
	(segment
		(start 258.2926 -142.494)
		(end 258.2926 -139.573)
		(width 0.1143)
		(layer "F.Cu")
		(net "CPU_S_RXD")
	)
	(segment
		(start 258.318 -137.2235)
		(end 258.318 -138.5062)
		(width 0.1143)
		(layer "F.Cu")
		(net "CPU_S_RXD")
	)
	(segment
		(start 328.667872 -168.410636)
		(end 329.167236 -168.91)
		(width 0.1143)
		(layer "F.Cu")
		(net "CPU_S_RXD")
	)
	(segment
		(start 258.2926 -139.573)
		(end 258.318 -139.5476)
		(width 0.1143)
		(layer "F.Cu")
		(net "CPU_S_RXD")
	)
	(segment
		(start 258.318 -139.5476)
		(end 258.318 -138.5062)
		(width 0.1143)
		(layer "F.Cu")
		(net "CPU_S_RXD")
	)
	(via
		(at 258.318 -138.5062)
		(size 0.7112)
		(drill 0.3556)
		(layers "F.Cu" "B.Cu")
		(net "CPU_S_RXD")
	)
	(via
		(at 329.565 -168.91)
		(size 0.5588)
		(drill 0.3048)
		(layers "F.Cu" "B.Cu")
		(net "CPU_S_RXD")
	)
	(via
		(at 258.2926 -142.494)
		(size 0.5588)
		(drill 0.3048)
		(layers "F.Cu" "B.Cu")
		(net "CPU_S_RXD")
	)
	(via
		(at 327.787 -161.417)
		(size 0.5588)
		(drill 0.3048)
		(layers "F.Cu" "B.Cu")
		(net "CPU_S_RXD")
	)
	(via
		(at 275.844 -141.224)
		(size 0.5588)
		(drill 0.3048)
		(layers "F.Cu" "B.Cu")
		(net "CPU_S_RXD")
	)
	(segment
		(start 328.676 -162.306)
		(end 327.787 -161.417)
		(width 0.1143)
		(layer "B.Cu")
		(net "CPU_S_RXD")
	)
	(segment
		(start 329.287886 -165.457886)
		(end 328.676 -164.846)
		(width 0.1143)
		(layer "B.Cu")
		(net "CPU_S_RXD")
	)
	(segment
		(start 329.287886 -168.632886)
		(end 329.287886 -165.457886)
		(width 0.1143)
		(layer "B.Cu")
		(net "CPU_S_RXD")
	)
	(segment
		(start 329.565 -168.91)
		(end 329.287886 -168.632886)
		(width 0.1143)
		(layer "B.Cu")
		(net "CPU_S_RXD")
	)
	(segment
		(start 328.676 -164.846)
		(end 328.676 -162.306)
		(width 0.1143)
		(layer "B.Cu")
		(net "CPU_S_RXD")
	)
	(segment
		(start 268.841728 -141.224)
		(end 275.844 -141.224)
		(width 0.127)
		(layer "In2.Cu")
		(net "CPU_S_RXD")
	)
	(segment
		(start 258.2926 -142.494)
		(end 267.571728 -142.494)
		(width 0.127)
		(layer "In2.Cu")
		(net "CPU_S_RXD")
	)
	(segment
		(start 267.571728 -142.494)
		(end 268.841728 -141.224)
		(width 0.127)
		(layer "In2.Cu")
		(net "CPU_S_RXD")
	)
	(segment
		(start 314.706 -158.877)
		(end 316.7507 -160.9217)
		(width 0.127)
		(layer "In5.Cu")
		(net "CPU_S_RXD")
	)
	(segment
		(start 277.241 -142.621)
		(end 277.241 -145.649188)
		(width 0.127)
		(layer "In5.Cu")
		(net "CPU_S_RXD")
	)
	(segment
		(start 296.864532 -157.988)
		(end 305.054 -157.988)
		(width 0.127)
		(layer "In5.Cu")
		(net "CPU_S_RXD")
	)
	(segment
		(start 277.241 -145.649188)
		(end 285.388812 -153.797)
		(width 0.127)
		(layer "In5.Cu")
		(net "CPU_S_RXD")
	)
	(segment
		(start 275.844 -141.224)
		(end 277.241 -142.621)
		(width 0.127)
		(layer "In5.Cu")
		(net "CPU_S_RXD")
	)
	(segment
		(start 305.943 -158.877)
		(end 314.706 -158.877)
		(width 0.127)
		(layer "In5.Cu")
		(net "CPU_S_RXD")
	)
	(segment
		(start 316.7507 -160.9217)
		(end 319.610232 -160.9217)
		(width 0.127)
		(layer "In5.Cu")
		(net "CPU_S_RXD")
	)
	(segment
		(start 319.610232 -160.9217)
		(end 320.105532 -161.417)
		(width 0.127)
		(layer "In5.Cu")
		(net "CPU_S_RXD")
	)
	(segment
		(start 292.673532 -153.797)
		(end 296.864532 -157.988)
		(width 0.127)
		(layer "In5.Cu")
		(net "CPU_S_RXD")
	)
	(segment
		(start 285.388812 -153.797)
		(end 292.673532 -153.797)
		(width 0.127)
		(layer "In5.Cu")
		(net "CPU_S_RXD")
	)
	(segment
		(start 320.105532 -161.417)
		(end 327.787 -161.417)
		(width 0.127)
		(layer "In5.Cu")
		(net "CPU_S_RXD")
	)
	(segment
		(start 305.054 -157.988)
		(end 305.943 -158.877)
		(width 0.127)
		(layer "In5.Cu")
		(net "CPU_S_RXD")
	)
	(segment
		(start 257.302 -137.2235)
		(end 257.302 -140.7414)
		(width 0.1143)
		(layer "F.Cu")
		(net "CPU_S_TXD")
	)
	(segment
		(start 330.191872 -168.029636)
		(end 331.283564 -168.029636)
		(width 0.1143)
		(layer "F.Cu")
		(net "CPU_S_TXD")
	)
	(segment
		(start 257.302 -141.859)
		(end 257.429 -141.986)
		(width 0.1143)
		(layer "F.Cu")
		(net "CPU_S_TXD")
	)
	(segment
		(start 257.302 -140.7414)
		(end 257.302 -141.859)
		(width 0.1143)
		(layer "F.Cu")
		(net "CPU_S_TXD")
	)
	(segment
		(start 331.283564 -168.029636)
		(end 331.3176 -167.9956)
		(width 0.1143)
		(layer "F.Cu")
		(net "CPU_S_TXD")
	)
	(via
		(at 257.302 -140.7414)
		(size 0.7112)
		(drill 0.3556)
		(layers "F.Cu" "B.Cu")
		(net "CPU_S_TXD")
	)
	(via
		(at 257.429 -141.986)
		(size 0.5588)
		(drill 0.3048)
		(layers "F.Cu" "B.Cu")
		(net "CPU_S_TXD")
	)
	(via
		(at 331.3176 -167.9956)
		(size 0.5588)
		(drill 0.3048)
		(layers "F.Cu" "B.Cu")
		(net "CPU_S_TXD")
	)
	(via
		(at 328.676 -159.512)
		(size 0.5588)
		(drill 0.3048)
		(layers "F.Cu" "B.Cu")
		(net "CPU_S_TXD")
	)
	(via
		(at 277.22195 -140.06195)
		(size 0.5588)
		(drill 0.3048)
		(layers "F.Cu" "B.Cu")
		(net "CPU_S_TXD")
	)
	(segment
		(start 330.708 -161.544)
		(end 330.708 -165.227)
		(width 0.1143)
		(layer "B.Cu")
		(net "CPU_S_TXD")
	)
	(segment
		(start 331.3176 -165.8366)
		(end 331.3176 -167.9956)
		(width 0.1143)
		(layer "B.Cu")
		(net "CPU_S_TXD")
	)
	(segment
		(start 328.676 -159.512)
		(end 330.708 -161.544)
		(width 0.1143)
		(layer "B.Cu")
		(net "CPU_S_TXD")
	)
	(segment
		(start 330.708 -165.227)
		(end 331.3176 -165.8366)
		(width 0.1143)
		(layer "B.Cu")
		(net "CPU_S_TXD")
	)
	(segment
		(start 267.54074 -141.986)
		(end 269.46479 -140.06195)
		(width 0.127)
		(layer "In2.Cu")
		(net "CPU_S_TXD")
	)
	(segment
		(start 257.429 -141.986)
		(end 267.54074 -141.986)
		(width 0.127)
		(layer "In2.Cu")
		(net "CPU_S_TXD")
	)
	(segment
		(start 269.46479 -140.06195)
		(end 277.22195 -140.06195)
		(width 0.127)
		(layer "In2.Cu")
		(net "CPU_S_TXD")
	)
	(segment
		(start 322.656962 -155.8417)
		(end 325.171562 -158.3563)
		(width 0.127)
		(layer "In5.Cu")
		(net "CPU_S_TXD")
	)
	(segment
		(start 291.846 -152.4)
		(end 295.7703 -156.3243)
		(width 0.127)
		(layer "In5.Cu")
		(net "CPU_S_TXD")
	)
	(segment
		(start 327.5203 -158.3563)
		(end 328.676 -159.512)
		(width 0.127)
		(layer "In5.Cu")
		(net "CPU_S_TXD")
	)
	(segment
		(start 295.7703 -156.3243)
		(end 300.556168 -156.3243)
		(width 0.127)
		(layer "In5.Cu")
		(net "CPU_S_TXD")
	)
	(segment
		(start 277.22195 -140.06195)
		(end 278.13 -140.97)
		(width 0.127)
		(layer "In5.Cu")
		(net "CPU_S_TXD")
	)
	(segment
		(start 301.038768 -155.8417)
		(end 322.656962 -155.8417)
		(width 0.127)
		(layer "In5.Cu")
		(net "CPU_S_TXD")
	)
	(segment
		(start 284.5308 -152.4)
		(end 291.846 -152.4)
		(width 0.127)
		(layer "In5.Cu")
		(net "CPU_S_TXD")
	)
	(segment
		(start 325.171562 -158.3563)
		(end 327.5203 -158.3563)
		(width 0.127)
		(layer "In5.Cu")
		(net "CPU_S_TXD")
	)
	(segment
		(start 278.13 -140.97)
		(end 278.13 -145.9992)
		(width 0.127)
		(layer "In5.Cu")
		(net "CPU_S_TXD")
	)
	(segment
		(start 278.13 -145.9992)
		(end 284.5308 -152.4)
		(width 0.127)
		(layer "In5.Cu")
		(net "CPU_S_TXD")
	)
	(segment
		(start 300.556168 -156.3243)
		(end 301.038768 -155.8417)
		(width 0.127)
		(layer "In5.Cu")
		(net "CPU_S_TXD")
	)
	(segment
		(start 85.344 -221.361)
		(end 85.217 -221.488)
		(width 0.1143)
		(layer "F.Cu")
		(net "EXP_SCL_L_0")
	)
	(segment
		(start 88.2015 -224.3455)
		(end 87.757 -223.901)
		(width 0.1143)
		(layer "F.Cu")
		(net "EXP_SCL_L_0")
	)
	(segment
		(start 37.058854 -213.79688)
		(end 38.124384 -212.73135)
		(width 0.1143)
		(layer "F.Cu")
		(net "EXP_SCL_L_0")
	)
	(segment
		(start 87.757 -223.901)
		(end 85.217 -223.901)
		(width 0.1143)
		(layer "F.Cu")
		(net "EXP_SCL_L_0")
	)
	(segment
		(start 85.217 -221.488)
		(end 85.217 -223.901)
		(width 0.1143)
		(layer "F.Cu")
		(net "EXP_SCL_L_0")
	)
	(segment
		(start 42.7736 -215.491822)
		(end 42.7736 -220.472)
		(width 0.1143)
		(layer "F.Cu")
		(net "EXP_SCL_L_0")
	)
	(segment
		(start 40.013128 -212.73135)
		(end 42.7736 -215.491822)
		(width 0.1143)
		(layer "F.Cu")
		(net "EXP_SCL_L_0")
	)
	(segment
		(start 89.2175 -224.663)
		(end 88.2015 -224.663)
		(width 0.1143)
		(layer "F.Cu")
		(net "EXP_SCL_L_0")
	)
	(segment
		(start 38.124384 -212.73135)
		(end 40.013128 -212.73135)
		(width 0.1143)
		(layer "F.Cu")
		(net "EXP_SCL_L_0")
	)
	(segment
		(start 36.1696 -213.79688)
		(end 37.058854 -213.79688)
		(width 0.1143)
		(layer "F.Cu")
		(net "EXP_SCL_L_0")
	)
	(segment
		(start 88.2015 -224.663)
		(end 88.2015 -224.3455)
		(width 0.1143)
		(layer "F.Cu")
		(net "EXP_SCL_L_0")
	)
	(via
		(at 85.344 -221.361)
		(size 0.508)
		(drill 0.254)
		(layers "F.Cu" "B.Cu")
		(net "EXP_SCL_L_0")
	)
	(via
		(at 122.809 -230.505)
		(size 0.5588)
		(drill 0.3048)
		(layers "F.Cu" "B.Cu")
		(net "EXP_SCL_L_0")
	)
	(via
		(at 85.217 -223.901)
		(size 0.7112)
		(drill 0.3556)
		(layers "F.Cu" "B.Cu")
		(net "EXP_SCL_L_0")
	)
	(via
		(at 42.7736 -220.472)
		(size 0.5588)
		(drill 0.3048)
		(layers "F.Cu" "B.Cu")
		(net "EXP_SCL_L_0")
	)
	(segment
		(start 124.848112 -216.535)
		(end 126.111 -216.535)
		(width 0.1143)
		(layer "B.Cu")
		(net "EXP_SCL_L_0")
	)
	(segment
		(start 125.857 -230.505)
		(end 122.809 -230.505)
		(width 0.1143)
		(layer "B.Cu")
		(net "EXP_SCL_L_0")
	)
	(segment
		(start 129.159 -219.583)
		(end 129.159 -227.203)
		(width 0.1143)
		(layer "B.Cu")
		(net "EXP_SCL_L_0")
	)
	(segment
		(start 126.111 -216.535)
		(end 129.159 -219.583)
		(width 0.1143)
		(layer "B.Cu")
		(net "EXP_SCL_L_0")
	)
	(segment
		(start 129.159 -227.203)
		(end 125.857 -230.505)
		(width 0.1143)
		(layer "B.Cu")
		(net "EXP_SCL_L_0")
	)
	(segment
		(start 82.931 -221.361)
		(end 80.645 -219.075)
		(width 0.127)
		(layer "In2.Cu")
		(net "EXP_SCL_L_0")
	)
	(segment
		(start 85.725 -221.361)
		(end 88.107266 -218.978734)
		(width 0.127)
		(layer "In2.Cu")
		(net "EXP_SCL_L_0")
	)
	(segment
		(start 85.344 -221.361)
		(end 82.931 -221.361)
		(width 0.127)
		(layer "In2.Cu")
		(net "EXP_SCL_L_0")
	)
	(segment
		(start 109.855 -229.997)
		(end 122.301 -229.997)
		(width 0.127)
		(layer "In2.Cu")
		(net "EXP_SCL_L_0")
	)
	(segment
		(start 105.918 -226.06)
		(end 109.855 -229.997)
		(width 0.127)
		(layer "In2.Cu")
		(net "EXP_SCL_L_0")
	)
	(segment
		(start 105.918 -224.917)
		(end 105.918 -226.06)
		(width 0.127)
		(layer "In2.Cu")
		(net "EXP_SCL_L_0")
	)
	(segment
		(start 65.234566 -220.98)
		(end 43.2816 -220.98)
		(width 0.127)
		(layer "In2.Cu")
		(net "EXP_SCL_L_0")
	)
	(segment
		(start 99.979734 -218.978734)
		(end 105.918 -224.917)
		(width 0.127)
		(layer "In2.Cu")
		(net "EXP_SCL_L_0")
	)
	(segment
		(start 67.139566 -219.075)
		(end 65.234566 -220.98)
		(width 0.127)
		(layer "In2.Cu")
		(net "EXP_SCL_L_0")
	)
	(segment
		(start 88.107266 -218.978734)
		(end 99.979734 -218.978734)
		(width 0.127)
		(layer "In2.Cu")
		(net "EXP_SCL_L_0")
	)
	(segment
		(start 122.301 -229.997)
		(end 122.809 -230.505)
		(width 0.127)
		(layer "In2.Cu")
		(net "EXP_SCL_L_0")
	)
	(segment
		(start 85.344 -221.361)
		(end 85.725 -221.361)
		(width 0.127)
		(layer "In2.Cu")
		(net "EXP_SCL_L_0")
	)
	(segment
		(start 43.2816 -220.98)
		(end 42.7736 -220.472)
		(width 0.127)
		(layer "In2.Cu")
		(net "EXP_SCL_L_0")
	)
	(segment
		(start 80.645 -219.075)
		(end 67.139566 -219.075)
		(width 0.127)
		(layer "In2.Cu")
		(net "EXP_SCL_L_0")
	)
	(segment
		(start 36.99764 -215.09736)
		(end 37.211 -214.884)
		(width 0.127)
		(layer "F.Cu")
		(net "EXP_I2C_VREF_4")
	)
	(segment
		(start 37.9095 -215.392)
		(end 37.9095 -214.376)
		(width 0.127)
		(layer "F.Cu")
		(net "EXP_I2C_VREF_4")
	)
	(segment
		(start 37.9095 -215.392)
		(end 37.9095 -216.3445)
		(width 0.127)
		(layer "F.Cu")
		(net "EXP_I2C_VREF_4")
	)
	(segment
		(start 36.1696 -214.44712)
		(end 37.02812 -214.44712)
		(width 0.127)
		(layer "F.Cu")
		(net "EXP_I2C_VREF_4")
	)
	(segment
		(start 37.83838 -214.44712)
		(end 37.02812 -214.44712)
		(width 0.127)
		(layer "F.Cu")
		(net "EXP_I2C_VREF_4")
	)
	(segment
		(start 37.9095 -214.376)
		(end 37.83838 -214.44712)
		(width 0.127)
		(layer "F.Cu")
		(net "EXP_I2C_VREF_4")
	)
	(segment
		(start 37.211 -214.884)
		(end 37.211 -214.63)
		(width 0.127)
		(layer "F.Cu")
		(net "EXP_I2C_VREF_4")
	)
	(segment
		(start 36.1696 -215.09736)
		(end 36.99764 -215.09736)
		(width 0.127)
		(layer "F.Cu")
		(net "EXP_I2C_VREF_4")
	)
	(segment
		(start 37.211 -214.63)
		(end 37.02812 -214.44712)
		(width 0.127)
		(layer "F.Cu")
		(net "EXP_I2C_VREF_4")
	)
	(via
		(at 37.9095 -216.3445)
		(size 0.7112)
		(drill 0.3556)
		(layers "F.Cu" "B.Cu")
		(net "EXP_I2C_VREF_4")
	)
	(segment
		(start 86.487 -221.869)
		(end 86.487 -221.8944)
		(width 0.1143)
		(layer "F.Cu")
		(net "EXP_SDA_L_0")
	)
	(segment
		(start 36.78936 -213.14664)
		(end 37.69995 -212.23605)
		(width 0.1143)
		(layer "F.Cu")
		(net "EXP_SDA_L_0")
	)
	(segment
		(start 88.2015 -223.139)
		(end 87.376 -222.3135)
		(width 0.1143)
		(layer "F.Cu")
		(net "EXP_SDA_L_0")
	)
	(segment
		(start 86.5124 -221.8944)
		(end 86.487 -221.8944)
		(width 0.1143)
		(layer "F.Cu")
		(net "EXP_SDA_L_0")
	)
	(segment
		(start 43.688 -215.70569)
		(end 43.688 -220.472)
		(width 0.1143)
		(layer "F.Cu")
		(net "EXP_SDA_L_0")
	)
	(segment
		(start 87.376 -222.3135)
		(end 86.9315 -222.3135)
		(width 0.1143)
		(layer "F.Cu")
		(net "EXP_SDA_L_0")
	)
	(segment
		(start 86.106 -221.361)
		(end 86.106 -221.488)
		(width 0.1143)
		(layer "F.Cu")
		(net "EXP_SDA_L_0")
	)
	(segment
		(start 89.2175 -223.139)
		(end 88.2015 -223.139)
		(width 0.1143)
		(layer "F.Cu")
		(net "EXP_SDA_L_0")
	)
	(segment
		(start 36.1696 -213.14664)
		(end 36.78936 -213.14664)
		(width 0.1143)
		(layer "F.Cu")
		(net "EXP_SDA_L_0")
	)
	(segment
		(start 86.9315 -222.3135)
		(end 86.5124 -221.8944)
		(width 0.1143)
		(layer "F.Cu")
		(net "EXP_SDA_L_0")
	)
	(segment
		(start 37.69995 -212.23605)
		(end 40.21836 -212.23605)
		(width 0.1143)
		(layer "F.Cu")
		(net "EXP_SDA_L_0")
	)
	(segment
		(start 85.217 -220.472)
		(end 86.106 -221.361)
		(width 0.1143)
		(layer "F.Cu")
		(net "EXP_SDA_L_0")
	)
	(segment
		(start 86.106 -221.488)
		(end 86.487 -221.869)
		(width 0.1143)
		(layer "F.Cu")
		(net "EXP_SDA_L_0")
	)
	(segment
		(start 40.21836 -212.23605)
		(end 43.688 -215.70569)
		(width 0.1143)
		(layer "F.Cu")
		(net "EXP_SDA_L_0")
	)
	(via
		(at 86.487 -221.8944)
		(size 0.7112)
		(drill 0.3556)
		(layers "F.Cu" "B.Cu")
		(net "EXP_SDA_L_0")
	)
	(via
		(at 85.217 -220.472)
		(size 0.5588)
		(drill 0.3048)
		(layers "F.Cu" "B.Cu")
		(net "EXP_SDA_L_0")
	)
	(via
		(at 43.688 -220.472)
		(size 0.5588)
		(drill 0.3048)
		(layers "F.Cu" "B.Cu")
		(net "EXP_SDA_L_0")
	)
	(via
		(at 123.952 -229.743)
		(size 0.5588)
		(drill 0.3048)
		(layers "F.Cu" "B.Cu")
		(net "EXP_SDA_L_0")
	)
	(segment
		(start 125.857 -229.743)
		(end 123.952 -229.743)
		(width 0.1143)
		(layer "B.Cu")
		(net "EXP_SDA_L_0")
	)
	(segment
		(start 126.492 -217.678)
		(end 128.397 -219.583)
		(width 0.1143)
		(layer "B.Cu")
		(net "EXP_SDA_L_0")
	)
	(segment
		(start 124.848112 -217.678)
		(end 126.492 -217.678)
		(width 0.1143)
		(layer "B.Cu")
		(net "EXP_SDA_L_0")
	)
	(segment
		(start 128.397 -219.583)
		(end 128.397 -227.203)
		(width 0.1143)
		(layer "B.Cu")
		(net "EXP_SDA_L_0")
	)
	(segment
		(start 128.397 -227.203)
		(end 125.857 -229.743)
		(width 0.1143)
		(layer "B.Cu")
		(net "EXP_SDA_L_0")
	)
	(segment
		(start 106.426 -225.806)
		(end 110.109 -229.489)
		(width 0.127)
		(layer "In2.Cu")
		(net "EXP_SDA_L_0")
	)
	(segment
		(start 66.929 -218.567)
		(end 65.024 -220.472)
		(width 0.127)
		(layer "In2.Cu")
		(net "EXP_SDA_L_0")
	)
	(segment
		(start 106.426 -224.663)
		(end 106.426 -225.806)
		(width 0.127)
		(layer "In2.Cu")
		(net "EXP_SDA_L_0")
	)
	(segment
		(start 85.217 -220.472)
		(end 83.7057 -220.472)
		(width 0.127)
		(layer "In2.Cu")
		(net "EXP_SDA_L_0")
	)
	(segment
		(start 123.698 -229.489)
		(end 123.952 -229.743)
		(width 0.127)
		(layer "In2.Cu")
		(net "EXP_SDA_L_0")
	)
	(segment
		(start 65.024 -220.472)
		(end 43.688 -220.472)
		(width 0.127)
		(layer "In2.Cu")
		(net "EXP_SDA_L_0")
	)
	(segment
		(start 81.8007 -218.567)
		(end 66.929 -218.567)
		(width 0.127)
		(layer "In2.Cu")
		(net "EXP_SDA_L_0")
	)
	(segment
		(start 100.203 -218.44)
		(end 106.426 -224.663)
		(width 0.127)
		(layer "In2.Cu")
		(net "EXP_SDA_L_0")
	)
	(segment
		(start 110.109 -229.489)
		(end 123.698 -229.489)
		(width 0.127)
		(layer "In2.Cu")
		(net "EXP_SDA_L_0")
	)
	(segment
		(start 85.217 -220.472)
		(end 85.852 -220.472)
		(width 0.127)
		(layer "In2.Cu")
		(net "EXP_SDA_L_0")
	)
	(segment
		(start 85.852 -220.472)
		(end 87.884 -218.44)
		(width 0.127)
		(layer "In2.Cu")
		(net "EXP_SDA_L_0")
	)
	(segment
		(start 87.884 -218.44)
		(end 100.203 -218.44)
		(width 0.127)
		(layer "In2.Cu")
		(net "EXP_SDA_L_0")
	)
	(segment
		(start 83.7057 -220.472)
		(end 81.8007 -218.567)
		(width 0.127)
		(layer "In2.Cu")
		(net "EXP_SDA_L_0")
	)
	(segment
		(start 298.0436 -187.9854)
		(end 297.688 -188.341)
		(width 0.1143)
		(layer "F.Cu")
		(net "BMC0_TACH15")
	)
	(segment
		(start 298.0436 -187.647072)
		(end 298.0436 -187.9854)
		(width 0.1143)
		(layer "F.Cu")
		(net "BMC0_TACH15")
	)
	(segment
		(start 296.834814 -184.24017)
		(end 296.834814 -184.457848)
		(width 0.1143)
		(layer "F.Cu")
		(net "BMC0_TACH15")
	)
	(segment
		(start 298.621196 -187.06973)
		(end 298.620942 -187.06973)
		(width 0.1143)
		(layer "F.Cu")
		(net "BMC0_TACH15")
	)
	(segment
		(start 298.620942 -187.06973)
		(end 298.0436 -187.647072)
		(width 0.1143)
		(layer "F.Cu")
		(net "BMC0_TACH15")
	)
	(segment
		(start 297.688 -188.976)
		(end 297.688 -191.4525)
		(width 0.1143)
		(layer "F.Cu")
		(net "BMC0_TACH15")
	)
	(segment
		(start 298.86275 -186.828176)
		(end 298.621196 -187.06973)
		(width 0.1143)
		(layer "F.Cu")
		(net "BMC0_TACH15")
	)
	(segment
		(start 297.688 -188.341)
		(end 297.688 -188.976)
		(width 0.1143)
		(layer "F.Cu")
		(net "BMC0_TACH15")
	)
	(segment
		(start 298.86275 -186.485784)
		(end 298.86275 -186.828176)
		(width 0.1143)
		(layer "F.Cu")
		(net "BMC0_TACH15")
	)
	(segment
		(start 296.834814 -184.457848)
		(end 298.86275 -186.485784)
		(width 0.1143)
		(layer "F.Cu")
		(net "BMC0_TACH15")
	)
	(via
		(at 297.688 -188.976)
		(size 0.7112)
		(drill 0.3556)
		(layers "F.Cu" "B.Cu")
		(net "BMC0_TACH15")
	)
	(segment
		(start 300.99 -220.7895)
		(end 300.99 -221.4245)
		(width 0.127)
		(layer "F.Cu")
		(net "DEBUG_OE_1_N")
	)
	(segment
		(start 255.905 -128.1684)
		(end 255.905 -128.778)
		(width 0.127)
		(layer "F.Cu")
		(net "DEBUG_OE_1_N")
	)
	(segment
		(start 305.06924 -222.74276)
		(end 304.419 -223.393)
		(width 0.127)
		(layer "F.Cu")
		(net "DEBUG_OE_1_N")
	)
	(segment
		(start 305.06924 -220.6625)
		(end 305.06924 -222.74276)
		(width 0.127)
		(layer "F.Cu")
		(net "DEBUG_OE_1_N")
	)
	(segment
		(start 256.84988 -132.38988)
		(end 256.84988 -133.7056)
		(width 0.127)
		(layer "F.Cu")
		(net "DEBUG_OE_1_N")
	)
	(segment
		(start 300.2915 -220.7895)
		(end 296.926 -217.424)
		(width 0.127)
		(layer "F.Cu")
		(net "DEBUG_OE_1_N")
	)
	(segment
		(start 302.9585 -223.393)
		(end 301.9425 -222.377)
		(width 0.127)
		(layer "F.Cu")
		(net "DEBUG_OE_1_N")
	)
	(segment
		(start 300.99 -220.7895)
		(end 300.2915 -220.7895)
		(width 0.127)
		(layer "F.Cu")
		(net "DEBUG_OE_1_N")
	)
	(segment
		(start 304.419 -223.393)
		(end 302.9585 -223.393)
		(width 0.127)
		(layer "F.Cu")
		(net "DEBUG_OE_1_N")
	)
	(segment
		(start 255.905 -128.778)
		(end 256.19964 -129.07264)
		(width 0.127)
		(layer "F.Cu")
		(net "DEBUG_OE_1_N")
	)
	(segment
		(start 256.0574 -128.016)
		(end 255.905 -128.1684)
		(width 0.127)
		(layer "F.Cu")
		(net "DEBUG_OE_1_N")
	)
	(segment
		(start 300.99 -221.4245)
		(end 301.9425 -222.377)
		(width 0.127)
		(layer "F.Cu")
		(net "DEBUG_OE_1_N")
	)
	(segment
		(start 256.19964 -129.07264)
		(end 256.19964 -130.4544)
		(width 0.127)
		(layer "F.Cu")
		(net "DEBUG_OE_1_N")
	)
	(segment
		(start 256.19964 -131.73964)
		(end 256.84988 -132.38988)
		(width 0.127)
		(layer "F.Cu")
		(net "DEBUG_OE_1_N")
	)
	(segment
		(start 256.19964 -130.4544)
		(end 256.19964 -131.73964)
		(width 0.127)
		(layer "F.Cu")
		(net "DEBUG_OE_1_N")
	)
	(via
		(at 262.89 -203.2)
		(size 0.5588)
		(drill 0.3048)
		(layers "F.Cu" "B.Cu")
		(net "DEBUG_OE_1_N")
	)
	(via
		(at 255.905 -128.778)
		(size 0.5588)
		(drill 0.3048)
		(layers "F.Cu" "B.Cu")
		(net "DEBUG_OE_1_N")
	)
	(via
		(at 256.0574 -128.016)
		(size 0.7112)
		(drill 0.3556)
		(layers "F.Cu" "B.Cu")
		(net "DEBUG_OE_1_N")
	)
	(via
		(at 296.926 -217.424)
		(size 0.5588)
		(drill 0.3048)
		(layers "F.Cu" "B.Cu")
		(net "DEBUG_OE_1_N")
	)
	(segment
		(start 296.672 -217.424)
		(end 296.926 -217.424)
		(width 0.127)
		(layer "In2.Cu")
		(net "DEBUG_OE_1_N")
	)
	(segment
		(start 274.447 -212.979)
		(end 293.689024 -212.979)
		(width 0.127)
		(layer "In2.Cu")
		(net "DEBUG_OE_1_N")
	)
	(segment
		(start 296.339006 -215.313006)
		(end 296.339006 -217.091006)
		(width 0.127)
		(layer "In2.Cu")
		(net "DEBUG_OE_1_N")
	)
	(segment
		(start 293.689278 -212.978746)
		(end 294.004746 -212.978746)
		(width 0.127)
		(layer "In2.Cu")
		(net "DEBUG_OE_1_N")
	)
	(segment
		(start 262.89 -203.2)
		(end 264.668 -203.2)
		(width 0.127)
		(layer "In2.Cu")
		(net "DEBUG_OE_1_N")
	)
	(segment
		(start 294.004746 -212.978746)
		(end 296.339006 -215.313006)
		(width 0.127)
		(layer "In2.Cu")
		(net "DEBUG_OE_1_N")
	)
	(segment
		(start 293.689024 -212.979)
		(end 293.689278 -212.978746)
		(width 0.127)
		(layer "In2.Cu")
		(net "DEBUG_OE_1_N")
	)
	(segment
		(start 264.668 -203.2)
		(end 274.447 -212.979)
		(width 0.127)
		(layer "In2.Cu")
		(net "DEBUG_OE_1_N")
	)
	(segment
		(start 296.339006 -217.091006)
		(end 296.672 -217.424)
		(width 0.127)
		(layer "In2.Cu")
		(net "DEBUG_OE_1_N")
	)
	(segment
		(start 255.905 -132.969)
		(end 255.905 -128.778)
		(width 0.127)
		(layer "In5.Cu")
		(net "DEBUG_OE_1_N")
	)
	(segment
		(start 259.207 -160.274)
		(end 255.6637 -156.7307)
		(width 0.127)
		(layer "In5.Cu")
		(net "DEBUG_OE_1_N")
	)
	(segment
		(start 255.6637 -133.2103)
		(end 255.905 -132.969)
		(width 0.127)
		(layer "In5.Cu")
		(net "DEBUG_OE_1_N")
	)
	(segment
		(start 261.112 -201.422)
		(end 261.112 -172.339)
		(width 0.127)
		(layer "In5.Cu")
		(net "DEBUG_OE_1_N")
	)
	(segment
		(start 255.6637 -156.7307)
		(end 255.6637 -133.2103)
		(width 0.127)
		(layer "In5.Cu")
		(net "DEBUG_OE_1_N")
	)
	(segment
		(start 262.89 -203.2)
		(end 261.112 -201.422)
		(width 0.127)
		(layer "In5.Cu")
		(net "DEBUG_OE_1_N")
	)
	(segment
		(start 259.207 -170.434)
		(end 259.207 -160.274)
		(width 0.127)
		(layer "In5.Cu")
		(net "DEBUG_OE_1_N")
	)
	(segment
		(start 261.112 -172.339)
		(end 259.207 -170.434)
		(width 0.127)
		(layer "In5.Cu")
		(net "DEBUG_OE_1_N")
	)
	(segment
		(start 303.657 -194.564)
		(end 303.657 -197.231)
		(width 0.1143)
		(layer "F.Cu")
		(net "BMC0_TACH10")
	)
	(segment
		(start 296.834814 -181.849522)
		(end 297.230546 -182.245254)
		(width 0.1143)
		(layer "F.Cu")
		(net "BMC0_TACH10")
	)
	(segment
		(start 308.737 -216.3445)
		(end 308.737 -213.233)
		(width 0.1143)
		(layer "F.Cu")
		(net "BMC0_TACH10")
	)
	(segment
		(start 308.737 -213.233)
		(end 303.657 -208.153)
		(width 0.1143)
		(layer "F.Cu")
		(net "BMC0_TACH10")
	)
	(segment
		(start 303.657 -208.153)
		(end 303.657 -197.231)
		(width 0.1143)
		(layer "F.Cu")
		(net "BMC0_TACH10")
	)
	(segment
		(start 303.276 -194.183)
		(end 303.657 -194.564)
		(width 0.1143)
		(layer "F.Cu")
		(net "BMC0_TACH10")
	)
	(segment
		(start 296.834814 -181.840124)
		(end 296.834814 -181.849522)
		(width 0.1143)
		(layer "F.Cu")
		(net "BMC0_TACH10")
	)
	(via
		(at 303.276 -194.183)
		(size 0.5588)
		(drill 0.3048)
		(layers "F.Cu" "B.Cu")
		(net "BMC0_TACH10")
	)
	(via
		(at 303.657 -197.231)
		(size 0.7112)
		(drill 0.3556)
		(layers "F.Cu" "B.Cu")
		(net "BMC0_TACH10")
	)
	(via
		(at 297.230546 -182.245254)
		(size 0.508)
		(drill 0.254)
		(layers "F.Cu" "B.Cu")
		(net "BMC0_TACH10")
	)
	(segment
		(start 303.276 -192.847214)
		(end 303.276 -194.183)
		(width 0.127)
		(layer "In5.Cu")
		(net "BMC0_TACH10")
	)
	(segment
		(start 297.357292 -182.650892)
		(end 297.357292 -183.06415)
		(width 0.127)
		(layer "In5.Cu")
		(net "BMC0_TACH10")
	)
	(segment
		(start 297.357292 -183.06415)
		(end 300.99 -186.696858)
		(width 0.127)
		(layer "In5.Cu")
		(net "BMC0_TACH10")
	)
	(segment
		(start 301.779178 -191.350392)
		(end 303.276 -192.847214)
		(width 0.127)
		(layer "In5.Cu")
		(net "BMC0_TACH10")
	)
	(segment
		(start 297.230546 -182.524146)
		(end 297.357292 -182.650892)
		(width 0.127)
		(layer "In5.Cu")
		(net "BMC0_TACH10")
	)
	(segment
		(start 300.99 -186.696858)
		(end 300.99 -189.484)
		(width 0.127)
		(layer "In5.Cu")
		(net "BMC0_TACH10")
	)
	(segment
		(start 301.779178 -190.273178)
		(end 301.779178 -191.350392)
		(width 0.127)
		(layer "In5.Cu")
		(net "BMC0_TACH10")
	)
	(segment
		(start 300.99 -189.484)
		(end 301.779178 -190.273178)
		(width 0.127)
		(layer "In5.Cu")
		(net "BMC0_TACH10")
	)
	(segment
		(start 297.230546 -182.245254)
		(end 297.230546 -182.524146)
		(width 0.127)
		(layer "In5.Cu")
		(net "BMC0_TACH10")
	)
	(segment
		(start 307.721 -217.3605)
		(end 307.721 -219.0115)
		(width 0.1143)
		(layer "F.Cu")
		(net "BMC_DEBUG_OE_2_N")
	)
	(segment
		(start 307.594 -217.2335)
		(end 307.721 -217.3605)
		(width 0.1143)
		(layer "F.Cu")
		(net "BMC_DEBUG_OE_2_N")
	)
	(segment
		(start 307.594 -217.2335)
		(end 308.737 -217.2335)
		(width 0.1143)
		(layer "F.Cu")
		(net "BMC_DEBUG_OE_2_N")
	)
	(segment
		(start 308.8005 -217.297)
		(end 309.6514 -217.297)
		(width 0.1143)
		(layer "F.Cu")
		(net "BMC_DEBUG_OE_2_N")
	)
	(segment
		(start 308.737 -217.2335)
		(end 308.8005 -217.297)
		(width 0.1143)
		(layer "F.Cu")
		(net "BMC_DEBUG_OE_2_N")
	)
	(via
		(at 309.6514 -217.297)
		(size 0.7112)
		(drill 0.3556)
		(layers "F.Cu" "B.Cu")
		(net "BMC_DEBUG_OE_2_N")
	)
	(segment
		(start 305.181 -217.2335)
		(end 304.038 -217.2335)
		(width 0.1143)
		(layer "F.Cu")
		(net "BMC_DEBUG_OE_1_N")
	)
	(segment
		(start 305.181 -217.2335)
		(end 305.2445 -217.17)
		(width 0.1143)
		(layer "F.Cu")
		(net "BMC_DEBUG_OE_1_N")
	)
	(segment
		(start 304.038 -217.2335)
		(end 304.419 -217.6145)
		(width 0.1143)
		(layer "F.Cu")
		(net "BMC_DEBUG_OE_1_N")
	)
	(segment
		(start 304.419 -217.6145)
		(end 304.419 -219.0115)
		(width 0.1143)
		(layer "F.Cu")
		(net "BMC_DEBUG_OE_1_N")
	)
	(segment
		(start 305.2445 -217.17)
		(end 306.0954 -217.17)
		(width 0.1143)
		(layer "F.Cu")
		(net "BMC_DEBUG_OE_1_N")
	)
	(via
		(at 306.0954 -217.17)
		(size 0.7112)
		(drill 0.3556)
		(layers "F.Cu" "B.Cu")
		(net "BMC_DEBUG_OE_1_N")
	)
	(segment
		(start 336.9945 -5.0673)
		(end 336.9945 -8.9535)
		(width 0.1778)
		(layer "F.Cu")
		(net "DEBUG CONSOLE_LED_1")
	)
	(segment
		(start 341.1855 -28.5115)
		(end 341.249 -28.448)
		(width 0.1778)
		(layer "F.Cu")
		(net "DEBUG CONSOLE_LED_1")
	)
	(segment
		(start 336.9945 -8.9535)
		(end 340.995 -12.954)
		(width 0.1778)
		(layer "F.Cu")
		(net "DEBUG CONSOLE_LED_1")
	)
	(segment
		(start 335.534 -3.6068)
		(end 336.9945 -5.0673)
		(width 0.1778)
		(layer "F.Cu")
		(net "DEBUG CONSOLE_LED_1")
	)
	(segment
		(start 340.106 -28.5115)
		(end 341.1855 -28.5115)
		(width 0.1778)
		(layer "F.Cu")
		(net "DEBUG CONSOLE_LED_1")
	)
	(via
		(at 340.995 -12.954)
		(size 0.5588)
		(drill 0.3048)
		(layers "F.Cu" "B.Cu")
		(net "DEBUG CONSOLE_LED_1")
	)
	(via
		(at 340.868 -27.178)
		(size 0.7112)
		(drill 0.3556)
		(layers "F.Cu" "B.Cu")
		(net "DEBUG CONSOLE_LED_1")
	)
	(via
		(at 341.249 -28.448)
		(size 0.5588)
		(drill 0.3048)
		(layers "F.Cu" "B.Cu")
		(net "DEBUG CONSOLE_LED_1")
	)
	(segment
		(start 340.868 -26.924)
		(end 340.868 -27.178)
		(width 0.1778)
		(layer "B.Cu")
		(net "DEBUG CONSOLE_LED_1")
	)
	(segment
		(start 344.805 -16.764)
		(end 344.805 -22.987)
		(width 0.1778)
		(layer "B.Cu")
		(net "DEBUG CONSOLE_LED_1")
	)
	(segment
		(start 341.249 -28.448)
		(end 340.868 -28.067)
		(width 0.1778)
		(layer "B.Cu")
		(net "DEBUG CONSOLE_LED_1")
	)
	(segment
		(start 340.995 -12.954)
		(end 344.805 -16.764)
		(width 0.1778)
		(layer "B.Cu")
		(net "DEBUG CONSOLE_LED_1")
	)
	(segment
		(start 340.868 -28.067)
		(end 340.868 -27.178)
		(width 0.1778)
		(layer "B.Cu")
		(net "DEBUG CONSOLE_LED_1")
	)
	(segment
		(start 344.805 -22.987)
		(end 340.868 -26.924)
		(width 0.1778)
		(layer "B.Cu")
		(net "DEBUG CONSOLE_LED_1")
	)
	(segment
		(start 337.82 -2.667)
		(end 337.82 -7.62)
		(width 0.1778)
		(layer "F.Cu")
		(net "DEBUG CONSOLE_LED_0")
	)
	(segment
		(start 343.916 -28.5115)
		(end 342.8365 -28.5115)
		(width 0.1778)
		(layer "F.Cu")
		(net "DEBUG CONSOLE_LED_0")
	)
	(segment
		(start 333.375 -3.6068)
		(end 335.4578 -1.524)
		(width 0.1778)
		(layer "F.Cu")
		(net "DEBUG CONSOLE_LED_0")
	)
	(segment
		(start 337.82 -7.62)
		(end 342.138 -11.938)
		(width 0.1778)
		(layer "F.Cu")
		(net "DEBUG CONSOLE_LED_0")
	)
	(segment
		(start 336.677 -1.524)
		(end 337.82 -2.667)
		(width 0.1778)
		(layer "F.Cu")
		(net "DEBUG CONSOLE_LED_0")
	)
	(segment
		(start 342.138 -11.938)
		(end 342.138 -12.192)
		(width 0.1778)
		(layer "F.Cu")
		(net "DEBUG CONSOLE_LED_0")
	)
	(segment
		(start 342.8365 -28.5115)
		(end 342.773 -28.448)
		(width 0.1778)
		(layer "F.Cu")
		(net "DEBUG CONSOLE_LED_0")
	)
	(segment
		(start 335.4578 -1.524)
		(end 336.677 -1.524)
		(width 0.1778)
		(layer "F.Cu")
		(net "DEBUG CONSOLE_LED_0")
	)
	(via
		(at 342.773 -28.448)
		(size 0.5588)
		(drill 0.3048)
		(layers "F.Cu" "B.Cu")
		(net "DEBUG CONSOLE_LED_0")
	)
	(via
		(at 342.9 -26.797)
		(size 0.7112)
		(drill 0.3556)
		(layers "F.Cu" "B.Cu")
		(net "DEBUG CONSOLE_LED_0")
	)
	(via
		(at 342.138 -12.192)
		(size 0.5588)
		(drill 0.3048)
		(layers "F.Cu" "B.Cu")
		(net "DEBUG CONSOLE_LED_0")
	)
	(segment
		(start 342.138 -12.192)
		(end 342.138 -12.576048)
		(width 0.1778)
		(layer "B.Cu")
		(net "DEBUG CONSOLE_LED_0")
	)
	(segment
		(start 345.2368 -23.3172)
		(end 342.9 -25.654)
		(width 0.1778)
		(layer "B.Cu")
		(net "DEBUG CONSOLE_LED_0")
	)
	(segment
		(start 345.2368 -15.674594)
		(end 345.2368 -23.3172)
		(width 0.1778)
		(layer "B.Cu")
		(net "DEBUG CONSOLE_LED_0")
	)
	(segment
		(start 342.138 -12.576048)
		(end 345.2368 -15.674594)
		(width 0.1778)
		(layer "B.Cu")
		(net "DEBUG CONSOLE_LED_0")
	)
	(segment
		(start 342.9 -25.654)
		(end 342.9 -26.797)
		(width 0.1778)
		(layer "B.Cu")
		(net "DEBUG CONSOLE_LED_0")
	)
	(segment
		(start 342.9 -26.797)
		(end 342.9 -28.067)
		(width 0.1778)
		(layer "B.Cu")
		(net "DEBUG CONSOLE_LED_0")
	)
	(segment
		(start 342.9 -28.067)
		(end 342.773 -28.194)
		(width 0.1778)
		(layer "B.Cu")
		(net "DEBUG CONSOLE_LED_0")
	)
	(segment
		(start 342.773 -28.194)
		(end 342.773 -28.448)
		(width 0.1778)
		(layer "B.Cu")
		(net "DEBUG CONSOLE_LED_0")
	)
	(segment
		(start 332.2955 -10.0965)
		(end 331.851 -9.652)
		(width 0.1778)
		(layer "F.Cu")
		(net "CONSOLE_LED_0")
	)
	(segment
		(start 332.867 -10.0965)
		(end 332.2955 -10.0965)
		(width 0.1778)
		(layer "F.Cu")
		(net "CONSOLE_LED_0")
	)
	(segment
		(start 333.375 -5.0292)
		(end 333.375 -6.5532)
		(width 0.1778)
		(layer "F.Cu")
		(net "CONSOLE_LED_0")
	)
	(segment
		(start 333.375 -6.5532)
		(end 331.851 -8.0772)
		(width 0.1778)
		(layer "F.Cu")
		(net "CONSOLE_LED_0")
	)
	(segment
		(start 331.851 -8.0772)
		(end 331.851 -9.652)
		(width 0.1778)
		(layer "F.Cu")
		(net "CONSOLE_LED_0")
	)
	(via
		(at 331.851 -9.652)
		(size 0.7112)
		(drill 0.3556)
		(layers "F.Cu" "B.Cu")
		(net "CONSOLE_LED_0")
	)
	(segment
		(start 335.534 -8.89)
		(end 335.534 -5.0292)
		(width 0.1778)
		(layer "F.Cu")
		(net "CONSOLE_LED_1")
	)
	(segment
		(start 334.899 -9.525)
		(end 335.534 -8.89)
		(width 0.1778)
		(layer "F.Cu")
		(net "CONSOLE_LED_1")
	)
	(segment
		(start 334.899 -9.525)
		(end 334.3275 -10.0965)
		(width 0.1778)
		(layer "F.Cu")
		(net "CONSOLE_LED_1")
	)
	(segment
		(start 334.3275 -10.0965)
		(end 333.883 -10.0965)
		(width 0.1778)
		(layer "F.Cu")
		(net "CONSOLE_LED_1")
	)
	(via
		(at 334.899 -9.525)
		(size 0.7112)
		(drill 0.3556)
		(layers "F.Cu" "B.Cu")
		(net "CONSOLE_LED_1")
	)
	(segment
		(start 339.471 -34.3535)
		(end 339.471 -32.766)
		(width 0.1143)
		(layer "F.Cu")
		(net "BMC_CONSOLE_LED1_R")
	)
	(segment
		(start 340.4235 -30.4165)
		(end 339.471 -31.369)
		(width 0.1143)
		(layer "F.Cu")
		(net "BMC_CONSOLE_LED1_R")
	)
	(segment
		(start 339.471 -31.369)
		(end 339.471 -32.766)
		(width 0.1143)
		(layer "F.Cu")
		(net "BMC_CONSOLE_LED1_R")
	)
	(segment
		(start 341.09025 -30.4165)
		(end 340.4235 -30.4165)
		(width 0.1143)
		(layer "F.Cu")
		(net "BMC_CONSOLE_LED1_R")
	)
	(via
		(at 339.471 -32.766)
		(size 0.7112)
		(drill 0.3556)
		(layers "F.Cu" "B.Cu")
		(net "BMC_CONSOLE_LED1_R")
	)
	(segment
		(start 186.055 -121.6025)
		(end 187.579 -120.0785)
		(width 0.127)
		(layer "F.Cu")
		(net "PMU_PLTRST#")
	)
	(segment
		(start 181.991 -110.617)
		(end 181.991 -81.407)
		(width 0.127)
		(layer "F.Cu")
		(net "PMU_PLTRST#")
	)
	(segment
		(start 184.9755 -121.6025)
		(end 186.055 -121.6025)
		(width 0.127)
		(layer "F.Cu")
		(net "PMU_PLTRST#")
	)
	(segment
		(start 184.785 -119.652288)
		(end 184.785 -121.412)
		(width 0.127)
		(layer "F.Cu")
		(net "PMU_PLTRST#")
	)
	(segment
		(start 181.991 -81.407)
		(end 181.61 -81.026)
		(width 0.127)
		(layer "F.Cu")
		(net "PMU_PLTRST#")
	)
	(segment
		(start 187.579 -116.205)
		(end 181.991 -110.617)
		(width 0.127)
		(layer "F.Cu")
		(net "PMU_PLTRST#")
	)
	(segment
		(start 187.579 -120.0785)
		(end 187.579 -116.205)
		(width 0.127)
		(layer "F.Cu")
		(net "PMU_PLTRST#")
	)
	(segment
		(start 181.61 -81.026)
		(end 181.61 -78.410054)
		(width 0.127)
		(layer "F.Cu")
		(net "PMU_PLTRST#")
	)
	(segment
		(start 181.61 -78.410054)
		(end 181.449726 -78.24978)
		(width 0.127)
		(layer "F.Cu")
		(net "PMU_PLTRST#")
	)
	(segment
		(start 184.785 -121.412)
		(end 184.9755 -121.6025)
		(width 0.127)
		(layer "F.Cu")
		(net "PMU_PLTRST#")
	)
	(segment
		(start 204.343 -81.534)
		(end 182.245 -81.534)
		(width 0.127)
		(layer "In2.Cu")
		(net "PMU_PLTRST#")
	)
	(segment
		(start 205.486 -79.502)
		(end 205.486 -80.391)
		(width 0.127)
		(layer "In2.Cu")
		(net "PMU_PLTRST#")
	)
	(segment
		(start 209.169 -75.311)
		(end 206.375 -78.105)
		(width 0.127)
		(layer "In2.Cu")
		(net "PMU_PLTRST#")
	)
	(segment
		(start 206.375 -78.613)
		(end 205.486 -79.502)
		(width 0.127)
		(layer "In2.Cu")
		(net "PMU_PLTRST#")
	)
	(segment
		(start 211.449666 -75.75042)
		(end 211.010246 -75.311)
		(width 0.127)
		(layer "In2.Cu")
		(net "PMU_PLTRST#")
	)
	(segment
		(start 206.375 -78.105)
		(end 206.375 -78.613)
		(width 0.127)
		(layer "In2.Cu")
		(net "PMU_PLTRST#")
	)
	(segment
		(start 211.010246 -75.311)
		(end 209.169 -75.311)
		(width 0.127)
		(layer "In2.Cu")
		(net "PMU_PLTRST#")
	)
	(segment
		(start 205.486 -80.391)
		(end 204.343 -81.534)
		(width 0.127)
		(layer "In2.Cu")
		(net "PMU_PLTRST#")
	)
	(segment
		(start 182.245 -81.534)
		(end 181.449726 -80.738726)
		(width 0.127)
		(layer "In2.Cu")
		(net "PMU_PLTRST#")
	)
	(segment
		(start 181.449726 -80.738726)
		(end 181.449726 -78.24978)
		(width 0.127)
		(layer "In2.Cu")
		(net "PMU_PLTRST#")
	)
	(segment
		(start 298.577 -189.992)
		(end 298.577 -187.814204)
		(width 0.1143)
		(layer "F.Cu")
		(net "BMC0_TACH14")
	)
	(segment
		(start 296.834814 -183.550814)
		(end 296.834814 -183.44007)
		(width 0.1143)
		(layer "F.Cu")
		(net "BMC0_TACH14")
	)
	(segment
		(start 299.10405 -186.385708)
		(end 297.18 -184.461658)
		(width 0.1143)
		(layer "F.Cu")
		(net "BMC0_TACH14")
	)
	(segment
		(start 298.704 -191.4525)
		(end 298.704 -190.119)
		(width 0.1143)
		(layer "F.Cu")
		(net "BMC0_TACH14")
	)
	(segment
		(start 298.734226 -187.656978)
		(end 298.734226 -187.332874)
		(width 0.1143)
		(layer "F.Cu")
		(net "BMC0_TACH14")
	)
	(segment
		(start 298.704 -190.119)
		(end 298.577 -189.992)
		(width 0.1143)
		(layer "F.Cu")
		(net "BMC0_TACH14")
	)
	(segment
		(start 297.18 -183.896)
		(end 296.834814 -183.550814)
		(width 0.1143)
		(layer "F.Cu")
		(net "BMC0_TACH14")
	)
	(segment
		(start 299.10405 -186.96305)
		(end 299.10405 -186.385708)
		(width 0.1143)
		(layer "F.Cu")
		(net "BMC0_TACH14")
	)
	(segment
		(start 298.577 -187.814204)
		(end 298.734226 -187.656978)
		(width 0.1143)
		(layer "F.Cu")
		(net "BMC0_TACH14")
	)
	(segment
		(start 297.18 -184.461658)
		(end 297.18 -183.896)
		(width 0.1143)
		(layer "F.Cu")
		(net "BMC0_TACH14")
	)
	(segment
		(start 298.734226 -187.332874)
		(end 299.10405 -186.96305)
		(width 0.1143)
		(layer "F.Cu")
		(net "BMC0_TACH14")
	)
	(via
		(at 298.577 -189.992)
		(size 0.7112)
		(drill 0.3556)
		(layers "F.Cu" "B.Cu")
		(net "BMC0_TACH14")
	)
	(segment
		(start 304.773076 -181.61)
		(end 304.639726 -181.74335)
		(width 0.1143)
		(layer "F.Cu")
		(net "TP_BMC_GPIOM1")
	)
	(segment
		(start 304.639726 -181.74335)
		(end 302.014128 -181.74335)
		(width 0.1143)
		(layer "F.Cu")
		(net "TP_BMC_GPIOM1")
	)
	(segment
		(start 302.014128 -181.74335)
		(end 301.774352 -181.503574)
		(width 0.1143)
		(layer "F.Cu")
		(net "TP_BMC_GPIOM1")
	)
	(segment
		(start 305.308 -181.61)
		(end 304.773076 -181.61)
		(width 0.1143)
		(layer "F.Cu")
		(net "TP_BMC_GPIOM1")
	)
	(segment
		(start 301.171356 -181.503574)
		(end 300.834806 -181.840124)
		(width 0.1143)
		(layer "F.Cu")
		(net "TP_BMC_GPIOM1")
	)
	(segment
		(start 301.774352 -181.503574)
		(end 301.171356 -181.503574)
		(width 0.1143)
		(layer "F.Cu")
		(net "TP_BMC_GPIOM1")
	)
	(segment
		(start 104.223058 -54.860444)
		(end 104.20858 -54.860444)
		(width 0.1143)
		(layer "F.Cu")
		(net "IOC_TDO")
	)
	(segment
		(start 104.20858 -54.860444)
		(end 103.949246 -54.60111)
		(width 0.1143)
		(layer "F.Cu")
		(net "IOC_TDO")
	)
	(segment
		(start 104.350058 -54.987444)
		(end 104.223058 -54.860444)
		(width 0.1143)
		(layer "F.Cu")
		(net "IOC_TDO")
	)
	(segment
		(start 104.350058 -54.99989)
		(end 104.350058 -54.987444)
		(width 0.1143)
		(layer "F.Cu")
		(net "IOC_TDO")
	)
	(via
		(at 103.949246 -54.60111)
		(size 0.508)
		(drill 0.254)
		(layers "F.Cu" "B.Cu")
		(net "IOC_TDO")
	)
	(segment
		(start 103.994966 -58.166)
		(end 103.994966 -56.0578)
		(width 0.1143)
		(layer "B.Cu")
		(net "IOC_TDO")
	)
	(segment
		(start 104.502966 -58.674)
		(end 103.994966 -58.166)
		(width 0.1143)
		(layer "B.Cu")
		(net "IOC_TDO")
	)
	(segment
		(start 105.010966 -60.1345)
		(end 105.264966 -59.8805)
		(width 0.1143)
		(layer "B.Cu")
		(net "IOC_TDO")
	)
	(segment
		(start 105.264966 -59.8805)
		(end 105.264966 -58.928)
		(width 0.1143)
		(layer "B.Cu")
		(net "IOC_TDO")
	)
	(segment
		(start 103.994966 -56.0578)
		(end 103.740966 -55.8038)
		(width 0.1143)
		(layer "B.Cu")
		(net "IOC_TDO")
	)
	(segment
		(start 105.264966 -58.928)
		(end 105.010966 -58.674)
		(width 0.1143)
		(layer "B.Cu")
		(net "IOC_TDO")
	)
	(segment
		(start 103.740966 -55.8038)
		(end 103.740966 -54.80939)
		(width 0.1143)
		(layer "B.Cu")
		(net "IOC_TDO")
	)
	(segment
		(start 105.010966 -58.674)
		(end 104.502966 -58.674)
		(width 0.1143)
		(layer "B.Cu")
		(net "IOC_TDO")
	)
	(segment
		(start 103.740966 -54.80939)
		(end 103.949246 -54.60111)
		(width 0.1143)
		(layer "B.Cu")
		(net "IOC_TDO")
	)
	(segment
		(start 80.264 -20.701)
		(end 79.121 -20.701)
		(width 0.3556)
		(layer "F.Cu")
		(net "AGND_P0V9_C")
	)
	(segment
		(start 79.121 -20.701)
		(end 77.8764 -20.701)
		(width 0.508)
		(layer "F.Cu")
		(net "AGND_P0V9_C")
	)
	(segment
		(start 80.648556 -20.36953)
		(end 80.59547 -20.36953)
		(width 0.3556)
		(layer "F.Cu")
		(net "AGND_P0V9_C")
	)
	(segment
		(start 80.59547 -20.36953)
		(end 80.264 -20.701)
		(width 0.3556)
		(layer "F.Cu")
		(net "AGND_P0V9_C")
	)
	(via
		(at 85.598 -18.669)
		(size 0.7112)
		(drill 0.3556)
		(layers "F.Cu" "B.Cu")
		(net "AGND_P0V9_C")
	)
	(via
		(at 79.121 -20.701)
		(size 0.5588)
		(drill 0.3048)
		(layers "F.Cu" "B.Cu")
		(net "AGND_P0V9_C")
	)
	(segment
		(start 82.804 -20.7645)
		(end 81.661 -20.7645)
		(width 0.508)
		(layer "B.Cu")
		(net "AGND_P0V9_C")
	)
	(segment
		(start 84.2518 -19.1262)
		(end 84.455 -18.923)
		(width 0.508)
		(layer "B.Cu")
		(net "AGND_P0V9_C")
	)
	(segment
		(start 80.137 -20.701)
		(end 79.121 -20.701)
		(width 0.508)
		(layer "B.Cu")
		(net "AGND_P0V9_C")
	)
	(segment
		(start 81.153 -19.558)
		(end 81.5848 -19.1262)
		(width 0.508)
		(layer "B.Cu")
		(net "AGND_P0V9_C")
	)
	(segment
		(start 84.455 -18.923)
		(end 84.709 -18.669)
		(width 0.508)
		(layer "B.Cu")
		(net "AGND_P0V9_C")
	)
	(segment
		(start 82.804 -19.1262)
		(end 82.804 -20.7645)
		(width 0.508)
		(layer "B.Cu")
		(net "AGND_P0V9_C")
	)
	(segment
		(start 79.883 -19.558)
		(end 81.153 -19.558)
		(width 0.508)
		(layer "B.Cu")
		(net "AGND_P0V9_C")
	)
	(segment
		(start 84.709 -18.669)
		(end 85.598 -18.669)
		(width 0.508)
		(layer "B.Cu")
		(net "AGND_P0V9_C")
	)
	(segment
		(start 80.2005 -20.7645)
		(end 80.137 -20.701)
		(width 0.508)
		(layer "B.Cu")
		(net "AGND_P0V9_C")
	)
	(segment
		(start 80.518 -20.7645)
		(end 80.2005 -20.7645)
		(width 0.508)
		(layer "B.Cu")
		(net "AGND_P0V9_C")
	)
	(segment
		(start 82.804 -19.1262)
		(end 84.2518 -19.1262)
		(width 0.508)
		(layer "B.Cu")
		(net "AGND_P0V9_C")
	)
	(segment
		(start 81.661 -20.7645)
		(end 80.518 -20.7645)
		(width 0.508)
		(layer "B.Cu")
		(net "AGND_P0V9_C")
	)
	(segment
		(start 81.5848 -19.1262)
		(end 82.804 -19.1262)
		(width 0.508)
		(layer "B.Cu")
		(net "AGND_P0V9_C")
	)
	(segment
		(start 111.296196 -73.8124)
		(end 112.286796 -74.803)
		(width 0.1778)
		(layer "F.Cu")
		(net "EXP_HW_LED_D")
	)
	(segment
		(start 115.189 -75.062842)
		(end 115.189 -77.089)
		(width 0.1778)
		(layer "F.Cu")
		(net "EXP_HW_LED_D")
	)
	(segment
		(start 115.056158 -74.93)
		(end 115.189 -75.062842)
		(width 0.1778)
		(layer "F.Cu")
		(net "EXP_HW_LED_D")
	)
	(segment
		(start 111.26597 -73.8124)
		(end 111.296196 -73.8124)
		(width 0.1778)
		(layer "F.Cu")
		(net "EXP_HW_LED_D")
	)
	(segment
		(start 114.929158 -74.803)
		(end 115.056158 -74.93)
		(width 0.1778)
		(layer "F.Cu")
		(net "EXP_HW_LED_D")
	)
	(segment
		(start 112.286796 -74.803)
		(end 114.929158 -74.803)
		(width 0.1778)
		(layer "F.Cu")
		(net "EXP_HW_LED_D")
	)
	(via
		(at 115.189 -77.089)
		(size 0.7112)
		(drill 0.3556)
		(layers "F.Cu" "B.Cu")
		(net "EXP_HW_LED_D")
	)
	(segment
		(start 110.49 -74.56043)
		(end 110.49 -74.676)
		(width 0.1778)
		(layer "F.Cu")
		(net "EXP_HW_LED_R")
	)
	(segment
		(start 109.74197 -73.8124)
		(end 110.49 -74.56043)
		(width 0.1778)
		(layer "F.Cu")
		(net "EXP_HW_LED_R")
	)
	(via
		(at 110.49 -74.676)
		(size 0.5588)
		(drill 0.3048)
		(layers "F.Cu" "B.Cu")
		(net "EXP_HW_LED_R")
	)
	(via
		(at 109.8804 -74.0156)
		(size 0.7112)
		(drill 0.3556)
		(layers "F.Cu" "B.Cu")
		(net "EXP_HW_LED_R")
	)
	(segment
		(start 110.4392 -74.676)
		(end 109.9058 -74.1426)
		(width 0.1778)
		(layer "B.Cu")
		(net "EXP_HW_LED_R")
	)
	(segment
		(start 109.9058 -74.041)
		(end 109.8804 -74.0156)
		(width 0.1778)
		(layer "B.Cu")
		(net "EXP_HW_LED_R")
	)
	(segment
		(start 110.50397 -73.0885)
		(end 109.8804 -73.71207)
		(width 0.1778)
		(layer "B.Cu")
		(net "EXP_HW_LED_R")
	)
	(segment
		(start 109.8804 -73.71207)
		(end 109.8804 -74.0156)
		(width 0.1778)
		(layer "B.Cu")
		(net "EXP_HW_LED_R")
	)
	(segment
		(start 109.9058 -74.1426)
		(end 109.9058 -74.041)
		(width 0.1778)
		(layer "B.Cu")
		(net "EXP_HW_LED_R")
	)
	(segment
		(start 110.49 -74.676)
		(end 110.4392 -74.676)
		(width 0.1778)
		(layer "B.Cu")
		(net "EXP_HW_LED_R")
	)
	(segment
		(start 298.09821 -184.22747)
		(end 297.76674 -183.896)
		(width 0.1143)
		(layer "F.Cu")
		(net "BMC0_TACH13")
	)
	(segment
		(start 300.736 -191.4525)
		(end 300.736 -191.262)
		(width 0.1143)
		(layer "F.Cu")
		(net "BMC0_TACH13")
	)
	(segment
		(start 300.228 -189.357)
		(end 300.228 -187.91682)
		(width 0.1143)
		(layer "F.Cu")
		(net "BMC0_TACH13")
	)
	(segment
		(start 300.736 -191.262)
		(end 300.228 -190.754)
		(width 0.1143)
		(layer "F.Cu")
		(net "BMC0_TACH13")
	)
	(segment
		(start 297.76674 -183.896)
		(end 297.614848 -183.896)
		(width 0.1143)
		(layer "F.Cu")
		(net "BMC0_TACH13")
	)
	(segment
		(start 297.298364 -183.103774)
		(end 296.834814 -182.640224)
		(width 0.1143)
		(layer "F.Cu")
		(net "BMC0_TACH13")
	)
	(segment
		(start 297.298364 -183.579516)
		(end 297.298364 -183.103774)
		(width 0.1143)
		(layer "F.Cu")
		(net "BMC0_TACH13")
	)
	(segment
		(start 300.228 -190.754)
		(end 300.228 -189.357)
		(width 0.1143)
		(layer "F.Cu")
		(net "BMC0_TACH13")
	)
	(segment
		(start 299.60824 -187.29706)
		(end 299.60824 -185.889646)
		(width 0.1143)
		(layer "F.Cu")
		(net "BMC0_TACH13")
	)
	(segment
		(start 298.09821 -184.379616)
		(end 298.09821 -184.22747)
		(width 0.1143)
		(layer "F.Cu")
		(net "BMC0_TACH13")
	)
	(segment
		(start 297.614848 -183.896)
		(end 297.298364 -183.579516)
		(width 0.1143)
		(layer "F.Cu")
		(net "BMC0_TACH13")
	)
	(segment
		(start 300.228 -187.91682)
		(end 299.60824 -187.29706)
		(width 0.1143)
		(layer "F.Cu")
		(net "BMC0_TACH13")
	)
	(segment
		(start 299.60824 -185.889646)
		(end 298.09821 -184.379616)
		(width 0.1143)
		(layer "F.Cu")
		(net "BMC0_TACH13")
	)
	(via
		(at 300.228 -189.357)
		(size 0.7112)
		(drill 0.3556)
		(layers "F.Cu" "B.Cu")
		(net "BMC0_TACH13")
	)
	(segment
		(start 297.634914 -184.350914)
		(end 299.34535 -186.06135)
		(width 0.1143)
		(layer "F.Cu")
		(net "BMC0_TACH12")
	)
	(segment
		(start 299.339 -190.627)
		(end 299.339 -188.341)
		(width 0.1143)
		(layer "F.Cu")
		(net "BMC0_TACH12")
	)
	(segment
		(start 299.34535 -187.063126)
		(end 299.25772 -187.150756)
		(width 0.1143)
		(layer "F.Cu")
		(net "BMC0_TACH12")
	)
	(segment
		(start 299.72 -191.008)
		(end 299.339 -190.627)
		(width 0.1143)
		(layer "F.Cu")
		(net "BMC0_TACH12")
	)
	(segment
		(start 299.25772 -188.25972)
		(end 299.339 -188.341)
		(width 0.1143)
		(layer "F.Cu")
		(net "BMC0_TACH12")
	)
	(segment
		(start 299.34535 -186.06135)
		(end 299.34535 -187.063126)
		(width 0.1143)
		(layer "F.Cu")
		(net "BMC0_TACH12")
	)
	(segment
		(start 299.72 -191.4525)
		(end 299.72 -191.008)
		(width 0.1143)
		(layer "F.Cu")
		(net "BMC0_TACH12")
	)
	(segment
		(start 299.25772 -187.150756)
		(end 299.25772 -188.25972)
		(width 0.1143)
		(layer "F.Cu")
		(net "BMC0_TACH12")
	)
	(segment
		(start 297.634914 -184.24017)
		(end 297.634914 -184.350914)
		(width 0.1143)
		(layer "F.Cu")
		(net "BMC0_TACH12")
	)
	(via
		(at 299.339 -188.341)
		(size 0.7112)
		(drill 0.3556)
		(layers "F.Cu" "B.Cu")
		(net "BMC0_TACH12")
	)
	(segment
		(start 300.57598 -186.057286)
		(end 299.684694 -185.166)
		(width 0.1143)
		(layer "F.Cu")
		(net "BMC0_TACH11")
	)
	(segment
		(start 298.77131 -184.100724)
		(end 298.574206 -183.90362)
		(width 0.1143)
		(layer "F.Cu")
		(net "BMC0_TACH11")
	)
	(segment
		(start 298.06138 -183.642)
		(end 297.836844 -183.642)
		(width 0.1143)
		(layer "F.Cu")
		(net "BMC0_TACH11")
	)
	(segment
		(start 302.006 -188.1378)
		(end 300.57598 -186.70778)
		(width 0.1143)
		(layer "F.Cu")
		(net "BMC0_TACH11")
	)
	(segment
		(start 298.323 -183.90362)
		(end 298.06138 -183.642)
		(width 0.1143)
		(layer "F.Cu")
		(net "BMC0_TACH11")
	)
	(segment
		(start 297.836844 -183.642)
		(end 297.634914 -183.44007)
		(width 0.1143)
		(layer "F.Cu")
		(net "BMC0_TACH11")
	)
	(segment
		(start 298.77131 -184.34431)
		(end 298.77131 -184.100724)
		(width 0.1143)
		(layer "F.Cu")
		(net "BMC0_TACH11")
	)
	(segment
		(start 300.57598 -186.70778)
		(end 300.57598 -186.057286)
		(width 0.1143)
		(layer "F.Cu")
		(net "BMC0_TACH11")
	)
	(segment
		(start 302.006 -188.5315)
		(end 302.006 -188.1378)
		(width 0.1143)
		(layer "F.Cu")
		(net "BMC0_TACH11")
	)
	(segment
		(start 299.684694 -185.166)
		(end 299.593 -185.166)
		(width 0.1143)
		(layer "F.Cu")
		(net "BMC0_TACH11")
	)
	(segment
		(start 298.574206 -183.90362)
		(end 298.323 -183.90362)
		(width 0.1143)
		(layer "F.Cu")
		(net "BMC0_TACH11")
	)
	(segment
		(start 299.593 -185.166)
		(end 298.77131 -184.34431)
		(width 0.1143)
		(layer "F.Cu")
		(net "BMC0_TACH11")
	)
	(via
		(at 300.57598 -186.70778)
		(size 0.7112)
		(drill 0.3556)
		(layers "F.Cu" "B.Cu")
		(net "BMC0_TACH11")
	)
	(segment
		(start 306.578 -183.007)
		(end 306.07 -183.515)
		(width 0.1143)
		(layer "F.Cu")
		(net "TP_BMC_GPIOM2")
	)
	(segment
		(start 303.149 -183.261)
		(end 302.528224 -182.640224)
		(width 0.1143)
		(layer "F.Cu")
		(net "TP_BMC_GPIOM2")
	)
	(segment
		(start 302.528224 -182.640224)
		(end 301.634906 -182.640224)
		(width 0.1143)
		(layer "F.Cu")
		(net "TP_BMC_GPIOM2")
	)
	(segment
		(start 304.573432 -183.261)
		(end 303.149 -183.261)
		(width 0.1143)
		(layer "F.Cu")
		(net "TP_BMC_GPIOM2")
	)
	(segment
		(start 304.827432 -183.515)
		(end 304.573432 -183.261)
		(width 0.1143)
		(layer "F.Cu")
		(net "TP_BMC_GPIOM2")
	)
	(segment
		(start 306.07 -183.515)
		(end 304.827432 -183.515)
		(width 0.1143)
		(layer "F.Cu")
		(net "TP_BMC_GPIOM2")
	)
	(segment
		(start 306.451 -179.324)
		(end 306.324 -179.451)
		(width 0.1143)
		(layer "F.Cu")
		(net "TP_BMC_GPIOM0")
	)
	(segment
		(start 301.213012 -180.186076)
		(end 301.213012 -180.337968)
		(width 0.1143)
		(layer "F.Cu")
		(net "TP_BMC_GPIOM0")
	)
	(segment
		(start 306.324 -179.451)
		(end 303.046892 -179.451)
		(width 0.1143)
		(layer "F.Cu")
		(net "TP_BMC_GPIOM0")
	)
	(segment
		(start 303.046892 -179.451)
		(end 302.721264 -179.776628)
		(width 0.1143)
		(layer "F.Cu")
		(net "TP_BMC_GPIOM0")
	)
	(segment
		(start 300.847506 -180.703474)
		(end 300.69536 -180.703474)
		(width 0.1143)
		(layer "F.Cu")
		(net "TP_BMC_GPIOM0")
	)
	(segment
		(start 300.69536 -180.703474)
		(end 300.35881 -181.040024)
		(width 0.1143)
		(layer "F.Cu")
		(net "TP_BMC_GPIOM0")
	)
	(segment
		(start 301.62246 -179.776628)
		(end 301.213012 -180.186076)
		(width 0.1143)
		(layer "F.Cu")
		(net "TP_BMC_GPIOM0")
	)
	(segment
		(start 301.213012 -180.337968)
		(end 300.847506 -180.703474)
		(width 0.1143)
		(layer "F.Cu")
		(net "TP_BMC_GPIOM0")
	)
	(segment
		(start 300.35881 -181.040024)
		(end 300.03496 -181.040024)
		(width 0.1143)
		(layer "F.Cu")
		(net "TP_BMC_GPIOM0")
	)
	(segment
		(start 302.721264 -179.776628)
		(end 301.62246 -179.776628)
		(width 0.1143)
		(layer "F.Cu")
		(net "TP_BMC_GPIOM0")
	)
	(segment
		(start 57.023 -104.648)
		(end 57.023 -109.601)
		(width 0.1143)
		(layer "F.Cu")
		(net "BMC_R_TXD5")
	)
	(segment
		(start 47.879 -114.0079)
		(end 47.5742 -114.3127)
		(width 0.1143)
		(layer "F.Cu")
		(net "BMC_R_TXD5")
	)
	(segment
		(start 54.991 -104.521)
		(end 54.991 -104.0384)
		(width 0.1143)
		(layer "F.Cu")
		(net "BMC_R_TXD5")
	)
	(segment
		(start 56.007 -103.632)
		(end 57.023 -104.648)
		(width 0.1143)
		(layer "F.Cu")
		(net "BMC_R_TXD5")
	)
	(segment
		(start 54.864 -111.76)
		(end 49.229772 -111.76)
		(width 0.1143)
		(layer "F.Cu")
		(net "BMC_R_TXD5")
	)
	(segment
		(start 47.879 -113.110772)
		(end 47.879 -114.0079)
		(width 0.1143)
		(layer "F.Cu")
		(net "BMC_R_TXD5")
	)
	(segment
		(start 54.991 -104.0384)
		(end 55.3974 -103.632)
		(width 0.1143)
		(layer "F.Cu")
		(net "BMC_R_TXD5")
	)
	(segment
		(start 57.023 -109.601)
		(end 54.864 -111.76)
		(width 0.1143)
		(layer "F.Cu")
		(net "BMC_R_TXD5")
	)
	(segment
		(start 49.229772 -111.76)
		(end 47.879 -113.110772)
		(width 0.1143)
		(layer "F.Cu")
		(net "BMC_R_TXD5")
	)
	(segment
		(start 55.3974 -103.632)
		(end 56.007 -103.632)
		(width 0.1143)
		(layer "F.Cu")
		(net "BMC_R_TXD5")
	)
	(segment
		(start 56.243728 -103.0605)
		(end 57.5945 -104.411272)
		(width 0.1143)
		(layer "F.Cu")
		(net "BMC_R_RXD5")
	)
	(segment
		(start 55.100728 -112.3315)
		(end 49.4665 -112.3315)
		(width 0.1143)
		(layer "F.Cu")
		(net "BMC_R_RXD5")
	)
	(segment
		(start 49.4665 -112.3315)
		(end 48.4505 -113.3475)
		(width 0.1143)
		(layer "F.Cu")
		(net "BMC_R_RXD5")
	)
	(segment
		(start 57.5945 -109.837728)
		(end 55.100728 -112.3315)
		(width 0.1143)
		(layer "F.Cu")
		(net "BMC_R_RXD5")
	)
	(segment
		(start 48.4505 -113.3475)
		(end 48.4505 -114.046)
		(width 0.1143)
		(layer "F.Cu")
		(net "BMC_R_RXD5")
	)
	(segment
		(start 54.991 -101.981)
		(end 54.991 -102.6795)
		(width 0.1143)
		(layer "F.Cu")
		(net "BMC_R_RXD5")
	)
	(segment
		(start 48.4505 -114.046)
		(end 48.7172 -114.3127)
		(width 0.1143)
		(layer "F.Cu")
		(net "BMC_R_RXD5")
	)
	(segment
		(start 57.5945 -104.411272)
		(end 57.5945 -109.837728)
		(width 0.1143)
		(layer "F.Cu")
		(net "BMC_R_RXD5")
	)
	(segment
		(start 55.372 -103.0605)
		(end 56.243728 -103.0605)
		(width 0.1143)
		(layer "F.Cu")
		(net "BMC_R_RXD5")
	)
	(segment
		(start 54.991 -102.6795)
		(end 55.372 -103.0605)
		(width 0.1143)
		(layer "F.Cu")
		(net "BMC_R_RXD5")
	)
	(segment
		(start 116.332 -72.771)
		(end 114.98072 -71.41972)
		(width 0.1143)
		(layer "F.Cu")
		(net "TEMP_4_ALERT")
	)
	(segment
		(start 114.98072 -71.41972)
		(end 114.28603 -71.41972)
		(width 0.1143)
		(layer "F.Cu")
		(net "TEMP_4_ALERT")
	)
	(segment
		(start 139.45997 -84.0105)
		(end 139.65047 -84.0105)
		(width 0.1143)
		(layer "F.Cu")
		(net "TEMP_3_A2")
	)
	(segment
		(start 139.65047 -84.0105)
		(end 140.50137 -84.8614)
		(width 0.1143)
		(layer "F.Cu")
		(net "TEMP_3_A2")
	)
	(segment
		(start 139.90701 -86.356952)
		(end 139.90701 -85.50656)
		(width 0.1143)
		(layer "F.Cu")
		(net "TEMP_3_A2")
	)
	(segment
		(start 140.50137 -84.8614)
		(end 140.50137 -84.9122)
		(width 0.1143)
		(layer "F.Cu")
		(net "TEMP_3_A2")
	)
	(segment
		(start 139.90701 -85.50656)
		(end 140.50137 -84.9122)
		(width 0.1143)
		(layer "F.Cu")
		(net "TEMP_3_A2")
	)
	(via
		(at 139.89177 -85.725)
		(size 0.7112)
		(drill 0.3556)
		(layers "F.Cu" "B.Cu")
		(net "TEMP_3_A2")
	)
	(via
		(at 140.50137 -84.9122)
		(size 0.5588)
		(drill 0.3048)
		(layers "F.Cu" "B.Cu")
		(net "TEMP_3_A2")
	)
	(segment
		(start 139.89177 -85.5218)
		(end 139.89177 -85.725)
		(width 0.1143)
		(layer "B.Cu")
		(net "TEMP_3_A2")
	)
	(segment
		(start 139.84097 -85.7758)
		(end 139.89177 -85.725)
		(width 0.1143)
		(layer "B.Cu")
		(net "TEMP_3_A2")
	)
	(segment
		(start 139.33297 -86.8045)
		(end 139.84097 -85.7758)
		(width 0.1143)
		(layer "B.Cu")
		(net "TEMP_3_A2")
	)
	(segment
		(start 140.50137 -84.9122)
		(end 139.89177 -85.5218)
		(width 0.1143)
		(layer "B.Cu")
		(net "TEMP_3_A2")
	)
	(segment
		(start 141.239494 -84.885276)
		(end 141.493494 -84.885276)
		(width 0.1143)
		(layer "F.Cu")
		(net "TEMP_3_A1")
	)
	(segment
		(start 140.618718 -84.0105)
		(end 141.493494 -84.885276)
		(width 0.1143)
		(layer "F.Cu")
		(net "TEMP_3_A1")
	)
	(segment
		(start 140.55725 -86.356952)
		(end 140.55725 -85.56752)
		(width 0.1143)
		(layer "F.Cu")
		(net "TEMP_3_A1")
	)
	(segment
		(start 140.55725 -85.56752)
		(end 141.239494 -84.885276)
		(width 0.1143)
		(layer "F.Cu")
		(net "TEMP_3_A1")
	)
	(segment
		(start 140.47597 -84.0105)
		(end 140.618718 -84.0105)
		(width 0.1143)
		(layer "F.Cu")
		(net "TEMP_3_A1")
	)
	(via
		(at 141.33957 -85.7758)
		(size 0.7112)
		(drill 0.3556)
		(layers "F.Cu" "B.Cu")
		(net "TEMP_3_A1")
	)
	(via
		(at 141.493494 -84.885276)
		(size 0.5588)
		(drill 0.3048)
		(layers "F.Cu" "B.Cu")
		(net "TEMP_3_A1")
	)
	(segment
		(start 140.85697 -86.2584)
		(end 141.33957 -85.7758)
		(width 0.1143)
		(layer "B.Cu")
		(net "TEMP_3_A1")
	)
	(segment
		(start 141.33957 -85.7758)
		(end 141.493494 -85.621876)
		(width 0.1143)
		(layer "B.Cu")
		(net "TEMP_3_A1")
	)
	(segment
		(start 141.493494 -85.621876)
		(end 141.493494 -84.885276)
		(width 0.1143)
		(layer "B.Cu")
		(net "TEMP_3_A1")
	)
	(segment
		(start 140.34897 -86.8045)
		(end 140.85697 -86.2584)
		(width 0.1143)
		(layer "B.Cu")
		(net "TEMP_3_A1")
	)
	(segment
		(start 142.55242 -83.941158)
		(end 142.304262 -83.693)
		(width 0.1143)
		(layer "F.Cu")
		(net "TEMP_3_A0")
	)
	(segment
		(start 141.20749 -86.356952)
		(end 141.20749 -85.62848)
		(width 0.1143)
		(layer "F.Cu")
		(net "TEMP_3_A0")
	)
	(segment
		(start 141.20749 -85.62848)
		(end 141.44117 -85.3948)
		(width 0.1143)
		(layer "F.Cu")
		(net "TEMP_3_A0")
	)
	(segment
		(start 142.22857 -83.693)
		(end 142.304262 -83.693)
		(width 0.1143)
		(layer "F.Cu")
		(net "TEMP_3_A0")
	)
	(segment
		(start 141.982444 -85.087968)
		(end 141.982444 -85.082126)
		(width 0.1143)
		(layer "F.Cu")
		(net "TEMP_3_A0")
	)
	(segment
		(start 141.91107 -84.0105)
		(end 142.22857 -83.693)
		(width 0.1143)
		(layer "F.Cu")
		(net "TEMP_3_A0")
	)
	(segment
		(start 141.982444 -85.082126)
		(end 142.33017 -84.7344)
		(width 0.1143)
		(layer "F.Cu")
		(net "TEMP_3_A0")
	)
	(segment
		(start 141.49197 -84.0105)
		(end 141.91107 -84.0105)
		(width 0.1143)
		(layer "F.Cu")
		(net "TEMP_3_A0")
	)
	(segment
		(start 142.55242 -84.51215)
		(end 142.55242 -83.941158)
		(width 0.1143)
		(layer "F.Cu")
		(net "TEMP_3_A0")
	)
	(segment
		(start 142.33017 -84.7344)
		(end 142.55242 -84.51215)
		(width 0.1143)
		(layer "F.Cu")
		(net "TEMP_3_A0")
	)
	(segment
		(start 141.696186 -85.374226)
		(end 141.982444 -85.087968)
		(width 0.1143)
		(layer "F.Cu")
		(net "TEMP_3_A0")
	)
	(segment
		(start 141.690344 -85.374226)
		(end 141.696186 -85.374226)
		(width 0.1143)
		(layer "F.Cu")
		(net "TEMP_3_A0")
	)
	(segment
		(start 141.66977 -85.3948)
		(end 141.690344 -85.374226)
		(width 0.1143)
		(layer "F.Cu")
		(net "TEMP_3_A0")
	)
	(segment
		(start 141.44117 -85.3948)
		(end 141.66977 -85.3948)
		(width 0.1143)
		(layer "F.Cu")
		(net "TEMP_3_A0")
	)
	(via
		(at 142.33017 -84.7344)
		(size 0.7112)
		(drill 0.3556)
		(layers "F.Cu" "B.Cu")
		(net "TEMP_3_A0")
	)
	(via
		(at 142.304262 -83.693)
		(size 0.5588)
		(drill 0.3048)
		(layers "F.Cu" "B.Cu")
		(net "TEMP_3_A0")
	)
	(segment
		(start 142.304262 -85.865208)
		(end 142.304262 -83.693)
		(width 0.1143)
		(layer "B.Cu")
		(net "TEMP_3_A0")
	)
	(segment
		(start 141.36497 -86.8045)
		(end 142.304262 -85.865208)
		(width 0.1143)
		(layer "B.Cu")
		(net "TEMP_3_A0")
	)
	(segment
		(start 139.07897 -92.583)
		(end 140.55725 -91.48572)
		(width 0.1143)
		(layer "F.Cu")
		(net "TEMP_3_ALERT")
	)
	(segment
		(start 140.55725 -91.48572)
		(end 140.55725 -90.466672)
		(width 0.1143)
		(layer "F.Cu")
		(net "TEMP_3_ALERT")
	)
	(segment
		(start 141.20749 -90.466672)
		(end 141.20749 -92.202)
		(width 0.1143)
		(layer "F.Cu")
		(net "TEMP_3_SCL")
	)
	(segment
		(start 140.47597 -93.1418)
		(end 140.47597 -92.583)
		(width 0.1143)
		(layer "F.Cu")
		(net "TEMP_3_SCL")
	)
	(segment
		(start 140.95857 -93.5101)
		(end 140.84427 -93.5101)
		(width 0.1143)
		(layer "F.Cu")
		(net "TEMP_3_SCL")
	)
	(segment
		(start 140.85697 -92.202)
		(end 140.47597 -92.583)
		(width 0.1143)
		(layer "F.Cu")
		(net "TEMP_3_SCL")
	)
	(segment
		(start 141.20749 -92.202)
		(end 140.85697 -92.202)
		(width 0.1143)
		(layer "F.Cu")
		(net "TEMP_3_SCL")
	)
	(segment
		(start 140.84427 -93.5101)
		(end 140.47597 -93.1418)
		(width 0.1143)
		(layer "F.Cu")
		(net "TEMP_3_SCL")
	)
	(via
		(at 141.20749 -92.202)
		(size 0.5588)
		(drill 0.3048)
		(layers "F.Cu" "B.Cu")
		(net "TEMP_3_SCL")
	)
	(via
		(at 140.47597 -92.583)
		(size 0.7112)
		(drill 0.3556)
		(layers "F.Cu" "B.Cu")
		(net "TEMP_3_SCL")
	)
	(segment
		(start 140.95857 -92.45092)
		(end 141.20749 -92.202)
		(width 0.1143)
		(layer "B.Cu")
		(net "TEMP_3_SCL")
	)
	(segment
		(start 140.95857 -93.5101)
		(end 140.95857 -92.45092)
		(width 0.1143)
		(layer "B.Cu")
		(net "TEMP_3_SCL")
	)
	(segment
		(start 142.63497 -92.583)
		(end 142.88897 -92.583)
		(width 0.1143)
		(layer "F.Cu")
		(net "TEMP_3_SDA")
	)
	(segment
		(start 142.88897 -92.5957)
		(end 142.88897 -92.583)
		(width 0.1143)
		(layer "F.Cu")
		(net "TEMP_3_SDA")
	)
	(segment
		(start 142.12697 -92.075)
		(end 142.63497 -92.583)
		(width 0.1143)
		(layer "F.Cu")
		(net "TEMP_3_SDA")
	)
	(segment
		(start 141.85773 -91.80576)
		(end 142.12697 -92.075)
		(width 0.1143)
		(layer "F.Cu")
		(net "TEMP_3_SDA")
	)
	(segment
		(start 141.85773 -90.466672)
		(end 141.85773 -91.80576)
		(width 0.1143)
		(layer "F.Cu")
		(net "TEMP_3_SDA")
	)
	(segment
		(start 141.97457 -93.5101)
		(end 142.88897 -92.5957)
		(width 0.1143)
		(layer "F.Cu")
		(net "TEMP_3_SDA")
	)
	(via
		(at 142.12697 -92.075)
		(size 0.7112)
		(drill 0.3556)
		(layers "F.Cu" "B.Cu")
		(net "TEMP_3_SDA")
	)
	(via
		(at 142.88897 -92.583)
		(size 0.5588)
		(drill 0.3048)
		(layers "F.Cu" "B.Cu")
		(net "TEMP_3_SDA")
	)
	(segment
		(start 141.97457 -93.5101)
		(end 141.97457 -93.4974)
		(width 0.1143)
		(layer "B.Cu")
		(net "TEMP_3_SDA")
	)
	(segment
		(start 141.97457 -93.4974)
		(end 142.88897 -92.583)
		(width 0.1143)
		(layer "B.Cu")
		(net "TEMP_3_SDA")
	)
	(segment
		(start 311.2135 -211.201)
		(end 312.293 -211.201)
		(width 0.1143)
		(layer "F.Cu")
		(net "JTAG_IOC_L_TDI_R")
	)
	(segment
		(start 313.82716 -211.9249)
		(end 313.10326 -211.201)
		(width 0.1143)
		(layer "F.Cu")
		(net "JTAG_IOC_L_TDI_R")
	)
	(segment
		(start 313.10326 -211.201)
		(end 312.293 -211.201)
		(width 0.1143)
		(layer "F.Cu")
		(net "JTAG_IOC_L_TDI_R")
	)
	(via
		(at 312.293 -211.201)
		(size 0.7112)
		(drill 0.3556)
		(layers "F.Cu" "B.Cu")
		(net "JTAG_IOC_L_TDI_R")
	)
	(segment
		(start 31.623 -130.937)
		(end 28.448 -134.112)
		(width 0.1143)
		(layer "F.Cu")
		(net "JTAG_IOC_L_TDI")
	)
	(segment
		(start 310.388 -224.049844)
		(end 310.388 -213.859872)
		(width 0.1143)
		(layer "F.Cu")
		(net "JTAG_IOC_L_TDI")
	)
	(segment
		(start 310.388 -213.859872)
		(end 310.138064 -213.609936)
		(width 0.1143)
		(layer "F.Cu")
		(net "JTAG_IOC_L_TDI")
	)
	(segment
		(start 109.074966 -67.437)
		(end 108.820966 -67.691)
		(width 0.1143)
		(layer "F.Cu")
		(net "JTAG_IOC_L_TDI")
	)
	(segment
		(start 28.448 -149.987)
		(end 12.7 -165.735)
		(width 0.1143)
		(layer "F.Cu")
		(net "JTAG_IOC_L_TDI")
	)
	(segment
		(start 304.821844 -229.616)
		(end 310.388 -224.049844)
		(width 0.1143)
		(layer "F.Cu")
		(net "JTAG_IOC_L_TDI")
	)
	(segment
		(start 310.3245 -211.201)
		(end 310.138064 -211.387436)
		(width 0.1143)
		(layer "F.Cu")
		(net "JTAG_IOC_L_TDI")
	)
	(segment
		(start 310.138064 -211.387436)
		(end 310.138064 -213.609936)
		(width 0.1143)
		(layer "F.Cu")
		(net "JTAG_IOC_L_TDI")
	)
	(segment
		(start 28.448 -134.112)
		(end 28.448 -149.987)
		(width 0.1143)
		(layer "F.Cu")
		(net "JTAG_IOC_L_TDI")
	)
	(segment
		(start 108.820966 -67.691)
		(end 108.7374 -67.691)
		(width 0.1143)
		(layer "F.Cu")
		(net "JTAG_IOC_L_TDI")
	)
	(segment
		(start 277.749 -229.997)
		(end 278.13 -229.616)
		(width 0.1143)
		(layer "F.Cu")
		(net "JTAG_IOC_L_TDI")
	)
	(segment
		(start 278.13 -229.616)
		(end 304.821844 -229.616)
		(width 0.1143)
		(layer "F.Cu")
		(net "JTAG_IOC_L_TDI")
	)
	(segment
		(start 12.7 -165.735)
		(end 12.7 -167.513)
		(width 0.1143)
		(layer "F.Cu")
		(net "JTAG_IOC_L_TDI")
	)
	(segment
		(start 109.074966 -66.3321)
		(end 109.074966 -67.437)
		(width 0.1143)
		(layer "F.Cu")
		(net "JTAG_IOC_L_TDI")
	)
	(via
		(at 12.7 -167.513)
		(size 0.508)
		(drill 0.254)
		(layers "F.Cu" "B.Cu")
		(net "JTAG_IOC_L_TDI")
	)
	(via
		(at 277.749 -229.997)
		(size 0.5588)
		(drill 0.3048)
		(layers "F.Cu" "B.Cu")
		(net "JTAG_IOC_L_TDI")
	)
	(via
		(at 31.623 -130.937)
		(size 0.508)
		(drill 0.254)
		(layers "F.Cu" "B.Cu")
		(net "JTAG_IOC_L_TDI")
	)
	(via
		(at 310.138064 -213.609936)
		(size 0.7112)
		(drill 0.3556)
		(layers "F.Cu" "B.Cu")
		(net "JTAG_IOC_L_TDI")
	)
	(via
		(at 94.996 -74.549)
		(size 0.5588)
		(drill 0.3048)
		(layers "F.Cu" "B.Cu")
		(net "JTAG_IOC_L_TDI")
	)
	(via
		(at 108.7374 -67.691)
		(size 0.5588)
		(drill 0.3048)
		(layers "F.Cu" "B.Cu")
		(net "JTAG_IOC_L_TDI")
	)
	(segment
		(start 96.703642 -74.549)
		(end 94.996 -74.549)
		(width 0.1143)
		(layer "B.Cu")
		(net "JTAG_IOC_L_TDI")
	)
	(segment
		(start 106.299 -69.85)
		(end 103.5812 -72.5678)
		(width 0.1143)
		(layer "B.Cu")
		(net "JTAG_IOC_L_TDI")
	)
	(segment
		(start 108.7374 -68.230496)
		(end 107.117896 -69.85)
		(width 0.1143)
		(layer "B.Cu")
		(net "JTAG_IOC_L_TDI")
	)
	(segment
		(start 108.7374 -67.691)
		(end 108.7374 -68.230496)
		(width 0.1143)
		(layer "B.Cu")
		(net "JTAG_IOC_L_TDI")
	)
	(segment
		(start 103.5812 -72.5678)
		(end 98.684842 -72.5678)
		(width 0.1143)
		(layer "B.Cu")
		(net "JTAG_IOC_L_TDI")
	)
	(segment
		(start 107.117896 -69.85)
		(end 106.299 -69.85)
		(width 0.1143)
		(layer "B.Cu")
		(net "JTAG_IOC_L_TDI")
	)
	(segment
		(start 98.684842 -72.5678)
		(end 96.703642 -74.549)
		(width 0.1143)
		(layer "B.Cu")
		(net "JTAG_IOC_L_TDI")
	)
	(segment
		(start 262.66648 -205.359)
		(end 261.601712 -204.294232)
		(width 0.127)
		(layer "In2.Cu")
		(net "JTAG_IOC_L_TDI")
	)
	(segment
		(start 51.816 -176.784)
		(end 46.609 -171.577)
		(width 0.127)
		(layer "In2.Cu")
		(net "JTAG_IOC_L_TDI")
	)
	(segment
		(start 277.749 -229.997)
		(end 277.749 -229.270052)
		(width 0.127)
		(layer "In2.Cu")
		(net "JTAG_IOC_L_TDI")
	)
	(segment
		(start 212.019388 -185.5216)
		(end 211.231988 -186.309)
		(width 0.127)
		(layer "In2.Cu")
		(net "JTAG_IOC_L_TDI")
	)
	(segment
		(start 253.778258 -185.5216)
		(end 212.019388 -185.5216)
		(width 0.127)
		(layer "In2.Cu")
		(net "JTAG_IOC_L_TDI")
	)
	(segment
		(start 261.601712 -204.294232)
		(end 261.601712 -193.345054)
		(width 0.127)
		(layer "In2.Cu")
		(net "JTAG_IOC_L_TDI")
	)
	(segment
		(start 277.245572 -227.62464)
		(end 277.46198 -227.408232)
		(width 0.127)
		(layer "In2.Cu")
		(net "JTAG_IOC_L_TDI")
	)
	(segment
		(start 35.194748 -167.147748)
		(end 13.065252 -167.147748)
		(width 0.127)
		(layer "In2.Cu")
		(net "JTAG_IOC_L_TDI")
	)
	(segment
		(start 64.135 -176.784)
		(end 51.816 -176.784)
		(width 0.127)
		(layer "In2.Cu")
		(net "JTAG_IOC_L_TDI")
	)
	(segment
		(start 66.167 -178.816)
		(end 64.135 -176.784)
		(width 0.127)
		(layer "In2.Cu")
		(net "JTAG_IOC_L_TDI")
	)
	(segment
		(start 277.749 -229.270052)
		(end 277.245572 -228.766624)
		(width 0.127)
		(layer "In2.Cu")
		(net "JTAG_IOC_L_TDI")
	)
	(segment
		(start 39.624 -171.577)
		(end 35.194748 -167.147748)
		(width 0.127)
		(layer "In2.Cu")
		(net "JTAG_IOC_L_TDI")
	)
	(segment
		(start 162.306 -178.816)
		(end 66.167 -178.816)
		(width 0.127)
		(layer "In2.Cu")
		(net "JTAG_IOC_L_TDI")
	)
	(segment
		(start 277.46198 -227.408232)
		(end 277.46198 -219.54744)
		(width 0.127)
		(layer "In2.Cu")
		(net "JTAG_IOC_L_TDI")
	)
	(segment
		(start 261.601712 -193.345054)
		(end 253.778258 -185.5216)
		(width 0.127)
		(layer "In2.Cu")
		(net "JTAG_IOC_L_TDI")
	)
	(segment
		(start 277.245572 -228.766624)
		(end 277.245572 -227.62464)
		(width 0.127)
		(layer "In2.Cu")
		(net "JTAG_IOC_L_TDI")
	)
	(segment
		(start 264.053828 -205.359)
		(end 262.66648 -205.359)
		(width 0.127)
		(layer "In2.Cu")
		(net "JTAG_IOC_L_TDI")
	)
	(segment
		(start 277.46198 -219.54744)
		(end 277.055072 -219.140532)
		(width 0.127)
		(layer "In2.Cu")
		(net "JTAG_IOC_L_TDI")
	)
	(segment
		(start 277.055072 -218.360244)
		(end 264.053828 -205.359)
		(width 0.127)
		(layer "In2.Cu")
		(net "JTAG_IOC_L_TDI")
	)
	(segment
		(start 169.799 -186.309)
		(end 162.306 -178.816)
		(width 0.127)
		(layer "In2.Cu")
		(net "JTAG_IOC_L_TDI")
	)
	(segment
		(start 211.231988 -186.309)
		(end 169.799 -186.309)
		(width 0.127)
		(layer "In2.Cu")
		(net "JTAG_IOC_L_TDI")
	)
	(segment
		(start 13.065252 -167.147748)
		(end 12.7 -167.513)
		(width 0.127)
		(layer "In2.Cu")
		(net "JTAG_IOC_L_TDI")
	)
	(segment
		(start 46.609 -171.577)
		(end 39.624 -171.577)
		(width 0.127)
		(layer "In2.Cu")
		(net "JTAG_IOC_L_TDI")
	)
	(segment
		(start 277.055072 -219.140532)
		(end 277.055072 -218.360244)
		(width 0.127)
		(layer "In2.Cu")
		(net "JTAG_IOC_L_TDI")
	)
	(segment
		(start 85.704934 -82.4103)
		(end 82.463894 -82.4103)
		(width 0.127)
		(layer "In5.Cu")
		(net "JTAG_IOC_L_TDI")
	)
	(segment
		(start 36.249864 -128.9177)
		(end 33.6423 -128.9177)
		(width 0.127)
		(layer "In5.Cu")
		(net "JTAG_IOC_L_TDI")
	)
	(segment
		(start 93.566234 -74.549)
		(end 85.704934 -82.4103)
		(width 0.127)
		(layer "In5.Cu")
		(net "JTAG_IOC_L_TDI")
	)
	(segment
		(start 43.082718 -122.084846)
		(end 36.249864 -128.9177)
		(width 0.127)
		(layer "In5.Cu")
		(net "JTAG_IOC_L_TDI")
	)
	(segment
		(start 94.996 -74.549)
		(end 93.566234 -74.549)
		(width 0.127)
		(layer "In5.Cu")
		(net "JTAG_IOC_L_TDI")
	)
	(segment
		(start 76.708 -93.187012)
		(end 47.810166 -122.084846)
		(width 0.127)
		(layer "In5.Cu")
		(net "JTAG_IOC_L_TDI")
	)
	(segment
		(start 47.810166 -122.084846)
		(end 43.082718 -122.084846)
		(width 0.127)
		(layer "In5.Cu")
		(net "JTAG_IOC_L_TDI")
	)
	(segment
		(start 82.463894 -82.4103)
		(end 76.708 -88.166194)
		(width 0.127)
		(layer "In5.Cu")
		(net "JTAG_IOC_L_TDI")
	)
	(segment
		(start 33.6423 -128.9177)
		(end 31.623 -130.937)
		(width 0.127)
		(layer "In5.Cu")
		(net "JTAG_IOC_L_TDI")
	)
	(segment
		(start 76.708 -88.166194)
		(end 76.708 -93.187012)
		(width 0.127)
		(layer "In5.Cu")
		(net "JTAG_IOC_L_TDI")
	)
	(segment
		(start 108.33227 -69.9008)
		(end 108.33227 -70.9168)
		(width 0.1143)
		(layer "F.Cu")
		(net "TEMP_4_A0")
	)
	(segment
		(start 108.34497 -69.8881)
		(end 108.34497 -68.961)
		(width 0.1143)
		(layer "F.Cu")
		(net "TEMP_4_A0")
	)
	(segment
		(start 108.33227 -70.9168)
		(end 108.570014 -70.9168)
		(width 0.1143)
		(layer "F.Cu")
		(net "TEMP_4_A0")
	)
	(segment
		(start 108.717334 -70.76948)
		(end 110.17631 -70.76948)
		(width 0.1143)
		(layer "F.Cu")
		(net "TEMP_4_A0")
	)
	(segment
		(start 108.33227 -69.9008)
		(end 108.34497 -69.8881)
		(width 0.1143)
		(layer "F.Cu")
		(net "TEMP_4_A0")
	)
	(segment
		(start 108.570014 -70.9168)
		(end 108.717334 -70.76948)
		(width 0.1143)
		(layer "F.Cu")
		(net "TEMP_4_A0")
	)
	(via
		(at 108.34497 -68.961)
		(size 0.7112)
		(drill 0.3556)
		(layers "F.Cu" "B.Cu")
		(net "TEMP_4_A0")
	)
	(segment
		(start 300.482 -101.6635)
		(end 299.466 -101.6635)
		(width 0.1143)
		(layer "F.Cu")
		(net "TEMP_2_A0")
	)
	(segment
		(start 300.482 -100.711)
		(end 300.482 -101.6635)
		(width 0.1143)
		(layer "F.Cu")
		(net "TEMP_2_A0")
	)
	(segment
		(start 301.04588 -99.08286)
		(end 301.04588 -100.02012)
		(width 0.1143)
		(layer "F.Cu")
		(net "TEMP_2_A0")
	)
	(segment
		(start 300.482 -100.584)
		(end 300.482 -100.711)
		(width 0.1143)
		(layer "F.Cu")
		(net "TEMP_2_A0")
	)
	(segment
		(start 301.04588 -100.02012)
		(end 300.482 -100.584)
		(width 0.1143)
		(layer "F.Cu")
		(net "TEMP_2_A0")
	)
	(via
		(at 300.482 -100.711)
		(size 0.7112)
		(drill 0.3556)
		(layers "F.Cu" "B.Cu")
		(net "TEMP_2_A0")
	)
	(segment
		(start 304.038 -92.964)
		(end 303.53 -93.472)
		(width 0.1143)
		(layer "F.Cu")
		(net "TEMP_2_ALERT")
	)
	(segment
		(start 302.26 -93.472)
		(end 301.69612 -94.03588)
		(width 0.1143)
		(layer "F.Cu")
		(net "TEMP_2_ALERT")
	)
	(segment
		(start 303.53 -93.472)
		(end 302.26 -93.472)
		(width 0.1143)
		(layer "F.Cu")
		(net "TEMP_2_ALERT")
	)
	(segment
		(start 301.69612 -94.03588)
		(end 301.69612 -94.97314)
		(width 0.1143)
		(layer "F.Cu")
		(net "TEMP_2_ALERT")
	)
	(segment
		(start 302.34636 -99.08286)
		(end 302.91786 -99.08286)
		(width 0.1143)
		(layer "F.Cu")
		(net "TEMP_2_A2")
	)
	(segment
		(start 304.419 -100.584)
		(end 304.546 -100.711)
		(width 0.1143)
		(layer "F.Cu")
		(net "TEMP_2_A2")
	)
	(segment
		(start 302.91786 -99.08286)
		(end 304.419 -100.584)
		(width 0.1143)
		(layer "F.Cu")
		(net "TEMP_2_A2")
	)
	(segment
		(start 304.546 -101.6635)
		(end 303.53 -101.6635)
		(width 0.1143)
		(layer "F.Cu")
		(net "TEMP_2_A2")
	)
	(segment
		(start 304.546 -100.711)
		(end 304.546 -101.6635)
		(width 0.1143)
		(layer "F.Cu")
		(net "TEMP_2_A2")
	)
	(via
		(at 304.419 -100.584)
		(size 0.7112)
		(drill 0.3556)
		(layers "F.Cu" "B.Cu")
		(net "TEMP_2_A2")
	)
	(segment
		(start 301.69612 -99.08286)
		(end 301.69612 -100.65512)
		(width 0.1143)
		(layer "F.Cu")
		(net "TEMP_2_A1")
	)
	(segment
		(start 301.69612 -100.65512)
		(end 301.752 -100.711)
		(width 0.1143)
		(layer "F.Cu")
		(net "TEMP_2_A1")
	)
	(segment
		(start 301.498 -100.965)
		(end 301.498 -101.6635)
		(width 0.1143)
		(layer "F.Cu")
		(net "TEMP_2_A1")
	)
	(segment
		(start 301.498 -101.6635)
		(end 302.514 -101.6635)
		(width 0.1143)
		(layer "F.Cu")
		(net "TEMP_2_A1")
	)
	(segment
		(start 301.752 -100.711)
		(end 301.498 -100.965)
		(width 0.1143)
		(layer "F.Cu")
		(net "TEMP_2_A1")
	)
	(via
		(at 301.752 -100.711)
		(size 0.7112)
		(drill 0.3556)
		(layers "F.Cu" "B.Cu")
		(net "TEMP_2_A1")
	)
	(segment
		(start 107.91952 -75.659742)
		(end 107.91952 -75.07605)
		(width 0.1143)
		(layer "F.Cu")
		(net "TEMP_4_A2")
	)
	(segment
		(start 109.28604 -72.06996)
		(end 110.17631 -72.06996)
		(width 0.1143)
		(layer "F.Cu")
		(net "TEMP_4_A2")
	)
	(segment
		(start 108.837222 -72.518778)
		(end 109.28604 -72.06996)
		(width 0.1143)
		(layer "F.Cu")
		(net "TEMP_4_A2")
	)
	(segment
		(start 107.45597 -74.6125)
		(end 107.96397 -74.1045)
		(width 0.1143)
		(layer "F.Cu")
		(net "TEMP_4_A2")
	)
	(segment
		(start 107.91952 -75.07605)
		(end 107.45597 -74.6125)
		(width 0.1143)
		(layer "F.Cu")
		(net "TEMP_4_A2")
	)
	(segment
		(start 108.32338 -76.063602)
		(end 107.91952 -75.659742)
		(width 0.1143)
		(layer "F.Cu")
		(net "TEMP_4_A2")
	)
	(segment
		(start 107.96397 -74.1045)
		(end 108.59897 -74.1045)
		(width 0.1143)
		(layer "F.Cu")
		(net "TEMP_4_A2")
	)
	(segment
		(start 108.837222 -73.866248)
		(end 108.837222 -72.518778)
		(width 0.1143)
		(layer "F.Cu")
		(net "TEMP_4_A2")
	)
	(segment
		(start 108.59897 -74.1045)
		(end 108.837222 -73.866248)
		(width 0.1143)
		(layer "F.Cu")
		(net "TEMP_4_A2")
	)
	(via
		(at 108.32338 -76.063602)
		(size 0.7112)
		(drill 0.3556)
		(layers "F.Cu" "B.Cu")
		(net "TEMP_4_A2")
	)
	(segment
		(start 107.074716 -73.62825)
		(end 107.042966 -73.66)
		(width 0.1143)
		(layer "F.Cu")
		(net "TEMP_4_A1")
	)
	(segment
		(start 107.66552 -73.62825)
		(end 107.074716 -73.62825)
		(width 0.1143)
		(layer "F.Cu")
		(net "TEMP_4_A1")
	)
	(segment
		(start 108.33227 -72.9615)
		(end 107.66552 -73.62825)
		(width 0.1143)
		(layer "F.Cu")
		(net "TEMP_4_A1")
	)
	(segment
		(start 108.33227 -72.9488)
		(end 108.33227 -71.9328)
		(width 0.1143)
		(layer "F.Cu")
		(net "TEMP_4_A1")
	)
	(segment
		(start 108.84535 -71.41972)
		(end 110.17631 -71.41972)
		(width 0.1143)
		(layer "F.Cu")
		(net "TEMP_4_A1")
	)
	(segment
		(start 107.042966 -73.66)
		(end 106.36377 -73.66)
		(width 0.1143)
		(layer "F.Cu")
		(net "TEMP_4_A1")
	)
	(segment
		(start 108.33227 -71.9328)
		(end 108.84535 -71.41972)
		(width 0.1143)
		(layer "F.Cu")
		(net "TEMP_4_A1")
	)
	(segment
		(start 108.33227 -72.9488)
		(end 108.33227 -72.9615)
		(width 0.1143)
		(layer "F.Cu")
		(net "TEMP_4_A1")
	)
	(via
		(at 106.36377 -73.66)
		(size 0.7112)
		(drill 0.3556)
		(layers "F.Cu" "B.Cu")
		(net "TEMP_4_A1")
	)
	(segment
		(start 115.86718 -71.41718)
		(end 115.86718 -71.480426)
		(width 0.1143)
		(layer "F.Cu")
		(net "TEMP_4_SCL")
	)
	(segment
		(start 114.28603 -70.76948)
		(end 115.21948 -70.76948)
		(width 0.1143)
		(layer "F.Cu")
		(net "TEMP_4_SCL")
	)
	(segment
		(start 115.21948 -70.76948)
		(end 115.86718 -71.41718)
		(width 0.1143)
		(layer "F.Cu")
		(net "TEMP_4_SCL")
	)
	(segment
		(start 117.4115 -72.263)
		(end 117.4115 -72.771)
		(width 0.1143)
		(layer "F.Cu")
		(net "TEMP_4_SCL")
	)
	(segment
		(start 116.7765 -71.628)
		(end 117.4115 -72.263)
		(width 0.1143)
		(layer "F.Cu")
		(net "TEMP_4_SCL")
	)
	(segment
		(start 115.951 -71.480426)
		(end 116.098574 -71.628)
		(width 0.1143)
		(layer "F.Cu")
		(net "TEMP_4_SCL")
	)
	(segment
		(start 116.098574 -71.628)
		(end 116.7765 -71.628)
		(width 0.1143)
		(layer "F.Cu")
		(net "TEMP_4_SCL")
	)
	(segment
		(start 115.86718 -71.480426)
		(end 115.951 -71.480426)
		(width 0.1143)
		(layer "F.Cu")
		(net "TEMP_4_SCL")
	)
	(via
		(at 115.86718 -71.480426)
		(size 0.7112)
		(drill 0.3556)
		(layers "F.Cu" "B.Cu")
		(net "TEMP_4_SCL")
	)
	(segment
		(start 116.205 -69.2785)
		(end 116.205 -68.4276)
		(width 0.1143)
		(layer "F.Cu")
		(net "TEMP_4_SDA")
	)
	(segment
		(start 116.2685 -69.342)
		(end 116.205 -69.2785)
		(width 0.1143)
		(layer "F.Cu")
		(net "TEMP_4_SDA")
	)
	(segment
		(start 116.2685 -70.485)
		(end 115.90274 -70.11924)
		(width 0.1143)
		(layer "F.Cu")
		(net "TEMP_4_SDA")
	)
	(segment
		(start 116.2685 -70.485)
		(end 116.2685 -69.342)
		(width 0.1143)
		(layer "F.Cu")
		(net "TEMP_4_SDA")
	)
	(segment
		(start 115.90274 -70.11924)
		(end 114.28603 -70.11924)
		(width 0.1143)
		(layer "F.Cu")
		(net "TEMP_4_SDA")
	)
	(via
		(at 116.205 -68.4276)
		(size 0.7112)
		(drill 0.3556)
		(layers "F.Cu" "B.Cu")
		(net "TEMP_4_SDA")
	)
	(segment
		(start 301.3075 -92.329)
		(end 301.3075 -93.0275)
		(width 0.1143)
		(layer "F.Cu")
		(net "TEMP_2_SCL")
	)
	(segment
		(start 301.3075 -93.0275)
		(end 300.99 -93.345)
		(width 0.1143)
		(layer "F.Cu")
		(net "TEMP_2_SCL")
	)
	(segment
		(start 301.04588 -93.40088)
		(end 300.99 -93.345)
		(width 0.1143)
		(layer "F.Cu")
		(net "TEMP_2_SCL")
	)
	(segment
		(start 301.3075 -91.186)
		(end 301.3075 -92.329)
		(width 0.1143)
		(layer "F.Cu")
		(net "TEMP_2_SCL")
	)
	(segment
		(start 301.04588 -94.97314)
		(end 301.04588 -93.40088)
		(width 0.1143)
		(layer "F.Cu")
		(net "TEMP_2_SCL")
	)
	(via
		(at 300.99 -93.345)
		(size 0.7112)
		(drill 0.3556)
		(layers "F.Cu" "B.Cu")
		(net "TEMP_2_SCL")
	)
	(segment
		(start 300.39564 -94.97314)
		(end 300.39564 -94.14764)
		(width 0.1143)
		(layer "F.Cu")
		(net "TEMP_2_SDA")
	)
	(segment
		(start 300.228 -92.3925)
		(end 299.212 -92.3925)
		(width 0.1143)
		(layer "F.Cu")
		(net "TEMP_2_SDA")
	)
	(segment
		(start 299.212 -92.964)
		(end 299.593 -93.345)
		(width 0.1143)
		(layer "F.Cu")
		(net "TEMP_2_SDA")
	)
	(segment
		(start 300.39564 -94.14764)
		(end 299.593 -93.345)
		(width 0.1143)
		(layer "F.Cu")
		(net "TEMP_2_SDA")
	)
	(segment
		(start 299.212 -92.3925)
		(end 299.212 -92.964)
		(width 0.1143)
		(layer "F.Cu")
		(net "TEMP_2_SDA")
	)
	(via
		(at 299.593 -93.345)
		(size 0.7112)
		(drill 0.3556)
		(layers "F.Cu" "B.Cu")
		(net "TEMP_2_SDA")
	)
	(segment
		(start 300.825154 -164.299646)
		(end 300.220126 -164.299646)
		(width 0.1143)
		(layer "F.Cu")
		(net "BMC_JTAG_L_EN_R")
	)
	(segment
		(start 298.43476 -167.925242)
		(end 298.43476 -168.240202)
		(width 0.1143)
		(layer "F.Cu")
		(net "BMC_JTAG_L_EN_R")
	)
	(segment
		(start 304.3047 -161.8488)
		(end 305.054 -161.0995)
		(width 0.1143)
		(layer "F.Cu")
		(net "BMC_JTAG_L_EN_R")
	)
	(segment
		(start 300.220126 -164.299646)
		(end 299.165772 -165.354)
		(width 0.1143)
		(layer "F.Cu")
		(net "BMC_JTAG_L_EN_R")
	)
	(segment
		(start 299.165772 -165.354)
		(end 299.127418 -165.354)
		(width 0.1143)
		(layer "F.Cu")
		(net "BMC_JTAG_L_EN_R")
	)
	(segment
		(start 298.77766 -165.703758)
		(end 298.77766 -167.582342)
		(width 0.1143)
		(layer "F.Cu")
		(net "BMC_JTAG_L_EN_R")
	)
	(segment
		(start 299.127418 -165.354)
		(end 298.77766 -165.703758)
		(width 0.1143)
		(layer "F.Cu")
		(net "BMC_JTAG_L_EN_R")
	)
	(segment
		(start 298.77766 -167.582342)
		(end 298.43476 -167.925242)
		(width 0.1143)
		(layer "F.Cu")
		(net "BMC_JTAG_L_EN_R")
	)
	(segment
		(start 303.276 -161.8488)
		(end 304.3047 -161.8488)
		(width 0.1143)
		(layer "F.Cu")
		(net "BMC_JTAG_L_EN_R")
	)
	(segment
		(start 303.276 -161.8488)
		(end 300.825154 -164.299646)
		(width 0.1143)
		(layer "F.Cu")
		(net "BMC_JTAG_L_EN_R")
	)
	(via
		(at 303.276 -161.8488)
		(size 0.7112)
		(drill 0.3556)
		(layers "F.Cu" "B.Cu")
		(net "BMC_JTAG_L_EN_R")
	)
	(segment
		(start 319.8495 -198.882)
		(end 319.8495 -204.2795)
		(width 0.1143)
		(layer "F.Cu")
		(net "BMC_JTAG_L_EN")
	)
	(segment
		(start 319.71361 -197.73011)
		(end 319.8495 -197.866)
		(width 0.1143)
		(layer "F.Cu")
		(net "BMC_JTAG_L_EN")
	)
	(segment
		(start 320.294 -211.8995)
		(end 320.5099 -212.1154)
		(width 0.1143)
		(layer "F.Cu")
		(net "BMC_JTAG_L_EN")
	)
	(segment
		(start 305.1175 -160.147)
		(end 305.1175 -159.258)
		(width 0.1143)
		(layer "F.Cu")
		(net "BMC_JTAG_L_EN")
	)
	(segment
		(start 305.054 -160.2105)
		(end 305.1175 -160.147)
		(width 0.1143)
		(layer "F.Cu")
		(net "BMC_JTAG_L_EN")
	)
	(segment
		(start 248.504964 -115.730528)
		(end 248.504964 -113.910872)
		(width 0.1143)
		(layer "F.Cu")
		(net "BMC_JTAG_L_EN")
	)
	(segment
		(start 320.5099 -212.90915)
		(end 321.0179 -213.41715)
		(width 0.1143)
		(layer "F.Cu")
		(net "BMC_JTAG_L_EN")
	)
	(segment
		(start 247.080024 -94.36989)
		(end 247.88749 -94.36989)
		(width 0.1143)
		(layer "F.Cu")
		(net "BMC_JTAG_L_EN")
	)
	(segment
		(start 318.389 -197.73011)
		(end 317.2333 -197.73011)
		(width 0.1143)
		(layer "F.Cu")
		(net "BMC_JTAG_L_EN")
	)
	(segment
		(start 320.294 -204.724)
		(end 320.294 -211.8995)
		(width 0.1143)
		(layer "F.Cu")
		(net "BMC_JTAG_L_EN")
	)
	(segment
		(start 248.285 -94.7674)
		(end 248.285 -99.695)
		(width 0.1143)
		(layer "F.Cu")
		(net "BMC_JTAG_L_EN")
	)
	(segment
		(start 318.389 -197.73011)
		(end 319.71361 -197.73011)
		(width 0.1143)
		(layer "F.Cu")
		(net "BMC_JTAG_L_EN")
	)
	(segment
		(start 247.142 -117.093492)
		(end 248.504964 -115.730528)
		(width 0.1143)
		(layer "F.Cu")
		(net "BMC_JTAG_L_EN")
	)
	(segment
		(start 248.285 -99.695)
		(end 249.555 -100.965)
		(width 0.1143)
		(layer "F.Cu")
		(net "BMC_JTAG_L_EN")
	)
	(segment
		(start 247.142 -135.255)
		(end 247.142 -117.093492)
		(width 0.1143)
		(layer "F.Cu")
		(net "BMC_JTAG_L_EN")
	)
	(segment
		(start 247.88749 -94.36989)
		(end 248.285 -94.7674)
		(width 0.1143)
		(layer "F.Cu")
		(net "BMC_JTAG_L_EN")
	)
	(segment
		(start 248.504964 -113.910872)
		(end 250.3551 -112.060736)
		(width 0.1143)
		(layer "F.Cu")
		(net "BMC_JTAG_L_EN")
	)
	(segment
		(start 320.5099 -212.1154)
		(end 320.5099 -212.90915)
		(width 0.1143)
		(layer "F.Cu")
		(net "BMC_JTAG_L_EN")
	)
	(segment
		(start 319.8495 -204.2795)
		(end 320.294 -204.724)
		(width 0.1143)
		(layer "F.Cu")
		(net "BMC_JTAG_L_EN")
	)
	(segment
		(start 250.3551 -101.7651)
		(end 249.555 -100.965)
		(width 0.1143)
		(layer "F.Cu")
		(net "BMC_JTAG_L_EN")
	)
	(segment
		(start 249.936 -139.192)
		(end 249.936 -138.049)
		(width 0.1143)
		(layer "F.Cu")
		(net "BMC_JTAG_L_EN")
	)
	(segment
		(start 250.3551 -112.060736)
		(end 250.3551 -101.7651)
		(width 0.1143)
		(layer "F.Cu")
		(net "BMC_JTAG_L_EN")
	)
	(segment
		(start 249.936 -138.049)
		(end 247.142 -135.255)
		(width 0.1143)
		(layer "F.Cu")
		(net "BMC_JTAG_L_EN")
	)
	(segment
		(start 319.8495 -197.866)
		(end 319.8495 -198.882)
		(width 0.1143)
		(layer "F.Cu")
		(net "BMC_JTAG_L_EN")
	)
	(segment
		(start 249.555 -139.573)
		(end 249.936 -139.192)
		(width 0.1143)
		(layer "F.Cu")
		(net "BMC_JTAG_L_EN")
	)
	(via
		(at 275.488146 -138.30808)
		(size 0.5588)
		(drill 0.3048)
		(layers "F.Cu" "B.Cu")
		(net "BMC_JTAG_L_EN")
	)
	(via
		(at 305.1175 -159.258)
		(size 0.508)
		(drill 0.254)
		(layers "F.Cu" "B.Cu")
		(net "BMC_JTAG_L_EN")
	)
	(via
		(at 318.389 -197.73011)
		(size 0.5588)
		(drill 0.3048)
		(layers "F.Cu" "B.Cu")
		(net "BMC_JTAG_L_EN")
	)
	(via
		(at 315.214 -160.401)
		(size 0.5588)
		(drill 0.3048)
		(layers "F.Cu" "B.Cu")
		(net "BMC_JTAG_L_EN")
	)
	(via
		(at 249.555 -139.573)
		(size 0.5588)
		(drill 0.3048)
		(layers "F.Cu" "B.Cu")
		(net "BMC_JTAG_L_EN")
	)
	(segment
		(start 318.008 -178.639216)
		(end 318.008 -197.34911)
		(width 0.127)
		(layer "In2.Cu")
		(net "BMC_JTAG_L_EN")
	)
	(segment
		(start 250.19 -138.938)
		(end 249.555 -139.573)
		(width 0.127)
		(layer "In2.Cu")
		(net "BMC_JTAG_L_EN")
	)
	(segment
		(start 275.44268 -138.30808)
		(end 274.9169 -137.7823)
		(width 0.127)
		(layer "In2.Cu")
		(net "BMC_JTAG_L_EN")
	)
	(segment
		(start 317.1825 -162.3695)
		(end 317.1825 -177.813716)
		(width 0.127)
		(layer "In2.Cu")
		(net "BMC_JTAG_L_EN")
	)
	(segment
		(start 260.985 -138.938)
		(end 250.19 -138.938)
		(width 0.127)
		(layer "In2.Cu")
		(net "BMC_JTAG_L_EN")
	)
	(segment
		(start 262.1407 -137.7823)
		(end 260.985 -138.938)
		(width 0.127)
		(layer "In2.Cu")
		(net "BMC_JTAG_L_EN")
	)
	(segment
		(start 318.008 -197.34911)
		(end 318.389 -197.73011)
		(width 0.127)
		(layer "In2.Cu")
		(net "BMC_JTAG_L_EN")
	)
	(segment
		(start 274.9169 -137.7823)
		(end 262.1407 -137.7823)
		(width 0.127)
		(layer "In2.Cu")
		(net "BMC_JTAG_L_EN")
	)
	(segment
		(start 275.488146 -138.30808)
		(end 275.44268 -138.30808)
		(width 0.127)
		(layer "In2.Cu")
		(net "BMC_JTAG_L_EN")
	)
	(segment
		(start 315.214 -160.401)
		(end 317.1825 -162.3695)
		(width 0.127)
		(layer "In2.Cu")
		(net "BMC_JTAG_L_EN")
	)
	(segment
		(start 317.1825 -177.813716)
		(end 318.008 -178.639216)
		(width 0.127)
		(layer "In2.Cu")
		(net "BMC_JTAG_L_EN")
	)
	(segment
		(start 293.497 -155.321)
		(end 290.703 -155.321)
		(width 0.127)
		(layer "In5.Cu")
		(net "BMC_JTAG_L_EN")
	)
	(segment
		(start 290.703 -155.321)
		(end 289.687 -154.305)
		(width 0.127)
		(layer "In5.Cu")
		(net "BMC_JTAG_L_EN")
	)
	(segment
		(start 314.5663 -159.7533)
		(end 305.6128 -159.7533)
		(width 0.127)
		(layer "In5.Cu")
		(net "BMC_JTAG_L_EN")
	)
	(segment
		(start 275.3487 -144.367758)
		(end 275.3487 -140.7033)
		(width 0.127)
		(layer "In5.Cu")
		(net "BMC_JTAG_L_EN")
	)
	(segment
		(start 304.546 -159.258)
		(end 303.7967 -160.0073)
		(width 0.127)
		(layer "In5.Cu")
		(net "BMC_JTAG_L_EN")
	)
	(segment
		(start 305.6128 -159.7533)
		(end 305.1175 -159.258)
		(width 0.127)
		(layer "In5.Cu")
		(net "BMC_JTAG_L_EN")
	)
	(segment
		(start 289.687 -154.305)
		(end 285.285942 -154.305)
		(width 0.127)
		(layer "In5.Cu")
		(net "BMC_JTAG_L_EN")
	)
	(segment
		(start 315.214 -160.401)
		(end 314.5663 -159.7533)
		(width 0.127)
		(layer "In5.Cu")
		(net "BMC_JTAG_L_EN")
	)
	(segment
		(start 285.285942 -154.305)
		(end 275.3487 -144.367758)
		(width 0.127)
		(layer "In5.Cu")
		(net "BMC_JTAG_L_EN")
	)
	(segment
		(start 275.5011 -138.4681)
		(end 275.488146 -138.455146)
		(width 0.127)
		(layer "In5.Cu")
		(net "BMC_JTAG_L_EN")
	)
	(segment
		(start 275.5011 -140.5509)
		(end 275.5011 -138.4681)
		(width 0.127)
		(layer "In5.Cu")
		(net "BMC_JTAG_L_EN")
	)
	(segment
		(start 298.1833 -160.0073)
		(end 293.497 -155.321)
		(width 0.127)
		(layer "In5.Cu")
		(net "BMC_JTAG_L_EN")
	)
	(segment
		(start 305.1175 -159.258)
		(end 304.546 -159.258)
		(width 0.127)
		(layer "In5.Cu")
		(net "BMC_JTAG_L_EN")
	)
	(segment
		(start 275.488146 -138.455146)
		(end 275.488146 -138.30808)
		(width 0.127)
		(layer "In5.Cu")
		(net "BMC_JTAG_L_EN")
	)
	(segment
		(start 275.3487 -140.7033)
		(end 275.5011 -140.5509)
		(width 0.127)
		(layer "In5.Cu")
		(net "BMC_JTAG_L_EN")
	)
	(segment
		(start 303.7967 -160.0073)
		(end 298.1833 -160.0073)
		(width 0.127)
		(layer "In5.Cu")
		(net "BMC_JTAG_L_EN")
	)
	(segment
		(start 315.12764 -213.5759)
		(end 316.4459 -213.5759)
		(width 0.1143)
		(layer "F.Cu")
		(net "EXP_TDO_EN")
	)
	(segment
		(start 316.4459 -213.5759)
		(end 316.484 -213.614)
		(width 0.1143)
		(layer "F.Cu")
		(net "EXP_TDO_EN")
	)
	(segment
		(start 319.1129 -214.4014)
		(end 318.9859 -214.4014)
		(width 0.1143)
		(layer "F.Cu")
		(net "EXP_TDO_EN")
	)
	(segment
		(start 318.9859 -214.4014)
		(end 317.6524 -213.0679)
		(width 0.1143)
		(layer "F.Cu")
		(net "EXP_TDO_EN")
	)
	(segment
		(start 317.1063 -213.614)
		(end 316.484 -213.614)
		(width 0.1143)
		(layer "F.Cu")
		(net "EXP_TDO_EN")
	)
	(segment
		(start 317.6524 -213.0679)
		(end 317.1063 -213.614)
		(width 0.1143)
		(layer "F.Cu")
		(net "EXP_TDO_EN")
	)
	(via
		(at 316.484 -213.614)
		(size 0.7112)
		(drill 0.3556)
		(layers "F.Cu" "B.Cu")
		(net "EXP_TDO_EN")
	)
	(segment
		(start 245.080028 -98.67011)
		(end 245.080028 -101.062028)
		(width 0.1143)
		(layer "F.Cu")
		(net "JTAG_IOC_TDO_L")
	)
	(segment
		(start 223.866202 -163.08324)
		(end 225.07575 -161.873692)
		(width 0.1143)
		(layer "F.Cu")
		(net "JTAG_IOC_TDO_L")
	)
	(segment
		(start 225.07575 -124.1933)
		(end 229.38105 -119.888)
		(width 0.1143)
		(layer "F.Cu")
		(net "JTAG_IOC_TDO_L")
	)
	(segment
		(start 220.98 -168.021)
		(end 220.98 -164.2872)
		(width 0.1143)
		(layer "F.Cu")
		(net "JTAG_IOC_TDO_L")
	)
	(segment
		(start 225.07575 -161.873692)
		(end 225.07575 -124.1933)
		(width 0.1143)
		(layer "F.Cu")
		(net "JTAG_IOC_TDO_L")
	)
	(segment
		(start 223.28124 -163.08324)
		(end 220.0148 -163.08324)
		(width 0.1143)
		(layer "F.Cu")
		(net "JTAG_IOC_TDO_L")
	)
	(segment
		(start 245.080028 -101.062028)
		(end 249.428 -105.41)
		(width 0.1143)
		(layer "F.Cu")
		(net "JTAG_IOC_TDO_L")
	)
	(segment
		(start 220.726 -168.275)
		(end 220.98 -168.021)
		(width 0.1143)
		(layer "F.Cu")
		(net "JTAG_IOC_TDO_L")
	)
	(segment
		(start 223.28124 -163.08324)
		(end 223.866202 -163.08324)
		(width 0.1143)
		(layer "F.Cu")
		(net "JTAG_IOC_TDO_L")
	)
	(segment
		(start 249.428 -111.506)
		(end 249.44705 -111.52505)
		(width 0.1143)
		(layer "F.Cu")
		(net "JTAG_IOC_TDO_L")
	)
	(segment
		(start 220.0148 -163.322)
		(end 220.0148 -163.08324)
		(width 0.1143)
		(layer "F.Cu")
		(net "JTAG_IOC_TDO_L")
	)
	(segment
		(start 249.44705 -111.52505)
		(end 249.44705 -111.633)
		(width 0.1143)
		(layer "F.Cu")
		(net "JTAG_IOC_TDO_L")
	)
	(segment
		(start 249.428 -105.41)
		(end 249.428 -111.506)
		(width 0.1143)
		(layer "F.Cu")
		(net "JTAG_IOC_TDO_L")
	)
	(segment
		(start 220.98 -164.2872)
		(end 220.0148 -163.322)
		(width 0.1143)
		(layer "F.Cu")
		(net "JTAG_IOC_TDO_L")
	)
	(segment
		(start 219.7735 -168.275)
		(end 220.726 -168.275)
		(width 0.1143)
		(layer "F.Cu")
		(net "JTAG_IOC_TDO_L")
	)
	(via
		(at 223.28124 -163.08324)
		(size 0.7112)
		(drill 0.3556)
		(layers "F.Cu" "B.Cu")
		(net "JTAG_IOC_TDO_L")
	)
	(via
		(at 229.38105 -119.888)
		(size 0.5588)
		(drill 0.3048)
		(layers "F.Cu" "B.Cu")
		(net "JTAG_IOC_TDO_L")
	)
	(via
		(at 249.44705 -111.633)
		(size 0.5588)
		(drill 0.3048)
		(layers "F.Cu" "B.Cu")
		(net "JTAG_IOC_TDO_L")
	)
	(segment
		(start 229.38105 -119.888)
		(end 229.5652 -119.888)
		(width 0.127)
		(layer "In2.Cu")
		(net "JTAG_IOC_TDO_L")
	)
	(segment
		(start 237.8202 -111.633)
		(end 249.44705 -111.633)
		(width 0.127)
		(layer "In2.Cu")
		(net "JTAG_IOC_TDO_L")
	)
	(segment
		(start 229.5652 -119.888)
		(end 237.8202 -111.633)
		(width 0.127)
		(layer "In2.Cu")
		(net "JTAG_IOC_TDO_L")
	)
	(segment
		(start 317.4365 -174.625)
		(end 317.5635 -174.752)
		(width 0.1143)
		(layer "F.Cu")
		(net "BMC_JTAG_L_R")
	)
	(segment
		(start 308.357016 -172.667422)
		(end 310.314594 -174.625)
		(width 0.1143)
		(layer "F.Cu")
		(net "BMC_JTAG_L_R")
	)
	(segment
		(start 301.809658 -173.04004)
		(end 302.182276 -172.667422)
		(width 0.1143)
		(layer "F.Cu")
		(net "BMC_JTAG_L_R")
	)
	(segment
		(start 316.484 -174.625)
		(end 317.4365 -174.625)
		(width 0.1143)
		(layer "F.Cu")
		(net "BMC_JTAG_L_R")
	)
	(segment
		(start 302.182276 -172.667422)
		(end 308.357016 -172.667422)
		(width 0.1143)
		(layer "F.Cu")
		(net "BMC_JTAG_L_R")
	)
	(segment
		(start 310.314594 -174.625)
		(end 316.484 -174.625)
		(width 0.1143)
		(layer "F.Cu")
		(net "BMC_JTAG_L_R")
	)
	(segment
		(start 301.634906 -173.04004)
		(end 301.809658 -173.04004)
		(width 0.1143)
		(layer "F.Cu")
		(net "BMC_JTAG_L_R")
	)
	(via
		(at 316.484 -174.625)
		(size 0.7112)
		(drill 0.3556)
		(layers "F.Cu" "B.Cu")
		(net "BMC_JTAG_L_R")
	)
	(segment
		(start 221.336362 -155.8925)
		(end 221.77375 -156.329888)
		(width 0.1143)
		(layer "F.Cu")
		(net "BMC_JTAG_L")
	)
	(segment
		(start 321.691 -173.2534)
		(end 321.691 -171.704)
		(width 0.1143)
		(layer "F.Cu")
		(net "BMC_JTAG_L")
	)
	(segment
		(start 220.345 -155.8925)
		(end 221.336362 -155.8925)
		(width 0.1143)
		(layer "F.Cu")
		(net "BMC_JTAG_L")
	)
	(segment
		(start 219.1385 -155.8925)
		(end 220.345 -155.8925)
		(width 0.1143)
		(layer "F.Cu")
		(net "BMC_JTAG_L")
	)
	(segment
		(start 320.1924 -174.752)
		(end 321.691 -173.2534)
		(width 0.1143)
		(layer "F.Cu")
		(net "BMC_JTAG_L")
	)
	(segment
		(start 318.4525 -174.752)
		(end 320.1924 -174.752)
		(width 0.1143)
		(layer "F.Cu")
		(net "BMC_JTAG_L")
	)
	(segment
		(start 321.691 -171.704)
		(end 321.945 -171.45)
		(width 0.1143)
		(layer "F.Cu")
		(net "BMC_JTAG_L")
	)
	(segment
		(start 219.1385 -155.8925)
		(end 219.0115 -155.8925)
		(width 0.1143)
		(layer "F.Cu")
		(net "BMC_JTAG_L")
	)
	(segment
		(start 218.313 -156.591)
		(end 218.313 -159.893)
		(width 0.1143)
		(layer "F.Cu")
		(net "BMC_JTAG_L")
	)
	(segment
		(start 219.0115 -155.8925)
		(end 218.313 -156.591)
		(width 0.1143)
		(layer "F.Cu")
		(net "BMC_JTAG_L")
	)
	(via
		(at 321.945 -171.45)
		(size 0.5588)
		(drill 0.3048)
		(layers "F.Cu" "B.Cu")
		(net "BMC_JTAG_L")
	)
	(via
		(at 219.1385 -155.8925)
		(size 0.7112)
		(drill 0.3556)
		(layers "F.Cu" "B.Cu")
		(net "BMC_JTAG_L")
	)
	(via
		(at 218.313 -159.893)
		(size 0.5588)
		(drill 0.3048)
		(layers "F.Cu" "B.Cu")
		(net "BMC_JTAG_L")
	)
	(segment
		(start 298.3738 -133.1722)
		(end 292.227 -139.319)
		(width 0.127)
		(layer "In2.Cu")
		(net "BMC_JTAG_L")
	)
	(segment
		(start 323.418454 -161.783014)
		(end 323.418454 -156.728922)
		(width 0.127)
		(layer "In2.Cu")
		(net "BMC_JTAG_L")
	)
	(segment
		(start 287.738566 -139.319)
		(end 268.879066 -158.1785)
		(width 0.127)
		(layer "In2.Cu")
		(net "BMC_JTAG_L")
	)
	(segment
		(start 321.31 -154.77236)
		(end 321.31 -154.726386)
		(width 0.127)
		(layer "In2.Cu")
		(net "BMC_JTAG_L")
	)
	(segment
		(start 310.005984 -133.679946)
		(end 303.962816 -133.679946)
		(width 0.127)
		(layer "In2.Cu")
		(net "BMC_JTAG_L")
	)
	(segment
		(start 312.09107 -133.6802)
		(end 310.006238 -133.6802)
		(width 0.127)
		(layer "In2.Cu")
		(net "BMC_JTAG_L")
	)
	(segment
		(start 227.203 -159.893)
		(end 218.313 -159.893)
		(width 0.127)
		(layer "In2.Cu")
		(net "BMC_JTAG_L")
	)
	(segment
		(start 321.945 -171.45)
		(end 322.6435 -170.7515)
		(width 0.127)
		(layer "In2.Cu")
		(net "BMC_JTAG_L")
	)
	(segment
		(start 303.962816 -133.679946)
		(end 303.45507 -133.1722)
		(width 0.127)
		(layer "In2.Cu")
		(net "BMC_JTAG_L")
	)
	(segment
		(start 323.94017 -162.30473)
		(end 323.418454 -161.783014)
		(width 0.127)
		(layer "In2.Cu")
		(net "BMC_JTAG_L")
	)
	(segment
		(start 323.94017 -167.93083)
		(end 323.94017 -162.30473)
		(width 0.127)
		(layer "In2.Cu")
		(net "BMC_JTAG_L")
	)
	(segment
		(start 317.1317 -150.548086)
		(end 317.1317 -141.178534)
		(width 0.127)
		(layer "In2.Cu")
		(net "BMC_JTAG_L")
	)
	(segment
		(start 310.006238 -133.6802)
		(end 310.005984 -133.679946)
		(width 0.127)
		(layer "In2.Cu")
		(net "BMC_JTAG_L")
	)
	(segment
		(start 322.87464 -156.337)
		(end 321.31 -154.77236)
		(width 0.127)
		(layer "In2.Cu")
		(net "BMC_JTAG_L")
	)
	(segment
		(start 268.879066 -158.1785)
		(end 228.9175 -158.1785)
		(width 0.127)
		(layer "In2.Cu")
		(net "BMC_JTAG_L")
	)
	(segment
		(start 317.912242 -139.501372)
		(end 314.269628 -135.858758)
		(width 0.127)
		(layer "In2.Cu")
		(net "BMC_JTAG_L")
	)
	(segment
		(start 303.45507 -133.1722)
		(end 298.3738 -133.1722)
		(width 0.127)
		(layer "In2.Cu")
		(net "BMC_JTAG_L")
	)
	(segment
		(start 322.6435 -169.2275)
		(end 323.94017 -167.93083)
		(width 0.127)
		(layer "In2.Cu")
		(net "BMC_JTAG_L")
	)
	(segment
		(start 317.912242 -140.397992)
		(end 317.912242 -139.501372)
		(width 0.127)
		(layer "In2.Cu")
		(net "BMC_JTAG_L")
	)
	(segment
		(start 312.35777 -133.9469)
		(end 312.09107 -133.6802)
		(width 0.127)
		(layer "In2.Cu")
		(net "BMC_JTAG_L")
	)
	(segment
		(start 292.227 -139.319)
		(end 287.738566 -139.319)
		(width 0.127)
		(layer "In2.Cu")
		(net "BMC_JTAG_L")
	)
	(segment
		(start 317.1317 -141.178534)
		(end 317.912242 -140.397992)
		(width 0.127)
		(layer "In2.Cu")
		(net "BMC_JTAG_L")
	)
	(segment
		(start 323.026532 -156.337)
		(end 322.87464 -156.337)
		(width 0.127)
		(layer "In2.Cu")
		(net "BMC_JTAG_L")
	)
	(segment
		(start 312.887868 -133.9469)
		(end 312.35777 -133.9469)
		(width 0.127)
		(layer "In2.Cu")
		(net "BMC_JTAG_L")
	)
	(segment
		(start 228.9175 -158.1785)
		(end 227.203 -159.893)
		(width 0.127)
		(layer "In2.Cu")
		(net "BMC_JTAG_L")
	)
	(segment
		(start 314.269628 -135.32866)
		(end 312.887868 -133.9469)
		(width 0.127)
		(layer "In2.Cu")
		(net "BMC_JTAG_L")
	)
	(segment
		(start 322.6435 -170.7515)
		(end 322.6435 -169.2275)
		(width 0.127)
		(layer "In2.Cu")
		(net "BMC_JTAG_L")
	)
	(segment
		(start 314.269628 -135.858758)
		(end 314.269628 -135.32866)
		(width 0.127)
		(layer "In2.Cu")
		(net "BMC_JTAG_L")
	)
	(segment
		(start 321.31 -154.726386)
		(end 317.1317 -150.548086)
		(width 0.127)
		(layer "In2.Cu")
		(net "BMC_JTAG_L")
	)
	(segment
		(start 323.418454 -156.728922)
		(end 323.026532 -156.337)
		(width 0.127)
		(layer "In2.Cu")
		(net "BMC_JTAG_L")
	)
	(segment
		(start 314.4774 -213.5759)
		(end 314.4774 -215.4936)
		(width 0.1143)
		(layer "F.Cu")
		(net "JTAG_EXP_R_TDO")
	)
	(segment
		(start 314.4774 -215.4936)
		(end 314.4774 -216.8779)
		(width 0.1143)
		(layer "F.Cu")
		(net "JTAG_EXP_R_TDO")
	)
	(via
		(at 314.4774 -215.4936)
		(size 0.7112)
		(drill 0.3556)
		(layers "F.Cu" "B.Cu")
		(net "JTAG_EXP_R_TDO")
	)
	(segment
		(start 265.43 -8.279892)
		(end 267.145008 -8.279892)
		(width 0.508)
		(layer "F.Cu")
		(net "AGND_USB")
	)
	(segment
		(start 263.714992 -8.279892)
		(end 265.43 -8.279892)
		(width 0.508)
		(layer "F.Cu")
		(net "AGND_USB")
	)
	(segment
		(start 278.569928 -8.279892)
		(end 278.569928 -9.9949)
		(width 0.508)
		(layer "F.Cu")
		(net "AGND_USB")
	)
	(segment
		(start 278.569928 -6.564884)
		(end 278.569928 -8.279892)
		(width 0.508)
		(layer "F.Cu")
		(net "AGND_USB")
	)
	(segment
		(start 265.43 -8.279892)
		(end 265.43 -9.9949)
		(width 0.508)
		(layer "F.Cu")
		(net "AGND_USB")
	)
	(segment
		(start 265.43 -6.564884)
		(end 265.43 -8.279892)
		(width 0.508)
		(layer "F.Cu")
		(net "AGND_USB")
	)
	(segment
		(start 276.85492 -8.279892)
		(end 278.569928 -8.279892)
		(width 0.508)
		(layer "F.Cu")
		(net "AGND_USB")
	)
	(via
		(at 83.947 -72.898)
		(size 0.7112)
		(drill 0.3556)
		(layers "F.Cu" "B.Cu")
		(net "PG_STAT")
	)
	(segment
		(start 83.947 -73.5965)
		(end 83.947 -72.898)
		(width 0.1143)
		(layer "B.Cu")
		(net "PG_STAT")
	)
	(segment
		(start 83.693 -73.8505)
		(end 83.947 -73.5965)
		(width 0.1143)
		(layer "B.Cu")
		(net "PG_STAT")
	)
	(segment
		(start 81.407 -73.66)
		(end 81.788 -73.279)
		(width 0.1143)
		(layer "B.Cu")
		(net "PG_STAT")
	)
	(segment
		(start 83.1215 -73.279)
		(end 83.693 -73.8505)
		(width 0.1143)
		(layer "B.Cu")
		(net "PG_STAT")
	)
	(segment
		(start 81.407 -74.1045)
		(end 81.407 -73.66)
		(width 0.1143)
		(layer "B.Cu")
		(net "PG_STAT")
	)
	(segment
		(start 81.788 -73.279)
		(end 83.1215 -73.279)
		(width 0.1143)
		(layer "B.Cu")
		(net "PG_STAT")
	)
	(segment
		(start 44.6786 -118.70563)
		(end 44.6786 -117.602)
		(width 0.1143)
		(layer "F.Cu")
		(net "SAS_R_SDBRX")
	)
	(segment
		(start 43.8277 -116.7511)
		(end 44.6786 -117.602)
		(width 0.1143)
		(layer "F.Cu")
		(net "SAS_R_SDBRX")
	)
	(segment
		(start 43.8277 -116.2812)
		(end 43.8277 -116.7511)
		(width 0.1143)
		(layer "F.Cu")
		(net "SAS_R_SDBRX")
	)
	(via
		(at 44.6786 -117.602)
		(size 0.7112)
		(drill 0.3556)
		(layers "F.Cu" "B.Cu")
		(net "SAS_R_SDBRX")
	)
	(segment
		(start 42.3418 -118.2624)
		(end 43.053 -117.5512)
		(width 0.1143)
		(layer "F.Cu")
		(net "SAS_R_SDBTX")
	)
	(segment
		(start 42.8117 -117.0686)
		(end 43.053 -117.3099)
		(width 0.1143)
		(layer "F.Cu")
		(net "SAS_R_SDBTX")
	)
	(segment
		(start 42.8117 -116.2812)
		(end 42.8117 -117.0686)
		(width 0.1143)
		(layer "F.Cu")
		(net "SAS_R_SDBTX")
	)
	(segment
		(start 43.053 -117.3099)
		(end 43.053 -117.5512)
		(width 0.1143)
		(layer "F.Cu")
		(net "SAS_R_SDBTX")
	)
	(segment
		(start 42.3418 -118.70563)
		(end 42.3418 -118.2624)
		(width 0.1143)
		(layer "F.Cu")
		(net "SAS_R_SDBTX")
	)
	(via
		(at 43.053 -117.5512)
		(size 0.7112)
		(drill 0.3556)
		(layers "F.Cu" "B.Cu")
		(net "SAS_R_SDBTX")
	)
	(segment
		(start 47.5107 -120.5992)
		(end 46.4312 -120.5992)
		(width 0.1143)
		(layer "F.Cu")
		(net "SDB_RX_R")
	)
	(segment
		(start 45.65777 -120.20677)
		(end 46.0502 -120.5992)
		(width 0.1143)
		(layer "F.Cu")
		(net "SDB_RX_R")
	)
	(segment
		(start 44.6786 -120.20677)
		(end 45.65777 -120.20677)
		(width 0.1143)
		(layer "F.Cu")
		(net "SDB_RX_R")
	)
	(segment
		(start 46.0502 -120.5992)
		(end 46.4312 -120.5992)
		(width 0.1143)
		(layer "F.Cu")
		(net "SDB_RX_R")
	)
	(via
		(at 46.4312 -120.5992)
		(size 0.7112)
		(drill 0.3556)
		(layers "F.Cu" "B.Cu")
		(net "SDB_RX_R")
	)
	(segment
		(start 41.0464 -120.777)
		(end 40.513 -120.777)
		(width 0.1143)
		(layer "F.Cu")
		(net "SDB_TX_R")
	)
	(segment
		(start 39.5097 -120.4722)
		(end 40.2082 -120.4722)
		(width 0.1143)
		(layer "F.Cu")
		(net "SDB_TX_R")
	)
	(segment
		(start 42.3418 -120.20677)
		(end 41.61663 -120.20677)
		(width 0.1143)
		(layer "F.Cu")
		(net "SDB_TX_R")
	)
	(segment
		(start 40.2082 -120.4722)
		(end 40.513 -120.777)
		(width 0.1143)
		(layer "F.Cu")
		(net "SDB_TX_R")
	)
	(segment
		(start 41.61663 -120.20677)
		(end 41.0464 -120.777)
		(width 0.1143)
		(layer "F.Cu")
		(net "SDB_TX_R")
	)
	(via
		(at 40.513 -120.777)
		(size 0.7112)
		(drill 0.3556)
		(layers "F.Cu" "B.Cu")
		(net "SDB_TX_R")
	)
	(segment
		(start 34.938716 -201.26198)
		(end 33.826196 -202.3745)
		(width 0.127)
		(layer "F.Cu")
		(net "P1V5_C_SENSE")
	)
	(segment
		(start 34.938716 -201.09688)
		(end 34.938716 -201.26198)
		(width 0.127)
		(layer "F.Cu")
		(net "P1V5_C_SENSE")
	)
	(segment
		(start 31.230316 -202.3745)
		(end 33.826196 -202.3745)
		(width 0.127)
		(layer "F.Cu")
		(net "P1V5_C_SENSE")
	)
	(via
		(at 33.826196 -202.3745)
		(size 0.7112)
		(drill 0.3556)
		(layers "F.Cu" "B.Cu")
		(net "P1V5_C_SENSE")
	)
	(segment
		(start 32.242506 -201.87539)
		(end 33.325816 -200.79208)
		(width 0.127)
		(layer "F.Cu")
		(net "P1V5_E_SENSE")
	)
	(segment
		(start 31.230316 -201.87539)
		(end 32.242506 -201.87539)
		(width 0.127)
		(layer "F.Cu")
		(net "P1V5_E_SENSE")
	)
	(segment
		(start 34.938716 -199.06488)
		(end 33.351216 -200.65238)
		(width 0.127)
		(layer "F.Cu")
		(net "P1V5_E_SENSE")
	)
	(segment
		(start 33.325816 -200.79208)
		(end 33.325816 -200.65238)
		(width 0.127)
		(layer "F.Cu")
		(net "P1V5_E_SENSE")
	)
	(segment
		(start 33.351216 -200.65238)
		(end 33.325816 -200.65238)
		(width 0.127)
		(layer "F.Cu")
		(net "P1V5_E_SENSE")
	)
	(via
		(at 33.325816 -200.65238)
		(size 0.7112)
		(drill 0.3556)
		(layers "F.Cu" "B.Cu")
		(net "P1V5_E_SENSE")
	)
	(segment
		(start 24.372316 -201.57948)
		(end 25.375616 -201.57948)
		(width 0.127)
		(layer "F.Cu")
		(net "P0V955_C_SENSE")
	)
	(segment
		(start 25.671526 -201.87539)
		(end 25.426416 -201.63028)
		(width 0.127)
		(layer "F.Cu")
		(net "P0V955_C_SENSE")
	)
	(segment
		(start 25.375616 -201.57948)
		(end 25.426416 -201.63028)
		(width 0.127)
		(layer "F.Cu")
		(net "P0V955_C_SENSE")
	)
	(segment
		(start 27.090116 -201.87539)
		(end 25.671526 -201.87539)
		(width 0.127)
		(layer "F.Cu")
		(net "P0V955_C_SENSE")
	)
	(segment
		(start 23.508716 -200.71588)
		(end 24.372316 -201.57948)
		(width 0.127)
		(layer "F.Cu")
		(net "P0V955_C_SENSE")
	)
	(via
		(at 25.426416 -201.63028)
		(size 0.7112)
		(drill 0.3556)
		(layers "F.Cu" "B.Cu")
		(net "P0V955_C_SENSE")
	)
	(segment
		(start 24.258016 -202.74788)
		(end 24.486616 -202.51928)
		(width 0.127)
		(layer "F.Cu")
		(net "P0V9_E_SENSE")
	)
	(segment
		(start 23.508716 -202.74788)
		(end 24.258016 -202.74788)
		(width 0.127)
		(layer "F.Cu")
		(net "P0V9_E_SENSE")
	)
	(segment
		(start 24.631396 -202.3745)
		(end 24.486616 -202.51928)
		(width 0.127)
		(layer "F.Cu")
		(net "P0V9_E_SENSE")
	)
	(segment
		(start 27.090116 -202.3745)
		(end 24.631396 -202.3745)
		(width 0.127)
		(layer "F.Cu")
		(net "P0V9_E_SENSE")
	)
	(via
		(at 24.486616 -202.51928)
		(size 0.7112)
		(drill 0.3556)
		(layers "F.Cu" "B.Cu")
		(net "P0V9_E_SENSE")
	)
	(segment
		(start 331.596492 -222.157036)
		(end 331.596492 -221.233492)
		(width 0.127)
		(layer "F.Cu")
		(net "1V8_STBY_SENSE")
	)
	(segment
		(start 329.556872 -215.146636)
		(end 329.556872 -217.466672)
		(width 0.127)
		(layer "F.Cu")
		(net "1V8_STBY_SENSE")
	)
	(segment
		(start 331.596492 -221.233492)
		(end 330.073 -219.71)
		(width 0.127)
		(layer "F.Cu")
		(net "1V8_STBY_SENSE")
	)
	(segment
		(start 330.073 -217.9828)
		(end 330.073 -219.71)
		(width 0.127)
		(layer "F.Cu")
		(net "1V8_STBY_SENSE")
	)
	(segment
		(start 329.556872 -217.466672)
		(end 330.073 -217.9828)
		(width 0.127)
		(layer "F.Cu")
		(net "1V8_STBY_SENSE")
	)
	(via
		(at 330.073 -219.71)
		(size 0.7112)
		(drill 0.3556)
		(layers "F.Cu" "B.Cu")
		(net "1V8_STBY_SENSE")
	)
	(segment
		(start 331.097382 -221.877382)
		(end 328.422 -219.202)
		(width 0.127)
		(layer "F.Cu")
		(net "3V3_STBY_SENSE")
	)
	(segment
		(start 328.422 -218.1098)
		(end 328.422 -218.9734)
		(width 0.127)
		(layer "F.Cu")
		(net "3V3_STBY_SENSE")
	)
	(segment
		(start 331.097382 -222.157036)
		(end 331.097382 -221.877382)
		(width 0.127)
		(layer "F.Cu")
		(net "3V3_STBY_SENSE")
	)
	(segment
		(start 328.422 -219.202)
		(end 328.422 -218.9734)
		(width 0.127)
		(layer "F.Cu")
		(net "3V3_STBY_SENSE")
	)
	(segment
		(start 328.413872 -215.146636)
		(end 328.413872 -218.101672)
		(width 0.127)
		(layer "F.Cu")
		(net "3V3_STBY_SENSE")
	)
	(segment
		(start 328.413872 -218.101672)
		(end 328.422 -218.1098)
		(width 0.127)
		(layer "F.Cu")
		(net "3V3_STBY_SENSE")
	)
	(via
		(at 328.422 -218.9734)
		(size 0.7112)
		(drill 0.3556)
		(layers "F.Cu" "B.Cu")
		(net "3V3_STBY_SENSE")
	)
	(segment
		(start 243.8527 -115.726972)
		(end 243.095272 -116.4844)
		(width 0.1143)
		(layer "F.Cu")
		(net "SAS_SMART_R_RX")
	)
	(segment
		(start 243.8527 -115.22837)
		(end 243.8527 -115.726972)
		(width 0.1143)
		(layer "F.Cu")
		(net "SAS_SMART_R_RX")
	)
	(segment
		(start 243.095272 -117.729)
		(end 243.095272 -116.4844)
		(width 0.1143)
		(layer "F.Cu")
		(net "SAS_SMART_R_RX")
	)
	(via
		(at 243.095272 -116.4844)
		(size 0.7112)
		(drill 0.3556)
		(layers "F.Cu" "B.Cu")
		(net "SAS_SMART_R_RX")
	)
	(segment
		(start 241.9223 -116.8908)
		(end 241.5413 -116.5098)
		(width 0.1143)
		(layer "F.Cu")
		(net "SAS_SMART_R_TX")
	)
	(segment
		(start 241.5159 -115.22837)
		(end 241.5159 -116.4844)
		(width 0.1143)
		(layer "F.Cu")
		(net "SAS_SMART_R_TX")
	)
	(segment
		(start 241.9223 -117.7163)
		(end 241.9223 -116.8908)
		(width 0.1143)
		(layer "F.Cu")
		(net "SAS_SMART_R_TX")
	)
	(segment
		(start 241.5159 -116.4844)
		(end 241.5413 -116.5098)
		(width 0.1143)
		(layer "F.Cu")
		(net "SAS_SMART_R_TX")
	)
	(via
		(at 241.5413 -116.5098)
		(size 0.7112)
		(drill 0.3556)
		(layers "F.Cu" "B.Cu")
		(net "SAS_SMART_R_TX")
	)
	(segment
		(start 330.699872 -231.38257)
		(end 330.97978 -231.102662)
		(width 0.127)
		(layer "F.Cu")
		(net "5V_STBY_SENSE")
	)
	(segment
		(start 330.699872 -232.037636)
		(end 330.699872 -231.38257)
		(width 0.127)
		(layer "F.Cu")
		(net "5V_STBY_SENSE")
	)
	(segment
		(start 331.089 -227.203)
		(end 331.097382 -227.194618)
		(width 0.127)
		(layer "F.Cu")
		(net "5V_STBY_SENSE")
	)
	(segment
		(start 331.097382 -227.194618)
		(end 331.097382 -226.297236)
		(width 0.127)
		(layer "F.Cu")
		(net "5V_STBY_SENSE")
	)
	(segment
		(start 330.97978 -231.102662)
		(end 331.089 -230.993442)
		(width 0.127)
		(layer "F.Cu")
		(net "5V_STBY_SENSE")
	)
	(segment
		(start 331.089 -230.993442)
		(end 331.089 -227.203)
		(width 0.127)
		(layer "F.Cu")
		(net "5V_STBY_SENSE")
	)
	(via
		(at 330.97978 -231.102662)
		(size 0.7112)
		(drill 0.3556)
		(layers "F.Cu" "B.Cu")
		(net "5V_STBY_SENSE")
	)
	(segment
		(start 243.8527 -113.72723)
		(end 243.8527 -113.0554)
		(width 0.1143)
		(layer "F.Cu")
		(net "EXP_SMART_RX_R")
	)
	(segment
		(start 243.3193 -112.1283)
		(end 243.8908 -112.1283)
		(width 0.1143)
		(layer "F.Cu")
		(net "EXP_SMART_RX_R")
	)
	(segment
		(start 243.8908 -112.1283)
		(end 244.3353 -112.5728)
		(width 0.1143)
		(layer "F.Cu")
		(net "EXP_SMART_RX_R")
	)
	(segment
		(start 243.8527 -113.0554)
		(end 244.3353 -112.5728)
		(width 0.1143)
		(layer "F.Cu")
		(net "EXP_SMART_RX_R")
	)
	(via
		(at 244.3353 -112.5728)
		(size 0.7112)
		(drill 0.3556)
		(layers "F.Cu" "B.Cu")
		(net "EXP_SMART_RX_R")
	)
	(segment
		(start 242.1763 -112.1283)
		(end 241.7318 -112.1283)
		(width 0.1143)
		(layer "F.Cu")
		(net "EXP_SMART_TX_R")
	)
	(segment
		(start 241.5159 -112.8014)
		(end 241.2873 -112.5728)
		(width 0.1143)
		(layer "F.Cu")
		(net "EXP_SMART_TX_R")
	)
	(segment
		(start 241.7318 -112.1283)
		(end 241.2873 -112.5728)
		(width 0.1143)
		(layer "F.Cu")
		(net "EXP_SMART_TX_R")
	)
	(segment
		(start 241.5159 -113.72723)
		(end 241.5159 -112.8014)
		(width 0.1143)
		(layer "F.Cu")
		(net "EXP_SMART_TX_R")
	)
	(via
		(at 241.2873 -112.5728)
		(size 0.7112)
		(drill 0.3556)
		(layers "F.Cu" "B.Cu")
		(net "EXP_SMART_TX_R")
	)
	(segment
		(start 42.3418 -119.70639)
		(end 40.68699 -119.70639)
		(width 0.1143)
		(layer "F.Cu")
		(net "SDB_UART_EN")
	)
	(segment
		(start 40.68699 -119.70639)
		(end 40.4368 -119.4562)
		(width 0.1143)
		(layer "F.Cu")
		(net "SDB_UART_EN")
	)
	(segment
		(start 39.5097 -119.3292)
		(end 40.3098 -119.3292)
		(width 0.1143)
		(layer "F.Cu")
		(net "SDB_UART_EN")
	)
	(segment
		(start 40.3098 -119.3292)
		(end 40.4368 -119.4562)
		(width 0.1143)
		(layer "F.Cu")
		(net "SDB_UART_EN")
	)
	(via
		(at 40.4368 -119.4562)
		(size 0.7112)
		(drill 0.3556)
		(layers "F.Cu" "B.Cu")
		(net "SDB_UART_EN")
	)
	(segment
		(start 238.5568 -114.9858)
		(end 239.6363 -114.9858)
		(width 0.1143)
		(layer "F.Cu")
		(net "SMART_UART_EN")
	)
	(segment
		(start 240.65611 -114.72799)
		(end 240.3983 -114.9858)
		(width 0.1143)
		(layer "F.Cu")
		(net "SMART_UART_EN")
	)
	(segment
		(start 241.5159 -114.72799)
		(end 240.65611 -114.72799)
		(width 0.1143)
		(layer "F.Cu")
		(net "SMART_UART_EN")
	)
	(segment
		(start 240.3983 -114.9858)
		(end 239.6363 -114.9858)
		(width 0.1143)
		(layer "F.Cu")
		(net "SMART_UART_EN")
	)
	(via
		(at 239.6363 -114.9858)
		(size 0.7112)
		(drill 0.3556)
		(layers "F.Cu" "B.Cu")
		(net "SMART_UART_EN")
	)
	(segment
		(start 24.562816 -205.66888)
		(end 23.889716 -205.66888)
		(width 0.1143)
		(layer "F.Cu")
		(net "VOL_SEN_ADDR_U17")
	)
	(segment
		(start 27.090116 -203.87437)
		(end 26.890726 -203.87437)
		(width 0.1143)
		(layer "F.Cu")
		(net "VOL_SEN_ADDR_U17")
	)
	(segment
		(start 23.508716 -206.04988)
		(end 23.508716 -207.06588)
		(width 0.1143)
		(layer "F.Cu")
		(net "VOL_SEN_ADDR_U17")
	)
	(segment
		(start 23.889716 -205.66888)
		(end 23.508716 -206.04988)
		(width 0.1143)
		(layer "F.Cu")
		(net "VOL_SEN_ADDR_U17")
	)
	(segment
		(start 25.096216 -205.66888)
		(end 24.562816 -205.66888)
		(width 0.1143)
		(layer "F.Cu")
		(net "VOL_SEN_ADDR_U17")
	)
	(segment
		(start 26.890726 -203.87437)
		(end 25.096216 -205.66888)
		(width 0.1143)
		(layer "F.Cu")
		(net "VOL_SEN_ADDR_U17")
	)
	(via
		(at 24.562816 -205.66888)
		(size 0.7112)
		(drill 0.3556)
		(layers "F.Cu" "B.Cu")
		(net "VOL_SEN_ADDR_U17")
	)
	(segment
		(start 31.230316 -203.87437)
		(end 32.598106 -203.87437)
		(width 0.1143)
		(layer "F.Cu")
		(net "VOL_SEN_SCL_U17")
	)
	(segment
		(start 32.598106 -203.87437)
		(end 33.808416 -205.08468)
		(width 0.1143)
		(layer "F.Cu")
		(net "VOL_SEN_SCL_U17")
	)
	(segment
		(start 34.938716 -205.28788)
		(end 34.938716 -206.43088)
		(width 0.1143)
		(layer "F.Cu")
		(net "VOL_SEN_SCL_U17")
	)
	(segment
		(start 33.808416 -205.08468)
		(end 34.011616 -205.28788)
		(width 0.1143)
		(layer "F.Cu")
		(net "VOL_SEN_SCL_U17")
	)
	(segment
		(start 34.011616 -205.28788)
		(end 34.938716 -205.28788)
		(width 0.1143)
		(layer "F.Cu")
		(net "VOL_SEN_SCL_U17")
	)
	(via
		(at 33.808416 -205.08468)
		(size 0.7112)
		(drill 0.3556)
		(layers "F.Cu" "B.Cu")
		(net "VOL_SEN_SCL_U17")
	)
	(segment
		(start 27.090116 -203.37526)
		(end 26.094436 -203.37526)
		(width 0.1143)
		(layer "F.Cu")
		(net "VOL_SEN_ALERT_U17")
	)
	(segment
		(start 24.105616 -204.90688)
		(end 24.842216 -204.17028)
		(width 0.1143)
		(layer "F.Cu")
		(net "VOL_SEN_ALERT_U17")
	)
	(segment
		(start 26.094436 -203.37526)
		(end 25.299416 -204.17028)
		(width 0.1143)
		(layer "F.Cu")
		(net "VOL_SEN_ALERT_U17")
	)
	(segment
		(start 25.299416 -204.17028)
		(end 24.842216 -204.17028)
		(width 0.1143)
		(layer "F.Cu")
		(net "VOL_SEN_ALERT_U17")
	)
	(segment
		(start 23.508716 -204.90688)
		(end 24.105616 -204.90688)
		(width 0.1143)
		(layer "F.Cu")
		(net "VOL_SEN_ALERT_U17")
	)
	(segment
		(start 32.803338 -203.37907)
		(end 33.264348 -203.84008)
		(width 0.1143)
		(layer "F.Cu")
		(net "VOL_SEN_SDA_U17")
	)
	(segment
		(start 33.264348 -203.84008)
		(end 33.783016 -203.84008)
		(width 0.1143)
		(layer "F.Cu")
		(net "VOL_SEN_SDA_U17")
	)
	(segment
		(start 31.230316 -203.37526)
		(end 32.632396 -203.37526)
		(width 0.1143)
		(layer "F.Cu")
		(net "VOL_SEN_SDA_U17")
	)
	(segment
		(start 32.632396 -203.37526)
		(end 32.636206 -203.37907)
		(width 0.1143)
		(layer "F.Cu")
		(net "VOL_SEN_SDA_U17")
	)
	(segment
		(start 34.938716 -204.14488)
		(end 34.938716 -203.12888)
		(width 0.1143)
		(layer "F.Cu")
		(net "VOL_SEN_SDA_U17")
	)
	(segment
		(start 34.227516 -203.84008)
		(end 33.783016 -203.84008)
		(width 0.1143)
		(layer "F.Cu")
		(net "VOL_SEN_SDA_U17")
	)
	(segment
		(start 34.938716 -203.12888)
		(end 34.227516 -203.84008)
		(width 0.1143)
		(layer "F.Cu")
		(net "VOL_SEN_SDA_U17")
	)
	(segment
		(start 32.636206 -203.37907)
		(end 32.803338 -203.37907)
		(width 0.1143)
		(layer "F.Cu")
		(net "VOL_SEN_SDA_U17")
	)
	(via
		(at 33.783016 -203.84008)
		(size 0.7112)
		(drill 0.3556)
		(layers "F.Cu" "B.Cu")
		(net "VOL_SEN_SDA_U17")
	)
	(segment
		(start 219.78366 -84.963)
		(end 219.00896 -85.7377)
		(width 0.1143)
		(layer "F.Cu")
		(net "IOC_UART_0_RX_R")
	)
	(segment
		(start 223.2025 -84.963)
		(end 219.78366 -84.963)
		(width 0.1143)
		(layer "F.Cu")
		(net "IOC_UART_0_RX_R")
	)
	(segment
		(start 219.00896 -85.7377)
		(end 219.00896 -85.96884)
		(width 0.1143)
		(layer "F.Cu")
		(net "IOC_UART_0_RX_R")
	)
	(segment
		(start 219.00896 -86.22284)
		(end 219.00896 -85.96884)
		(width 0.1143)
		(layer "F.Cu")
		(net "IOC_UART_0_RX_R")
	)
	(segment
		(start 219.00388 -86.22792)
		(end 219.00896 -86.22284)
		(width 0.1143)
		(layer "F.Cu")
		(net "IOC_UART_0_RX_R")
	)
	(segment
		(start 219.00388 -87.10295)
		(end 219.00388 -86.22792)
		(width 0.1143)
		(layer "F.Cu")
		(net "IOC_UART_0_RX_R")
	)
	(via
		(at 219.00896 -85.96884)
		(size 0.7112)
		(drill 0.3556)
		(layers "F.Cu" "B.Cu")
		(net "IOC_UART_0_RX_R")
	)
	(segment
		(start 221.34068 -86.18474)
		(end 221.55658 -85.96884)
		(width 0.1143)
		(layer "F.Cu")
		(net "IOC_UART_0_TX_R")
	)
	(segment
		(start 223.19234 -85.96884)
		(end 221.615 -85.96884)
		(width 0.1143)
		(layer "F.Cu")
		(net "IOC_UART_0_TX_R")
	)
	(segment
		(start 221.55658 -85.96884)
		(end 221.615 -85.96884)
		(width 0.1143)
		(layer "F.Cu")
		(net "IOC_UART_0_TX_R")
	)
	(segment
		(start 221.34068 -87.10295)
		(end 221.34068 -86.18474)
		(width 0.1143)
		(layer "F.Cu")
		(net "IOC_UART_0_TX_R")
	)
	(segment
		(start 223.2025 -85.979)
		(end 223.19234 -85.96884)
		(width 0.1143)
		(layer "F.Cu")
		(net "IOC_UART_0_TX_R")
	)
	(via
		(at 221.615 -85.96884)
		(size 0.7112)
		(drill 0.3556)
		(layers "F.Cu" "B.Cu")
		(net "IOC_UART_0_TX_R")
	)
	(segment
		(start 301.371 -153.5684)
		(end 301.371 -152.5905)
		(width 0.1143)
		(layer "F.Cu")
		(net "50M_CLK_OUT_R")
	)
	(segment
		(start 301.097188 -152.316688)
		(end 299.703236 -152.316688)
		(width 0.1143)
		(layer "F.Cu")
		(net "50M_CLK_OUT_R")
	)
	(segment
		(start 301.371 -152.5905)
		(end 301.097188 -152.316688)
		(width 0.1143)
		(layer "F.Cu")
		(net "50M_CLK_OUT_R")
	)
	(via
		(at 301.371 -153.5684)
		(size 0.7112)
		(drill 0.3556)
		(layers "F.Cu" "B.Cu")
		(net "50M_CLK_OUT_R")
	)
	(segment
		(start 225.0948 -17.907)
		(end 224.155 -17.907)
		(width 0.1778)
		(layer "F.Cu")
		(net "ENCLO_LED_RED_R")
	)
	(segment
		(start 105.158032 -2.029968)
		(end 105.156 -2.032)
		(width 0.1778)
		(layer "F.Cu")
		(net "ENCLO_LED_RED_R")
	)
	(segment
		(start 224.155 -17.907)
		(end 223.393 -17.145)
		(width 0.1778)
		(layer "F.Cu")
		(net "ENCLO_LED_RED_R")
	)
	(segment
		(start 223.393 -17.145)
		(end 221.869 -15.621)
		(width 0.1778)
		(layer "F.Cu")
		(net "ENCLO_LED_RED_R")
	)
	(segment
		(start 106.969052 -2.029968)
		(end 105.158032 -2.029968)
		(width 0.1778)
		(layer "F.Cu")
		(net "ENCLO_LED_RED_R")
	)
	(via
		(at 223.393 -17.145)
		(size 0.7112)
		(drill 0.3556)
		(layers "F.Cu" "B.Cu")
		(net "ENCLO_LED_RED_R")
	)
	(via
		(at 221.869 -15.621)
		(size 0.508)
		(drill 0.254)
		(layers "F.Cu" "B.Cu")
		(net "ENCLO_LED_RED_R")
	)
	(via
		(at 105.156 -2.032)
		(size 0.5588)
		(drill 0.3048)
		(layers "F.Cu" "B.Cu")
		(net "ENCLO_LED_RED_R")
	)
	(segment
		(start 145.971768 -22.479)
		(end 137.411968 -13.9192)
		(width 0.1778)
		(layer "In2.Cu")
		(net "ENCLO_LED_RED_R")
	)
	(segment
		(start 137.3759 -13.9192)
		(end 137.2997 -13.843)
		(width 0.1778)
		(layer "In2.Cu")
		(net "ENCLO_LED_RED_R")
	)
	(segment
		(start 167.9448 -18.21307)
		(end 163.67887 -22.479)
		(width 0.1778)
		(layer "In2.Cu")
		(net "ENCLO_LED_RED_R")
	)
	(segment
		(start 106.553 -3.429)
		(end 105.156 -2.032)
		(width 0.1778)
		(layer "In2.Cu")
		(net "ENCLO_LED_RED_R")
	)
	(segment
		(start 167.9448 -15.6972)
		(end 167.9448 -18.21307)
		(width 0.1778)
		(layer "In2.Cu")
		(net "ENCLO_LED_RED_R")
	)
	(segment
		(start 137.2997 -13.843)
		(end 125.857 -13.843)
		(width 0.1778)
		(layer "In2.Cu")
		(net "ENCLO_LED_RED_R")
	)
	(segment
		(start 172.6692 -10.9728)
		(end 167.9448 -15.6972)
		(width 0.1778)
		(layer "In2.Cu")
		(net "ENCLO_LED_RED_R")
	)
	(segment
		(start 115.443 -3.429)
		(end 106.553 -3.429)
		(width 0.1778)
		(layer "In2.Cu")
		(net "ENCLO_LED_RED_R")
	)
	(segment
		(start 163.67887 -22.479)
		(end 145.971768 -22.479)
		(width 0.1778)
		(layer "In2.Cu")
		(net "ENCLO_LED_RED_R")
	)
	(segment
		(start 221.234 -15.621)
		(end 216.5858 -10.9728)
		(width 0.1778)
		(layer "In2.Cu")
		(net "ENCLO_LED_RED_R")
	)
	(segment
		(start 216.5858 -10.9728)
		(end 172.6692 -10.9728)
		(width 0.1778)
		(layer "In2.Cu")
		(net "ENCLO_LED_RED_R")
	)
	(segment
		(start 125.857 -13.843)
		(end 115.443 -3.429)
		(width 0.1778)
		(layer "In2.Cu")
		(net "ENCLO_LED_RED_R")
	)
	(segment
		(start 137.411968 -13.9192)
		(end 137.3759 -13.9192)
		(width 0.1778)
		(layer "In2.Cu")
		(net "ENCLO_LED_RED_R")
	)
	(segment
		(start 221.869 -15.621)
		(end 221.234 -15.621)
		(width 0.1778)
		(layer "In2.Cu")
		(net "ENCLO_LED_RED_R")
	)
	(segment
		(start 231.99725 -16.54175)
		(end 231.7115 -16.8275)
		(width 0.1778)
		(layer "F.Cu")
		(net "ENCLO_LED_RED_G")
	)
	(segment
		(start 232.9815 -17.907)
		(end 231.7115 -17.907)
		(width 0.1778)
		(layer "F.Cu")
		(net "ENCLO_LED_RED_G")
	)
	(segment
		(start 231.99725 -15.4305)
		(end 231.99725 -16.54175)
		(width 0.1778)
		(layer "F.Cu")
		(net "ENCLO_LED_RED_G")
	)
	(segment
		(start 231.7115 -17.907)
		(end 231.7115 -16.8275)
		(width 0.1778)
		(layer "F.Cu")
		(net "ENCLO_LED_RED_G")
	)
	(via
		(at 231.7115 -16.8275)
		(size 0.7112)
		(drill 0.3556)
		(layers "F.Cu" "B.Cu")
		(net "ENCLO_LED_RED_G")
	)
	(segment
		(start 224.9805 -14.351)
		(end 223.393 -14.351)
		(width 0.1778)
		(layer "F.Cu")
		(net "ENCLO_LED_RED_D1")
	)
	(segment
		(start 110.111032 -2.029968)
		(end 111.122968 -2.029968)
		(width 0.1778)
		(layer "F.Cu")
		(net "ENCLO_LED_RED_D1")
	)
	(segment
		(start 222.123 -14.351)
		(end 221.996 -14.224)
		(width 0.1778)
		(layer "F.Cu")
		(net "ENCLO_LED_RED_D1")
	)
	(segment
		(start 223.393 -14.351)
		(end 222.123 -14.351)
		(width 0.1778)
		(layer "F.Cu")
		(net "ENCLO_LED_RED_D1")
	)
	(segment
		(start 111.122968 -2.029968)
		(end 111.379 -2.286)
		(width 0.1778)
		(layer "F.Cu")
		(net "ENCLO_LED_RED_D1")
	)
	(via
		(at 221.996 -14.224)
		(size 0.508)
		(drill 0.254)
		(layers "F.Cu" "B.Cu")
		(net "ENCLO_LED_RED_D1")
	)
	(via
		(at 223.393 -14.351)
		(size 0.7112)
		(drill 0.3556)
		(layers "F.Cu" "B.Cu")
		(net "ENCLO_LED_RED_D1")
	)
	(via
		(at 111.379 -2.286)
		(size 0.5588)
		(drill 0.3048)
		(layers "F.Cu" "B.Cu")
		(net "ENCLO_LED_RED_D1")
	)
	(segment
		(start 221.996 -14.224)
		(end 218.313 -10.541)
		(width 0.1778)
		(layer "In2.Cu")
		(net "ENCLO_LED_RED_D1")
	)
	(segment
		(start 218.313 -10.541)
		(end 171.958 -10.541)
		(width 0.1778)
		(layer "In2.Cu")
		(net "ENCLO_LED_RED_D1")
	)
	(segment
		(start 167.513 -18.034)
		(end 163.576 -21.971)
		(width 0.1778)
		(layer "In2.Cu")
		(net "ENCLO_LED_RED_D1")
	)
	(segment
		(start 163.576 -21.971)
		(end 146.939 -21.971)
		(width 0.1778)
		(layer "In2.Cu")
		(net "ENCLO_LED_RED_D1")
	)
	(segment
		(start 115.824 -2.921)
		(end 112.014 -2.921)
		(width 0.1778)
		(layer "In2.Cu")
		(net "ENCLO_LED_RED_D1")
	)
	(segment
		(start 167.513 -14.986)
		(end 167.513 -18.034)
		(width 0.1778)
		(layer "In2.Cu")
		(net "ENCLO_LED_RED_D1")
	)
	(segment
		(start 138.049 -13.081)
		(end 125.984 -13.081)
		(width 0.1778)
		(layer "In2.Cu")
		(net "ENCLO_LED_RED_D1")
	)
	(segment
		(start 146.939 -21.971)
		(end 138.049 -13.081)
		(width 0.1778)
		(layer "In2.Cu")
		(net "ENCLO_LED_RED_D1")
	)
	(segment
		(start 112.014 -2.921)
		(end 111.379 -2.286)
		(width 0.1778)
		(layer "In2.Cu")
		(net "ENCLO_LED_RED_D1")
	)
	(segment
		(start 125.984 -13.081)
		(end 115.824 -2.921)
		(width 0.1778)
		(layer "In2.Cu")
		(net "ENCLO_LED_RED_D1")
	)
	(segment
		(start 171.958 -10.541)
		(end 167.513 -14.986)
		(width 0.1778)
		(layer "In2.Cu")
		(net "ENCLO_LED_RED_D1")
	)
	(segment
		(start 221.869 -172.6565)
		(end 220.9165 -172.6565)
		(width 0.1143)
		(layer "F.Cu")
		(net "INVERTER_G2_EXP")
	)
	(segment
		(start 221.359984 -174.678594)
		(end 221.359984 -173.165516)
		(width 0.1143)
		(layer "F.Cu")
		(net "INVERTER_G2_EXP")
	)
	(segment
		(start 221.359984 -173.165516)
		(end 221.869 -172.6565)
		(width 0.1143)
		(layer "F.Cu")
		(net "INVERTER_G2_EXP")
	)
	(segment
		(start 220.9165 -172.6565)
		(end 220.726 -172.466)
		(width 0.1143)
		(layer "F.Cu")
		(net "INVERTER_G2_EXP")
	)
	(segment
		(start 222.010224 -172.797724)
		(end 222.010224 -174.678594)
		(width 0.1143)
		(layer "F.Cu")
		(net "INVERTER_G2_EXP")
	)
	(segment
		(start 221.869 -172.6565)
		(end 222.010224 -172.797724)
		(width 0.1143)
		(layer "F.Cu")
		(net "INVERTER_G2_EXP")
	)
	(via
		(at 220.726 -172.466)
		(size 0.7112)
		(drill 0.3556)
		(layers "F.Cu" "B.Cu")
		(net "INVERTER_G2_EXP")
	)
	(segment
		(start 303.5427 -184.1373)
		(end 308.2417 -184.1373)
		(width 0.127)
		(layer "F.Cu")
		(net "BMC0_LED_DR_R_LED1")
	)
	(segment
		(start 310.4515 -183.515)
		(end 310.3245 -183.642)
		(width 0.127)
		(layer "F.Cu")
		(net "BMC0_LED_DR_R_LED1")
	)
	(segment
		(start 300.834806 -183.44007)
		(end 301.203106 -183.07177)
		(width 0.127)
		(layer "F.Cu")
		(net "BMC0_LED_DR_R_LED1")
	)
	(segment
		(start 310.3245 -183.642)
		(end 308.737 -183.642)
		(width 0.127)
		(layer "F.Cu")
		(net "BMC0_LED_DR_R_LED1")
	)
	(segment
		(start 301.203106 -183.07177)
		(end 302.47717 -183.07177)
		(width 0.127)
		(layer "F.Cu")
		(net "BMC0_LED_DR_R_LED1")
	)
	(segment
		(start 302.47717 -183.07177)
		(end 303.5427 -184.1373)
		(width 0.127)
		(layer "F.Cu")
		(net "BMC0_LED_DR_R_LED1")
	)
	(segment
		(start 308.2417 -184.1373)
		(end 308.737 -183.642)
		(width 0.127)
		(layer "F.Cu")
		(net "BMC0_LED_DR_R_LED1")
	)
	(via
		(at 308.737 -183.642)
		(size 0.7112)
		(drill 0.3556)
		(layers "F.Cu" "B.Cu")
		(net "BMC0_LED_DR_R_LED1")
	)
	(segment
		(start 239.649 -38.608)
		(end 239.649 -63.436754)
		(width 0.127)
		(layer "F.Cu")
		(net "LED_DR_LED1")
	)
	(segment
		(start 263.56945 -92.150438)
		(end 269.929864 -98.510852)
		(width 0.127)
		(layer "F.Cu")
		(net "LED_DR_LED1")
	)
	(segment
		(start 269.929864 -98.510852)
		(end 269.929864 -100.960936)
		(width 0.127)
		(layer "F.Cu")
		(net "LED_DR_LED1")
	)
	(segment
		(start 312.1406 -182.7784)
		(end 312.166 -182.7784)
		(width 0.127)
		(layer "F.Cu")
		(net "LED_DR_LED1")
	)
	(segment
		(start 307.975 -194.2465)
		(end 307.402992 -194.818508)
		(width 0.127)
		(layer "F.Cu")
		(net "LED_DR_LED1")
	)
	(segment
		(start 311.3405 -183.515)
		(end 311.404 -183.515)
		(width 0.127)
		(layer "F.Cu")
		(net "LED_DR_LED1")
	)
	(segment
		(start 239.649 -63.436754)
		(end 263.56945 -87.357204)
		(width 0.127)
		(layer "F.Cu")
		(net "LED_DR_LED1")
	)
	(segment
		(start 224.2185 -23.1775)
		(end 239.649 -38.608)
		(width 0.127)
		(layer "F.Cu")
		(net "LED_DR_LED1")
	)
	(segment
		(start 310.134 -194.2465)
		(end 307.975 -194.2465)
		(width 0.127)
		(layer "F.Cu")
		(net "LED_DR_LED1")
	)
	(segment
		(start 263.56945 -87.357204)
		(end 263.56945 -92.150438)
		(width 0.127)
		(layer "F.Cu")
		(net "LED_DR_LED1")
	)
	(segment
		(start 307.402992 -195.390008)
		(end 307.41112 -197.0659)
		(width 0.127)
		(layer "F.Cu")
		(net "LED_DR_LED1")
	)
	(segment
		(start 269.929864 -100.960936)
		(end 269.5448 -101.346)
		(width 0.127)
		(layer "F.Cu")
		(net "LED_DR_LED1")
	)
	(segment
		(start 223.393 -23.1775)
		(end 224.2185 -23.1775)
		(width 0.127)
		(layer "F.Cu")
		(net "LED_DR_LED1")
	)
	(segment
		(start 311.404 -183.515)
		(end 312.1406 -182.7784)
		(width 0.127)
		(layer "F.Cu")
		(net "LED_DR_LED1")
	)
	(segment
		(start 307.402992 -194.818508)
		(end 307.402992 -195.390008)
		(width 0.127)
		(layer "F.Cu")
		(net "LED_DR_LED1")
	)
	(via
		(at 338.201 -178.562)
		(size 0.7112)
		(drill 0.3556)
		(layers "F.Cu" "B.Cu")
		(net "LED_DR_LED1")
	)
	(via
		(at 312.166 -182.7784)
		(size 0.5588)
		(drill 0.3048)
		(layers "F.Cu" "B.Cu")
		(net "LED_DR_LED1")
	)
	(via
		(at 338.963 -169.926)
		(size 0.5588)
		(drill 0.3048)
		(layers "F.Cu" "B.Cu")
		(net "LED_DR_LED1")
	)
	(via
		(at 269.5448 -101.346)
		(size 0.5588)
		(drill 0.3048)
		(layers "F.Cu" "B.Cu")
		(net "LED_DR_LED1")
	)
	(via
		(at 325.12 -106.807)
		(size 0.5588)
		(drill 0.3048)
		(layers "F.Cu" "B.Cu")
		(net "LED_DR_LED1")
	)
	(via
		(at 310.134 -194.2465)
		(size 0.5588)
		(drill 0.3048)
		(layers "F.Cu" "B.Cu")
		(net "LED_DR_LED1")
	)
	(segment
		(start 338.709 -170.18)
		(end 338.963 -169.926)
		(width 0.127)
		(layer "B.Cu")
		(net "LED_DR_LED1")
	)
	(segment
		(start 319.659 -186.944)
		(end 331.597 -186.944)
		(width 0.127)
		(layer "B.Cu")
		(net "LED_DR_LED1")
	)
	(segment
		(start 338.201 -171.069)
		(end 338.709 -170.561)
		(width 0.127)
		(layer "B.Cu")
		(net "LED_DR_LED1")
	)
	(segment
		(start 332.4479 -187.7949)
		(end 333.061818 -187.7949)
		(width 0.127)
		(layer "B.Cu")
		(net "LED_DR_LED1")
	)
	(segment
		(start 317.1444 -184.4294)
		(end 319.659 -186.944)
		(width 0.127)
		(layer "B.Cu")
		(net "LED_DR_LED1")
	)
	(segment
		(start 280.433018 -101.1555)
		(end 280.242518 -101.346)
		(width 0.127)
		(layer "B.Cu")
		(net "LED_DR_LED1")
	)
	(segment
		(start 331.597 -186.944)
		(end 332.4479 -187.7949)
		(width 0.127)
		(layer "B.Cu")
		(net "LED_DR_LED1")
	)
	(segment
		(start 338.709 -170.561)
		(end 338.709 -170.18)
		(width 0.127)
		(layer "B.Cu")
		(net "LED_DR_LED1")
	)
	(segment
		(start 286.2199 -106.468418)
		(end 280.906982 -101.1555)
		(width 0.127)
		(layer "B.Cu")
		(net "LED_DR_LED1")
	)
	(segment
		(start 280.906982 -101.1555)
		(end 280.433018 -101.1555)
		(width 0.127)
		(layer "B.Cu")
		(net "LED_DR_LED1")
	)
	(segment
		(start 280.242518 -101.346)
		(end 269.5448 -101.346)
		(width 0.127)
		(layer "B.Cu")
		(net "LED_DR_LED1")
	)
	(segment
		(start 324.781418 -106.468418)
		(end 286.2199 -106.468418)
		(width 0.127)
		(layer "B.Cu")
		(net "LED_DR_LED1")
	)
	(segment
		(start 312.166 -182.7784)
		(end 313.817 -184.4294)
		(width 0.127)
		(layer "B.Cu")
		(net "LED_DR_LED1")
	)
	(segment
		(start 313.817 -184.4294)
		(end 317.1444 -184.4294)
		(width 0.127)
		(layer "B.Cu")
		(net "LED_DR_LED1")
	)
	(segment
		(start 325.12 -106.807)
		(end 324.781418 -106.468418)
		(width 0.127)
		(layer "B.Cu")
		(net "LED_DR_LED1")
	)
	(segment
		(start 338.201 -178.562)
		(end 338.201 -171.069)
		(width 0.127)
		(layer "B.Cu")
		(net "LED_DR_LED1")
	)
	(segment
		(start 338.201 -182.655718)
		(end 338.201 -178.562)
		(width 0.127)
		(layer "B.Cu")
		(net "LED_DR_LED1")
	)
	(segment
		(start 333.061818 -187.7949)
		(end 338.201 -182.655718)
		(width 0.127)
		(layer "B.Cu")
		(net "LED_DR_LED1")
	)
	(segment
		(start 312.140092 -182.7784)
		(end 310.134 -184.784492)
		(width 0.127)
		(layer "In2.Cu")
		(net "LED_DR_LED1")
	)
	(segment
		(start 310.134 -184.784492)
		(end 310.134 -194.2465)
		(width 0.127)
		(layer "In2.Cu")
		(net "LED_DR_LED1")
	)
	(segment
		(start 312.166 -182.7784)
		(end 312.140092 -182.7784)
		(width 0.127)
		(layer "In2.Cu")
		(net "LED_DR_LED1")
	)
	(segment
		(start 336.296 -160.303464)
		(end 336.296 -167.259)
		(width 0.127)
		(layer "In5.Cu")
		(net "LED_DR_LED1")
	)
	(segment
		(start 337.075018 -158.69285)
		(end 337.075018 -159.524446)
		(width 0.127)
		(layer "In5.Cu")
		(net "LED_DR_LED1")
	)
	(segment
		(start 338.180172 -169.143172)
		(end 338.963 -169.926)
		(width 0.127)
		(layer "In5.Cu")
		(net "LED_DR_LED1")
	)
	(segment
		(start 327.7235 -112.250982)
		(end 327.9648 -112.492282)
		(width 0.127)
		(layer "In5.Cu")
		(net "LED_DR_LED1")
	)
	(segment
		(start 327.9648 -111.535718)
		(end 327.7235 -111.777018)
		(width 0.127)
		(layer "In5.Cu")
		(net "LED_DR_LED1")
	)
	(segment
		(start 328.1553 -119.447818)
		(end 329.1205 -120.413018)
		(width 0.127)
		(layer "In5.Cu")
		(net "LED_DR_LED1")
	)
	(segment
		(start 327.9648 -114.025934)
		(end 328.1553 -114.216434)
		(width 0.127)
		(layer "In5.Cu")
		(net "LED_DR_LED1")
	)
	(segment
		(start 326.263 -107.95)
		(end 326.263 -108.839)
		(width 0.127)
		(layer "In5.Cu")
		(net "LED_DR_LED1")
	)
	(segment
		(start 328.1553 -114.216434)
		(end 328.1553 -119.447818)
		(width 0.127)
		(layer "In5.Cu")
		(net "LED_DR_LED1")
	)
	(segment
		(start 328.1553 -121.852182)
		(end 328.1553 -134.8867)
		(width 0.127)
		(layer "In5.Cu")
		(net "LED_DR_LED1")
	)
	(segment
		(start 336.296 -143.0274)
		(end 336.296 -157.913832)
		(width 0.127)
		(layer "In5.Cu")
		(net "LED_DR_LED1")
	)
	(segment
		(start 337.824572 -168.787572)
		(end 337.890104 -168.787572)
		(width 0.127)
		(layer "In5.Cu")
		(net "LED_DR_LED1")
	)
	(segment
		(start 327.9648 -110.5408)
		(end 327.9648 -111.535718)
		(width 0.127)
		(layer "In5.Cu")
		(net "LED_DR_LED1")
	)
	(segment
		(start 337.075018 -159.524446)
		(end 336.296 -160.303464)
		(width 0.127)
		(layer "In5.Cu")
		(net "LED_DR_LED1")
	)
	(segment
		(start 327.9648 -112.492282)
		(end 327.9648 -114.025934)
		(width 0.127)
		(layer "In5.Cu")
		(net "LED_DR_LED1")
	)
	(segment
		(start 338.180172 -169.07764)
		(end 338.180172 -169.143172)
		(width 0.127)
		(layer "In5.Cu")
		(net "LED_DR_LED1")
	)
	(segment
		(start 326.263 -108.839)
		(end 327.9648 -110.5408)
		(width 0.127)
		(layer "In5.Cu")
		(net "LED_DR_LED1")
	)
	(segment
		(start 328.1553 -134.8867)
		(end 336.296 -143.0274)
		(width 0.127)
		(layer "In5.Cu")
		(net "LED_DR_LED1")
	)
	(segment
		(start 336.296 -157.913832)
		(end 337.075018 -158.69285)
		(width 0.127)
		(layer "In5.Cu")
		(net "LED_DR_LED1")
	)
	(segment
		(start 337.890104 -168.787572)
		(end 338.180172 -169.07764)
		(width 0.127)
		(layer "In5.Cu")
		(net "LED_DR_LED1")
	)
	(segment
		(start 325.12 -106.807)
		(end 326.263 -107.95)
		(width 0.127)
		(layer "In5.Cu")
		(net "LED_DR_LED1")
	)
	(segment
		(start 336.296 -167.259)
		(end 337.824572 -168.787572)
		(width 0.127)
		(layer "In5.Cu")
		(net "LED_DR_LED1")
	)
	(segment
		(start 329.1205 -120.413018)
		(end 329.1205 -120.886982)
		(width 0.127)
		(layer "In5.Cu")
		(net "LED_DR_LED1")
	)
	(segment
		(start 327.7235 -111.777018)
		(end 327.7235 -112.250982)
		(width 0.127)
		(layer "In5.Cu")
		(net "LED_DR_LED1")
	)
	(segment
		(start 329.1205 -120.886982)
		(end 328.1553 -121.852182)
		(width 0.127)
		(layer "In5.Cu")
		(net "LED_DR_LED1")
	)
	(via
		(at 78.74 -26.035)
		(size 0.7112)
		(drill 0.3556)
		(layers "F.Cu" "B.Cu")
		(net "P3V3_STBY_R9")
	)
	(segment
		(start 78.6765 -26.035)
		(end 77.6605 -25.019)
		(width 0.254)
		(layer "B.Cu")
		(net "P3V3_STBY_R9")
	)
	(segment
		(start 77.6605 -25.019)
		(end 76.5175 -25.019)
		(width 0.254)
		(layer "B.Cu")
		(net "P3V3_STBY_R9")
	)
	(segment
		(start 76.5175 -25.019)
		(end 76.5175 -24.7015)
		(width 0.254)
		(layer "B.Cu")
		(net "P3V3_STBY_R9")
	)
	(segment
		(start 76.5175 -24.7015)
		(end 75.946 -24.13)
		(width 0.254)
		(layer "B.Cu")
		(net "P3V3_STBY_R9")
	)
	(segment
		(start 75.946 -24.13)
		(end 75.946 -22.5425)
		(width 0.254)
		(layer "B.Cu")
		(net "P3V3_STBY_R9")
	)
	(segment
		(start 75.946 -22.5425)
		(end 76.1365 -22.352)
		(width 0.254)
		(layer "B.Cu")
		(net "P3V3_STBY_R9")
	)
	(segment
		(start 78.74 -26.035)
		(end 78.6765 -26.035)
		(width 0.254)
		(layer "B.Cu")
		(net "P3V3_STBY_R9")
	)
	(segment
		(start 345.962478 -152.829768)
		(end 345.959684 -152.828498)
		(width 0.1397)
		(layer "F.Cu")
		(net "USB_P4_DN")
	)
	(segment
		(start 345.959684 -152.828498)
		(end 345.953588 -152.825958)
		(width 0.1397)
		(layer "F.Cu")
		(net "USB_P4_DN")
	)
	(segment
		(start 344.507058 -152.226772)
		(end 344.402918 -152.226772)
		(width 0.1397)
		(layer "F.Cu")
		(net "USB_P4_DN")
	)
	(segment
		(start 347.412564 -154.279854)
		(end 345.962478 -152.829768)
		(width 0.1397)
		(layer "F.Cu")
		(net "USB_P4_DN")
	)
	(segment
		(start 347.743018 -154.358848)
		(end 347.603318 -154.358848)
		(width 0.1397)
		(layer "F.Cu")
		(net "USB_P4_DN")
	)
	(arc
		(start 347.603318 -154.358848)
		(mid 347.50009 -154.338315)
		(end 347.412564 -154.279854)
		(width 0.1397)
		(layer "F.Cu")
		(net "USB_P4_DN")
	)
	(arc
		(start 347.946218 -154.155648)
		(mid 347.886702 -154.299332)
		(end 347.743018 -154.358848)
		(width 0.1397)
		(layer "F.Cu")
		(net "USB_P4_DN")
	)
	(arc
		(start 345.953588 -152.825958)
		(mid 345.289914 -152.382505)
		(end 344.507058 -152.226772)
		(width 0.1397)
		(layer "F.Cu")
		(net "USB_P4_DN")
	)
	(segment
		(start 347.946218 -155.298648)
		(end 345.768168 -153.120598)
		(width 0.1397)
		(layer "F.Cu")
		(net "USB_P4_DP")
	)
	(segment
		(start 344.817192 -152.726644)
		(end 344.491818 -152.726644)
		(width 0.1397)
		(layer "F.Cu")
		(net "USB_P4_DP")
	)
	(arc
		(start 345.768168 -153.120598)
		(mid 345.331857 -152.829064)
		(end 344.817192 -152.726644)
		(width 0.1397)
		(layer "F.Cu")
		(net "USB_P4_DP")
	)
	(segment
		(start 349.22333 -154.54376)
		(end 349.742252 -154.54376)
		(width 0.1397)
		(layer "F.Cu")
		(net "BMC_USB1_HDN2")
	)
	(segment
		(start 300.03496 -174.64024)
		(end 300.03496 -174.644812)
		(width 0.1397)
		(layer "F.Cu")
		(net "BMC_USB1_HDN2")
	)
	(segment
		(start 348.835218 -154.155648)
		(end 349.22333 -154.54376)
		(width 0.1397)
		(layer "F.Cu")
		(net "BMC_USB1_HDN2")
	)
	(segment
		(start 349.742252 -154.54376)
		(end 350.010984 -154.275028)
		(width 0.1397)
		(layer "F.Cu")
		(net "BMC_USB1_HDN2")
	)
	(segment
		(start 300.03496 -174.644812)
		(end 300.435518 -175.04537)
		(width 0.1397)
		(layer "F.Cu")
		(net "BMC_USB1_HDN2")
	)
	(via
		(at 350.010984 -154.275028)
		(size 0.508)
		(drill 0.254)
		(layers "F.Cu" "B.Cu")
		(net "BMC_USB1_HDN2")
	)
	(via
		(at 300.435518 -175.04537)
		(size 0.508)
		(drill 0.254)
		(layers "F.Cu" "B.Cu")
		(net "BMC_USB1_HDN2")
	)
	(segment
		(start 351.282 -171.196)
		(end 347.599 -174.879)
		(width 0.127)
		(layer "In5.Cu")
		(net "BMC_USB1_HDN2")
	)
	(segment
		(start 300.435518 -175.26127)
		(end 300.435518 -175.04537)
		(width 0.127)
		(layer "In5.Cu")
		(net "BMC_USB1_HDN2")
	)
	(segment
		(start 349.25 -154.559)
		(end 348.615 -155.194)
		(width 0.127)
		(layer "In5.Cu")
		(net "BMC_USB1_HDN2")
	)
	(segment
		(start 343.415366 -174.72914)
		(end 343.265506 -174.879)
		(width 0.127)
		(layer "In5.Cu")
		(net "BMC_USB1_HDN2")
	)
	(segment
		(start 348.615 -159.766)
		(end 351.282 -162.433)
		(width 0.127)
		(layer "In5.Cu")
		(net "BMC_USB1_HDN2")
	)
	(segment
		(start 338.021168 -174.72914)
		(end 337.871308 -174.879)
		(width 0.127)
		(layer "In5.Cu")
		(net "BMC_USB1_HDN2")
	)
	(segment
		(start 351.282 -162.433)
		(end 351.282 -171.196)
		(width 0.127)
		(layer "In5.Cu")
		(net "BMC_USB1_HDN2")
	)
	(segment
		(start 343.796366 -174.72914)
		(end 343.415366 -174.72914)
		(width 0.127)
		(layer "In5.Cu")
		(net "BMC_USB1_HDN2")
	)
	(segment
		(start 337.871308 -174.879)
		(end 337.490308 -174.879)
		(width 0.127)
		(layer "In5.Cu")
		(net "BMC_USB1_HDN2")
	)
	(segment
		(start 308.855364 -176.5046)
		(end 302.421544 -176.5046)
		(width 0.127)
		(layer "In5.Cu")
		(net "BMC_USB1_HDN2")
	)
	(segment
		(start 332.497176 -177.9016)
		(end 322.568824 -177.9016)
		(width 0.127)
		(layer "In5.Cu")
		(net "BMC_USB1_HDN2")
	)
	(segment
		(start 322.568824 -177.9016)
		(end 321.298824 -176.6316)
		(width 0.127)
		(layer "In5.Cu")
		(net "BMC_USB1_HDN2")
	)
	(segment
		(start 338.933028 -174.879)
		(end 338.552028 -174.879)
		(width 0.127)
		(layer "In5.Cu")
		(net "BMC_USB1_HDN2")
	)
	(segment
		(start 337.340448 -174.72914)
		(end 336.959448 -174.72914)
		(width 0.127)
		(layer "In5.Cu")
		(net "BMC_USB1_HDN2")
	)
	(segment
		(start 338.402168 -174.72914)
		(end 338.021168 -174.72914)
		(width 0.127)
		(layer "In5.Cu")
		(net "BMC_USB1_HDN2")
	)
	(segment
		(start 336.809588 -174.879)
		(end 335.519776 -174.879)
		(width 0.127)
		(layer "In5.Cu")
		(net "BMC_USB1_HDN2")
	)
	(segment
		(start 345.388946 -174.879)
		(end 345.007946 -174.879)
		(width 0.127)
		(layer "In5.Cu")
		(net "BMC_USB1_HDN2")
	)
	(segment
		(start 344.858086 -174.72914)
		(end 344.477086 -174.72914)
		(width 0.127)
		(layer "In5.Cu")
		(net "BMC_USB1_HDN2")
	)
	(segment
		(start 336.959448 -174.72914)
		(end 336.809588 -174.879)
		(width 0.127)
		(layer "In5.Cu")
		(net "BMC_USB1_HDN2")
	)
	(segment
		(start 347.599 -174.879)
		(end 346.069666 -174.879)
		(width 0.127)
		(layer "In5.Cu")
		(net "BMC_USB1_HDN2")
	)
	(segment
		(start 345.538806 -174.72914)
		(end 345.388946 -174.879)
		(width 0.127)
		(layer "In5.Cu")
		(net "BMC_USB1_HDN2")
	)
	(segment
		(start 350.010984 -154.275028)
		(end 349.727012 -154.559)
		(width 0.127)
		(layer "In5.Cu")
		(net "BMC_USB1_HDN2")
	)
	(segment
		(start 335.519776 -174.879)
		(end 332.497176 -177.9016)
		(width 0.127)
		(layer "In5.Cu")
		(net "BMC_USB1_HDN2")
	)
	(segment
		(start 343.946226 -174.879)
		(end 343.796366 -174.72914)
		(width 0.127)
		(layer "In5.Cu")
		(net "BMC_USB1_HDN2")
	)
	(segment
		(start 300.640242 -175.465994)
		(end 300.435518 -175.26127)
		(width 0.127)
		(layer "In5.Cu")
		(net "BMC_USB1_HDN2")
	)
	(segment
		(start 310.633364 -178.2826)
		(end 308.855364 -176.5046)
		(width 0.127)
		(layer "In5.Cu")
		(net "BMC_USB1_HDN2")
	)
	(segment
		(start 345.007946 -174.879)
		(end 344.858086 -174.72914)
		(width 0.127)
		(layer "In5.Cu")
		(net "BMC_USB1_HDN2")
	)
	(segment
		(start 346.069666 -174.879)
		(end 345.919806 -174.72914)
		(width 0.127)
		(layer "In5.Cu")
		(net "BMC_USB1_HDN2")
	)
	(segment
		(start 344.477086 -174.72914)
		(end 344.327226 -174.879)
		(width 0.127)
		(layer "In5.Cu")
		(net "BMC_USB1_HDN2")
	)
	(segment
		(start 317.9064 -178.2826)
		(end 310.633364 -178.2826)
		(width 0.127)
		(layer "In5.Cu")
		(net "BMC_USB1_HDN2")
	)
	(segment
		(start 338.552028 -174.879)
		(end 338.402168 -174.72914)
		(width 0.127)
		(layer "In5.Cu")
		(net "BMC_USB1_HDN2")
	)
	(segment
		(start 339.463888 -174.72914)
		(end 339.082888 -174.72914)
		(width 0.127)
		(layer "In5.Cu")
		(net "BMC_USB1_HDN2")
	)
	(segment
		(start 321.298824 -176.6316)
		(end 319.5574 -176.6316)
		(width 0.127)
		(layer "In5.Cu")
		(net "BMC_USB1_HDN2")
	)
	(segment
		(start 343.265506 -174.879)
		(end 339.613748 -174.879)
		(width 0.127)
		(layer "In5.Cu")
		(net "BMC_USB1_HDN2")
	)
	(segment
		(start 302.421544 -176.5046)
		(end 301.382938 -175.465994)
		(width 0.127)
		(layer "In5.Cu")
		(net "BMC_USB1_HDN2")
	)
	(segment
		(start 348.615 -155.194)
		(end 348.615 -159.766)
		(width 0.127)
		(layer "In5.Cu")
		(net "BMC_USB1_HDN2")
	)
	(segment
		(start 319.5574 -176.6316)
		(end 317.9064 -178.2826)
		(width 0.127)
		(layer "In5.Cu")
		(net "BMC_USB1_HDN2")
	)
	(segment
		(start 345.919806 -174.72914)
		(end 345.538806 -174.72914)
		(width 0.127)
		(layer "In5.Cu")
		(net "BMC_USB1_HDN2")
	)
	(segment
		(start 339.082888 -174.72914)
		(end 338.933028 -174.879)
		(width 0.127)
		(layer "In5.Cu")
		(net "BMC_USB1_HDN2")
	)
	(segment
		(start 349.727012 -154.559)
		(end 349.25 -154.559)
		(width 0.127)
		(layer "In5.Cu")
		(net "BMC_USB1_HDN2")
	)
	(segment
		(start 301.382938 -175.465994)
		(end 300.640242 -175.465994)
		(width 0.127)
		(layer "In5.Cu")
		(net "BMC_USB1_HDN2")
	)
	(segment
		(start 339.613748 -174.879)
		(end 339.463888 -174.72914)
		(width 0.127)
		(layer "In5.Cu")
		(net "BMC_USB1_HDN2")
	)
	(segment
		(start 344.327226 -174.879)
		(end 343.946226 -174.879)
		(width 0.127)
		(layer "In5.Cu")
		(net "BMC_USB1_HDN2")
	)
	(segment
		(start 337.490308 -174.879)
		(end 337.340448 -174.72914)
		(width 0.127)
		(layer "In5.Cu")
		(net "BMC_USB1_HDN2")
	)
	(segment
		(start 348.835218 -148.694648)
		(end 349.037148 -148.694648)
		(width 0.1397)
		(layer "F.Cu")
		(net "BMC_USB2_HDN")
	)
	(segment
		(start 286.020002 -184.412128)
		(end 285.65856 -184.773316)
		(width 0.1397)
		(layer "F.Cu")
		(net "BMC_USB2_HDN")
	)
	(segment
		(start 350.7867 -149.0853)
		(end 351.1804 -148.6916)
		(width 0.1397)
		(layer "F.Cu")
		(net "BMC_USB2_HDN")
	)
	(segment
		(start 349.4278 -149.0853)
		(end 350.7867 -149.0853)
		(width 0.1397)
		(layer "F.Cu")
		(net "BMC_USB2_HDN")
	)
	(segment
		(start 351.1804 -147.92452)
		(end 350.87941 -147.62353)
		(width 0.1397)
		(layer "F.Cu")
		(net "BMC_USB2_HDN")
	)
	(segment
		(start 351.1804 -148.6916)
		(end 351.1804 -147.92452)
		(width 0.1397)
		(layer "F.Cu")
		(net "BMC_USB2_HDN")
	)
	(segment
		(start 349.037148 -148.694648)
		(end 349.4278 -149.0853)
		(width 0.1397)
		(layer "F.Cu")
		(net "BMC_USB2_HDN")
	)
	(via
		(at 285.496 -185.166)
		(size 0.5588)
		(drill 0.3048)
		(layers "F.Cu" "B.Cu")
		(net "BMC_USB2_HDN")
	)
	(via
		(at 350.87941 -147.62353)
		(size 0.508)
		(drill 0.254)
		(layers "F.Cu" "B.Cu")
		(net "BMC_USB2_HDN")
	)
	(arc
		(start 286.434784 -184.24017)
		(mid 286.210302 -184.284916)
		(end 286.020002 -184.412128)
		(width 0.1397)
		(layer "F.Cu")
		(net "BMC_USB2_HDN")
	)
	(arc
		(start 285.65856 -184.773316)
		(mid 285.538231 -184.953495)
		(end 285.496 -185.166)
		(width 0.1397)
		(layer "F.Cu")
		(net "BMC_USB2_HDN")
	)
	(segment
		(start 351.2566 -148.00072)
		(end 350.87941 -147.62353)
		(width 0.127)
		(layer "In5.Cu")
		(net "BMC_USB2_HDN")
	)
	(segment
		(start 346.651834 -176.7078)
		(end 348.1832 -176.7078)
		(width 0.127)
		(layer "In5.Cu")
		(net "BMC_USB2_HDN")
	)
	(segment
		(start 339.471762 -176.55794)
		(end 339.852762 -176.55794)
		(width 0.127)
		(layer "In5.Cu")
		(net "BMC_USB2_HDN")
	)
	(segment
		(start 340.002622 -176.7078)
		(end 340.800436 -176.7078)
		(width 0.127)
		(layer "In5.Cu")
		(net "BMC_USB2_HDN")
	)
	(segment
		(start 340.950296 -176.55794)
		(end 341.331296 -176.55794)
		(width 0.127)
		(layer "In5.Cu")
		(net "BMC_USB2_HDN")
	)
	(segment
		(start 284.734 -186.887612)
		(end 284.734 -193.681604)
		(width 0.127)
		(layer "In5.Cu")
		(net "BMC_USB2_HDN")
	)
	(segment
		(start 338.410042 -176.55794)
		(end 338.791042 -176.55794)
		(width 0.127)
		(layer "In5.Cu")
		(net "BMC_USB2_HDN")
	)
	(segment
		(start 341.862156 -176.7078)
		(end 342.012016 -176.55794)
		(width 0.127)
		(layer "In5.Cu")
		(net "BMC_USB2_HDN")
	)
	(segment
		(start 337.198462 -176.7078)
		(end 337.348322 -176.55794)
		(width 0.127)
		(layer "In5.Cu")
		(net "BMC_USB2_HDN")
	)
	(segment
		(start 319.035176 -182.0926)
		(end 321.575176 -179.5526)
		(width 0.127)
		(layer "In5.Cu")
		(net "BMC_USB2_HDN")
	)
	(segment
		(start 338.940902 -176.7078)
		(end 339.321902 -176.7078)
		(width 0.127)
		(layer "In5.Cu")
		(net "BMC_USB2_HDN")
	)
	(segment
		(start 311.1246 -187.479178)
		(end 316.511178 -182.0926)
		(width 0.127)
		(layer "In5.Cu")
		(net "BMC_USB2_HDN")
	)
	(segment
		(start 283.2608 -204.7748)
		(end 284.7721 -206.2861)
		(width 0.127)
		(layer "In5.Cu")
		(net "BMC_USB2_HDN")
	)
	(segment
		(start 311.1246 -191.033146)
		(end 311.1246 -187.479178)
		(width 0.127)
		(layer "In5.Cu")
		(net "BMC_USB2_HDN")
	)
	(segment
		(start 282.9814 -196.7738)
		(end 282.9814 -204.100176)
		(width 0.127)
		(layer "In5.Cu")
		(net "BMC_USB2_HDN")
	)
	(segment
		(start 351.132902 -173.758098)
		(end 351.132902 -173.546262)
		(width 0.127)
		(layer "In5.Cu")
		(net "BMC_USB2_HDN")
	)
	(segment
		(start 341.331296 -176.55794)
		(end 341.481156 -176.7078)
		(width 0.127)
		(layer "In5.Cu")
		(net "BMC_USB2_HDN")
	)
	(segment
		(start 350.591628 -174.299372)
		(end 351.132902 -173.758098)
		(width 0.127)
		(layer "In5.Cu")
		(net "BMC_USB2_HDN")
	)
	(segment
		(start 341.481156 -176.7078)
		(end 341.862156 -176.7078)
		(width 0.127)
		(layer "In5.Cu")
		(net "BMC_USB2_HDN")
	)
	(segment
		(start 333.513176 -179.5526)
		(end 336.357976 -176.7078)
		(width 0.127)
		(layer "In5.Cu")
		(net "BMC_USB2_HDN")
	)
	(segment
		(start 321.575176 -179.5526)
		(end 333.513176 -179.5526)
		(width 0.127)
		(layer "In5.Cu")
		(net "BMC_USB2_HDN")
	)
	(segment
		(start 342.542876 -176.7078)
		(end 342.923876 -176.7078)
		(width 0.127)
		(layer "In5.Cu")
		(net "BMC_USB2_HDN")
	)
	(segment
		(start 351.614232 -173.276768)
		(end 352.679 -172.212)
		(width 0.127)
		(layer "In5.Cu")
		(net "BMC_USB2_HDN")
	)
	(segment
		(start 303.145444 -199.07758)
		(end 303.145444 -199.012302)
		(width 0.127)
		(layer "In5.Cu")
		(net "BMC_USB2_HDN")
	)
	(segment
		(start 337.348322 -176.55794)
		(end 337.729322 -176.55794)
		(width 0.127)
		(layer "In5.Cu")
		(net "BMC_USB2_HDN")
	)
	(segment
		(start 343.454736 -176.55794)
		(end 343.604596 -176.7078)
		(width 0.127)
		(layer "In5.Cu")
		(net "BMC_USB2_HDN")
	)
	(segment
		(start 303.145444 -199.012302)
		(end 311.1246 -191.033146)
		(width 0.127)
		(layer "In5.Cu")
		(net "BMC_USB2_HDN")
	)
	(segment
		(start 285.906464 -206.756)
		(end 297.407076 -206.756)
		(width 0.127)
		(layer "In5.Cu")
		(net "BMC_USB2_HDN")
	)
	(segment
		(start 284.2895 -194.7545)
		(end 283.48432 -195.55968)
		(width 0.127)
		(layer "In5.Cu")
		(net "BMC_USB2_HDN")
	)
	(segment
		(start 285.2166 -185.840624)
		(end 285.2166 -185.9026)
		(width 0.127)
		(layer "In5.Cu")
		(net "BMC_USB2_HDN")
	)
	(segment
		(start 342.923876 -176.7078)
		(end 343.073736 -176.55794)
		(width 0.127)
		(layer "In5.Cu")
		(net "BMC_USB2_HDN")
	)
	(segment
		(start 351.132902 -173.546262)
		(end 351.402142 -173.276768)
		(width 0.127)
		(layer "In5.Cu")
		(net "BMC_USB2_HDN")
	)
	(segment
		(start 345.971114 -176.7078)
		(end 346.120974 -176.55794)
		(width 0.127)
		(layer "In5.Cu")
		(net "BMC_USB2_HDN")
	)
	(segment
		(start 346.501974 -176.55794)
		(end 346.651834 -176.7078)
		(width 0.127)
		(layer "In5.Cu")
		(net "BMC_USB2_HDN")
	)
	(segment
		(start 351.2566 -150.2156)
		(end 351.2566 -148.00072)
		(width 0.127)
		(layer "In5.Cu")
		(net "BMC_USB2_HDN")
	)
	(segment
		(start 302.7426 -201.600054)
		(end 302.7426 -200.151492)
		(width 0.127)
		(layer "In5.Cu")
		(net "BMC_USB2_HDN")
	)
	(segment
		(start 337.729322 -176.55794)
		(end 337.879182 -176.7078)
		(width 0.127)
		(layer "In5.Cu")
		(net "BMC_USB2_HDN")
	)
	(segment
		(start 349.628968 -175.050196)
		(end 349.840804 -175.050196)
		(width 0.127)
		(layer "In5.Cu")
		(net "BMC_USB2_HDN")
	)
	(segment
		(start 316.511178 -182.0926)
		(end 319.035176 -182.0926)
		(width 0.127)
		(layer "In5.Cu")
		(net "BMC_USB2_HDN")
	)
	(segment
		(start 302.7426 -200.151492)
		(end 303.145444 -199.07758)
		(width 0.127)
		(layer "In5.Cu")
		(net "BMC_USB2_HDN")
	)
	(segment
		(start 346.120974 -176.55794)
		(end 346.501974 -176.55794)
		(width 0.127)
		(layer "In5.Cu")
		(net "BMC_USB2_HDN")
	)
	(segment
		(start 343.073736 -176.55794)
		(end 343.454736 -176.55794)
		(width 0.127)
		(layer "In5.Cu")
		(net "BMC_USB2_HDN")
	)
	(segment
		(start 338.791042 -176.55794)
		(end 338.940902 -176.7078)
		(width 0.127)
		(layer "In5.Cu")
		(net "BMC_USB2_HDN")
	)
	(segment
		(start 345.440254 -176.55794)
		(end 345.590114 -176.7078)
		(width 0.127)
		(layer "In5.Cu")
		(net "BMC_USB2_HDN")
	)
	(segment
		(start 336.357976 -176.7078)
		(end 337.198462 -176.7078)
		(width 0.127)
		(layer "In5.Cu")
		(net "BMC_USB2_HDN")
	)
	(segment
		(start 337.879182 -176.7078)
		(end 338.260182 -176.7078)
		(width 0.127)
		(layer "In5.Cu")
		(net "BMC_USB2_HDN")
	)
	(segment
		(start 339.321902 -176.7078)
		(end 339.471762 -176.55794)
		(width 0.127)
		(layer "In5.Cu")
		(net "BMC_USB2_HDN")
	)
	(segment
		(start 340.800436 -176.7078)
		(end 340.950296 -176.55794)
		(width 0.127)
		(layer "In5.Cu")
		(net "BMC_USB2_HDN")
	)
	(segment
		(start 345.059254 -176.55794)
		(end 345.440254 -176.55794)
		(width 0.127)
		(layer "In5.Cu")
		(net "BMC_USB2_HDN")
	)
	(segment
		(start 285.001208 -186.422792)
		(end 284.8737 -186.5503)
		(width 0.127)
		(layer "In5.Cu")
		(net "BMC_USB2_HDN")
	)
	(segment
		(start 348.878144 -175.800766)
		(end 349.090234 -175.800766)
		(width 0.127)
		(layer "In5.Cu")
		(net "BMC_USB2_HDN")
	)
	(segment
		(start 350.110298 -174.568866)
		(end 350.379792 -174.299372)
		(width 0.127)
		(layer "In5.Cu")
		(net "BMC_USB2_HDN")
	)
	(segment
		(start 348.608904 -176.07026)
		(end 348.878144 -175.800766)
		(width 0.127)
		(layer "In5.Cu")
		(net "BMC_USB2_HDN")
	)
	(segment
		(start 352.679 -151.638)
		(end 351.2566 -150.2156)
		(width 0.127)
		(layer "In5.Cu")
		(net "BMC_USB2_HDN")
	)
	(segment
		(start 345.590114 -176.7078)
		(end 345.971114 -176.7078)
		(width 0.127)
		(layer "In5.Cu")
		(net "BMC_USB2_HDN")
	)
	(segment
		(start 349.359474 -175.319436)
		(end 349.628968 -175.050196)
		(width 0.127)
		(layer "In5.Cu")
		(net "BMC_USB2_HDN")
	)
	(segment
		(start 348.1832 -176.7078)
		(end 348.608904 -176.282096)
		(width 0.127)
		(layer "In5.Cu")
		(net "BMC_USB2_HDN")
	)
	(segment
		(start 338.260182 -176.7078)
		(end 338.410042 -176.55794)
		(width 0.127)
		(layer "In5.Cu")
		(net "BMC_USB2_HDN")
	)
	(segment
		(start 350.110298 -174.780702)
		(end 350.110298 -174.568866)
		(width 0.127)
		(layer "In5.Cu")
		(net "BMC_USB2_HDN")
	)
	(segment
		(start 352.679 -172.212)
		(end 352.679 -151.638)
		(width 0.127)
		(layer "In5.Cu")
		(net "BMC_USB2_HDN")
	)
	(segment
		(start 342.012016 -176.55794)
		(end 342.393016 -176.55794)
		(width 0.127)
		(layer "In5.Cu")
		(net "BMC_USB2_HDN")
	)
	(segment
		(start 343.604596 -176.7078)
		(end 344.909394 -176.7078)
		(width 0.127)
		(layer "In5.Cu")
		(net "BMC_USB2_HDN")
	)
	(segment
		(start 348.608904 -176.282096)
		(end 348.608904 -176.07026)
		(width 0.127)
		(layer "In5.Cu")
		(net "BMC_USB2_HDN")
	)
	(segment
		(start 349.840804 -175.050196)
		(end 350.110298 -174.780702)
		(width 0.127)
		(layer "In5.Cu")
		(net "BMC_USB2_HDN")
	)
	(segment
		(start 344.909394 -176.7078)
		(end 345.059254 -176.55794)
		(width 0.127)
		(layer "In5.Cu")
		(net "BMC_USB2_HDN")
	)
	(segment
		(start 350.379792 -174.299372)
		(end 350.591628 -174.299372)
		(width 0.127)
		(layer "In5.Cu")
		(net "BMC_USB2_HDN")
	)
	(segment
		(start 298.9707 -206.1083)
		(end 302.2219 -202.8571)
		(width 0.127)
		(layer "In5.Cu")
		(net "BMC_USB2_HDN")
	)
	(segment
		(start 339.852762 -176.55794)
		(end 340.002622 -176.7078)
		(width 0.127)
		(layer "In5.Cu")
		(net "BMC_USB2_HDN")
	)
	(segment
		(start 342.393016 -176.55794)
		(end 342.542876 -176.7078)
		(width 0.127)
		(layer "In5.Cu")
		(net "BMC_USB2_HDN")
	)
	(segment
		(start 349.359474 -175.531526)
		(end 349.359474 -175.319436)
		(width 0.127)
		(layer "In5.Cu")
		(net "BMC_USB2_HDN")
	)
	(segment
		(start 351.402142 -173.276768)
		(end 351.614232 -173.276768)
		(width 0.127)
		(layer "In5.Cu")
		(net "BMC_USB2_HDN")
	)
	(segment
		(start 349.090234 -175.800766)
		(end 349.359474 -175.531526)
		(width 0.127)
		(layer "In5.Cu")
		(net "BMC_USB2_HDN")
	)
	(arc
		(start 285.496 -185.166)
		(mid 285.289185 -185.47552)
		(end 285.2166 -185.840624)
		(width 0.127)
		(layer "In5.Cu")
		(net "BMC_USB2_HDN")
	)
	(arc
		(start 283.48432 -195.55968)
		(mid 283.112116 -196.116723)
		(end 282.9814 -196.7738)
		(width 0.127)
		(layer "In5.Cu")
		(net "BMC_USB2_HDN")
	)
	(arc
		(start 302.2219 -202.8571)
		(mid 302.607264 -202.280362)
		(end 302.7426 -201.600054)
		(width 0.127)
		(layer "In5.Cu")
		(net "BMC_USB2_HDN")
	)
	(arc
		(start 282.9814 -204.100176)
		(mid 283.054021 -204.465265)
		(end 283.2608 -204.7748)
		(width 0.127)
		(layer "In5.Cu")
		(net "BMC_USB2_HDN")
	)
	(arc
		(start 284.8737 -186.5503)
		(mid 284.770293 -186.70506)
		(end 284.734 -186.887612)
		(width 0.127)
		(layer "In5.Cu")
		(net "BMC_USB2_HDN")
	)
	(arc
		(start 297.407076 -206.756)
		(mid 298.253313 -206.587673)
		(end 298.9707 -206.1083)
		(width 0.127)
		(layer "In5.Cu")
		(net "BMC_USB2_HDN")
	)
	(arc
		(start 285.2166 -185.9026)
		(mid 285.160622 -186.18411)
		(end 285.001208 -186.422792)
		(width 0.127)
		(layer "In5.Cu")
		(net "BMC_USB2_HDN")
	)
	(arc
		(start 284.7721 -206.2861)
		(mid 285.292551 -206.633854)
		(end 285.906464 -206.756)
		(width 0.127)
		(layer "In5.Cu")
		(net "BMC_USB2_HDN")
	)
	(arc
		(start 284.734 -193.681604)
		(mid 284.618427 -194.262247)
		(end 284.2895 -194.7545)
		(width 0.127)
		(layer "In5.Cu")
		(net "BMC_USB2_HDN")
	)
	(segment
		(start 349.4278 -149.4282)
		(end 350.92894 -149.4282)
		(width 0.1397)
		(layer "F.Cu")
		(net "BMC_USB2_HDP")
	)
	(segment
		(start 351.5233 -148.83384)
		(end 351.5233 -147.92452)
		(width 0.1397)
		(layer "F.Cu")
		(net "BMC_USB2_HDP")
	)
	(segment
		(start 285.496 -184.450482)
		(end 284.846014 -185.100468)
		(width 0.1397)
		(layer "F.Cu")
		(net "BMC_USB2_HDP")
	)
	(segment
		(start 348.835218 -149.837648)
		(end 349.018352 -149.837648)
		(width 0.1397)
		(layer "F.Cu")
		(net "BMC_USB2_HDP")
	)
	(segment
		(start 284.846014 -185.100468)
		(end 284.686502 -185.260234)
		(width 0.1397)
		(layer "F.Cu")
		(net "BMC_USB2_HDP")
	)
	(segment
		(start 349.018352 -149.837648)
		(end 349.4278 -149.4282)
		(width 0.1397)
		(layer "F.Cu")
		(net "BMC_USB2_HDP")
	)
	(segment
		(start 351.5233 -147.92452)
		(end 351.82429 -147.62353)
		(width 0.1397)
		(layer "F.Cu")
		(net "BMC_USB2_HDP")
	)
	(segment
		(start 285.584392 -184.361836)
		(end 285.496 -184.450482)
		(width 0.1397)
		(layer "F.Cu")
		(net "BMC_USB2_HDP")
	)
	(segment
		(start 350.92894 -149.4282)
		(end 351.5233 -148.83384)
		(width 0.1397)
		(layer "F.Cu")
		(net "BMC_USB2_HDP")
	)
	(via
		(at 284.607 -185.293)
		(size 0.5588)
		(drill 0.3048)
		(layers "F.Cu" "B.Cu")
		(net "BMC_USB2_HDP")
	)
	(via
		(at 351.82429 -147.62353)
		(size 0.508)
		(drill 0.254)
		(layers "F.Cu" "B.Cu")
		(net "BMC_USB2_HDP")
	)
	(arc
		(start 285.634938 -184.24017)
		(mid 285.621746 -184.306019)
		(end 285.584392 -184.361836)
		(width 0.1397)
		(layer "F.Cu")
		(net "BMC_USB2_HDP")
	)
	(arc
		(start 284.686502 -185.260234)
		(mid 284.650011 -185.284523)
		(end 284.607 -185.293)
		(width 0.1397)
		(layer "F.Cu")
		(net "BMC_USB2_HDP")
	)
	(segment
		(start 321.691 -179.832)
		(end 319.151 -182.372)
		(width 0.127)
		(layer "In5.Cu")
		(net "BMC_USB2_HDP")
	)
	(segment
		(start 303.424844 -199.12838)
		(end 303.022 -200.2028)
		(width 0.127)
		(layer "In5.Cu")
		(net "BMC_USB2_HDP")
	)
	(segment
		(start 319.151 -182.372)
		(end 316.627002 -182.372)
		(width 0.127)
		(layer "In5.Cu")
		(net "BMC_USB2_HDP")
	)
	(segment
		(start 311.404 -191.14897)
		(end 303.424844 -199.128126)
		(width 0.127)
		(layer "In5.Cu")
		(net "BMC_USB2_HDP")
	)
	(segment
		(start 283.286708 -195.362068)
		(end 284.091888 -194.556888)
		(width 0.127)
		(layer "In5.Cu")
		(net "BMC_USB2_HDP")
	)
	(segment
		(start 282.702 -204.100176)
		(end 282.702 -196.7738)
		(width 0.127)
		(layer "In5.Cu")
		(net "BMC_USB2_HDP")
	)
	(segment
		(start 316.627002 -182.372)
		(end 311.404 -187.595002)
		(width 0.127)
		(layer "In5.Cu")
		(net "BMC_USB2_HDP")
	)
	(segment
		(start 297.40733 -207.0354)
		(end 285.90621 -207.0354)
		(width 0.127)
		(layer "In5.Cu")
		(net "BMC_USB2_HDP")
	)
	(segment
		(start 352.9584 -172.327824)
		(end 348.299024 -176.9872)
		(width 0.127)
		(layer "In5.Cu")
		(net "BMC_USB2_HDP")
	)
	(segment
		(start 351.536 -150.099776)
		(end 352.9584 -151.522176)
		(width 0.127)
		(layer "In5.Cu")
		(net "BMC_USB2_HDP")
	)
	(segment
		(start 303.424844 -199.128126)
		(end 303.424844 -199.12838)
		(width 0.127)
		(layer "In5.Cu")
		(net "BMC_USB2_HDP")
	)
	(segment
		(start 336.4738 -176.9872)
		(end 333.629 -179.832)
		(width 0.127)
		(layer "In5.Cu")
		(net "BMC_USB2_HDP")
	)
	(segment
		(start 352.9584 -151.522176)
		(end 352.9584 -172.327824)
		(width 0.127)
		(layer "In5.Cu")
		(net "BMC_USB2_HDP")
	)
	(segment
		(start 311.404 -187.595002)
		(end 311.404 -191.14897)
		(width 0.127)
		(layer "In5.Cu")
		(net "BMC_USB2_HDP")
	)
	(segment
		(start 303.022 -200.2028)
		(end 303.022 -201.600308)
		(width 0.127)
		(layer "In5.Cu")
		(net "BMC_USB2_HDP")
	)
	(segment
		(start 351.82429 -147.62353)
		(end 351.536 -147.91182)
		(width 0.127)
		(layer "In5.Cu")
		(net "BMC_USB2_HDP")
	)
	(segment
		(start 284.574488 -206.483712)
		(end 283.063188 -204.972412)
		(width 0.127)
		(layer "In5.Cu")
		(net "BMC_USB2_HDP")
	)
	(segment
		(start 351.536 -147.91182)
		(end 351.536 -150.099776)
		(width 0.127)
		(layer "In5.Cu")
		(net "BMC_USB2_HDP")
	)
	(segment
		(start 284.739588 -185.425588)
		(end 284.607 -185.293)
		(width 0.127)
		(layer "In5.Cu")
		(net "BMC_USB2_HDP")
	)
	(segment
		(start 302.419512 -203.054712)
		(end 299.168312 -206.305912)
		(width 0.127)
		(layer "In5.Cu")
		(net "BMC_USB2_HDP")
	)
	(segment
		(start 284.676088 -186.352688)
		(end 284.803596 -186.22518)
		(width 0.127)
		(layer "In5.Cu")
		(net "BMC_USB2_HDP")
	)
	(segment
		(start 333.629 -179.832)
		(end 321.691 -179.832)
		(width 0.127)
		(layer "In5.Cu")
		(net "BMC_USB2_HDP")
	)
	(segment
		(start 348.299024 -176.9872)
		(end 336.4738 -176.9872)
		(width 0.127)
		(layer "In5.Cu")
		(net "BMC_USB2_HDP")
	)
	(segment
		(start 284.4546 -193.68135)
		(end 284.4546 -186.887612)
		(width 0.127)
		(layer "In5.Cu")
		(net "BMC_USB2_HDP")
	)
	(arc
		(start 284.9372 -185.9026)
		(mid 284.885847 -185.644433)
		(end 284.739588 -185.425588)
		(width 0.127)
		(layer "In5.Cu")
		(net "BMC_USB2_HDP")
	)
	(arc
		(start 284.803596 -186.22518)
		(mid 284.902487 -186.077179)
		(end 284.9372 -185.9026)
		(width 0.127)
		(layer "In5.Cu")
		(net "BMC_USB2_HDP")
	)
	(arc
		(start 299.168312 -206.305912)
		(mid 298.360367 -206.845793)
		(end 297.40733 -207.0354)
		(width 0.127)
		(layer "In5.Cu")
		(net "BMC_USB2_HDP")
	)
	(arc
		(start 284.091888 -194.556888)
		(mid 284.360296 -194.155188)
		(end 284.4546 -193.68135)
		(width 0.127)
		(layer "In5.Cu")
		(net "BMC_USB2_HDP")
	)
	(arc
		(start 284.4546 -186.887612)
		(mid 284.512178 -186.598146)
		(end 284.676088 -186.352688)
		(width 0.127)
		(layer "In5.Cu")
		(net "BMC_USB2_HDP")
	)
	(arc
		(start 303.022 -201.600308)
		(mid 302.86536 -202.387407)
		(end 302.419512 -203.054712)
		(width 0.127)
		(layer "In5.Cu")
		(net "BMC_USB2_HDP")
	)
	(arc
		(start 285.90621 -207.0354)
		(mid 285.1855 -206.891966)
		(end 284.574488 -206.483712)
		(width 0.127)
		(layer "In5.Cu")
		(net "BMC_USB2_HDP")
	)
	(arc
		(start 282.702 -196.7738)
		(mid 282.853955 -196.009781)
		(end 283.286708 -195.362068)
		(width 0.127)
		(layer "In5.Cu")
		(net "BMC_USB2_HDP")
	)
	(arc
		(start 283.063188 -204.972412)
		(mid 282.795876 -204.572212)
		(end 282.702 -204.100176)
		(width 0.127)
		(layer "In5.Cu")
		(net "BMC_USB2_HDP")
	)
	(segment
		(start 347.946218 -149.837648)
		(end 347.832934 -149.724364)
		(width 0.1397)
		(layer "F.Cu")
		(net "USB_P2_DP")
	)
	(segment
		(start 346.024962 -149.767544)
		(end 345.953588 -149.838918)
		(width 0.1397)
		(layer "F.Cu")
		(net "USB_P2_DP")
	)
	(segment
		(start 347.323918 -149.513544)
		(end 346.638118 -149.513544)
		(width 0.1397)
		(layer "F.Cu")
		(net "USB_P2_DP")
	)
	(segment
		(start 345.017852 -150.226522)
		(end 344.402918 -150.226522)
		(width 0.1397)
		(layer "F.Cu")
		(net "USB_P2_DP")
	)
	(arc
		(start 346.638118 -149.513544)
		(mid 346.306272 -149.579552)
		(end 346.024962 -149.767544)
		(width 0.1397)
		(layer "F.Cu")
		(net "USB_P2_DP")
	)
	(arc
		(start 345.953588 -149.838918)
		(mid 345.524269 -150.12578)
		(end 345.017852 -150.226522)
		(width 0.1397)
		(layer "F.Cu")
		(net "USB_P2_DP")
	)
	(arc
		(start 347.832934 -149.724364)
		(mid 347.599395 -149.568319)
		(end 347.323918 -149.513544)
		(width 0.1397)
		(layer "F.Cu")
		(net "USB_P2_DP")
	)
	(segment
		(start 347.271594 -152.149048)
		(end 346.797884 -152.149048)
		(width 0.1397)
		(layer "F.Cu")
		(net "USB_P3_DN")
	)
	(segment
		(start 346.162376 -151.68499)
		(end 345.888056 -151.410416)
		(width 0.1397)
		(layer "F.Cu")
		(net "USB_P3_DN")
	)
	(segment
		(start 346.505276 -152.02789)
		(end 346.162376 -151.68499)
		(width 0.1397)
		(layer "F.Cu")
		(net "USB_P3_DN")
	)
	(segment
		(start 345.444318 -151.226774)
		(end 344.402918 -151.226774)
		(width 0.1397)
		(layer "F.Cu")
		(net "USB_P3_DN")
	)
	(arc
		(start 347.946218 -151.869648)
		(mid 347.636698 -152.076463)
		(end 347.271594 -152.149048)
		(width 0.1397)
		(layer "F.Cu")
		(net "USB_P3_DN")
	)
	(arc
		(start 345.888056 -151.410416)
		(mid 345.684452 -151.274465)
		(end 345.444318 -151.226774)
		(width 0.1397)
		(layer "F.Cu")
		(net "USB_P3_DN")
	)
	(arc
		(start 346.797884 -152.149048)
		(mid 346.639543 -152.117552)
		(end 346.505276 -152.02789)
		(width 0.1397)
		(layer "F.Cu")
		(net "USB_P3_DN")
	)
	(segment
		(start 345.326716 -151.726646)
		(end 344.402918 -151.726646)
		(width 0.1397)
		(layer "F.Cu")
		(net "USB_P3_DP")
	)
	(segment
		(start 346.262706 -152.27046)
		(end 345.995752 -152.00376)
		(width 0.1397)
		(layer "F.Cu")
		(net "USB_P3_DP")
	)
	(segment
		(start 347.946218 -153.012648)
		(end 347.53423 -152.600914)
		(width 0.1397)
		(layer "F.Cu")
		(net "USB_P3_DP")
	)
	(segment
		(start 347.271594 -152.491948)
		(end 346.798138 -152.491948)
		(width 0.1397)
		(layer "F.Cu")
		(net "USB_P3_DP")
	)
	(arc
		(start 346.798138 -152.491948)
		(mid 346.508384 -152.434482)
		(end 346.262706 -152.27046)
		(width 0.1397)
		(layer "F.Cu")
		(net "USB_P3_DP")
	)
	(arc
		(start 347.53423 -152.600914)
		(mid 347.413747 -152.520317)
		(end 347.271594 -152.491948)
		(width 0.1397)
		(layer "F.Cu")
		(net "USB_P3_DP")
	)
	(arc
		(start 345.995752 -152.00376)
		(mid 345.688796 -151.798658)
		(end 345.326716 -151.726646)
		(width 0.1397)
		(layer "F.Cu")
		(net "USB_P3_DP")
	)
	(segment
		(start 345.295474 -149.72665)
		(end 344.402918 -149.72665)
		(width 0.1397)
		(layer "F.Cu")
		(net "USB_P2_DN")
	)
	(segment
		(start 347.196918 -149.170644)
		(end 346.638118 -149.170644)
		(width 0.1397)
		(layer "F.Cu")
		(net "USB_P2_DN")
	)
	(segment
		(start 347.946218 -148.694648)
		(end 347.663516 -148.97735)
		(width 0.1397)
		(layer "F.Cu")
		(net "USB_P2_DN")
	)
	(arc
		(start 346.638118 -149.170644)
		(mid 346.174996 -149.262671)
		(end 345.782392 -149.524974)
		(width 0.1397)
		(layer "F.Cu")
		(net "USB_P2_DN")
	)
	(arc
		(start 347.663516 -148.97735)
		(mid 347.449439 -149.120392)
		(end 347.196918 -149.170644)
		(width 0.1397)
		(layer "F.Cu")
		(net "USB_P2_DN")
	)
	(arc
		(start 345.782392 -149.524974)
		(mid 345.558992 -149.674245)
		(end 345.295474 -149.72665)
		(width 0.1397)
		(layer "F.Cu")
		(net "USB_P2_DN")
	)
	(segment
		(start 272.18767 -14.10081)
		(end 275.749004 -17.662144)
		(width 0.1397)
		(layer "F.Cu")
		(net "USB_P1_F_DN1")
	)
	(segment
		(start 276.5552 -17.9959)
		(end 277.44674 -17.9959)
		(width 0.1397)
		(layer "F.Cu")
		(net "USB_P1_F_DN1")
	)
	(segment
		(start 276.9997 -23.9903)
		(end 277.3045 -23.6855)
		(width 0.1397)
		(layer "F.Cu")
		(net "USB_P1_F_DN1")
	)
	(segment
		(start 271.828514 -11.34999)
		(end 271.828514 -13.2334)
		(width 0.1397)
		(layer "F.Cu")
		(net "USB_P1_F_DN1")
	)
	(segment
		(start 277.3045 -23.6855)
		(end 277.4696 -23.5204)
		(width 0.1016)
		(layer "F.Cu")
		(net "USB_P1_F_DN1")
	)
	(segment
		(start 277.9395 -18.811748)
		(end 277.9395 -20.2438)
		(width 0.1397)
		(layer "F.Cu")
		(net "USB_P1_F_DN1")
	)
	(segment
		(start 276.875494 -24.953468)
		(end 276.875494 -24.290274)
		(width 0.1397)
		(layer "F.Cu")
		(net "USB_P1_F_DN1")
	)
	(segment
		(start 277.939246 -18.812002)
		(end 277.9395 -18.811748)
		(width 0.1397)
		(layer "F.Cu")
		(net "USB_P1_F_DN1")
	)
	(segment
		(start 277.4696 -22.2758)
		(end 277.4696 -21.944838)
		(width 0.1397)
		(layer "F.Cu")
		(net "USB_P1_F_DN1")
	)
	(segment
		(start 277.9395 -21.132038)
		(end 277.9395 -20.2438)
		(width 0.1397)
		(layer "F.Cu")
		(net "USB_P1_F_DN1")
	)
	(segment
		(start 277.82393 -21.41093)
		(end 277.82393 -21.410676)
		(width 0.1397)
		(layer "F.Cu")
		(net "USB_P1_F_DN1")
	)
	(segment
		(start 270.999966 -10.989818)
		(end 271.560798 -10.989818)
		(width 0.1397)
		(layer "F.Cu")
		(net "USB_P1_F_DN1")
	)
	(segment
		(start 277.4696 -23.5204)
		(end 277.4696 -22.2758)
		(width 0.1016)
		(layer "F.Cu")
		(net "USB_P1_F_DN1")
	)
	(segment
		(start 277.5966 -21.63826)
		(end 277.82393 -21.41093)
		(width 0.1397)
		(layer "F.Cu")
		(net "USB_P1_F_DN1")
	)
	(arc
		(start 271.828514 -13.2334)
		(mid 271.921798 -13.70284)
		(end 272.18767 -14.10081)
		(width 0.1397)
		(layer "F.Cu")
		(net "USB_P1_F_DN1")
	)
	(arc
		(start 277.63343 -18.07337)
		(mid 277.859784 -18.412272)
		(end 277.939246 -18.812002)
		(width 0.1397)
		(layer "F.Cu")
		(net "USB_P1_F_DN1")
	)
	(arc
		(start 276.875494 -24.290274)
		(mid 276.907783 -24.127947)
		(end 276.9997 -23.9903)
		(width 0.1397)
		(layer "F.Cu")
		(net "USB_P1_F_DN1")
	)
	(arc
		(start 271.560798 -10.989818)
		(mid 271.63817 -11.005208)
		(end 271.7038 -11.049)
		(width 0.1397)
		(layer "F.Cu")
		(net "USB_P1_F_DN1")
	)
	(arc
		(start 277.82393 -21.410676)
		(mid 277.909433 -21.282851)
		(end 277.9395 -21.132038)
		(width 0.1397)
		(layer "F.Cu")
		(net "USB_P1_F_DN1")
	)
	(arc
		(start 277.4696 -21.944838)
		(mid 277.502604 -21.778915)
		(end 277.5966 -21.63826)
		(width 0.1397)
		(layer "F.Cu")
		(net "USB_P1_F_DN1")
	)
	(arc
		(start 271.7038 -11.049)
		(mid 271.796072 -11.187095)
		(end 271.828514 -11.34999)
		(width 0.1397)
		(layer "F.Cu")
		(net "USB_P1_F_DN1")
	)
	(arc
		(start 275.749004 -17.662144)
		(mid 276.118919 -17.909157)
		(end 276.5552 -17.9959)
		(width 0.1397)
		(layer "F.Cu")
		(net "USB_P1_F_DN1")
	)
	(arc
		(start 277.44674 -17.9959)
		(mid 277.547776 -18.016091)
		(end 277.63343 -18.07337)
		(width 0.1397)
		(layer "F.Cu")
		(net "USB_P1_F_DN1")
	)
	(segment
		(start 278.511 -19.737578)
		(end 278.511 -21.2598)
		(width 0.1397)
		(layer "F.Cu")
		(net "USB_P1_F_DP1")
	)
	(segment
		(start 272.999962 -10.989818)
		(end 272.589498 -10.989818)
		(width 0.1397)
		(layer "F.Cu")
		(net "USB_P1_F_DP1")
	)
	(segment
		(start 277.840694 -24.953468)
		(end 277.840694 -23.174706)
		(width 0.1397)
		(layer "F.Cu")
		(net "USB_P1_F_DP1")
	)
	(segment
		(start 276.5552 -17.653)
		(end 277.44674 -17.653)
		(width 0.1397)
		(layer "F.Cu")
		(net "USB_P1_F_DP1")
	)
	(segment
		(start 278.2824 -18.812002)
		(end 278.2824 -19.185636)
		(width 0.1397)
		(layer "F.Cu")
		(net "USB_P1_F_DP1")
	)
	(segment
		(start 272.171414 -11.345418)
		(end 272.171414 -13.2334)
		(width 0.1397)
		(layer "F.Cu")
		(net "USB_P1_F_DP1")
	)
	(segment
		(start 278.271732 -21.448014)
		(end 278.0665 -21.6535)
		(width 0.1397)
		(layer "F.Cu")
		(net "USB_P1_F_DP1")
	)
	(segment
		(start 272.43024 -13.85824)
		(end 275.991574 -17.419574)
		(width 0.1397)
		(layer "F.Cu")
		(net "USB_P1_F_DP1")
	)
	(segment
		(start 277.9395 -21.960078)
		(end 277.9395 -22.9362)
		(width 0.1397)
		(layer "F.Cu")
		(net "USB_P1_F_DP1")
	)
	(arc
		(start 277.876 -17.8308)
		(mid 278.1768 -18.280979)
		(end 278.2824 -18.812002)
		(width 0.1397)
		(layer "F.Cu")
		(net "USB_P1_F_DP1")
	)
	(arc
		(start 272.589498 -10.989818)
		(mid 272.412591 -11.025007)
		(end 272.2626 -11.1252)
		(width 0.1397)
		(layer "F.Cu")
		(net "USB_P1_F_DP1")
	)
	(arc
		(start 277.44674 -17.653)
		(mid 277.679052 -17.69921)
		(end 277.876 -17.8308)
		(width 0.1397)
		(layer "F.Cu")
		(net "USB_P1_F_DP1")
	)
	(arc
		(start 277.840694 -23.174706)
		(mid 277.86637 -23.045622)
		(end 277.9395 -22.9362)
		(width 0.1397)
		(layer "F.Cu")
		(net "USB_P1_F_DP1")
	)
	(arc
		(start 278.384 -19.431)
		(mid 278.477985 -19.571659)
		(end 278.511 -19.737578)
		(width 0.1397)
		(layer "F.Cu")
		(net "USB_P1_F_DP1")
	)
	(arc
		(start 278.511 -21.2598)
		(mid 278.466363 -21.367563)
		(end 278.3586 -21.4122)
		(width 0.1397)
		(layer "F.Cu")
		(net "USB_P1_F_DP1")
	)
	(arc
		(start 272.2626 -11.1252)
		(mid 272.195089 -11.226237)
		(end 272.171414 -11.345418)
		(width 0.1397)
		(layer "F.Cu")
		(net "USB_P1_F_DP1")
	)
	(arc
		(start 278.3586 -21.4122)
		(mid 278.311598 -21.421456)
		(end 278.271732 -21.448014)
		(width 0.1397)
		(layer "F.Cu")
		(net "USB_P1_F_DP1")
	)
	(arc
		(start 278.0665 -21.6535)
		(mid 277.972515 -21.794159)
		(end 277.9395 -21.960078)
		(width 0.1397)
		(layer "F.Cu")
		(net "USB_P1_F_DP1")
	)
	(arc
		(start 278.2824 -19.185636)
		(mid 278.308811 -19.318413)
		(end 278.384 -19.431)
		(width 0.1397)
		(layer "F.Cu")
		(net "USB_P1_F_DP1")
	)
	(arc
		(start 272.171414 -13.2334)
		(mid 272.238679 -13.571564)
		(end 272.43024 -13.85824)
		(width 0.1397)
		(layer "F.Cu")
		(net "USB_P1_F_DP1")
	)
	(arc
		(start 275.991574 -17.419574)
		(mid 276.250168 -17.592361)
		(end 276.5552 -17.653)
		(width 0.1397)
		(layer "F.Cu")
		(net "USB_P1_F_DP1")
	)
	(segment
		(start 349.631 -143.82496)
		(end 349.631 -141.964664)
		(width 0.1397)
		(layer "F.Cu")
		(net "USB_P1_DN")
	)
	(segment
		(start 347.07322 -146.652488)
		(end 347.369384 -146.35607)
		(width 0.1397)
		(layer "F.Cu")
		(net "USB_P1_DN")
	)
	(segment
		(start 346.634816 -147.374356)
		(end 346.931234 -147.078192)
		(width 0.1397)
		(layer "F.Cu")
		(net "USB_P1_DN")
	)
	(segment
		(start 348.95536 -145.054066)
		(end 349.239586 -144.76984)
		(width 0.1397)
		(layer "F.Cu")
		(net "USB_P1_DN")
	)
	(segment
		(start 347.795088 -146.214084)
		(end 348.091506 -145.91792)
		(width 0.1397)
		(layer "F.Cu")
		(net "USB_P1_DN")
	)
	(segment
		(start 349.631 -137.461244)
		(end 349.631 -137.042144)
		(width 0.1397)
		(layer "F.Cu")
		(net "USB_P1_DN")
	)
	(segment
		(start 349.43034 -138.281664)
		(end 349.43034 -137.862564)
		(width 0.1397)
		(layer "F.Cu")
		(net "USB_P1_DN")
	)
	(segment
		(start 343.3826 -135.4074)
		(end 343.5096 -135.5344)
		(width 0.1397)
		(layer "F.Cu")
		(net "USB_P1_DN")
	)
	(segment
		(start 347.599 -134.6073)
		(end 343.781126 -134.6073)
		(width 0.1397)
		(layer "F.Cu")
		(net "USB_P1_DN")
	)
	(segment
		(start 349.631 -139.102084)
		(end 349.631 -138.682984)
		(width 0.1397)
		(layer "F.Cu")
		(net "USB_P1_DN")
	)
	(segment
		(start 348.996 -135.509)
		(end 348.444566 -134.957566)
		(width 0.1397)
		(layer "F.Cu")
		(net "USB_P1_DN")
	)
	(segment
		(start 349.43034 -141.563344)
		(end 349.43034 -141.144244)
		(width 0.1397)
		(layer "F.Cu")
		(net "USB_P1_DN")
	)
	(segment
		(start 345.474544 -148.534628)
		(end 345.770962 -148.23821)
		(width 0.1397)
		(layer "F.Cu")
		(net "USB_P1_DN")
	)
	(segment
		(start 349.631 -140.742924)
		(end 349.631 -140.323824)
		(width 0.1397)
		(layer "F.Cu")
		(net "USB_P1_DN")
	)
	(segment
		(start 345.912694 -147.812506)
		(end 346.209112 -147.516342)
		(width 0.1397)
		(layer "F.Cu")
		(net "USB_P1_DN")
	)
	(segment
		(start 344.491818 -148.726652)
		(end 345.010994 -148.726652)
		(width 0.1397)
		(layer "F.Cu")
		(net "USB_P1_DN")
	)
	(segment
		(start 349.43034 -139.922504)
		(end 349.43034 -139.503404)
		(width 0.1397)
		(layer "F.Cu")
		(net "USB_P1_DN")
	)
	(segment
		(start 348.233492 -145.492216)
		(end 348.529656 -145.195798)
		(width 0.1397)
		(layer "F.Cu")
		(net "USB_P1_DN")
	)
	(via
		(at 343.5096 -135.5344)
		(size 0.508)
		(drill 0.254)
		(layers "F.Cu" "B.Cu")
		(net "USB_P1_DN")
	)
	(arc
		(start 349.631 -138.682984)
		(mid 349.604476 -138.570827)
		(end 349.53067 -138.482324)
		(width 0.1397)
		(layer "F.Cu")
		(net "USB_P1_DN")
	)
	(arc
		(start 347.369384 -146.35607)
		(mid 347.467466 -146.295563)
		(end 347.582236 -146.285204)
		(width 0.1397)
		(layer "F.Cu")
		(net "USB_P1_DN")
	)
	(arc
		(start 346.421964 -147.445476)
		(mid 346.536747 -147.434952)
		(end 346.634816 -147.374356)
		(width 0.1397)
		(layer "F.Cu")
		(net "USB_P1_DN")
	)
	(arc
		(start 349.631 -137.042144)
		(mid 349.46596 -136.212431)
		(end 348.996 -135.509)
		(width 0.1397)
		(layer "F.Cu")
		(net "USB_P1_DN")
	)
	(arc
		(start 349.53067 -138.482324)
		(mid 349.45691 -138.393798)
		(end 349.43034 -138.281664)
		(width 0.1397)
		(layer "F.Cu")
		(net "USB_P1_DN")
	)
	(arc
		(start 349.43034 -139.503404)
		(mid 349.456864 -139.391247)
		(end 349.53067 -139.302744)
		(width 0.1397)
		(layer "F.Cu")
		(net "USB_P1_DN")
	)
	(arc
		(start 349.631 -141.964664)
		(mid 349.604476 -141.852507)
		(end 349.53067 -141.764004)
		(width 0.1397)
		(layer "F.Cu")
		(net "USB_P1_DN")
	)
	(arc
		(start 349.43034 -137.862564)
		(mid 349.456864 -137.750407)
		(end 349.53067 -137.661904)
		(width 0.1397)
		(layer "F.Cu")
		(net "USB_P1_DN")
	)
	(arc
		(start 347.582236 -146.285204)
		(mid 347.697019 -146.27468)
		(end 347.795088 -146.214084)
		(width 0.1397)
		(layer "F.Cu")
		(net "USB_P1_DN")
	)
	(arc
		(start 349.53067 -137.661904)
		(mid 349.60443 -137.573378)
		(end 349.631 -137.461244)
		(width 0.1397)
		(layer "F.Cu")
		(net "USB_P1_DN")
	)
	(arc
		(start 349.53067 -139.302744)
		(mid 349.60443 -139.214218)
		(end 349.631 -139.102084)
		(width 0.1397)
		(layer "F.Cu")
		(net "USB_P1_DN")
	)
	(arc
		(start 345.841828 -148.025358)
		(mid 345.852214 -147.910589)
		(end 345.912694 -147.812506)
		(width 0.1397)
		(layer "F.Cu")
		(net "USB_P1_DN")
	)
	(arc
		(start 348.742508 -145.124932)
		(mid 348.857266 -145.114539)
		(end 348.95536 -145.054066)
		(width 0.1397)
		(layer "F.Cu")
		(net "USB_P1_DN")
	)
	(arc
		(start 349.239586 -144.76984)
		(mid 349.529251 -144.336325)
		(end 349.631 -143.82496)
		(width 0.1397)
		(layer "F.Cu")
		(net "USB_P1_DN")
	)
	(arc
		(start 349.53067 -141.764004)
		(mid 349.45691 -141.675478)
		(end 349.43034 -141.563344)
		(width 0.1397)
		(layer "F.Cu")
		(net "USB_P1_DN")
	)
	(arc
		(start 343.3826 -134.7724)
		(mid 343.251087 -135.0899)
		(end 343.3826 -135.4074)
		(width 0.1397)
		(layer "F.Cu")
		(net "USB_P1_DN")
	)
	(arc
		(start 348.529656 -145.195798)
		(mid 348.627738 -145.135291)
		(end 348.742508 -145.124932)
		(width 0.1397)
		(layer "F.Cu")
		(net "USB_P1_DN")
	)
	(arc
		(start 349.43034 -141.144244)
		(mid 349.456864 -141.032087)
		(end 349.53067 -140.943584)
		(width 0.1397)
		(layer "F.Cu")
		(net "USB_P1_DN")
	)
	(arc
		(start 349.53067 -140.943584)
		(mid 349.60443 -140.855058)
		(end 349.631 -140.742924)
		(width 0.1397)
		(layer "F.Cu")
		(net "USB_P1_DN")
	)
	(arc
		(start 348.162372 -145.705068)
		(mid 348.172896 -145.590285)
		(end 348.233492 -145.492216)
		(width 0.1397)
		(layer "F.Cu")
		(net "USB_P1_DN")
	)
	(arc
		(start 347.0021 -146.86534)
		(mid 347.012624 -146.750557)
		(end 347.07322 -146.652488)
		(width 0.1397)
		(layer "F.Cu")
		(net "USB_P1_DN")
	)
	(arc
		(start 346.209112 -147.516342)
		(mid 346.307194 -147.455835)
		(end 346.421964 -147.445476)
		(width 0.1397)
		(layer "F.Cu")
		(net "USB_P1_DN")
	)
	(arc
		(start 348.444566 -134.957566)
		(mid 348.056617 -134.698347)
		(end 347.599 -134.6073)
		(width 0.1397)
		(layer "F.Cu")
		(net "USB_P1_DN")
	)
	(arc
		(start 348.091506 -145.91792)
		(mid 348.152013 -145.819838)
		(end 348.162372 -145.705068)
		(width 0.1397)
		(layer "F.Cu")
		(net "USB_P1_DN")
	)
	(arc
		(start 343.781126 -134.6073)
		(mid 343.565436 -134.650203)
		(end 343.3826 -134.7724)
		(width 0.1397)
		(layer "F.Cu")
		(net "USB_P1_DN")
	)
	(arc
		(start 346.931234 -147.078192)
		(mid 346.991741 -146.98011)
		(end 347.0021 -146.86534)
		(width 0.1397)
		(layer "F.Cu")
		(net "USB_P1_DN")
	)
	(arc
		(start 345.770962 -148.23821)
		(mid 345.831469 -148.140128)
		(end 345.841828 -148.025358)
		(width 0.1397)
		(layer "F.Cu")
		(net "USB_P1_DN")
	)
	(arc
		(start 345.010994 -148.726652)
		(mid 345.261871 -148.676749)
		(end 345.474544 -148.534628)
		(width 0.1397)
		(layer "F.Cu")
		(net "USB_P1_DN")
	)
	(arc
		(start 349.53067 -140.123164)
		(mid 349.45691 -140.034638)
		(end 349.43034 -139.922504)
		(width 0.1397)
		(layer "F.Cu")
		(net "USB_P1_DN")
	)
	(arc
		(start 349.631 -140.323824)
		(mid 349.604476 -140.211667)
		(end 349.53067 -140.123164)
		(width 0.1397)
		(layer "F.Cu")
		(net "USB_P1_DN")
	)
	(segment
		(start 342.269318 -135.385048)
		(end 343.360248 -135.385048)
		(width 0.1397)
		(layer "B.Cu")
		(net "USB_P1_DN")
	)
	(segment
		(start 343.360248 -135.385048)
		(end 343.5096 -135.5344)
		(width 0.1397)
		(layer "B.Cu")
		(net "USB_P1_DN")
	)
	(segment
		(start 342.54313 -138.6332)
		(end 342.54313 -139.483592)
		(width 0.1143)
		(layer "F.Cu")
		(net "USB_HUB_XTAL_IN")
	)
	(segment
		(start 342.54313 -139.483592)
		(end 341.82558 -140.201142)
		(width 0.1143)
		(layer "F.Cu")
		(net "USB_HUB_XTAL_IN")
	)
	(segment
		(start 342.032844 -146.409156)
		(end 342.519 -145.923)
		(width 0.1143)
		(layer "F.Cu")
		(net "USB_HUB_XTAL_IN")
	)
	(segment
		(start 342.231218 -144.122648)
		(end 342.231218 -143.043148)
		(width 0.1143)
		(layer "F.Cu")
		(net "USB_HUB_XTAL_IN")
	)
	(segment
		(start 342.231218 -143.043148)
		(end 342.421718 -142.852648)
		(width 0.1143)
		(layer "F.Cu")
		(net "USB_HUB_XTAL_IN")
	)
	(segment
		(start 342.519 -144.41043)
		(end 342.231218 -144.122648)
		(width 0.1143)
		(layer "F.Cu")
		(net "USB_HUB_XTAL_IN")
	)
	(segment
		(start 341.82558 -141.87551)
		(end 342.421718 -142.471648)
		(width 0.1143)
		(layer "F.Cu")
		(net "USB_HUB_XTAL_IN")
	)
	(segment
		(start 341.82558 -140.201142)
		(end 341.82558 -141.87551)
		(width 0.1143)
		(layer "F.Cu")
		(net "USB_HUB_XTAL_IN")
	)
	(segment
		(start 342.519 -145.923)
		(end 342.519 -144.41043)
		(width 0.1143)
		(layer "F.Cu")
		(net "USB_HUB_XTAL_IN")
	)
	(segment
		(start 342.421718 -142.471648)
		(end 342.421718 -142.852648)
		(width 0.1143)
		(layer "F.Cu")
		(net "USB_HUB_XTAL_IN")
	)
	(segment
		(start 342.032844 -147.856448)
		(end 342.032844 -146.409156)
		(width 0.1143)
		(layer "F.Cu")
		(net "USB_HUB_XTAL_IN")
	)
	(via
		(at 342.519 -145.923)
		(size 0.7112)
		(drill 0.3556)
		(layers "F.Cu" "B.Cu")
		(net "USB_HUB_XTAL_IN")
	)
	(segment
		(start 341.342218 -144.122648)
		(end 341.342218 -145.0848)
		(width 0.1143)
		(layer "F.Cu")
		(net "USB_HUB_XTAL_OUT")
	)
	(segment
		(start 341.342218 -145.0848)
		(end 341.342218 -145.508218)
		(width 0.1143)
		(layer "F.Cu")
		(net "USB_HUB_XTAL_OUT")
	)
	(segment
		(start 341.342218 -143.170148)
		(end 341.024718 -142.852648)
		(width 0.1143)
		(layer "F.Cu")
		(net "USB_HUB_XTAL_OUT")
	)
	(segment
		(start 341.342218 -144.122648)
		(end 341.342218 -143.170148)
		(width 0.1143)
		(layer "F.Cu")
		(net "USB_HUB_XTAL_OUT")
	)
	(segment
		(start 341.030306 -142.84706)
		(end 341.024718 -142.852648)
		(width 0.1143)
		(layer "F.Cu")
		(net "USB_HUB_XTAL_OUT")
	)
	(segment
		(start 341.342218 -145.508218)
		(end 341.532718 -145.698718)
		(width 0.1143)
		(layer "F.Cu")
		(net "USB_HUB_XTAL_OUT")
	)
	(segment
		(start 341.532718 -145.698718)
		(end 341.532718 -147.856448)
		(width 0.1143)
		(layer "F.Cu")
		(net "USB_HUB_XTAL_OUT")
	)
	(segment
		(start 341.030306 -140.976096)
		(end 341.030306 -142.84706)
		(width 0.1143)
		(layer "F.Cu")
		(net "USB_HUB_XTAL_OUT")
	)
	(via
		(at 341.342218 -145.0848)
		(size 0.7112)
		(drill 0.3556)
		(layers "F.Cu" "B.Cu")
		(net "USB_HUB_XTAL_OUT")
	)
	(segment
		(start 81.026762 -22.733)
		(end 81.027524 -22.733762)
		(width 0.254)
		(layer "F.Cu")
		(net "PG_STAT_P0V955_C")
	)
	(segment
		(start 81.102962 -22.6568)
		(end 81.026762 -22.733)
		(width 0.254)
		(layer "F.Cu")
		(net "PG_STAT_P0V955_C")
	)
	(segment
		(start 261.42315 -102.68585)
		(end 261.42315 -121.677684)
		(width 0.254)
		(layer "F.Cu")
		(net "PG_STAT_P0V955_C")
	)
	(segment
		(start 262.61695 -122.871484)
		(end 262.61695 -144.723612)
		(width 0.254)
		(layer "F.Cu")
		(net "PG_STAT_P0V955_C")
	)
	(segment
		(start 81.027524 -22.733762)
		(end 81.104486 -22.733762)
		(width 0.254)
		(layer "F.Cu")
		(net "PG_STAT_P0V955_C")
	)
	(segment
		(start 261.62 -102.489)
		(end 261.42315 -102.68585)
		(width 0.254)
		(layer "F.Cu")
		(net "PG_STAT_P0V955_C")
	)
	(segment
		(start 264.725404 -146.832066)
		(end 264.725404 -159.028892)
		(width 0.254)
		(layer "F.Cu")
		(net "PG_STAT_P0V955_C")
	)
	(segment
		(start 261.42315 -121.677684)
		(end 262.61695 -122.871484)
		(width 0.254)
		(layer "F.Cu")
		(net "PG_STAT_P0V955_C")
	)
	(segment
		(start 273.747992 -166.624)
		(end 273.7485 -166.624)
		(width 0.254)
		(layer "F.Cu")
		(net "PG_STAT_P0V955_C")
	)
	(segment
		(start 82.034126 -21.851874)
		(end 81.2292 -22.6568)
		(width 0.254)
		(layer "F.Cu")
		(net "PG_STAT_P0V955_C")
	)
	(segment
		(start 272.307812 -166.6113)
		(end 273.689572 -166.6113)
		(width 0.254)
		(layer "F.Cu")
		(net "PG_STAT_P0V955_C")
	)
	(segment
		(start 82.034126 -21.255228)
		(end 82.034126 -21.851874)
		(width 0.254)
		(layer "F.Cu")
		(net "PG_STAT_P0V955_C")
	)
	(segment
		(start 262.61695 -144.723612)
		(end 264.725404 -146.832066)
		(width 0.254)
		(layer "F.Cu")
		(net "PG_STAT_P0V955_C")
	)
	(segment
		(start 81.2292 -22.6568)
		(end 81.102962 -22.6568)
		(width 0.254)
		(layer "F.Cu")
		(net "PG_STAT_P0V955_C")
	)
	(segment
		(start 273.689572 -166.6113)
		(end 273.747992 -166.624)
		(width 0.254)
		(layer "F.Cu")
		(net "PG_STAT_P0V955_C")
	)
	(segment
		(start 264.725404 -159.028892)
		(end 272.307812 -166.6113)
		(width 0.254)
		(layer "F.Cu")
		(net "PG_STAT_P0V955_C")
	)
	(via
		(at 80.415892 -23.241)
		(size 0.7112)
		(drill 0.3556)
		(layers "F.Cu" "B.Cu")
		(net "PG_STAT_P0V955_C")
	)
	(via
		(at 81.104486 -22.733762)
		(size 0.5588)
		(drill 0.3048)
		(layers "F.Cu" "B.Cu")
		(net "PG_STAT_P0V955_C")
	)
	(via
		(at 247.523 -47.879)
		(size 0.508)
		(drill 0.254)
		(layers "F.Cu" "B.Cu")
		(net "PG_STAT_P0V955_C")
	)
	(via
		(at 261.62 -102.489)
		(size 0.5588)
		(drill 0.3048)
		(layers "F.Cu" "B.Cu")
		(net "PG_STAT_P0V955_C")
	)
	(segment
		(start 79.690976 -22.6695)
		(end 79.502 -22.6695)
		(width 0.254)
		(layer "B.Cu")
		(net "PG_STAT_P0V955_C")
	)
	(segment
		(start 80.415892 -23.241)
		(end 80.262476 -23.241)
		(width 0.254)
		(layer "B.Cu")
		(net "PG_STAT_P0V955_C")
	)
	(segment
		(start 80.772 -23.241)
		(end 81.104486 -22.908514)
		(width 0.254)
		(layer "B.Cu")
		(net "PG_STAT_P0V955_C")
	)
	(segment
		(start 79.502 -22.6695)
		(end 78.70825 -22.6695)
		(width 0.254)
		(layer "B.Cu")
		(net "PG_STAT_P0V955_C")
	)
	(segment
		(start 78.70825 -22.6695)
		(end 78.0415 -23.33625)
		(width 0.254)
		(layer "B.Cu")
		(net "PG_STAT_P0V955_C")
	)
	(segment
		(start 81.104486 -22.908514)
		(end 81.104486 -22.733762)
		(width 0.254)
		(layer "B.Cu")
		(net "PG_STAT_P0V955_C")
	)
	(segment
		(start 80.415892 -23.241)
		(end 80.772 -23.241)
		(width 0.254)
		(layer "B.Cu")
		(net "PG_STAT_P0V955_C")
	)
	(segment
		(start 80.262476 -23.241)
		(end 79.690976 -22.6695)
		(width 0.254)
		(layer "B.Cu")
		(net "PG_STAT_P0V955_C")
	)
	(segment
		(start 261.62 -102.489)
		(end 263.017 -101.092)
		(width 0.254)
		(layer "In2.Cu")
		(net "PG_STAT_P0V955_C")
	)
	(segment
		(start 263.017 -86.106)
		(end 247.004078 -70.093078)
		(width 0.254)
		(layer "In2.Cu")
		(net "PG_STAT_P0V955_C")
	)
	(segment
		(start 263.017 -101.092)
		(end 263.017 -86.106)
		(width 0.254)
		(layer "In2.Cu")
		(net "PG_STAT_P0V955_C")
	)
	(segment
		(start 247.004078 -70.093078)
		(end 247.004078 -48.397922)
		(width 0.254)
		(layer "In2.Cu")
		(net "PG_STAT_P0V955_C")
	)
	(segment
		(start 247.004078 -48.397922)
		(end 247.523 -47.879)
		(width 0.254)
		(layer "In2.Cu")
		(net "PG_STAT_P0V955_C")
	)
	(segment
		(start 81.104486 -22.733762)
		(end 81.104486 -22.344634)
		(width 0.254)
		(layer "In5.Cu")
		(net "PG_STAT_P0V955_C")
	)
	(segment
		(start 96.334326 -17.313148)
		(end 126.654306 -17.313148)
		(width 0.254)
		(layer "In5.Cu")
		(net "PG_STAT_P0V955_C")
	)
	(segment
		(start 145.447258 -36.1061)
		(end 174.62754 -36.1061)
		(width 0.254)
		(layer "In5.Cu")
		(net "PG_STAT_P0V955_C")
	)
	(segment
		(start 93.850206 -16.306546)
		(end 95.327724 -16.306546)
		(width 0.254)
		(layer "In5.Cu")
		(net "PG_STAT_P0V955_C")
	)
	(segment
		(start 203.735178 -37.592)
		(end 210.593178 -44.45)
		(width 0.254)
		(layer "In5.Cu")
		(net "PG_STAT_P0V955_C")
	)
	(segment
		(start 126.654306 -17.313148)
		(end 145.447258 -36.1061)
		(width 0.254)
		(layer "In5.Cu")
		(net "PG_STAT_P0V955_C")
	)
	(segment
		(start 81.104486 -22.344634)
		(end 87.82812 -15.621)
		(width 0.254)
		(layer "In5.Cu")
		(net "PG_STAT_P0V955_C")
	)
	(segment
		(start 210.593178 -44.45)
		(end 244.094 -44.45)
		(width 0.254)
		(layer "In5.Cu")
		(net "PG_STAT_P0V955_C")
	)
	(segment
		(start 95.327724 -16.306546)
		(end 96.334326 -17.313148)
		(width 0.254)
		(layer "In5.Cu")
		(net "PG_STAT_P0V955_C")
	)
	(segment
		(start 244.094 -44.45)
		(end 247.523 -47.879)
		(width 0.254)
		(layer "In5.Cu")
		(net "PG_STAT_P0V955_C")
	)
	(segment
		(start 93.16466 -15.621)
		(end 93.850206 -16.306546)
		(width 0.254)
		(layer "In5.Cu")
		(net "PG_STAT_P0V955_C")
	)
	(segment
		(start 87.82812 -15.621)
		(end 93.16466 -15.621)
		(width 0.254)
		(layer "In5.Cu")
		(net "PG_STAT_P0V955_C")
	)
	(segment
		(start 174.62754 -36.1061)
		(end 176.11344 -37.592)
		(width 0.254)
		(layer "In5.Cu")
		(net "PG_STAT_P0V955_C")
	)
	(segment
		(start 176.11344 -37.592)
		(end 203.735178 -37.592)
		(width 0.254)
		(layer "In5.Cu")
		(net "PG_STAT_P0V955_C")
	)
	(segment
		(start 346.104718 -143.805148)
		(end 346.104718 -145.392648)
		(width 0.1143)
		(layer "F.Cu")
		(net "RBIAS")
	)
	(segment
		(start 343.032842 -147.067524)
		(end 343.520268 -146.580098)
		(width 0.1143)
		(layer "F.Cu")
		(net "RBIAS")
	)
	(segment
		(start 343.520268 -146.580098)
		(end 344.917268 -146.580098)
		(width 0.1143)
		(layer "F.Cu")
		(net "RBIAS")
	)
	(segment
		(start 344.917268 -146.580098)
		(end 345.469718 -146.027648)
		(width 0.1143)
		(layer "F.Cu")
		(net "RBIAS")
	)
	(segment
		(start 346.104718 -145.392648)
		(end 345.469718 -146.027648)
		(width 0.1143)
		(layer "F.Cu")
		(net "RBIAS")
	)
	(segment
		(start 346.231718 -143.678148)
		(end 346.104718 -143.805148)
		(width 0.1143)
		(layer "F.Cu")
		(net "RBIAS")
	)
	(segment
		(start 343.032842 -147.856448)
		(end 343.032842 -147.067524)
		(width 0.1143)
		(layer "F.Cu")
		(net "RBIAS")
	)
	(via
		(at 345.469718 -146.027648)
		(size 0.7112)
		(drill 0.3556)
		(layers "F.Cu" "B.Cu")
		(net "RBIAS")
	)
	(segment
		(start 277.186644 -27.7622)
		(end 277.186644 -31.496)
		(width 0.1397)
		(layer "F.Cu")
		(net "USB_DN_R")
	)
	(segment
		(start 276.963632 -32.03448)
		(end 276.867112 -32.131)
		(width 0.1397)
		(layer "F.Cu")
		(net "USB_DN_R")
	)
	(segment
		(start 277.012908 -27.380438)
		(end 277.039578 -27.407108)
		(width 0.1397)
		(layer "F.Cu")
		(net "USB_DN_R")
	)
	(segment
		(start 276.875494 -26.629868)
		(end 276.875494 -27.048714)
		(width 0.1397)
		(layer "F.Cu")
		(net "USB_DN_R")
	)
	(via
		(at 276.867112 -32.131)
		(size 0.5588)
		(drill 0.3048)
		(layers "F.Cu" "B.Cu")
		(net "USB_DN_R")
	)
	(via
		(at 293.497 -113.510568)
		(size 0.5588)
		(drill 0.3048)
		(layers "F.Cu" "B.Cu")
		(net "USB_DN_R")
	)
	(arc
		(start 276.875494 -27.048714)
		(mid 276.911205 -27.228245)
		(end 277.012908 -27.380438)
		(width 0.1397)
		(layer "F.Cu")
		(net "USB_DN_R")
	)
	(arc
		(start 277.186644 -31.496)
		(mid 277.128679 -31.78741)
		(end 276.963632 -32.03448)
		(width 0.1397)
		(layer "F.Cu")
		(net "USB_DN_R")
	)
	(arc
		(start 277.039578 -27.407108)
		(mid 277.148436 -27.570026)
		(end 277.186644 -27.7622)
		(width 0.1397)
		(layer "F.Cu")
		(net "USB_DN_R")
	)
	(segment
		(start 306.684172 -114.827558)
		(end 316.70498 -124.848366)
		(width 0.1397)
		(layer "B.Cu")
		(net "USB_DN_R")
	)
	(segment
		(start 294.0304 -113.8301)
		(end 304.368454 -113.8301)
		(width 0.1397)
		(layer "B.Cu")
		(net "USB_DN_R")
	)
	(segment
		(start 339.165692 -126.285752)
		(end 344.915744 -132.035804)
		(width 0.1397)
		(layer "B.Cu")
		(net "USB_DN_R")
	)
	(segment
		(start 341.296752 -135.385048)
		(end 340.872318 -135.385048)
		(width 0.1397)
		(layer "B.Cu")
		(net "USB_DN_R")
	)
	(segment
		(start 293.497 -113.510568)
		(end 293.665148 -113.67897)
		(width 0.1397)
		(layer "B.Cu")
		(net "USB_DN_R")
	)
	(segment
		(start 318.220344 -125.476)
		(end 337.2104 -125.476)
		(width 0.1397)
		(layer "B.Cu")
		(net "USB_DN_R")
	)
	(segment
		(start 341.5284 -134.845298)
		(end 341.5284 -135.1534)
		(width 0.1397)
		(layer "B.Cu")
		(net "USB_DN_R")
	)
	(segment
		(start 344.0938 -134.540498)
		(end 341.8332 -134.540498)
		(width 0.1397)
		(layer "B.Cu")
		(net "USB_DN_R")
	)
	(segment
		(start 345.2495 -132.842)
		(end 345.2495 -133.384798)
		(width 0.1397)
		(layer "B.Cu")
		(net "USB_DN_R")
	)
	(segment
		(start 306.618386 -114.762026)
		(end 306.684172 -114.827558)
		(width 0.1397)
		(layer "B.Cu")
		(net "USB_DN_R")
	)
	(arc
		(start 337.2104 -125.476)
		(mid 338.26859 -125.686393)
		(end 339.165692 -126.285752)
		(width 0.1397)
		(layer "B.Cu")
		(net "USB_DN_R")
	)
	(arc
		(start 345.2495 -133.384798)
		(mid 344.911003 -134.202001)
		(end 344.0938 -134.540498)
		(width 0.1397)
		(layer "B.Cu")
		(net "USB_DN_R")
	)
	(arc
		(start 341.5284 -135.1534)
		(mid 341.460552 -135.3172)
		(end 341.296752 -135.385048)
		(width 0.1397)
		(layer "B.Cu")
		(net "USB_DN_R")
	)
	(arc
		(start 344.915744 -132.035804)
		(mid 345.162757 -132.405719)
		(end 345.2495 -132.842)
		(width 0.1397)
		(layer "B.Cu")
		(net "USB_DN_R")
	)
	(arc
		(start 316.70498 -124.848366)
		(mid 317.400235 -125.31292)
		(end 318.220344 -125.476)
		(width 0.1397)
		(layer "B.Cu")
		(net "USB_DN_R")
	)
	(arc
		(start 341.8332 -134.540498)
		(mid 341.617674 -134.629772)
		(end 341.5284 -134.845298)
		(width 0.1397)
		(layer "B.Cu")
		(net "USB_DN_R")
	)
	(arc
		(start 304.368454 -113.8301)
		(mid 305.586087 -114.072342)
		(end 306.618386 -114.762026)
		(width 0.1397)
		(layer "B.Cu")
		(net "USB_DN_R")
	)
	(arc
		(start 293.665148 -113.67897)
		(mid 293.832742 -113.79086)
		(end 294.0304 -113.8301)
		(width 0.1397)
		(layer "B.Cu")
		(net "USB_DN_R")
	)
	(segment
		(start 294.386 -111.02086)
		(end 294.386 -113.503964)
		(width 0.127)
		(layer "In2.Cu")
		(net "USB_DN_R")
	)
	(segment
		(start 277.310342 -54.566312)
		(end 280.439114 -57.695338)
		(width 0.127)
		(layer "In2.Cu")
		(net "USB_DN_R")
	)
	(segment
		(start 294.028114 -113.86185)
		(end 293.90086 -113.86185)
		(width 0.127)
		(layer "In2.Cu")
		(net "USB_DN_R")
	)
	(segment
		(start 276.867112 -32.131)
		(end 276.87397 -32.138112)
		(width 0.127)
		(layer "In2.Cu")
		(net "USB_DN_R")
	)
	(segment
		(start 277.017988 -35.971988)
		(end 276.968966 -36.02101)
		(width 0.127)
		(layer "In2.Cu")
		(net "USB_DN_R")
	)
	(segment
		(start 292.9636 -88.389968)
		(end 292.9636 -92.202)
		(width 0.127)
		(layer "In2.Cu")
		(net "USB_DN_R")
	)
	(segment
		(start 280.6446 -58.1914)
		(end 280.6446 -75.42911)
		(width 0.127)
		(layer "In2.Cu")
		(net "USB_DN_R")
	)
	(segment
		(start 293.811198 -113.824766)
		(end 293.497 -113.510568)
		(width 0.127)
		(layer "In2.Cu")
		(net "USB_DN_R")
	)
	(segment
		(start 277.218394 -32.9692)
		(end 277.218394 -35.488118)
		(width 0.127)
		(layer "In2.Cu")
		(net "USB_DN_R")
	)
	(segment
		(start 276.7076 -36.6522)
		(end 276.7076 -53.111654)
		(width 0.127)
		(layer "In2.Cu")
		(net "USB_DN_R")
	)
	(segment
		(start 280.912316 -76.07554)
		(end 292.777672 -87.940896)
		(width 0.127)
		(layer "In2.Cu")
		(net "USB_DN_R")
	)
	(segment
		(start 292.62197 -108.994702)
		(end 294.199818 -110.571788)
		(width 0.127)
		(layer "In2.Cu")
		(net "USB_DN_R")
	)
	(segment
		(start 292.354 -93.371924)
		(end 292.354 -108.348018)
		(width 0.127)
		(layer "In2.Cu")
		(net "USB_DN_R")
	)
	(segment
		(start 292.776148 -92.654628)
		(end 292.562788 -92.867988)
		(width 0.127)
		(layer "In2.Cu")
		(net "USB_DN_R")
	)
	(arc
		(start 293.90086 -113.86185)
		(mid 293.852342 -113.852217)
		(end 293.811198 -113.824766)
		(width 0.127)
		(layer "In2.Cu")
		(net "USB_DN_R")
	)
	(arc
		(start 292.9636 -92.202)
		(mid 292.914877 -92.446948)
		(end 292.776148 -92.654628)
		(width 0.127)
		(layer "In2.Cu")
		(net "USB_DN_R")
	)
	(arc
		(start 276.968966 -36.02101)
		(mid 276.77552 -36.310617)
		(end 276.7076 -36.6522)
		(width 0.127)
		(layer "In2.Cu")
		(net "USB_DN_R")
	)
	(arc
		(start 276.87397 -32.138112)
		(mid 277.128834 -32.519403)
		(end 277.218394 -32.9692)
		(width 0.127)
		(layer "In2.Cu")
		(net "USB_DN_R")
	)
	(arc
		(start 292.777672 -87.940896)
		(mid 292.915341 -88.146932)
		(end 292.9636 -88.389968)
		(width 0.127)
		(layer "In2.Cu")
		(net "USB_DN_R")
	)
	(arc
		(start 294.386 -113.503964)
		(mid 294.281178 -113.757028)
		(end 294.028114 -113.86185)
		(width 0.127)
		(layer "In2.Cu")
		(net "USB_DN_R")
	)
	(arc
		(start 276.7076 -53.111654)
		(mid 276.864278 -53.898947)
		(end 277.310342 -54.566312)
		(width 0.127)
		(layer "In2.Cu")
		(net "USB_DN_R")
	)
	(arc
		(start 292.354 -108.348018)
		(mid 292.423639 -108.698027)
		(end 292.62197 -108.994702)
		(width 0.127)
		(layer "In2.Cu")
		(net "USB_DN_R")
	)
	(arc
		(start 292.562788 -92.867988)
		(mid 292.408271 -93.099195)
		(end 292.354 -93.371924)
		(width 0.127)
		(layer "In2.Cu")
		(net "USB_DN_R")
	)
	(arc
		(start 280.439114 -57.695338)
		(mid 280.591188 -57.922933)
		(end 280.6446 -58.1914)
		(width 0.127)
		(layer "In2.Cu")
		(net "USB_DN_R")
	)
	(arc
		(start 277.218394 -35.488118)
		(mid 277.166375 -35.750019)
		(end 277.017988 -35.971988)
		(width 0.127)
		(layer "In2.Cu")
		(net "USB_DN_R")
	)
	(arc
		(start 294.199818 -110.571788)
		(mid 294.337541 -110.77781)
		(end 294.386 -111.02086)
		(width 0.127)
		(layer "In2.Cu")
		(net "USB_DN_R")
	)
	(arc
		(start 280.6446 -75.42911)
		(mid 280.71417 -75.778953)
		(end 280.912316 -76.07554)
		(width 0.127)
		(layer "In2.Cu")
		(net "USB_DN_R")
	)
	(segment
		(start 277.752556 -32.03448)
		(end 277.849076 -32.131)
		(width 0.1397)
		(layer "F.Cu")
		(net "USB_DP_R")
	)
	(segment
		(start 277.529544 -27.7622)
		(end 277.529544 -31.496)
		(width 0.1397)
		(layer "F.Cu")
		(net "USB_DP_R")
	)
	(segment
		(start 277.725632 -27.358086)
		(end 277.67661 -27.407108)
		(width 0.1397)
		(layer "F.Cu")
		(net "USB_DP_R")
	)
	(segment
		(start 277.840694 -26.629868)
		(end 277.840694 -27.08021)
		(width 0.1397)
		(layer "F.Cu")
		(net "USB_DP_R")
	)
	(via
		(at 277.849076 -32.131)
		(size 0.5588)
		(drill 0.3048)
		(layers "F.Cu" "B.Cu")
		(net "USB_DP_R")
	)
	(via
		(at 293.497 -114.492532)
		(size 0.5588)
		(drill 0.3048)
		(layers "F.Cu" "B.Cu")
		(net "USB_DP_R")
	)
	(arc
		(start 277.67661 -27.407108)
		(mid 277.567752 -27.570026)
		(end 277.529544 -27.7622)
		(width 0.1397)
		(layer "F.Cu")
		(net "USB_DP_R")
	)
	(arc
		(start 277.840694 -27.08021)
		(mid 277.810783 -27.230581)
		(end 277.725632 -27.358086)
		(width 0.1397)
		(layer "F.Cu")
		(net "USB_DP_R")
	)
	(arc
		(start 277.529544 -31.496)
		(mid 277.587509 -31.78741)
		(end 277.752556 -32.03448)
		(width 0.1397)
		(layer "F.Cu")
		(net "USB_DP_R")
	)
	(segment
		(start 306.44211 -115.070636)
		(end 316.46241 -125.090936)
		(width 0.1397)
		(layer "B.Cu")
		(net "USB_DP_R")
	)
	(segment
		(start 344.9066 -132.842)
		(end 344.9066 -133.384798)
		(width 0.1397)
		(layer "B.Cu")
		(net "USB_DP_R")
	)
	(segment
		(start 338.923122 -126.528322)
		(end 344.673174 -132.278374)
		(width 0.1397)
		(layer "B.Cu")
		(net "USB_DP_R")
	)
	(segment
		(start 341.404448 -133.353048)
		(end 340.872318 -133.353048)
		(width 0.1397)
		(layer "B.Cu")
		(net "USB_DP_R")
	)
	(segment
		(start 318.220344 -125.8189)
		(end 337.2104 -125.8189)
		(width 0.1397)
		(layer "B.Cu")
		(net "USB_DP_R")
	)
	(segment
		(start 344.0938 -134.197598)
		(end 341.8332 -134.197598)
		(width 0.1397)
		(layer "B.Cu")
		(net "USB_DP_R")
	)
	(segment
		(start 293.497 -114.492532)
		(end 293.665148 -114.32413)
		(width 0.1397)
		(layer "B.Cu")
		(net "USB_DP_R")
	)
	(segment
		(start 294.0304 -114.173)
		(end 304.3682 -114.173)
		(width 0.1397)
		(layer "B.Cu")
		(net "USB_DP_R")
	)
	(segment
		(start 306.37607 -115.00485)
		(end 306.44211 -115.070636)
		(width 0.1397)
		(layer "B.Cu")
		(net "USB_DP_R")
	)
	(segment
		(start 341.5538 -133.918198)
		(end 341.5538 -133.5024)
		(width 0.1397)
		(layer "B.Cu")
		(net "USB_DP_R")
	)
	(arc
		(start 304.3682 -114.173)
		(mid 305.45486 -114.389244)
		(end 306.37607 -115.00485)
		(width 0.1397)
		(layer "B.Cu")
		(net "USB_DP_R")
	)
	(arc
		(start 341.8332 -134.197598)
		(mid 341.635634 -134.115764)
		(end 341.5538 -133.918198)
		(width 0.1397)
		(layer "B.Cu")
		(net "USB_DP_R")
	)
	(arc
		(start 341.5538 -133.5024)
		(mid 341.510056 -133.396792)
		(end 341.404448 -133.353048)
		(width 0.1397)
		(layer "B.Cu")
		(net "USB_DP_R")
	)
	(arc
		(start 337.2104 -125.8189)
		(mid 338.137314 -126.003275)
		(end 338.923122 -126.528322)
		(width 0.1397)
		(layer "B.Cu")
		(net "USB_DP_R")
	)
	(arc
		(start 293.665148 -114.32413)
		(mid 293.832742 -114.21224)
		(end 294.0304 -114.173)
		(width 0.1397)
		(layer "B.Cu")
		(net "USB_DP_R")
	)
	(arc
		(start 344.9066 -133.384798)
		(mid 344.668536 -133.959534)
		(end 344.0938 -134.197598)
		(width 0.1397)
		(layer "B.Cu")
		(net "USB_DP_R")
	)
	(arc
		(start 344.673174 -132.278374)
		(mid 344.845961 -132.536968)
		(end 344.9066 -132.842)
		(width 0.1397)
		(layer "B.Cu")
		(net "USB_DP_R")
	)
	(arc
		(start 316.46241 -125.090936)
		(mid 317.268972 -125.62977)
		(end 318.220344 -125.8189)
		(width 0.1397)
		(layer "B.Cu")
		(net "USB_DP_R")
	)
	(segment
		(start 276.987 -36.6522)
		(end 276.987 -40.555926)
		(width 0.127)
		(layer "In2.Cu")
		(net "USB_DP_R")
	)
	(segment
		(start 294.028114 -114.14125)
		(end 293.90086 -114.14125)
		(width 0.127)
		(layer "In2.Cu")
		(net "USB_DP_R")
	)
	(segment
		(start 280.924 -58.1914)
		(end 280.924 -75.428856)
		(width 0.127)
		(layer "In2.Cu")
		(net "USB_DP_R")
	)
	(segment
		(start 276.987 -49.14265)
		(end 276.987 -49.52365)
		(width 0.127)
		(layer "In2.Cu")
		(net "USB_DP_R")
	)
	(segment
		(start 277.13686 -49.82337)
		(end 277.13686 -50.20437)
		(width 0.127)
		(layer "In2.Cu")
		(net "USB_DP_R")
	)
	(segment
		(start 277.507954 -54.3687)
		(end 280.636726 -57.497726)
		(width 0.127)
		(layer "In2.Cu")
		(net "USB_DP_R")
	)
	(segment
		(start 277.13686 -51.18481)
		(end 277.13686 -51.56581)
		(width 0.127)
		(layer "In2.Cu")
		(net "USB_DP_R")
	)
	(segment
		(start 281.109928 -75.877928)
		(end 292.975284 -87.743284)
		(width 0.127)
		(layer "In2.Cu")
		(net "USB_DP_R")
	)
	(segment
		(start 292.819582 -108.79709)
		(end 294.39743 -110.374176)
		(width 0.127)
		(layer "In2.Cu")
		(net "USB_DP_R")
	)
	(segment
		(start 293.811198 -114.178334)
		(end 293.497 -114.492532)
		(width 0.127)
		(layer "In2.Cu")
		(net "USB_DP_R")
	)
	(segment
		(start 277.13686 -43.631612)
		(end 277.13686 -44.012612)
		(width 0.127)
		(layer "In2.Cu")
		(net "USB_DP_R")
	)
	(segment
		(start 277.2156 -36.1696)
		(end 277.166578 -36.218622)
		(width 0.127)
		(layer "In2.Cu")
		(net "USB_DP_R")
	)
	(segment
		(start 293.243 -88.389714)
		(end 293.243 -92.202)
		(width 0.127)
		(layer "In2.Cu")
		(net "USB_DP_R")
	)
	(segment
		(start 276.987 -51.86553)
		(end 276.987 -53.1114)
		(width 0.127)
		(layer "In2.Cu")
		(net "USB_DP_R")
	)
	(segment
		(start 277.497794 -32.9692)
		(end 277.497794 -35.488372)
		(width 0.127)
		(layer "In2.Cu")
		(net "USB_DP_R")
	)
	(segment
		(start 277.13686 -44.993052)
		(end 277.13686 -45.374052)
		(width 0.127)
		(layer "In2.Cu")
		(net "USB_DP_R")
	)
	(segment
		(start 277.13686 -48.46193)
		(end 277.13686 -48.84293)
		(width 0.127)
		(layer "In2.Cu")
		(net "USB_DP_R")
	)
	(segment
		(start 276.987 -45.673772)
		(end 276.987 -48.16221)
		(width 0.127)
		(layer "In2.Cu")
		(net "USB_DP_R")
	)
	(segment
		(start 292.97376 -92.85224)
		(end 292.7604 -93.0656)
		(width 0.127)
		(layer "In2.Cu")
		(net "USB_DP_R")
	)
	(segment
		(start 277.13686 -40.855646)
		(end 277.13686 -41.236646)
		(width 0.127)
		(layer "In2.Cu")
		(net "USB_DP_R")
	)
	(segment
		(start 276.987 -44.312332)
		(end 276.987 -44.693332)
		(width 0.127)
		(layer "In2.Cu")
		(net "USB_DP_R")
	)
	(segment
		(start 277.849076 -32.131)
		(end 277.842218 -32.138112)
		(width 0.127)
		(layer "In2.Cu")
		(net "USB_DP_R")
	)
	(segment
		(start 294.6654 -111.02086)
		(end 294.6654 -113.503964)
		(width 0.127)
		(layer "In2.Cu")
		(net "USB_DP_R")
	)
	(segment
		(start 292.6334 -93.372178)
		(end 292.6334 -108.348018)
		(width 0.127)
		(layer "In2.Cu")
		(net "USB_DP_R")
	)
	(segment
		(start 276.987 -50.50409)
		(end 276.987 -50.88509)
		(width 0.127)
		(layer "In2.Cu")
		(net "USB_DP_R")
	)
	(segment
		(start 276.987 -41.536366)
		(end 276.987 -43.331892)
		(width 0.127)
		(layer "In2.Cu")
		(net "USB_DP_R")
	)
	(arc
		(start 277.497794 -35.488372)
		(mid 277.424458 -35.857058)
		(end 277.2156 -36.1696)
		(width 0.127)
		(layer "In2.Cu")
		(net "USB_DP_R")
	)
	(arc
		(start 276.987 -49.52365)
		(mid 277.008064 -49.606786)
		(end 277.06193 -49.67351)
		(width 0.127)
		(layer "In2.Cu")
		(net "USB_DP_R")
	)
	(arc
		(start 277.06193 -44.162472)
		(mid 277.008106 -44.229217)
		(end 276.987 -44.312332)
		(width 0.127)
		(layer "In2.Cu")
		(net "USB_DP_R")
	)
	(arc
		(start 277.13686 -51.56581)
		(mid 277.115796 -51.648946)
		(end 277.06193 -51.71567)
		(width 0.127)
		(layer "In2.Cu")
		(net "USB_DP_R")
	)
	(arc
		(start 276.987 -44.693332)
		(mid 277.008064 -44.776468)
		(end 277.06193 -44.843192)
		(width 0.127)
		(layer "In2.Cu")
		(net "USB_DP_R")
	)
	(arc
		(start 277.06193 -45.523912)
		(mid 277.008106 -45.590657)
		(end 276.987 -45.673772)
		(width 0.127)
		(layer "In2.Cu")
		(net "USB_DP_R")
	)
	(arc
		(start 276.987 -40.555926)
		(mid 277.008083 -40.639041)
		(end 277.06193 -40.705786)
		(width 0.127)
		(layer "In2.Cu")
		(net "USB_DP_R")
	)
	(arc
		(start 277.06193 -49.67351)
		(mid 277.115819 -49.740234)
		(end 277.13686 -49.82337)
		(width 0.127)
		(layer "In2.Cu")
		(net "USB_DP_R")
	)
	(arc
		(start 277.06193 -50.35423)
		(mid 277.008041 -50.420954)
		(end 276.987 -50.50409)
		(width 0.127)
		(layer "In2.Cu")
		(net "USB_DP_R")
	)
	(arc
		(start 292.975284 -87.743284)
		(mid 293.173402 -88.039883)
		(end 293.243 -88.389714)
		(width 0.127)
		(layer "In2.Cu")
		(net "USB_DP_R")
	)
	(arc
		(start 280.636726 -57.497726)
		(mid 280.849327 -57.816001)
		(end 280.924 -58.1914)
		(width 0.127)
		(layer "In2.Cu")
		(net "USB_DP_R")
	)
	(arc
		(start 277.13686 -44.012612)
		(mid 277.115796 -44.095748)
		(end 277.06193 -44.162472)
		(width 0.127)
		(layer "In2.Cu")
		(net "USB_DP_R")
	)
	(arc
		(start 292.6334 -108.348018)
		(mid 292.681854 -108.591051)
		(end 292.819582 -108.79709)
		(width 0.127)
		(layer "In2.Cu")
		(net "USB_DP_R")
	)
	(arc
		(start 280.924 -75.428856)
		(mid 280.972336 -75.67186)
		(end 281.109928 -75.877928)
		(width 0.127)
		(layer "In2.Cu")
		(net "USB_DP_R")
	)
	(arc
		(start 277.13686 -41.236646)
		(mid 277.115777 -41.319761)
		(end 277.06193 -41.386506)
		(width 0.127)
		(layer "In2.Cu")
		(net "USB_DP_R")
	)
	(arc
		(start 294.39743 -110.374176)
		(mid 294.595733 -110.670863)
		(end 294.6654 -111.02086)
		(width 0.127)
		(layer "In2.Cu")
		(net "USB_DP_R")
	)
	(arc
		(start 277.06193 -43.481752)
		(mid 277.115754 -43.548497)
		(end 277.13686 -43.631612)
		(width 0.127)
		(layer "In2.Cu")
		(net "USB_DP_R")
	)
	(arc
		(start 277.166578 -36.218622)
		(mid 277.033659 -36.417549)
		(end 276.987 -36.6522)
		(width 0.127)
		(layer "In2.Cu")
		(net "USB_DP_R")
	)
	(arc
		(start 277.06193 -48.99279)
		(mid 277.008041 -49.059514)
		(end 276.987 -49.14265)
		(width 0.127)
		(layer "In2.Cu")
		(net "USB_DP_R")
	)
	(arc
		(start 277.06193 -51.71567)
		(mid 277.008041 -51.782394)
		(end 276.987 -51.86553)
		(width 0.127)
		(layer "In2.Cu")
		(net "USB_DP_R")
	)
	(arc
		(start 293.90086 -114.14125)
		(mid 293.852342 -114.150883)
		(end 293.811198 -114.178334)
		(width 0.127)
		(layer "In2.Cu")
		(net "USB_DP_R")
	)
	(arc
		(start 277.06193 -41.386506)
		(mid 277.008106 -41.453251)
		(end 276.987 -41.536366)
		(width 0.127)
		(layer "In2.Cu")
		(net "USB_DP_R")
	)
	(arc
		(start 277.06193 -51.03495)
		(mid 277.115819 -51.101674)
		(end 277.13686 -51.18481)
		(width 0.127)
		(layer "In2.Cu")
		(net "USB_DP_R")
	)
	(arc
		(start 277.06193 -48.31207)
		(mid 277.115819 -48.378794)
		(end 277.13686 -48.46193)
		(width 0.127)
		(layer "In2.Cu")
		(net "USB_DP_R")
	)
	(arc
		(start 276.987 -53.1114)
		(mid 277.122444 -53.791855)
		(end 277.507954 -54.3687)
		(width 0.127)
		(layer "In2.Cu")
		(net "USB_DP_R")
	)
	(arc
		(start 277.13686 -50.20437)
		(mid 277.115796 -50.287506)
		(end 277.06193 -50.35423)
		(width 0.127)
		(layer "In2.Cu")
		(net "USB_DP_R")
	)
	(arc
		(start 292.7604 -93.0656)
		(mid 292.666415 -93.206259)
		(end 292.6334 -93.372178)
		(width 0.127)
		(layer "In2.Cu")
		(net "USB_DP_R")
	)
	(arc
		(start 276.987 -50.88509)
		(mid 277.008064 -50.968226)
		(end 277.06193 -51.03495)
		(width 0.127)
		(layer "In2.Cu")
		(net "USB_DP_R")
	)
	(arc
		(start 277.13686 -48.84293)
		(mid 277.115796 -48.926066)
		(end 277.06193 -48.99279)
		(width 0.127)
		(layer "In2.Cu")
		(net "USB_DP_R")
	)
	(arc
		(start 277.13686 -45.374052)
		(mid 277.115796 -45.457188)
		(end 277.06193 -45.523912)
		(width 0.127)
		(layer "In2.Cu")
		(net "USB_DP_R")
	)
	(arc
		(start 277.842218 -32.138112)
		(mid 277.587354 -32.519403)
		(end 277.497794 -32.9692)
		(width 0.127)
		(layer "In2.Cu")
		(net "USB_DP_R")
	)
	(arc
		(start 293.243 -92.202)
		(mid 293.173024 -92.553884)
		(end 292.97376 -92.85224)
		(width 0.127)
		(layer "In2.Cu")
		(net "USB_DP_R")
	)
	(arc
		(start 277.06193 -44.843192)
		(mid 277.115754 -44.909937)
		(end 277.13686 -44.993052)
		(width 0.127)
		(layer "In2.Cu")
		(net "USB_DP_R")
	)
	(arc
		(start 277.06193 -40.705786)
		(mid 277.115754 -40.772531)
		(end 277.13686 -40.855646)
		(width 0.127)
		(layer "In2.Cu")
		(net "USB_DP_R")
	)
	(arc
		(start 294.6654 -113.503964)
		(mid 294.478743 -113.954593)
		(end 294.028114 -114.14125)
		(width 0.127)
		(layer "In2.Cu")
		(net "USB_DP_R")
	)
	(arc
		(start 276.987 -43.331892)
		(mid 277.008064 -43.415028)
		(end 277.06193 -43.481752)
		(width 0.127)
		(layer "In2.Cu")
		(net "USB_DP_R")
	)
	(arc
		(start 276.987 -48.16221)
		(mid 277.008064 -48.245346)
		(end 277.06193 -48.31207)
		(width 0.127)
		(layer "In2.Cu")
		(net "USB_DP_R")
	)
	(segment
		(start 347.599 -134.2644)
		(end 344.177874 -134.2644)
		(width 0.1397)
		(layer "F.Cu")
		(net "USB_P1_DP")
	)
	(segment
		(start 343.3826 -133.533388)
		(end 343.3826 -133.2484)
		(width 0.1397)
		(layer "F.Cu")
		(net "USB_P1_DP")
	)
	(segment
		(start 343.730834 -134.079234)
		(end 343.5223 -133.8707)
		(width 0.1397)
		(layer "F.Cu")
		(net "USB_P1_DP")
	)
	(segment
		(start 345.749118 -148.745448)
		(end 349.482156 -145.01241)
		(width 0.1397)
		(layer "F.Cu")
		(net "USB_P1_DP")
	)
	(segment
		(start 349.23857 -135.26643)
		(end 348.687136 -134.714996)
		(width 0.1397)
		(layer "F.Cu")
		(net "USB_P1_DP")
	)
	(segment
		(start 349.9739 -143.825214)
		(end 349.9739 -137.042144)
		(width 0.1397)
		(layer "F.Cu")
		(net "USB_P1_DP")
	)
	(segment
		(start 344.402918 -149.226524)
		(end 344.587576 -149.226524)
		(width 0.1397)
		(layer "F.Cu")
		(net "USB_P1_DP")
	)
	(via
		(at 343.3826 -133.2484)
		(size 0.508)
		(drill 0.254)
		(layers "F.Cu" "B.Cu")
		(net "USB_P1_DP")
	)
	(arc
		(start 344.156284 -134.263892)
		(mid 343.926001 -134.212009)
		(end 343.730834 -134.079234)
		(width 0.1397)
		(layer "F.Cu")
		(net "USB_P1_DP")
	)
	(arc
		(start 349.482156 -145.01241)
		(mid 349.846053 -144.467706)
		(end 349.9739 -143.825214)
		(width 0.1397)
		(layer "F.Cu")
		(net "USB_P1_DP")
	)
	(arc
		(start 344.177874 -134.2644)
		(mid 344.167077 -134.264238)
		(end 344.156284 -134.263892)
		(width 0.1397)
		(layer "F.Cu")
		(net "USB_P1_DP")
	)
	(arc
		(start 344.587576 -149.226524)
		(mid 345.216179 -149.101487)
		(end 345.749118 -148.745448)
		(width 0.1397)
		(layer "F.Cu")
		(net "USB_P1_DP")
	)
	(arc
		(start 349.9739 -137.042144)
		(mid 349.782841 -136.081155)
		(end 349.23857 -135.26643)
		(width 0.1397)
		(layer "F.Cu")
		(net "USB_P1_DP")
	)
	(arc
		(start 343.5223 -133.8707)
		(mid 343.418893 -133.71594)
		(end 343.3826 -133.533388)
		(width 0.1397)
		(layer "F.Cu")
		(net "USB_P1_DP")
	)
	(arc
		(start 348.687136 -134.714996)
		(mid 348.18788 -134.381497)
		(end 347.599 -134.2644)
		(width 0.1397)
		(layer "F.Cu")
		(net "USB_P1_DP")
	)
	(segment
		(start 342.269318 -133.353048)
		(end 343.277952 -133.353048)
		(width 0.1397)
		(layer "B.Cu")
		(net "USB_P1_DP")
	)
	(segment
		(start 343.277952 -133.353048)
		(end 343.3826 -133.2484)
		(width 0.1397)
		(layer "B.Cu")
		(net "USB_P1_DP")
	)
	(segment
		(start 337.7311 -137.36701)
		(end 337.7311 -135.128)
		(width 0.1397)
		(layer "F.Cu")
		(net "USB_P0_DN_R")
	)
	(segment
		(start 337.1088 -134.5057)
		(end 336.12963 -134.5057)
		(width 0.1397)
		(layer "F.Cu")
		(net "USB_P0_DN_R")
	)
	(segment
		(start 340.53272 -147.856448)
		(end 340.53272 -146.748246)
		(width 0.1397)
		(layer "F.Cu")
		(net "USB_P0_DN_R")
	)
	(segment
		(start 340.197948 -145.940018)
		(end 338.603082 -144.345152)
		(width 0.1397)
		(layer "F.Cu")
		(net "USB_P0_DN_R")
	)
	(segment
		(start 337.7311 -142.24)
		(end 337.7311 -140.22959)
		(width 0.1397)
		(layer "F.Cu")
		(net "USB_P0_DN_R")
	)
	(segment
		(start 337.53044 -138.18743)
		(end 337.53044 -137.76833)
		(width 0.1397)
		(layer "F.Cu")
		(net "USB_P0_DN_R")
	)
	(segment
		(start 337.7311 -139.00785)
		(end 337.7311 -138.58875)
		(width 0.1397)
		(layer "F.Cu")
		(net "USB_P0_DN_R")
	)
	(segment
		(start 335.8896 -134.655814)
		(end 335.8896 -135.4074)
		(width 0.1397)
		(layer "F.Cu")
		(net "USB_P0_DN_R")
	)
	(segment
		(start 337.53044 -139.82827)
		(end 337.53044 -139.40917)
		(width 0.1397)
		(layer "F.Cu")
		(net "USB_P0_DN_R")
	)
	(via
		(at 335.8896 -135.4074)
		(size 0.508)
		(drill 0.254)
		(layers "F.Cu" "B.Cu")
		(net "USB_P0_DN_R")
	)
	(arc
		(start 338.603082 -144.345152)
		(mid 337.95772 -143.3793)
		(end 337.7311 -142.24)
		(width 0.1397)
		(layer "F.Cu")
		(net "USB_P0_DN_R")
	)
	(arc
		(start 337.63077 -138.38809)
		(mid 337.55701 -138.299564)
		(end 337.53044 -138.18743)
		(width 0.1397)
		(layer "F.Cu")
		(net "USB_P0_DN_R")
	)
	(arc
		(start 337.7311 -140.22959)
		(mid 337.704576 -140.117433)
		(end 337.63077 -140.02893)
		(width 0.1397)
		(layer "F.Cu")
		(net "USB_P0_DN_R")
	)
	(arc
		(start 337.53044 -137.76833)
		(mid 337.556964 -137.656173)
		(end 337.63077 -137.56767)
		(width 0.1397)
		(layer "F.Cu")
		(net "USB_P0_DN_R")
	)
	(arc
		(start 337.7311 -138.58875)
		(mid 337.704576 -138.476593)
		(end 337.63077 -138.38809)
		(width 0.1397)
		(layer "F.Cu")
		(net "USB_P0_DN_R")
	)
	(arc
		(start 336.12963 -134.5057)
		(mid 336.013474 -134.528805)
		(end 335.915 -134.5946)
		(width 0.1397)
		(layer "F.Cu")
		(net "USB_P0_DN_R")
	)
	(arc
		(start 337.7311 -135.128)
		(mid 337.548833 -134.687967)
		(end 337.1088 -134.5057)
		(width 0.1397)
		(layer "F.Cu")
		(net "USB_P0_DN_R")
	)
	(arc
		(start 337.63077 -140.02893)
		(mid 337.55701 -139.940404)
		(end 337.53044 -139.82827)
		(width 0.1397)
		(layer "F.Cu")
		(net "USB_P0_DN_R")
	)
	(arc
		(start 340.53272 -146.748246)
		(mid 340.445714 -146.310839)
		(end 340.197948 -145.940018)
		(width 0.1397)
		(layer "F.Cu")
		(net "USB_P0_DN_R")
	)
	(arc
		(start 335.915 -134.5946)
		(mid 335.896234 -134.622685)
		(end 335.8896 -134.655814)
		(width 0.1397)
		(layer "F.Cu")
		(net "USB_P0_DN_R")
	)
	(arc
		(start 337.53044 -139.40917)
		(mid 337.556964 -139.297013)
		(end 337.63077 -139.20851)
		(width 0.1397)
		(layer "F.Cu")
		(net "USB_P0_DN_R")
	)
	(arc
		(start 337.63077 -137.56767)
		(mid 337.70453 -137.479144)
		(end 337.7311 -137.36701)
		(width 0.1397)
		(layer "F.Cu")
		(net "USB_P0_DN_R")
	)
	(arc
		(start 337.63077 -139.20851)
		(mid 337.70453 -139.119984)
		(end 337.7311 -139.00785)
		(width 0.1397)
		(layer "F.Cu")
		(net "USB_P0_DN_R")
	)
	(segment
		(start 337.951318 -135.385048)
		(end 335.911952 -135.385048)
		(width 0.1397)
		(layer "B.Cu")
		(net "USB_P0_DN_R")
	)
	(segment
		(start 335.911952 -135.385048)
		(end 335.8896 -135.4074)
		(width 0.1397)
		(layer "B.Cu")
		(net "USB_P0_DN_R")
	)
	(segment
		(start 338.074 -135.128)
		(end 338.074 -142.24)
		(width 0.1397)
		(layer "F.Cu")
		(net "USB_P0_DP_R")
	)
	(segment
		(start 338.845652 -144.102582)
		(end 340.440518 -145.697448)
		(width 0.1397)
		(layer "F.Cu")
		(net "USB_P0_DP_R")
	)
	(segment
		(start 336.432144 -134.1628)
		(end 337.1088 -134.1628)
		(width 0.1397)
		(layer "F.Cu")
		(net "USB_P0_DP_R")
	)
	(segment
		(start 341.032592 -147.12696)
		(end 341.032592 -147.856448)
		(width 0.1397)
		(layer "F.Cu")
		(net "USB_P0_DP_R")
	)
	(segment
		(start 336.0166 -133.2484)
		(end 336.0166 -133.711188)
		(width 0.1397)
		(layer "F.Cu")
		(net "USB_P0_DP_R")
	)
	(via
		(at 336.0166 -133.2484)
		(size 0.508)
		(drill 0.254)
		(layers "F.Cu" "B.Cu")
		(net "USB_P0_DP_R")
	)
	(arc
		(start 336.0166 -133.711188)
		(mid 336.05291 -133.893733)
		(end 336.1563 -134.0485)
		(width 0.1397)
		(layer "F.Cu")
		(net "USB_P0_DP_R")
	)
	(arc
		(start 336.277204 -134.130542)
		(mid 336.353019 -134.154631)
		(end 336.432144 -134.1628)
		(width 0.1397)
		(layer "F.Cu")
		(net "USB_P0_DP_R")
	)
	(arc
		(start 340.440518 -145.697448)
		(mid 340.878753 -146.353314)
		(end 341.032592 -147.12696)
		(width 0.1397)
		(layer "F.Cu")
		(net "USB_P0_DP_R")
	)
	(arc
		(start 336.1563 -134.0485)
		(mid 336.21288 -134.095225)
		(end 336.277204 -134.130542)
		(width 0.1397)
		(layer "F.Cu")
		(net "USB_P0_DP_R")
	)
	(arc
		(start 337.1088 -134.1628)
		(mid 337.791299 -134.445501)
		(end 338.074 -135.128)
		(width 0.1397)
		(layer "F.Cu")
		(net "USB_P0_DP_R")
	)
	(arc
		(start 338.074 -142.24)
		(mid 338.274602 -143.248024)
		(end 338.845652 -144.102582)
		(width 0.1397)
		(layer "F.Cu")
		(net "USB_P0_DP_R")
	)
	(segment
		(start 337.951318 -133.353048)
		(end 336.121248 -133.353048)
		(width 0.1397)
		(layer "B.Cu")
		(net "USB_P0_DP_R")
	)
	(segment
		(start 336.121248 -133.353048)
		(end 336.0166 -133.2484)
		(width 0.1397)
		(layer "B.Cu")
		(net "USB_P0_DP_R")
	)
	(segment
		(start 341.532718 -155.171648)
		(end 341.532718 -153.596848)
		(width 0.1143)
		(layer "F.Cu")
		(net "CRFILT")
	)
	(segment
		(start 343.056718 -157.775148)
		(end 343.056718 -156.568648)
		(width 0.1143)
		(layer "F.Cu")
		(net "CRFILT")
	)
	(segment
		(start 342.434418 -155.946348)
		(end 342.307418 -155.946348)
		(width 0.1143)
		(layer "F.Cu")
		(net "CRFILT")
	)
	(segment
		(start 343.056718 -156.568648)
		(end 342.904318 -156.416248)
		(width 0.1143)
		(layer "F.Cu")
		(net "CRFILT")
	)
	(segment
		(start 342.307418 -155.946348)
		(end 341.532718 -155.171648)
		(width 0.1143)
		(layer "F.Cu")
		(net "CRFILT")
	)
	(segment
		(start 342.904318 -156.416248)
		(end 342.434418 -155.946348)
		(width 0.1143)
		(layer "F.Cu")
		(net "CRFILT")
	)
	(segment
		(start 342.532716 -147.856448)
		(end 342.532716 -146.80565)
		(width 0.1143)
		(layer "F.Cu")
		(net "PLLFILT")
	)
	(segment
		(start 342.532716 -146.80565)
		(end 343.310718 -146.027648)
		(width 0.1143)
		(layer "F.Cu")
		(net "PLLFILT")
	)
	(segment
		(start 345.088718 -144.884648)
		(end 343.945718 -146.027648)
		(width 0.1143)
		(layer "F.Cu")
		(net "PLLFILT")
	)
	(segment
		(start 343.310718 -146.027648)
		(end 343.945718 -146.027648)
		(width 0.1143)
		(layer "F.Cu")
		(net "PLLFILT")
	)
	(segment
		(start 345.088718 -143.678148)
		(end 345.088718 -144.884648)
		(width 0.1143)
		(layer "F.Cu")
		(net "PLLFILT")
	)
	(segment
		(start 336.528918 -148.567648)
		(end 335.407508 -147.446238)
		(width 0.1143)
		(layer "F.Cu")
		(net "USB_RESET_N")
	)
	(segment
		(start 334.674718 -145.838418)
		(end 334.3783 -145.542)
		(width 0.1143)
		(layer "F.Cu")
		(net "USB_RESET_N")
	)
	(segment
		(start 334.674718 -146.662648)
		(end 334.674718 -145.838418)
		(width 0.1143)
		(layer "F.Cu")
		(net "USB_RESET_N")
	)
	(segment
		(start 337.187794 -149.226524)
		(end 336.528918 -148.567648)
		(width 0.1143)
		(layer "F.Cu")
		(net "USB_RESET_N")
	)
	(segment
		(start 335.407508 -147.446238)
		(end 335.407508 -147.395438)
		(width 0.1143)
		(layer "F.Cu")
		(net "USB_RESET_N")
	)
	(segment
		(start 335.407508 -147.395438)
		(end 334.674718 -146.662648)
		(width 0.1143)
		(layer "F.Cu")
		(net "USB_RESET_N")
	)
	(segment
		(start 334.3783 -144.52473)
		(end 334.3783 -145.542)
		(width 0.1143)
		(layer "F.Cu")
		(net "USB_RESET_N")
	)
	(segment
		(start 338.662518 -149.226524)
		(end 337.187794 -149.226524)
		(width 0.1143)
		(layer "F.Cu")
		(net "USB_RESET_N")
	)
	(segment
		(start 334.357218 -144.503648)
		(end 334.3783 -144.52473)
		(width 0.1143)
		(layer "F.Cu")
		(net "USB_RESET_N")
	)
	(via
		(at 336.528918 -148.567648)
		(size 0.7112)
		(drill 0.3556)
		(layers "F.Cu" "B.Cu")
		(net "USB_RESET_N")
	)
	(segment
		(start 334.357218 -143.678148)
		(end 336.325718 -145.646648)
		(width 0.1143)
		(layer "F.Cu")
		(net "VBUS_DET")
	)
	(segment
		(start 336.325718 -145.646648)
		(end 336.325718 -146.180048)
		(width 0.1143)
		(layer "F.Cu")
		(net "VBUS_DET")
	)
	(segment
		(start 338.573618 -148.726652)
		(end 336.325718 -146.478752)
		(width 0.1143)
		(layer "F.Cu")
		(net "VBUS_DET")
	)
	(segment
		(start 336.325718 -146.478752)
		(end 336.325718 -146.180048)
		(width 0.1143)
		(layer "F.Cu")
		(net "VBUS_DET")
	)
	(segment
		(start 334.357218 -143.360648)
		(end 334.357218 -143.678148)
		(width 0.1143)
		(layer "F.Cu")
		(net "VBUS_DET")
	)
	(via
		(at 336.325718 -146.180048)
		(size 0.7112)
		(drill 0.3556)
		(layers "F.Cu" "B.Cu")
		(net "VBUS_DET")
	)
	(segment
		(start 335.98612 -149.72665)
		(end 335.436718 -149.177248)
		(width 0.1143)
		(layer "F.Cu")
		(net "CFG_SEL1")
	)
	(segment
		(start 334.357218 -148.948648)
		(end 334.357218 -147.805648)
		(width 0.1143)
		(layer "F.Cu")
		(net "CFG_SEL1")
	)
	(segment
		(start 335.208118 -148.948648)
		(end 334.357218 -148.948648)
		(width 0.1143)
		(layer "F.Cu")
		(net "CFG_SEL1")
	)
	(segment
		(start 335.436718 -149.177248)
		(end 335.208118 -148.948648)
		(width 0.1143)
		(layer "F.Cu")
		(net "CFG_SEL1")
	)
	(segment
		(start 338.662518 -149.72665)
		(end 335.98612 -149.72665)
		(width 0.1143)
		(layer "F.Cu")
		(net "CFG_SEL1")
	)
	(via
		(at 335.436718 -149.177248)
		(size 0.7112)
		(drill 0.3556)
		(layers "F.Cu" "B.Cu")
		(net "CFG_SEL1")
	)
	(segment
		(start 334.357218 -151.234648)
		(end 334.357218 -150.091648)
		(width 0.1143)
		(layer "F.Cu")
		(net "CFG_SEL0")
	)
	(segment
		(start 335.970118 -150.472648)
		(end 334.738218 -150.472648)
		(width 0.1143)
		(layer "F.Cu")
		(net "CFG_SEL0")
	)
	(segment
		(start 334.738218 -150.472648)
		(end 334.357218 -150.091648)
		(width 0.1143)
		(layer "F.Cu")
		(net "CFG_SEL0")
	)
	(segment
		(start 334.357218 -152.377648)
		(end 334.357218 -151.234648)
		(width 0.1143)
		(layer "F.Cu")
		(net "CFG_SEL0")
	)
	(segment
		(start 336.216244 -150.226522)
		(end 335.970118 -150.472648)
		(width 0.1143)
		(layer "F.Cu")
		(net "CFG_SEL0")
	)
	(segment
		(start 338.662518 -150.226522)
		(end 336.216244 -150.226522)
		(width 0.1143)
		(layer "F.Cu")
		(net "CFG_SEL0")
	)
	(via
		(at 335.970118 -150.472648)
		(size 0.7112)
		(drill 0.3556)
		(layers "F.Cu" "B.Cu")
		(net "CFG_SEL0")
	)
	(segment
		(start 335.713578 -144.070578)
		(end 335.713578 -143.574008)
		(width 0.1143)
		(layer "F.Cu")
		(net "USB_SUSP_IND")
	)
	(segment
		(start 335.713578 -143.574008)
		(end 334.357218 -142.217648)
		(width 0.1143)
		(layer "F.Cu")
		(net "USB_SUSP_IND")
	)
	(segment
		(start 339.410548 -147.767548)
		(end 335.713578 -144.070578)
		(width 0.1143)
		(layer "F.Cu")
		(net "USB_SUSP_IND")
	)
	(segment
		(start 339.532722 -147.767548)
		(end 339.410548 -147.767548)
		(width 0.1143)
		(layer "F.Cu")
		(net "USB_SUSP_IND")
	)
	(via
		(at 335.713578 -143.574008)
		(size 0.7112)
		(drill 0.3556)
		(layers "F.Cu" "B.Cu")
		(net "USB_SUSP_IND")
	)
	(segment
		(start 338.072476 -152.226772)
		(end 337.466432 -152.832816)
		(width 0.1143)
		(layer "F.Cu")
		(net "USB_EN_4")
	)
	(segment
		(start 335.944718 -154.689048)
		(end 335.944718 -154.663648)
		(width 0.1143)
		(layer "F.Cu")
		(net "USB_EN_4")
	)
	(segment
		(start 338.662518 -152.226772)
		(end 338.072476 -152.226772)
		(width 0.1143)
		(layer "F.Cu")
		(net "USB_EN_4")
	)
	(segment
		(start 334.357218 -155.552648)
		(end 335.081118 -155.552648)
		(width 0.1143)
		(layer "F.Cu")
		(net "USB_EN_4")
	)
	(segment
		(start 334.357218 -156.695648)
		(end 334.357218 -155.552648)
		(width 0.1143)
		(layer "F.Cu")
		(net "USB_EN_4")
	)
	(segment
		(start 337.466432 -152.832816)
		(end 337.466432 -153.141934)
		(width 0.1143)
		(layer "F.Cu")
		(net "USB_EN_4")
	)
	(segment
		(start 335.081118 -155.552648)
		(end 335.944718 -154.689048)
		(width 0.1143)
		(layer "F.Cu")
		(net "USB_EN_4")
	)
	(segment
		(start 337.466432 -153.141934)
		(end 335.944718 -154.663648)
		(width 0.1143)
		(layer "F.Cu")
		(net "USB_EN_4")
	)
	(via
		(at 335.944718 -154.663648)
		(size 0.7112)
		(drill 0.3556)
		(layers "F.Cu" "B.Cu")
		(net "USB_EN_4")
	)
	(segment
		(start 338.084668 -155.190698)
		(end 337.570318 -155.705048)
		(width 0.1143)
		(layer "F.Cu")
		(net "USB_EN_3")
	)
	(segment
		(start 338.656168 -155.190698)
		(end 338.084668 -155.190698)
		(width 0.1143)
		(layer "F.Cu")
		(net "USB_EN_3")
	)
	(segment
		(start 337.214718 -156.060648)
		(end 337.570318 -155.705048)
		(width 0.1143)
		(layer "F.Cu")
		(net "USB_EN_3")
	)
	(segment
		(start 337.214718 -157.140148)
		(end 337.214718 -156.060648)
		(width 0.1143)
		(layer "F.Cu")
		(net "USB_EN_3")
	)
	(segment
		(start 336.071718 -157.140148)
		(end 337.214718 -157.140148)
		(width 0.1143)
		(layer "F.Cu")
		(net "USB_EN_3")
	)
	(segment
		(start 339.532722 -153.685748)
		(end 339.532722 -154.314144)
		(width 0.1143)
		(layer "F.Cu")
		(net "USB_EN_3")
	)
	(segment
		(start 339.532722 -154.314144)
		(end 338.656168 -155.190698)
		(width 0.1143)
		(layer "F.Cu")
		(net "USB_EN_3")
	)
	(via
		(at 337.570318 -155.705048)
		(size 0.7112)
		(drill 0.3556)
		(layers "F.Cu" "B.Cu")
		(net "USB_EN_3")
	)
	(segment
		(start 340.072218 -158.473648)
		(end 340.072218 -157.330648)
		(width 0.1143)
		(layer "F.Cu")
		(net "USB_EN_2")
	)
	(segment
		(start 340.53272 -153.596848)
		(end 340.53272 -155.028646)
		(width 0.1143)
		(layer "F.Cu")
		(net "USB_EN_2")
	)
	(segment
		(start 340.072218 -157.330648)
		(end 340.072218 -156.345636)
		(width 0.1143)
		(layer "F.Cu")
		(net "USB_EN_2")
	)
	(segment
		(start 340.072218 -155.489148)
		(end 340.072218 -156.345636)
		(width 0.1143)
		(layer "F.Cu")
		(net "USB_EN_2")
	)
	(segment
		(start 340.53272 -155.028646)
		(end 340.072218 -155.489148)
		(width 0.1143)
		(layer "F.Cu")
		(net "USB_EN_2")
	)
	(via
		(at 340.072218 -156.345636)
		(size 0.7112)
		(drill 0.3556)
		(layers "F.Cu" "B.Cu")
		(net "USB_EN_2")
	)
	(segment
		(start 344.255852 -157.394148)
		(end 344.021918 -157.394148)
		(width 0.1143)
		(layer "F.Cu")
		(net "USB_EN_1")
	)
	(segment
		(start 342.532716 -154.520646)
		(end 343.056718 -155.044648)
		(width 0.1143)
		(layer "F.Cu")
		(net "USB_EN_1")
	)
	(segment
		(start 342.532716 -153.596848)
		(end 342.532716 -154.520646)
		(width 0.1143)
		(layer "F.Cu")
		(net "USB_EN_1")
	)
	(segment
		(start 343.056718 -155.044648)
		(end 343.056718 -155.223718)
		(width 0.1143)
		(layer "F.Cu")
		(net "USB_EN_1")
	)
	(segment
		(start 345.252548 -157.394148)
		(end 344.7542 -156.8958)
		(width 0.1143)
		(layer "F.Cu")
		(net "USB_EN_1")
	)
	(segment
		(start 343.056718 -155.223718)
		(end 343.385648 -155.552648)
		(width 0.1143)
		(layer "F.Cu")
		(net "USB_EN_1")
	)
	(segment
		(start 252.095 -20.701)
		(end 252.095 -16.764)
		(width 0.1143)
		(layer "F.Cu")
		(net "USB_EN_1")
	)
	(segment
		(start 264.795 -55.0926)
		(end 264.795 -50.756566)
		(width 0.1143)
		(layer "F.Cu")
		(net "USB_EN_1")
	)
	(segment
		(start 256.413 -44.533566)
		(end 256.413 -25.019)
		(width 0.1143)
		(layer "F.Cu")
		(net "USB_EN_1")
	)
	(segment
		(start 253.746 -15.113)
		(end 254.762 -15.113)
		(width 0.1143)
		(layer "F.Cu")
		(net "USB_EN_1")
	)
	(segment
		(start 262.6106 -57.277)
		(end 264.795 -55.0926)
		(width 0.1143)
		(layer "F.Cu")
		(net "USB_EN_1")
	)
	(segment
		(start 345.596718 -157.394148)
		(end 345.252548 -157.394148)
		(width 0.1143)
		(layer "F.Cu")
		(net "USB_EN_1")
	)
	(segment
		(start 256.413 -25.019)
		(end 252.095 -20.701)
		(width 0.1143)
		(layer "F.Cu")
		(net "USB_EN_1")
	)
	(segment
		(start 264.795 -50.756566)
		(end 262.679434 -48.641)
		(width 0.1143)
		(layer "F.Cu")
		(net "USB_EN_1")
	)
	(segment
		(start 260.520434 -48.641)
		(end 256.413 -44.533566)
		(width 0.1143)
		(layer "F.Cu")
		(net "USB_EN_1")
	)
	(segment
		(start 344.021918 -157.394148)
		(end 344.021918 -156.307282)
		(width 0.1143)
		(layer "F.Cu")
		(net "USB_EN_1")
	)
	(segment
		(start 344.301318 -156.027882)
		(end 344.301318 -155.857448)
		(width 0.1143)
		(layer "F.Cu")
		(net "USB_EN_1")
	)
	(segment
		(start 252.095 -16.764)
		(end 253.746 -15.113)
		(width 0.1143)
		(layer "F.Cu")
		(net "USB_EN_1")
	)
	(segment
		(start 343.996518 -155.552648)
		(end 344.301318 -155.857448)
		(width 0.1143)
		(layer "F.Cu")
		(net "USB_EN_1")
	)
	(segment
		(start 344.7542 -156.8958)
		(end 344.255852 -157.394148)
		(width 0.1143)
		(layer "F.Cu")
		(net "USB_EN_1")
	)
	(segment
		(start 344.021918 -156.307282)
		(end 344.301318 -156.027882)
		(width 0.1143)
		(layer "F.Cu")
		(net "USB_EN_1")
	)
	(segment
		(start 343.385648 -155.552648)
		(end 343.996518 -155.552648)
		(width 0.1143)
		(layer "F.Cu")
		(net "USB_EN_1")
	)
	(segment
		(start 262.679434 -48.641)
		(end 260.520434 -48.641)
		(width 0.1143)
		(layer "F.Cu")
		(net "USB_EN_1")
	)
	(via
		(at 344.7542 -156.8958)
		(size 0.5588)
		(drill 0.3048)
		(layers "F.Cu" "B.Cu")
		(net "USB_EN_1")
	)
	(via
		(at 262.6106 -57.277)
		(size 0.5588)
		(drill 0.3048)
		(layers "F.Cu" "B.Cu")
		(net "USB_EN_1")
	)
	(via
		(at 344.301318 -155.857448)
		(size 0.7112)
		(drill 0.3556)
		(layers "F.Cu" "B.Cu")
		(net "USB_EN_1")
	)
	(via
		(at 273.939 -117.856)
		(size 0.5588)
		(drill 0.3048)
		(layers "F.Cu" "B.Cu")
		(net "USB_EN_1")
	)
	(via
		(at 328.66584 -134.29996)
		(size 0.5588)
		(drill 0.3048)
		(layers "F.Cu" "B.Cu")
		(net "USB_EN_1")
	)
	(via
		(at 254.762 -15.113)
		(size 0.5588)
		(drill 0.3048)
		(layers "F.Cu" "B.Cu")
		(net "USB_EN_1")
	)
	(segment
		(start 319.659 -130.302)
		(end 317.268098 -130.302)
		(width 0.1143)
		(layer "B.Cu")
		(net "USB_EN_1")
	)
	(segment
		(start 304.856642 -119.119396)
		(end 302.963326 -119.119396)
		(width 0.1143)
		(layer "B.Cu")
		(net "USB_EN_1")
	)
	(segment
		(start 317.268098 -130.302)
		(end 306.085748 -119.11965)
		(width 0.1143)
		(layer "B.Cu")
		(net "USB_EN_1")
	)
	(segment
		(start 275.463 -119.38)
		(end 273.939 -117.856)
		(width 0.1143)
		(layer "B.Cu")
		(net "USB_EN_1")
	)
	(segment
		(start 302.963326 -119.119396)
		(end 302.963072 -119.11965)
		(width 0.1143)
		(layer "B.Cu")
		(net "USB_EN_1")
	)
	(segment
		(start 294.771826 -119.11965)
		(end 294.511476 -119.38)
		(width 0.1143)
		(layer "B.Cu")
		(net "USB_EN_1")
	)
	(segment
		(start 256.09804 -15.113)
		(end 254.762 -15.113)
		(width 0.1143)
		(layer "B.Cu")
		(net "USB_EN_1")
	)
	(segment
		(start 328.66584 -134.29996)
		(end 327.5838 -135.382)
		(width 0.1143)
		(layer "B.Cu")
		(net "USB_EN_1")
	)
	(segment
		(start 327.5838 -135.382)
		(end 324.739 -135.382)
		(width 0.1143)
		(layer "B.Cu")
		(net "USB_EN_1")
	)
	(segment
		(start 324.739 -135.382)
		(end 319.659 -130.302)
		(width 0.1143)
		(layer "B.Cu")
		(net "USB_EN_1")
	)
	(segment
		(start 294.511476 -119.38)
		(end 275.463 -119.38)
		(width 0.1143)
		(layer "B.Cu")
		(net "USB_EN_1")
	)
	(segment
		(start 306.085748 -119.11965)
		(end 304.856896 -119.11965)
		(width 0.1143)
		(layer "B.Cu")
		(net "USB_EN_1")
	)
	(segment
		(start 302.963072 -119.11965)
		(end 294.771826 -119.11965)
		(width 0.1143)
		(layer "B.Cu")
		(net "USB_EN_1")
	)
	(segment
		(start 304.856896 -119.11965)
		(end 304.856642 -119.119396)
		(width 0.1143)
		(layer "B.Cu")
		(net "USB_EN_1")
	)
	(segment
		(start 268.7955 -92.075)
		(end 268.7955 -82.382868)
		(width 0.127)
		(layer "In2.Cu")
		(net "USB_EN_1")
	)
	(segment
		(start 263.7917 -62.958218)
		(end 262.6106 -61.777118)
		(width 0.127)
		(layer "In2.Cu")
		(net "USB_EN_1")
	)
	(segment
		(start 268.507464 -112.424464)
		(end 268.507464 -92.363036)
		(width 0.127)
		(layer "In2.Cu")
		(net "USB_EN_1")
	)
	(segment
		(start 263.7917 -70.6247)
		(end 263.7917 -62.958218)
		(width 0.127)
		(layer "In2.Cu")
		(net "USB_EN_1")
	)
	(segment
		(start 268.507464 -92.363036)
		(end 268.7955 -92.075)
		(width 0.127)
		(layer "In2.Cu")
		(net "USB_EN_1")
	)
	(segment
		(start 262.6106 -61.777118)
		(end 262.6106 -57.277)
		(width 0.127)
		(layer "In2.Cu")
		(net "USB_EN_1")
	)
	(segment
		(start 273.939 -117.856)
		(end 268.507464 -112.424464)
		(width 0.127)
		(layer "In2.Cu")
		(net "USB_EN_1")
	)
	(segment
		(start 266.5476 -80.134968)
		(end 266.5476 -73.3806)
		(width 0.127)
		(layer "In2.Cu")
		(net "USB_EN_1")
	)
	(segment
		(start 268.7955 -82.382868)
		(end 266.5476 -80.134968)
		(width 0.127)
		(layer "In2.Cu")
		(net "USB_EN_1")
	)
	(segment
		(start 266.5476 -73.3806)
		(end 263.7917 -70.6247)
		(width 0.127)
		(layer "In2.Cu")
		(net "USB_EN_1")
	)
	(segment
		(start 339.848698 -156.718)
		(end 344.5764 -156.718)
		(width 0.127)
		(layer "In5.Cu")
		(net "USB_EN_1")
	)
	(segment
		(start 337.693 -143.5608)
		(end 337.693 -154.562302)
		(width 0.127)
		(layer "In5.Cu")
		(net "USB_EN_1")
	)
	(segment
		(start 344.5764 -156.718)
		(end 344.7542 -156.8958)
		(width 0.127)
		(layer "In5.Cu")
		(net "USB_EN_1")
	)
	(segment
		(start 330.962 -136.8298)
		(end 337.693 -143.5608)
		(width 0.127)
		(layer "In5.Cu")
		(net "USB_EN_1")
	)
	(segment
		(start 328.66584 -134.29996)
		(end 328.66584 -134.33044)
		(width 0.127)
		(layer "In5.Cu")
		(net "USB_EN_1")
	)
	(segment
		(start 328.66584 -134.33044)
		(end 330.962 -136.6266)
		(width 0.127)
		(layer "In5.Cu")
		(net "USB_EN_1")
	)
	(segment
		(start 337.693 -154.562302)
		(end 339.848698 -156.718)
		(width 0.127)
		(layer "In5.Cu")
		(net "USB_EN_1")
	)
	(segment
		(start 330.962 -136.6266)
		(end 330.962 -136.8298)
		(width 0.127)
		(layer "In5.Cu")
		(net "USB_EN_1")
	)
	(segment
		(start 350.45396 -152.273)
		(end 350.75495 -151.97201)
		(width 0.1397)
		(layer "F.Cu")
		(net "BMC_USB1_HDN")
	)
	(segment
		(start 300.861984 -173.84014)
		(end 301.271178 -174.249334)
		(width 0.1397)
		(layer "F.Cu")
		(net "BMC_USB1_HDN")
	)
	(segment
		(start 349.23857 -152.273)
		(end 350.45396 -152.273)
		(width 0.1397)
		(layer "F.Cu")
		(net "BMC_USB1_HDN")
	)
	(segment
		(start 348.835218 -151.869648)
		(end 349.23857 -152.273)
		(width 0.1397)
		(layer "F.Cu")
		(net "BMC_USB1_HDN")
	)
	(segment
		(start 300.834806 -173.84014)
		(end 300.861984 -173.84014)
		(width 0.1397)
		(layer "F.Cu")
		(net "BMC_USB1_HDN")
	)
	(segment
		(start 301.271178 -174.249334)
		(end 302.470058 -174.249334)
		(width 0.1397)
		(layer "F.Cu")
		(net "BMC_USB1_HDN")
	)
	(segment
		(start 302.470058 -174.249334)
		(end 303.005998 -173.713394)
		(width 0.1397)
		(layer "F.Cu")
		(net "BMC_USB1_HDN")
	)
	(via
		(at 303.005998 -173.713394)
		(size 0.5588)
		(drill 0.3048)
		(layers "F.Cu" "B.Cu")
		(net "BMC_USB1_HDN")
	)
	(via
		(at 350.75495 -151.97201)
		(size 0.508)
		(drill 0.254)
		(layers "F.Cu" "B.Cu")
		(net "BMC_USB1_HDN")
	)
	(segment
		(start 303.024794 -174.113444)
		(end 303.005998 -173.713394)
		(width 0.127)
		(layer "In5.Cu")
		(net "BMC_USB1_HDN")
	)
	(segment
		(start 309.218838 -175.3362)
		(end 309.218584 -175.335946)
		(width 0.127)
		(layer "In5.Cu")
		(net "BMC_USB1_HDN")
	)
	(segment
		(start 349.758 -170.307)
		(end 346.6084 -173.4566)
		(width 0.127)
		(layer "In5.Cu")
		(net "BMC_USB1_HDN")
	)
	(segment
		(start 303.024794 -175.008794)
		(end 303.024794 -174.113444)
		(width 0.127)
		(layer "In5.Cu")
		(net "BMC_USB1_HDN")
	)
	(segment
		(start 350.393 -152.3746)
		(end 348.8944 -152.3746)
		(width 0.127)
		(layer "In5.Cu")
		(net "BMC_USB1_HDN")
	)
	(segment
		(start 348.8944 -152.3746)
		(end 347.345 -153.924)
		(width 0.127)
		(layer "In5.Cu")
		(net "BMC_USB1_HDN")
	)
	(segment
		(start 332.116176 -176.5046)
		(end 326.759824 -176.5046)
		(width 0.127)
		(layer "In5.Cu")
		(net "BMC_USB1_HDN")
	)
	(segment
		(start 326.759824 -176.5046)
		(end 325.616824 -175.3616)
		(width 0.127)
		(layer "In5.Cu")
		(net "BMC_USB1_HDN")
	)
	(segment
		(start 310.758078 -176.644554)
		(end 309.449724 -175.3362)
		(width 0.127)
		(layer "In5.Cu")
		(net "BMC_USB1_HDN")
	)
	(segment
		(start 309.10403 -175.335946)
		(end 309.103776 -175.3362)
		(width 0.127)
		(layer "In5.Cu")
		(net "BMC_USB1_HDN")
	)
	(segment
		(start 347.345 -153.924)
		(end 347.345 -160.528)
		(width 0.127)
		(layer "In5.Cu")
		(net "BMC_USB1_HDN")
	)
	(segment
		(start 309.103776 -175.3362)
		(end 303.3522 -175.3362)
		(width 0.127)
		(layer "In5.Cu")
		(net "BMC_USB1_HDN")
	)
	(segment
		(start 347.345 -160.528)
		(end 349.758 -162.941)
		(width 0.127)
		(layer "In5.Cu")
		(net "BMC_USB1_HDN")
	)
	(segment
		(start 317.639446 -176.644554)
		(end 310.758078 -176.644554)
		(width 0.127)
		(layer "In5.Cu")
		(net "BMC_USB1_HDN")
	)
	(segment
		(start 309.218584 -175.335946)
		(end 309.10403 -175.335946)
		(width 0.127)
		(layer "In5.Cu")
		(net "BMC_USB1_HDN")
	)
	(segment
		(start 346.6084 -173.4566)
		(end 335.164176 -173.4566)
		(width 0.127)
		(layer "In5.Cu")
		(net "BMC_USB1_HDN")
	)
	(segment
		(start 309.449724 -175.3362)
		(end 309.218838 -175.3362)
		(width 0.127)
		(layer "In5.Cu")
		(net "BMC_USB1_HDN")
	)
	(segment
		(start 335.164176 -173.4566)
		(end 332.116176 -176.5046)
		(width 0.127)
		(layer "In5.Cu")
		(net "BMC_USB1_HDN")
	)
	(segment
		(start 350.75495 -152.01265)
		(end 350.393 -152.3746)
		(width 0.127)
		(layer "In5.Cu")
		(net "BMC_USB1_HDN")
	)
	(segment
		(start 318.9224 -175.3616)
		(end 317.639446 -176.644554)
		(width 0.127)
		(layer "In5.Cu")
		(net "BMC_USB1_HDN")
	)
	(segment
		(start 350.75495 -151.97201)
		(end 350.75495 -152.01265)
		(width 0.127)
		(layer "In5.Cu")
		(net "BMC_USB1_HDN")
	)
	(segment
		(start 325.616824 -175.3616)
		(end 318.9224 -175.3616)
		(width 0.127)
		(layer "In5.Cu")
		(net "BMC_USB1_HDN")
	)
	(segment
		(start 303.3522 -175.3362)
		(end 303.024794 -175.008794)
		(width 0.127)
		(layer "In5.Cu")
		(net "BMC_USB1_HDN")
	)
	(segment
		(start 349.758 -162.941)
		(end 349.758 -170.307)
		(width 0.127)
		(layer "In5.Cu")
		(net "BMC_USB1_HDN")
	)
	(segment
		(start 302.141382 -173.84014)
		(end 302.23206 -173.749462)
		(width 0.1397)
		(layer "F.Cu")
		(net "BMC_USB1_HDP")
	)
	(segment
		(start 350.45396 -152.6159)
		(end 350.75495 -152.91689)
		(width 0.1397)
		(layer "F.Cu")
		(net "BMC_USB1_HDP")
	)
	(segment
		(start 301.634906 -173.84014)
		(end 302.141382 -173.84014)
		(width 0.1397)
		(layer "F.Cu")
		(net "BMC_USB1_HDP")
	)
	(segment
		(start 349.231966 -152.6159)
		(end 350.45396 -152.6159)
		(width 0.1397)
		(layer "F.Cu")
		(net "BMC_USB1_HDP")
	)
	(segment
		(start 348.835218 -153.012648)
		(end 349.231966 -152.6159)
		(width 0.1397)
		(layer "F.Cu")
		(net "BMC_USB1_HDP")
	)
	(via
		(at 302.23206 -173.749462)
		(size 0.5588)
		(drill 0.3048)
		(layers "F.Cu" "B.Cu")
		(net "BMC_USB1_HDP")
	)
	(via
		(at 350.75495 -152.91689)
		(size 0.508)
		(drill 0.254)
		(layers "F.Cu" "B.Cu")
		(net "BMC_USB1_HDP")
	)
	(segment
		(start 347.6244 -154.039824)
		(end 347.6244 -160.412176)
		(width 0.127)
		(layer "In5.Cu")
		(net "BMC_USB1_HDP")
	)
	(segment
		(start 302.244252 -174.011082)
		(end 302.23206 -173.749462)
		(width 0.127)
		(layer "In5.Cu")
		(net "BMC_USB1_HDP")
	)
	(segment
		(start 350.18726 -167.888666)
		(end 350.18726 -168.269666)
		(width 0.127)
		(layer "In5.Cu")
		(net "BMC_USB1_HDP")
	)
	(segment
		(start 314.337954 -176.923954)
		(end 314.188094 -177.073814)
		(width 0.127)
		(layer "In5.Cu")
		(net "BMC_USB1_HDP")
	)
	(segment
		(start 315.930534 -177.073814)
		(end 315.780674 -176.923954)
		(width 0.127)
		(layer "In5.Cu")
		(net "BMC_USB1_HDP")
	)
	(segment
		(start 309.3339 -175.6156)
		(end 303.236376 -175.6156)
		(width 0.127)
		(layer "In5.Cu")
		(net "BMC_USB1_HDP")
	)
	(segment
		(start 349.010224 -152.654)
		(end 347.6244 -154.039824)
		(width 0.127)
		(layer "In5.Cu")
		(net "BMC_USB1_HDP")
	)
	(segment
		(start 313.807094 -177.073814)
		(end 313.657234 -176.923954)
		(width 0.127)
		(layer "In5.Cu")
		(net "BMC_USB1_HDP")
	)
	(segment
		(start 302.745394 -174.512224)
		(end 302.244252 -174.011082)
		(width 0.127)
		(layer "In5.Cu")
		(net "BMC_USB1_HDP")
	)
	(segment
		(start 313.657234 -176.923954)
		(end 312.851038 -176.923954)
		(width 0.127)
		(layer "In5.Cu")
		(net "BMC_USB1_HDP")
	)
	(segment
		(start 350.0374 -168.800526)
		(end 350.18726 -168.950386)
		(width 0.127)
		(layer "In5.Cu")
		(net "BMC_USB1_HDP")
	)
	(segment
		(start 310.642254 -176.923954)
		(end 309.3339 -175.6156)
		(width 0.127)
		(layer "In5.Cu")
		(net "BMC_USB1_HDP")
	)
	(segment
		(start 303.236376 -175.6156)
		(end 302.745394 -175.124618)
		(width 0.127)
		(layer "In5.Cu")
		(net "BMC_USB1_HDP")
	)
	(segment
		(start 350.0374 -169.481246)
		(end 350.0374 -170.422824)
		(width 0.127)
		(layer "In5.Cu")
		(net "BMC_USB1_HDP")
	)
	(segment
		(start 350.18726 -166.826946)
		(end 350.18726 -167.207946)
		(width 0.127)
		(layer "In5.Cu")
		(net "BMC_USB1_HDP")
	)
	(segment
		(start 326.644 -176.784)
		(end 325.501 -175.641)
		(width 0.127)
		(layer "In5.Cu")
		(net "BMC_USB1_HDP")
	)
	(segment
		(start 312.851038 -176.923954)
		(end 312.701178 -177.073814)
		(width 0.127)
		(layer "In5.Cu")
		(net "BMC_USB1_HDP")
	)
	(segment
		(start 350.0374 -162.825176)
		(end 350.0374 -166.677086)
		(width 0.127)
		(layer "In5.Cu")
		(net "BMC_USB1_HDP")
	)
	(segment
		(start 316.461394 -176.923954)
		(end 316.311534 -177.073814)
		(width 0.127)
		(layer "In5.Cu")
		(net "BMC_USB1_HDP")
	)
	(segment
		(start 350.75495 -152.91689)
		(end 350.49206 -152.654)
		(width 0.127)
		(layer "In5.Cu")
		(net "BMC_USB1_HDP")
	)
	(segment
		(start 317.75527 -176.923954)
		(end 316.461394 -176.923954)
		(width 0.127)
		(layer "In5.Cu")
		(net "BMC_USB1_HDP")
	)
	(segment
		(start 341.277194 -173.736)
		(end 340.896194 -173.736)
		(width 0.127)
		(layer "In5.Cu")
		(net "BMC_USB1_HDP")
	)
	(segment
		(start 349.360236 -171.099988)
		(end 349.360236 -171.312078)
		(width 0.127)
		(layer "In5.Cu")
		(net "BMC_USB1_HDP")
	)
	(segment
		(start 348.878906 -171.581318)
		(end 346.724224 -173.736)
		(width 0.127)
		(layer "In5.Cu")
		(net "BMC_USB1_HDP")
	)
	(segment
		(start 314.868814 -177.073814)
		(end 314.718954 -176.923954)
		(width 0.127)
		(layer "In5.Cu")
		(net "BMC_USB1_HDP")
	)
	(segment
		(start 350.0374 -170.422824)
		(end 349.360236 -171.099988)
		(width 0.127)
		(layer "In5.Cu")
		(net "BMC_USB1_HDP")
	)
	(segment
		(start 350.49206 -152.654)
		(end 349.010224 -152.654)
		(width 0.127)
		(layer "In5.Cu")
		(net "BMC_USB1_HDP")
	)
	(segment
		(start 342.338914 -173.736)
		(end 341.957914 -173.736)
		(width 0.127)
		(layer "In5.Cu")
		(net "BMC_USB1_HDP")
	)
	(segment
		(start 342.488774 -173.88586)
		(end 342.338914 -173.736)
		(width 0.127)
		(layer "In5.Cu")
		(net "BMC_USB1_HDP")
	)
	(segment
		(start 349.360236 -171.312078)
		(end 349.090742 -171.581318)
		(width 0.127)
		(layer "In5.Cu")
		(net "BMC_USB1_HDP")
	)
	(segment
		(start 314.188094 -177.073814)
		(end 313.807094 -177.073814)
		(width 0.127)
		(layer "In5.Cu")
		(net "BMC_USB1_HDP")
	)
	(segment
		(start 302.745394 -175.124618)
		(end 302.745394 -174.512224)
		(width 0.127)
		(layer "In5.Cu")
		(net "BMC_USB1_HDP")
	)
	(segment
		(start 350.18726 -169.331386)
		(end 350.0374 -169.481246)
		(width 0.127)
		(layer "In5.Cu")
		(net "BMC_USB1_HDP")
	)
	(segment
		(start 312.320178 -177.073814)
		(end 312.170318 -176.923954)
		(width 0.127)
		(layer "In5.Cu")
		(net "BMC_USB1_HDP")
	)
	(segment
		(start 350.18726 -167.207946)
		(end 350.0374 -167.357806)
		(width 0.127)
		(layer "In5.Cu")
		(net "BMC_USB1_HDP")
	)
	(segment
		(start 335.28 -173.736)
		(end 332.232 -176.784)
		(width 0.127)
		(layer "In5.Cu")
		(net "BMC_USB1_HDP")
	)
	(segment
		(start 350.18726 -168.269666)
		(end 350.0374 -168.419526)
		(width 0.127)
		(layer "In5.Cu")
		(net "BMC_USB1_HDP")
	)
	(segment
		(start 314.718954 -176.923954)
		(end 314.337954 -176.923954)
		(width 0.127)
		(layer "In5.Cu")
		(net "BMC_USB1_HDP")
	)
	(segment
		(start 343.019634 -173.736)
		(end 342.869774 -173.88586)
		(width 0.127)
		(layer "In5.Cu")
		(net "BMC_USB1_HDP")
	)
	(segment
		(start 342.869774 -173.88586)
		(end 342.488774 -173.88586)
		(width 0.127)
		(layer "In5.Cu")
		(net "BMC_USB1_HDP")
	)
	(segment
		(start 315.249814 -177.073814)
		(end 314.868814 -177.073814)
		(width 0.127)
		(layer "In5.Cu")
		(net "BMC_USB1_HDP")
	)
	(segment
		(start 312.170318 -176.923954)
		(end 310.642254 -176.923954)
		(width 0.127)
		(layer "In5.Cu")
		(net "BMC_USB1_HDP")
	)
	(segment
		(start 341.808054 -173.88586)
		(end 341.427054 -173.88586)
		(width 0.127)
		(layer "In5.Cu")
		(net "BMC_USB1_HDP")
	)
	(segment
		(start 315.780674 -176.923954)
		(end 315.399674 -176.923954)
		(width 0.127)
		(layer "In5.Cu")
		(net "BMC_USB1_HDP")
	)
	(segment
		(start 332.232 -176.784)
		(end 326.644 -176.784)
		(width 0.127)
		(layer "In5.Cu")
		(net "BMC_USB1_HDP")
	)
	(segment
		(start 315.399674 -176.923954)
		(end 315.249814 -177.073814)
		(width 0.127)
		(layer "In5.Cu")
		(net "BMC_USB1_HDP")
	)
	(segment
		(start 340.215474 -173.736)
		(end 335.28 -173.736)
		(width 0.127)
		(layer "In5.Cu")
		(net "BMC_USB1_HDP")
	)
	(segment
		(start 316.311534 -177.073814)
		(end 315.930534 -177.073814)
		(width 0.127)
		(layer "In5.Cu")
		(net "BMC_USB1_HDP")
	)
	(segment
		(start 350.0374 -167.738806)
		(end 350.18726 -167.888666)
		(width 0.127)
		(layer "In5.Cu")
		(net "BMC_USB1_HDP")
	)
	(segment
		(start 346.724224 -173.736)
		(end 343.019634 -173.736)
		(width 0.127)
		(layer "In5.Cu")
		(net "BMC_USB1_HDP")
	)
	(segment
		(start 341.427054 -173.88586)
		(end 341.277194 -173.736)
		(width 0.127)
		(layer "In5.Cu")
		(net "BMC_USB1_HDP")
	)
	(segment
		(start 341.957914 -173.736)
		(end 341.808054 -173.88586)
		(width 0.127)
		(layer "In5.Cu")
		(net "BMC_USB1_HDP")
	)
	(segment
		(start 325.501 -175.641)
		(end 319.038224 -175.641)
		(width 0.127)
		(layer "In5.Cu")
		(net "BMC_USB1_HDP")
	)
	(segment
		(start 319.038224 -175.641)
		(end 317.75527 -176.923954)
		(width 0.127)
		(layer "In5.Cu")
		(net "BMC_USB1_HDP")
	)
	(segment
		(start 349.090742 -171.581318)
		(end 348.878906 -171.581318)
		(width 0.127)
		(layer "In5.Cu")
		(net "BMC_USB1_HDP")
	)
	(segment
		(start 350.18726 -168.950386)
		(end 350.18726 -169.331386)
		(width 0.127)
		(layer "In5.Cu")
		(net "BMC_USB1_HDP")
	)
	(segment
		(start 347.6244 -160.412176)
		(end 350.0374 -162.825176)
		(width 0.127)
		(layer "In5.Cu")
		(net "BMC_USB1_HDP")
	)
	(segment
		(start 340.746334 -173.88586)
		(end 340.365334 -173.88586)
		(width 0.127)
		(layer "In5.Cu")
		(net "BMC_USB1_HDP")
	)
	(segment
		(start 340.896194 -173.736)
		(end 340.746334 -173.88586)
		(width 0.127)
		(layer "In5.Cu")
		(net "BMC_USB1_HDP")
	)
	(segment
		(start 350.0374 -166.677086)
		(end 350.18726 -166.826946)
		(width 0.127)
		(layer "In5.Cu")
		(net "BMC_USB1_HDP")
	)
	(segment
		(start 312.701178 -177.073814)
		(end 312.320178 -177.073814)
		(width 0.127)
		(layer "In5.Cu")
		(net "BMC_USB1_HDP")
	)
	(segment
		(start 350.0374 -167.357806)
		(end 350.0374 -167.738806)
		(width 0.127)
		(layer "In5.Cu")
		(net "BMC_USB1_HDP")
	)
	(segment
		(start 350.0374 -168.419526)
		(end 350.0374 -168.800526)
		(width 0.127)
		(layer "In5.Cu")
		(net "BMC_USB1_HDP")
	)
	(segment
		(start 340.365334 -173.88586)
		(end 340.215474 -173.736)
		(width 0.127)
		(layer "In5.Cu")
		(net "BMC_USB1_HDP")
	)
	(segment
		(start 349.247206 -154.88666)
		(end 349.742506 -154.88666)
		(width 0.1397)
		(layer "F.Cu")
		(net "BMC_USB1_HDP2")
	)
	(segment
		(start 299.23486 -174.64024)
		(end 299.244258 -174.64024)
		(width 0.1397)
		(layer "F.Cu")
		(net "BMC_USB1_HDP2")
	)
	(segment
		(start 299.244258 -174.64024)
		(end 299.638212 -175.034194)
		(width 0.1397)
		(layer "F.Cu")
		(net "BMC_USB1_HDP2")
	)
	(segment
		(start 348.835218 -155.298648)
		(end 349.247206 -154.88666)
		(width 0.1397)
		(layer "F.Cu")
		(net "BMC_USB1_HDP2")
	)
	(segment
		(start 349.742506 -154.88666)
		(end 350.010984 -155.155138)
		(width 0.1397)
		(layer "F.Cu")
		(net "BMC_USB1_HDP2")
	)
	(via
		(at 299.638212 -175.034194)
		(size 0.508)
		(drill 0.254)
		(layers "F.Cu" "B.Cu")
		(net "BMC_USB1_HDP2")
	)
	(via
		(at 350.010984 -155.155138)
		(size 0.508)
		(drill 0.254)
		(layers "F.Cu" "B.Cu")
		(net "BMC_USB1_HDP2")
	)
	(segment
		(start 335.6356 -175.1584)
		(end 332.613 -178.181)
		(width 0.127)
		(layer "In5.Cu")
		(net "BMC_USB1_HDP2")
	)
	(segment
		(start 321.183 -176.911)
		(end 319.673224 -176.911)
		(width 0.127)
		(layer "In5.Cu")
		(net "BMC_USB1_HDP2")
	)
	(segment
		(start 348.8944 -155.309824)
		(end 348.8944 -159.650176)
		(width 0.127)
		(layer "In5.Cu")
		(net "BMC_USB1_HDP2")
	)
	(segment
		(start 348.8944 -159.650176)
		(end 351.5614 -162.317176)
		(width 0.127)
		(layer "In5.Cu")
		(net "BMC_USB1_HDP2")
	)
	(segment
		(start 347.714824 -175.1584)
		(end 335.6356 -175.1584)
		(width 0.127)
		(layer "In5.Cu")
		(net "BMC_USB1_HDP2")
	)
	(segment
		(start 351.5614 -162.317176)
		(end 351.5614 -171.311824)
		(width 0.127)
		(layer "In5.Cu")
		(net "BMC_USB1_HDP2")
	)
	(segment
		(start 319.673224 -176.911)
		(end 318.022224 -178.562)
		(width 0.127)
		(layer "In5.Cu")
		(net "BMC_USB1_HDP2")
	)
	(segment
		(start 318.022224 -178.562)
		(end 310.51754 -178.562)
		(width 0.127)
		(layer "In5.Cu")
		(net "BMC_USB1_HDP2")
	)
	(segment
		(start 349.365824 -154.8384)
		(end 348.8944 -155.309824)
		(width 0.127)
		(layer "In5.Cu")
		(net "BMC_USB1_HDP2")
	)
	(segment
		(start 301.267114 -175.745394)
		(end 300.349412 -175.745394)
		(width 0.127)
		(layer "In5.Cu")
		(net "BMC_USB1_HDP2")
	)
	(segment
		(start 300.349412 -175.745394)
		(end 299.638212 -175.034194)
		(width 0.127)
		(layer "In5.Cu")
		(net "BMC_USB1_HDP2")
	)
	(segment
		(start 350.010984 -155.155138)
		(end 349.694246 -154.8384)
		(width 0.127)
		(layer "In5.Cu")
		(net "BMC_USB1_HDP2")
	)
	(segment
		(start 322.453 -178.181)
		(end 321.183 -176.911)
		(width 0.127)
		(layer "In5.Cu")
		(net "BMC_USB1_HDP2")
	)
	(segment
		(start 308.73954 -176.784)
		(end 302.30572 -176.784)
		(width 0.127)
		(layer "In5.Cu")
		(net "BMC_USB1_HDP2")
	)
	(segment
		(start 332.613 -178.181)
		(end 322.453 -178.181)
		(width 0.127)
		(layer "In5.Cu")
		(net "BMC_USB1_HDP2")
	)
	(segment
		(start 351.5614 -171.311824)
		(end 347.714824 -175.1584)
		(width 0.127)
		(layer "In5.Cu")
		(net "BMC_USB1_HDP2")
	)
	(segment
		(start 310.51754 -178.562)
		(end 308.73954 -176.784)
		(width 0.127)
		(layer "In5.Cu")
		(net "BMC_USB1_HDP2")
	)
	(segment
		(start 302.30572 -176.784)
		(end 301.267114 -175.745394)
		(width 0.127)
		(layer "In5.Cu")
		(net "BMC_USB1_HDP2")
	)
	(segment
		(start 349.694246 -154.8384)
		(end 349.365824 -154.8384)
		(width 0.127)
		(layer "In5.Cu")
		(net "BMC_USB1_HDP2")
	)
	(segment
		(start 336.312764 -153.393648)
		(end 336.318352 -153.393648)
		(width 0.1143)
		(layer "F.Cu")
		(net "USB_OCS_N4")
	)
	(segment
		(start 336.318352 -153.393648)
		(end 336.7786 -152.9334)
		(width 0.1143)
		(layer "F.Cu")
		(net "USB_OCS_N4")
	)
	(segment
		(start 336.7786 -152.9334)
		(end 336.7786 -152.927812)
		(width 0.1143)
		(layer "F.Cu")
		(net "USB_OCS_N4")
	)
	(segment
		(start 335.296764 -154.409648)
		(end 336.312764 -153.393648)
		(width 0.1143)
		(layer "F.Cu")
		(net "USB_OCS_N4")
	)
	(segment
		(start 336.7786 -152.927812)
		(end 337.979766 -151.726646)
		(width 0.1143)
		(layer "F.Cu")
		(net "USB_OCS_N4")
	)
	(segment
		(start 334.357218 -154.409648)
		(end 335.296764 -154.409648)
		(width 0.1143)
		(layer "F.Cu")
		(net "USB_OCS_N4")
	)
	(segment
		(start 337.979766 -151.726646)
		(end 338.662518 -151.726646)
		(width 0.1143)
		(layer "F.Cu")
		(net "USB_OCS_N4")
	)
	(via
		(at 336.7786 -152.9334)
		(size 0.7112)
		(drill 0.3556)
		(layers "F.Cu" "B.Cu")
		(net "USB_OCS_N4")
	)
	(via
		(at 81.915 -75.692)
		(size 0.7112)
		(drill 0.3556)
		(layers "F.Cu" "B.Cu")
		(net "P0V955_C_PG_R")
	)
	(segment
		(start 79.248 -74.3585)
		(end 79.248 -75.057)
		(width 0.254)
		(layer "B.Cu")
		(net "P0V955_C_PG_R")
	)
	(segment
		(start 85.2805 -74.1045)
		(end 85.2805 -74.041)
		(width 0.254)
		(layer "B.Cu")
		(net "P0V955_C_PG_R")
	)
	(segment
		(start 79.883 -75.692)
		(end 81.915 -75.692)
		(width 0.254)
		(layer "B.Cu")
		(net "P0V955_C_PG_R")
	)
	(segment
		(start 84.6455 -74.7395)
		(end 85.2805 -74.1045)
		(width 0.254)
		(layer "B.Cu")
		(net "P0V955_C_PG_R")
	)
	(segment
		(start 83.693 -74.7395)
		(end 84.6455 -74.7395)
		(width 0.254)
		(layer "B.Cu")
		(net "P0V955_C_PG_R")
	)
	(segment
		(start 81.915 -75.692)
		(end 82.7405 -75.692)
		(width 0.254)
		(layer "B.Cu")
		(net "P0V955_C_PG_R")
	)
	(segment
		(start 79.248 -75.057)
		(end 79.883 -75.692)
		(width 0.254)
		(layer "B.Cu")
		(net "P0V955_C_PG_R")
	)
	(segment
		(start 82.7405 -75.692)
		(end 83.693 -74.7395)
		(width 0.254)
		(layer "B.Cu")
		(net "P0V955_C_PG_R")
	)
	(segment
		(start 335.182718 -157.584648)
		(end 335.182718 -156.416248)
		(width 0.1143)
		(layer "F.Cu")
		(net "USB_OCS_N3")
	)
	(segment
		(start 338.573618 -152.726644)
		(end 338.573618 -153.025348)
		(width 0.1143)
		(layer "F.Cu")
		(net "USB_OCS_N3")
	)
	(segment
		(start 335.182718 -156.416248)
		(end 335.690718 -155.908248)
		(width 0.1143)
		(layer "F.Cu")
		(net "USB_OCS_N3")
	)
	(segment
		(start 334.357218 -157.838648)
		(end 334.928718 -157.838648)
		(width 0.1143)
		(layer "F.Cu")
		(net "USB_OCS_N3")
	)
	(segment
		(start 338.573618 -153.025348)
		(end 335.690718 -155.908248)
		(width 0.1143)
		(layer "F.Cu")
		(net "USB_OCS_N3")
	)
	(segment
		(start 334.928718 -157.838648)
		(end 335.182718 -157.584648)
		(width 0.1143)
		(layer "F.Cu")
		(net "USB_OCS_N3")
	)
	(via
		(at 335.690718 -155.908248)
		(size 0.7112)
		(drill 0.3556)
		(layers "F.Cu" "B.Cu")
		(net "USB_OCS_N3")
	)
	(segment
		(start 340.032594 -154.673554)
		(end 338.933536 -155.772612)
		(width 0.1143)
		(layer "F.Cu")
		(net "USB_OCS_N2")
	)
	(segment
		(start 340.032594 -153.596848)
		(end 340.032594 -154.673554)
		(width 0.1143)
		(layer "F.Cu")
		(net "USB_OCS_N2")
	)
	(segment
		(start 338.357718 -157.140148)
		(end 338.357718 -156.34843)
		(width 0.1143)
		(layer "F.Cu")
		(net "USB_OCS_N2")
	)
	(segment
		(start 338.357718 -156.34843)
		(end 338.933536 -155.772612)
		(width 0.1143)
		(layer "F.Cu")
		(net "USB_OCS_N2")
	)
	(via
		(at 338.933536 -155.772612)
		(size 0.7112)
		(drill 0.3556)
		(layers "F.Cu" "B.Cu")
		(net "USB_OCS_N2")
	)
	(segment
		(start 257.302 -23.241)
		(end 258.191 -22.352)
		(width 0.1143)
		(layer "F.Cu")
		(net "USB_OCS_N1")
	)
	(segment
		(start 256.921 -44.323)
		(end 256.921 -23.622)
		(width 0.1143)
		(layer "F.Cu")
		(net "USB_OCS_N1")
	)
	(segment
		(start 342.032844 -154.782774)
		(end 342.294718 -155.044648)
		(width 0.1143)
		(layer "F.Cu")
		(net "USB_OCS_N1")
	)
	(segment
		(start 256.921 -23.622)
		(end 257.302 -23.241)
		(width 0.1143)
		(layer "F.Cu")
		(net "USB_OCS_N1")
	)
	(segment
		(start 263.525 -48.768)
		(end 262.89 -48.133)
		(width 0.1143)
		(layer "F.Cu")
		(net "USB_OCS_N1")
	)
	(segment
		(start 272.373598 -163.957)
		(end 270.31315 -161.896552)
		(width 0.1143)
		(layer "F.Cu")
		(net "USB_OCS_N1")
	)
	(segment
		(start 260.731 -48.133)
		(end 256.921 -44.323)
		(width 0.1143)
		(layer "F.Cu")
		(net "USB_OCS_N1")
	)
	(segment
		(start 331.3938 -136.144)
		(end 331.1398 -135.89)
		(width 0.1143)
		(layer "F.Cu")
		(net "USB_OCS_N1")
	)
	(segment
		(start 270.31315 -161.896552)
		(end 270.31315 -160.33242)
		(width 0.1143)
		(layer "F.Cu")
		(net "USB_OCS_N1")
	)
	(segment
		(start 265.2141 -50.58283)
		(end 263.525 -48.89373)
		(width 0.1143)
		(layer "F.Cu")
		(net "USB_OCS_N1")
	)
	(segment
		(start 258.191 -22.352)
		(end 258.191 -22.225)
		(width 0.1143)
		(layer "F.Cu")
		(net "USB_OCS_N1")
	)
	(segment
		(start 273.3675 -163.957)
		(end 272.373598 -163.957)
		(width 0.1143)
		(layer "F.Cu")
		(net "USB_OCS_N1")
	)
	(segment
		(start 262.89 -48.133)
		(end 260.731 -48.133)
		(width 0.1143)
		(layer "F.Cu")
		(net "USB_OCS_N1")
	)
	(segment
		(start 273.7485 -163.576)
		(end 273.3675 -163.957)
		(width 0.1143)
		(layer "F.Cu")
		(net "USB_OCS_N1")
	)
	(segment
		(start 263.525 -56.955436)
		(end 265.2141 -55.266336)
		(width 0.1143)
		(layer "F.Cu")
		(net "USB_OCS_N1")
	)
	(segment
		(start 263.525 -57.277)
		(end 263.525 -56.955436)
		(width 0.1143)
		(layer "F.Cu")
		(net "USB_OCS_N1")
	)
	(segment
		(start 317.442342 -140.011658)
		(end 317.442342 -140.081)
		(width 0.1143)
		(layer "F.Cu")
		(net "USB_OCS_N1")
	)
	(segment
		(start 263.525 -48.89373)
		(end 263.525 -48.768)
		(width 0.1143)
		(layer "F.Cu")
		(net "USB_OCS_N1")
	)
	(segment
		(start 270.31315 -160.33242)
		(end 269.98676 -160.00603)
		(width 0.1143)
		(layer "F.Cu")
		(net "USB_OCS_N1")
	)
	(segment
		(start 321.564 -135.89)
		(end 317.442342 -140.011658)
		(width 0.1143)
		(layer "F.Cu")
		(net "USB_OCS_N1")
	)
	(segment
		(start 342.032844 -153.596848)
		(end 342.032844 -154.782774)
		(width 0.1143)
		(layer "F.Cu")
		(net "USB_OCS_N1")
	)
	(segment
		(start 265.2141 -55.266336)
		(end 265.2141 -50.58283)
		(width 0.1143)
		(layer "F.Cu")
		(net "USB_OCS_N1")
	)
	(segment
		(start 331.1398 -135.89)
		(end 321.564 -135.89)
		(width 0.1143)
		(layer "F.Cu")
		(net "USB_OCS_N1")
	)
	(via
		(at 257.302 -23.241)
		(size 0.7112)
		(drill 0.3556)
		(layers "F.Cu" "B.Cu")
		(net "USB_OCS_N1")
	)
	(via
		(at 285.579058 -118.209314)
		(size 0.5588)
		(drill 0.3048)
		(layers "F.Cu" "B.Cu")
		(net "USB_OCS_N1")
	)
	(via
		(at 258.191 -22.225)
		(size 0.5588)
		(drill 0.3048)
		(layers "F.Cu" "B.Cu")
		(net "USB_OCS_N1")
	)
	(via
		(at 342.294718 -155.044648)
		(size 0.5588)
		(drill 0.3048)
		(layers "F.Cu" "B.Cu")
		(net "USB_OCS_N1")
	)
	(via
		(at 317.442342 -140.081)
		(size 0.508)
		(drill 0.254)
		(layers "F.Cu" "B.Cu")
		(net "USB_OCS_N1")
	)
	(via
		(at 269.98676 -160.00603)
		(size 0.508)
		(drill 0.254)
		(layers "F.Cu" "B.Cu")
		(net "USB_OCS_N1")
	)
	(via
		(at 331.3938 -136.144)
		(size 0.5588)
		(drill 0.3048)
		(layers "F.Cu" "B.Cu")
		(net "USB_OCS_N1")
	)
	(via
		(at 263.525 -57.277)
		(size 0.5588)
		(drill 0.3048)
		(layers "F.Cu" "B.Cu")
		(net "USB_OCS_N1")
	)
	(segment
		(start 256.6035 -16.891)
		(end 256.794 -16.7005)
		(width 0.1143)
		(layer "B.Cu")
		(net "USB_OCS_N1")
	)
	(segment
		(start 256.09804 -13.40104)
		(end 256.09804 -12.827)
		(width 0.1143)
		(layer "B.Cu")
		(net "USB_OCS_N1")
	)
	(segment
		(start 256.794 -16.7005)
		(end 256.794 -14.097)
		(width 0.1143)
		(layer "B.Cu")
		(net "USB_OCS_N1")
	)
	(segment
		(start 258.191 -20.32)
		(end 258.191 -22.225)
		(width 0.1143)
		(layer "B.Cu")
		(net "USB_OCS_N1")
	)
	(segment
		(start 256.6035 -16.891)
		(end 256.6035 -17.907)
		(width 0.1143)
		(layer "B.Cu")
		(net "USB_OCS_N1")
	)
	(segment
		(start 256.667 -18.9865)
		(end 256.8575 -18.9865)
		(width 0.1143)
		(layer "B.Cu")
		(net "USB_OCS_N1")
	)
	(segment
		(start 256.6035 -17.907)
		(end 256.667 -17.9705)
		(width 0.1143)
		(layer "B.Cu")
		(net "USB_OCS_N1")
	)
	(segment
		(start 256.8575 -18.9865)
		(end 258.191 -20.32)
		(width 0.1143)
		(layer "B.Cu")
		(net "USB_OCS_N1")
	)
	(segment
		(start 256.667 -17.9705)
		(end 256.667 -18.9865)
		(width 0.1143)
		(layer "B.Cu")
		(net "USB_OCS_N1")
	)
	(segment
		(start 256.794 -14.097)
		(end 256.09804 -13.40104)
		(width 0.1143)
		(layer "B.Cu")
		(net "USB_OCS_N1")
	)
	(segment
		(start 317.373 -140.011658)
		(end 317.373 -139.573)
		(width 0.127)
		(layer "In2.Cu")
		(net "USB_OCS_N1")
	)
	(segment
		(start 309.827168 -134.112)
		(end 309.826914 -134.111746)
		(width 0.127)
		(layer "In2.Cu")
		(net "USB_OCS_N1")
	)
	(segment
		(start 283.94279 -146.05)
		(end 269.98676 -160.00603)
		(width 0.127)
		(layer "In2.Cu")
		(net "USB_OCS_N1")
	)
	(segment
		(start 267.462 -79.756)
		(end 267.462 -72.898)
		(width 0.127)
		(layer "In2.Cu")
		(net "USB_OCS_N1")
	)
	(segment
		(start 269.2273 -92.583)
		(end 269.2273 -81.5213)
		(width 0.127)
		(layer "In2.Cu")
		(net "USB_OCS_N1")
	)
	(segment
		(start 309.826914 -134.111746)
		(end 303.783746 -134.111746)
		(width 0.127)
		(layer "In2.Cu")
		(net "USB_OCS_N1")
	)
	(segment
		(start 285.579058 -118.209314)
		(end 280.272744 -112.903)
		(width 0.127)
		(layer "In2.Cu")
		(net "USB_OCS_N1")
	)
	(segment
		(start 312.1787 -134.3787)
		(end 311.912 -134.112)
		(width 0.127)
		(layer "In2.Cu")
		(net "USB_OCS_N1")
	)
	(segment
		(start 263.525 -62.080648)
		(end 263.525 -57.277)
		(width 0.127)
		(layer "In2.Cu")
		(net "USB_OCS_N1")
	)
	(segment
		(start 297.110912 -142.50035)
		(end 288.357818 -142.50035)
		(width 0.127)
		(layer "In2.Cu")
		(net "USB_OCS_N1")
	)
	(segment
		(start 288.357818 -142.50035)
		(end 288.110168 -142.2527)
		(width 0.127)
		(layer "In2.Cu")
		(net "USB_OCS_N1")
	)
	(segment
		(start 269.2273 -81.5213)
		(end 267.462 -79.756)
		(width 0.127)
		(layer "In2.Cu")
		(net "USB_OCS_N1")
	)
	(segment
		(start 298.653454 -136.806432)
		(end 298.653454 -140.957808)
		(width 0.127)
		(layer "In2.Cu")
		(net "USB_OCS_N1")
	)
	(segment
		(start 268.939264 -110.959646)
		(end 268.939264 -92.871036)
		(width 0.127)
		(layer "In2.Cu")
		(net "USB_OCS_N1")
	)
	(segment
		(start 311.912 -134.112)
		(end 309.827168 -134.112)
		(width 0.127)
		(layer "In2.Cu")
		(net "USB_OCS_N1")
	)
	(segment
		(start 313.837828 -136.037828)
		(end 313.837828 -135.50773)
		(width 0.127)
		(layer "In2.Cu")
		(net "USB_OCS_N1")
	)
	(segment
		(start 303.783746 -134.111746)
		(end 303.276 -133.604)
		(width 0.127)
		(layer "In2.Cu")
		(net "USB_OCS_N1")
	)
	(segment
		(start 287.322768 -142.2527)
		(end 283.94279 -145.632678)
		(width 0.127)
		(layer "In2.Cu")
		(net "USB_OCS_N1")
	)
	(segment
		(start 270.882618 -112.903)
		(end 268.939264 -110.959646)
		(width 0.127)
		(layer "In2.Cu")
		(net "USB_OCS_N1")
	)
	(segment
		(start 303.276 -133.604)
		(end 301.855886 -133.604)
		(width 0.127)
		(layer "In2.Cu")
		(net "USB_OCS_N1")
	)
	(segment
		(start 264.2235 -69.6595)
		(end 264.2235 -62.779148)
		(width 0.127)
		(layer "In2.Cu")
		(net "USB_OCS_N1")
	)
	(segment
		(start 283.94279 -145.632678)
		(end 283.94279 -146.05)
		(width 0.127)
		(layer "In2.Cu")
		(net "USB_OCS_N1")
	)
	(segment
		(start 317.373 -139.573)
		(end 313.837828 -136.037828)
		(width 0.127)
		(layer "In2.Cu")
		(net "USB_OCS_N1")
	)
	(segment
		(start 312.708798 -134.3787)
		(end 312.1787 -134.3787)
		(width 0.127)
		(layer "In2.Cu")
		(net "USB_OCS_N1")
	)
	(segment
		(start 298.653454 -140.957808)
		(end 297.110912 -142.50035)
		(width 0.127)
		(layer "In2.Cu")
		(net "USB_OCS_N1")
	)
	(segment
		(start 288.110168 -142.2527)
		(end 287.322768 -142.2527)
		(width 0.127)
		(layer "In2.Cu")
		(net "USB_OCS_N1")
	)
	(segment
		(start 268.939264 -92.871036)
		(end 269.2273 -92.583)
		(width 0.127)
		(layer "In2.Cu")
		(net "USB_OCS_N1")
	)
	(segment
		(start 267.462 -72.898)
		(end 264.2235 -69.6595)
		(width 0.127)
		(layer "In2.Cu")
		(net "USB_OCS_N1")
	)
	(segment
		(start 301.855886 -133.604)
		(end 298.653454 -136.806432)
		(width 0.127)
		(layer "In2.Cu")
		(net "USB_OCS_N1")
	)
	(segment
		(start 264.2235 -62.779148)
		(end 263.525 -62.080648)
		(width 0.127)
		(layer "In2.Cu")
		(net "USB_OCS_N1")
	)
	(segment
		(start 280.272744 -112.903)
		(end 270.882618 -112.903)
		(width 0.127)
		(layer "In2.Cu")
		(net "USB_OCS_N1")
	)
	(segment
		(start 317.442342 -140.081)
		(end 317.373 -140.011658)
		(width 0.127)
		(layer "In2.Cu")
		(net "USB_OCS_N1")
	)
	(segment
		(start 313.837828 -135.50773)
		(end 312.708798 -134.3787)
		(width 0.127)
		(layer "In2.Cu")
		(net "USB_OCS_N1")
	)
	(segment
		(start 338.201 -153.822654)
		(end 339.318854 -154.940508)
		(width 0.127)
		(layer "In5.Cu")
		(net "USB_OCS_N1")
	)
	(segment
		(start 271.653 -152.019)
		(end 271.653 -158.623)
		(width 0.127)
		(layer "In5.Cu")
		(net "USB_OCS_N1")
	)
	(segment
		(start 339.318854 -154.940508)
		(end 342.190578 -154.940508)
		(width 0.127)
		(layer "In5.Cu")
		(net "USB_OCS_N1")
	)
	(segment
		(start 270.129 -150.495)
		(end 271.653 -152.019)
		(width 0.127)
		(layer "In5.Cu")
		(net "USB_OCS_N1")
	)
	(segment
		(start 338.201 -139.761468)
		(end 338.201 -153.822654)
		(width 0.127)
		(layer "In5.Cu")
		(net "USB_OCS_N1")
	)
	(segment
		(start 285.579058 -118.209314)
		(end 285.015686 -118.209314)
		(width 0.127)
		(layer "In5.Cu")
		(net "USB_OCS_N1")
	)
	(segment
		(start 271.653 -158.623)
		(end 270.26997 -160.00603)
		(width 0.127)
		(layer "In5.Cu")
		(net "USB_OCS_N1")
	)
	(segment
		(start 285.015686 -118.209314)
		(end 270.712184 -132.512816)
		(width 0.127)
		(layer "In5.Cu")
		(net "USB_OCS_N1")
	)
	(segment
		(start 331.3938 -136.144)
		(end 331.5208 -136.271)
		(width 0.127)
		(layer "In5.Cu")
		(net "USB_OCS_N1")
	)
	(segment
		(start 342.190578 -154.940508)
		(end 342.294718 -155.044648)
		(width 0.127)
		(layer "In5.Cu")
		(net "USB_OCS_N1")
	)
	(segment
		(start 334.710532 -136.271)
		(end 338.201 -139.761468)
		(width 0.127)
		(layer "In5.Cu")
		(net "USB_OCS_N1")
	)
	(segment
		(start 270.26997 -160.00603)
		(end 269.98676 -160.00603)
		(width 0.127)
		(layer "In5.Cu")
		(net "USB_OCS_N1")
	)
	(segment
		(start 331.5208 -136.271)
		(end 334.710532 -136.271)
		(width 0.127)
		(layer "In5.Cu")
		(net "USB_OCS_N1")
	)
	(segment
		(start 270.712184 -148.133816)
		(end 270.129 -148.717)
		(width 0.127)
		(layer "In5.Cu")
		(net "USB_OCS_N1")
	)
	(segment
		(start 270.129 -148.717)
		(end 270.129 -150.495)
		(width 0.127)
		(layer "In5.Cu")
		(net "USB_OCS_N1")
	)
	(segment
		(start 270.712184 -132.512816)
		(end 270.712184 -148.133816)
		(width 0.127)
		(layer "In5.Cu")
		(net "USB_OCS_N1")
	)
	(via
		(at 73.914 -25.019)
		(size 0.7112)
		(drill 0.3556)
		(layers "F.Cu" "B.Cu")
		(net "P3V3_STBY_G9")
	)
	(via
		(at 92.075 -72.644)
		(size 0.5588)
		(drill 0.254)
		(layers "F.Cu" "B.Cu")
		(net "P3V3_STBY_G9")
	)
	(via
		(at 74.803 -25.019)
		(size 0.5588)
		(drill 0.254)
		(layers "F.Cu" "B.Cu")
		(net "P3V3_STBY_G9")
	)
	(segment
		(start 74.803 -25.019)
		(end 75.6285 -25.019)
		(width 0.254)
		(layer "B.Cu")
		(net "P3V3_STBY_G9")
	)
	(segment
		(start 87.1855 -75.02525)
		(end 89.69375 -75.02525)
		(width 0.254)
		(layer "B.Cu")
		(net "P3V3_STBY_G9")
	)
	(segment
		(start 89.69375 -75.02525)
		(end 92.075 -72.644)
		(width 0.254)
		(layer "B.Cu")
		(net "P3V3_STBY_G9")
	)
	(segment
		(start 73.914 -25.019)
		(end 74.803 -25.019)
		(width 0.254)
		(layer "B.Cu")
		(net "P3V3_STBY_G9")
	)
	(segment
		(start 69.80428 -56.21528)
		(end 69.80428 -43.09872)
		(width 0.254)
		(layer "In2.Cu")
		(net "P3V3_STBY_G9")
	)
	(segment
		(start 69.80428 -43.09872)
		(end 70.739 -42.164)
		(width 0.254)
		(layer "In2.Cu")
		(net "P3V3_STBY_G9")
	)
	(segment
		(start 70.739 -42.164)
		(end 70.739 -28.931362)
		(width 0.254)
		(layer "In2.Cu")
		(net "P3V3_STBY_G9")
	)
	(segment
		(start 79.610966 -66.021966)
		(end 79.610966 -65.141856)
		(width 0.254)
		(layer "In2.Cu")
		(net "P3V3_STBY_G9")
	)
	(segment
		(start 70.739 -28.931362)
		(end 74.651362 -25.019)
		(width 0.254)
		(layer "In2.Cu")
		(net "P3V3_STBY_G9")
	)
	(segment
		(start 79.610966 -65.141856)
		(end 79.23911 -64.77)
		(width 0.254)
		(layer "In2.Cu")
		(net "P3V3_STBY_G9")
	)
	(segment
		(start 86.233 -72.644)
		(end 79.610966 -66.021966)
		(width 0.254)
		(layer "In2.Cu")
		(net "P3V3_STBY_G9")
	)
	(segment
		(start 74.651362 -25.019)
		(end 74.803 -25.019)
		(width 0.254)
		(layer "In2.Cu")
		(net "P3V3_STBY_G9")
	)
	(segment
		(start 79.23911 -64.77)
		(end 78.359 -64.77)
		(width 0.254)
		(layer "In2.Cu")
		(net "P3V3_STBY_G9")
	)
	(segment
		(start 78.359 -64.77)
		(end 69.80428 -56.21528)
		(width 0.254)
		(layer "In2.Cu")
		(net "P3V3_STBY_G9")
	)
	(segment
		(start 92.075 -72.644)
		(end 86.233 -72.644)
		(width 0.254)
		(layer "In2.Cu")
		(net "P3V3_STBY_G9")
	)
	(segment
		(start 212.217 -219.71)
		(end 211.963 -219.964)
		(width 0.1143)
		(layer "F.Cu")
		(net "DP_BMC_CPU_RST_N_U177_OUT")
	)
	(segment
		(start 212.1535 -217.932)
		(end 212.217 -217.9955)
		(width 0.1143)
		(layer "F.Cu")
		(net "DP_BMC_CPU_RST_N_U177_OUT")
	)
	(segment
		(start 212.217 -217.9955)
		(end 212.217 -219.71)
		(width 0.1143)
		(layer "F.Cu")
		(net "DP_BMC_CPU_RST_N_U177_OUT")
	)
	(segment
		(start 209.94624 -216.29624)
		(end 211.5185 -216.29624)
		(width 0.1143)
		(layer "F.Cu")
		(net "DP_BMC_CPU_RST_N_U177_OUT")
	)
	(segment
		(start 211.963 -219.964)
		(end 211.3915 -219.964)
		(width 0.1143)
		(layer "F.Cu")
		(net "DP_BMC_CPU_RST_N_U177_OUT")
	)
	(segment
		(start 211.5185 -216.29624)
		(end 211.5185 -217.297)
		(width 0.1143)
		(layer "F.Cu")
		(net "DP_BMC_CPU_RST_N_U177_OUT")
	)
	(segment
		(start 211.5185 -217.297)
		(end 212.1535 -217.932)
		(width 0.1143)
		(layer "F.Cu")
		(net "DP_BMC_CPU_RST_N_U177_OUT")
	)
	(segment
		(start 209.931 -216.281)
		(end 209.94624 -216.29624)
		(width 0.1143)
		(layer "F.Cu")
		(net "DP_BMC_CPU_RST_N_U177_OUT")
	)
	(via
		(at 209.931 -216.281)
		(size 0.7112)
		(drill 0.3556)
		(layers "F.Cu" "B.Cu")
		(net "DP_BMC_CPU_RST_N_U177_OUT")
	)
	(segment
		(start 102.616 -73.787)
		(end 102.616 -74.15403)
		(width 0.1143)
		(layer "F.Cu")
		(net "JTAG_BMC_L_TDO")
	)
	(segment
		(start 102.616 -74.15403)
		(end 103.01097 -74.549)
		(width 0.1143)
		(layer "F.Cu")
		(net "JTAG_BMC_L_TDO")
	)
	(segment
		(start 315.964062 -198.755)
		(end 315.964062 -200.406)
		(width 0.1143)
		(layer "F.Cu")
		(net "JTAG_BMC_L_TDO")
	)
	(segment
		(start 103.01097 -76.0095)
		(end 103.01097 -74.549)
		(width 0.1143)
		(layer "F.Cu")
		(net "JTAG_BMC_L_TDO")
	)
	(via
		(at 102.616 -73.787)
		(size 0.7112)
		(drill 0.3556)
		(layers "F.Cu" "B.Cu")
		(net "JTAG_BMC_L_TDO")
	)
	(via
		(at 33.655 -140.081)
		(size 0.5588)
		(drill 0.3048)
		(layers "F.Cu" "B.Cu")
		(net "JTAG_BMC_L_TDO")
	)
	(via
		(at 103.01097 -74.549)
		(size 0.5588)
		(drill 0.3048)
		(layers "F.Cu" "B.Cu")
		(net "JTAG_BMC_L_TDO")
	)
	(via
		(at 315.964062 -200.406)
		(size 0.5588)
		(drill 0.3048)
		(layers "F.Cu" "B.Cu")
		(net "JTAG_BMC_L_TDO")
	)
	(segment
		(start 315.964062 -200.895458)
		(end 306.33162 -210.5279)
		(width 0.127)
		(layer "In2.Cu")
		(net "JTAG_BMC_L_TDO")
	)
	(segment
		(start 273.678396 -210.312)
		(end 262.744712 -199.378316)
		(width 0.127)
		(layer "In2.Cu")
		(net "JTAG_BMC_L_TDO")
	)
	(segment
		(start 52.832 -174.625)
		(end 44.704 -166.497)
		(width 0.127)
		(layer "In2.Cu")
		(net "JTAG_BMC_L_TDO")
	)
	(segment
		(start 32.6517 -141.0843)
		(end 33.655 -140.081)
		(width 0.127)
		(layer "In2.Cu")
		(net "JTAG_BMC_L_TDO")
	)
	(segment
		(start 66.548 -176.022)
		(end 65.151 -174.625)
		(width 0.127)
		(layer "In2.Cu")
		(net "JTAG_BMC_L_TDO")
	)
	(segment
		(start 206.173832 -184.7723)
		(end 197.2183 -184.7723)
		(width 0.127)
		(layer "In2.Cu")
		(net "JTAG_BMC_L_TDO")
	)
	(segment
		(start 262.744712 -192.87109)
		(end 251.242322 -181.3687)
		(width 0.127)
		(layer "In2.Cu")
		(net "JTAG_BMC_L_TDO")
	)
	(segment
		(start 170.815 -183.515)
		(end 163.322 -176.022)
		(width 0.127)
		(layer "In2.Cu")
		(net "JTAG_BMC_L_TDO")
	)
	(segment
		(start 209.577432 -181.3687)
		(end 206.173832 -184.7723)
		(width 0.127)
		(layer "In2.Cu")
		(net "JTAG_BMC_L_TDO")
	)
	(segment
		(start 262.744712 -199.378316)
		(end 262.744712 -192.87109)
		(width 0.127)
		(layer "In2.Cu")
		(net "JTAG_BMC_L_TDO")
	)
	(segment
		(start 44.704 -166.497)
		(end 41.782492 -166.497)
		(width 0.127)
		(layer "In2.Cu")
		(net "JTAG_BMC_L_TDO")
	)
	(segment
		(start 195.961 -183.515)
		(end 170.815 -183.515)
		(width 0.127)
		(layer "In2.Cu")
		(net "JTAG_BMC_L_TDO")
	)
	(segment
		(start 41.782492 -166.497)
		(end 32.6517 -157.366208)
		(width 0.127)
		(layer "In2.Cu")
		(net "JTAG_BMC_L_TDO")
	)
	(segment
		(start 251.242322 -181.3687)
		(end 209.577432 -181.3687)
		(width 0.127)
		(layer "In2.Cu")
		(net "JTAG_BMC_L_TDO")
	)
	(segment
		(start 65.151 -174.625)
		(end 52.832 -174.625)
		(width 0.127)
		(layer "In2.Cu")
		(net "JTAG_BMC_L_TDO")
	)
	(segment
		(start 163.322 -176.022)
		(end 66.548 -176.022)
		(width 0.127)
		(layer "In2.Cu")
		(net "JTAG_BMC_L_TDO")
	)
	(segment
		(start 197.2183 -184.7723)
		(end 195.961 -183.515)
		(width 0.127)
		(layer "In2.Cu")
		(net "JTAG_BMC_L_TDO")
	)
	(segment
		(start 306.33162 -210.5279)
		(end 290.949888 -210.5279)
		(width 0.127)
		(layer "In2.Cu")
		(net "JTAG_BMC_L_TDO")
	)
	(segment
		(start 315.964062 -200.406)
		(end 315.964062 -200.895458)
		(width 0.127)
		(layer "In2.Cu")
		(net "JTAG_BMC_L_TDO")
	)
	(segment
		(start 290.949888 -210.5279)
		(end 290.733988 -210.312)
		(width 0.127)
		(layer "In2.Cu")
		(net "JTAG_BMC_L_TDO")
	)
	(segment
		(start 290.733988 -210.312)
		(end 273.678396 -210.312)
		(width 0.127)
		(layer "In2.Cu")
		(net "JTAG_BMC_L_TDO")
	)
	(segment
		(start 32.6517 -157.366208)
		(end 32.6517 -141.0843)
		(width 0.127)
		(layer "In2.Cu")
		(net "JTAG_BMC_L_TDO")
	)
	(segment
		(start 88.011 -84.328)
		(end 95.504 -76.835)
		(width 0.127)
		(layer "In5.Cu")
		(net "JTAG_BMC_L_TDO")
	)
	(segment
		(start 33.655 -140.081)
		(end 35.687 -138.049)
		(width 0.127)
		(layer "In5.Cu")
		(net "JTAG_BMC_L_TDO")
	)
	(segment
		(start 96.204532 -76.835)
		(end 97.982532 -75.057)
		(width 0.127)
		(layer "In5.Cu")
		(net "JTAG_BMC_L_TDO")
	)
	(segment
		(start 35.687 -138.049)
		(end 35.687 -137.033)
		(width 0.127)
		(layer "In5.Cu")
		(net "JTAG_BMC_L_TDO")
	)
	(segment
		(start 82.133948 -91.4781)
		(end 82.133948 -89.2937)
		(width 0.127)
		(layer "In5.Cu")
		(net "JTAG_BMC_L_TDO")
	)
	(segment
		(start 35.687 -137.033)
		(end 44.831 -127.889)
		(width 0.127)
		(layer "In5.Cu")
		(net "JTAG_BMC_L_TDO")
	)
	(segment
		(start 102.50297 -75.057)
		(end 103.01097 -74.549)
		(width 0.127)
		(layer "In5.Cu")
		(net "JTAG_BMC_L_TDO")
	)
	(segment
		(start 82.468466 -88.959182)
		(end 82.468466 -88.092534)
		(width 0.127)
		(layer "In5.Cu")
		(net "JTAG_BMC_L_TDO")
	)
	(segment
		(start 95.504 -76.835)
		(end 96.204532 -76.835)
		(width 0.127)
		(layer "In5.Cu")
		(net "JTAG_BMC_L_TDO")
	)
	(segment
		(start 44.831 -127.889)
		(end 45.723048 -127.889)
		(width 0.127)
		(layer "In5.Cu")
		(net "JTAG_BMC_L_TDO")
	)
	(segment
		(start 86.233 -84.328)
		(end 88.011 -84.328)
		(width 0.127)
		(layer "In5.Cu")
		(net "JTAG_BMC_L_TDO")
	)
	(segment
		(start 97.982532 -75.057)
		(end 102.50297 -75.057)
		(width 0.127)
		(layer "In5.Cu")
		(net "JTAG_BMC_L_TDO")
	)
	(segment
		(start 82.133948 -89.2937)
		(end 82.468466 -88.959182)
		(width 0.127)
		(layer "In5.Cu")
		(net "JTAG_BMC_L_TDO")
	)
	(segment
		(start 82.468466 -88.092534)
		(end 86.233 -84.328)
		(width 0.127)
		(layer "In5.Cu")
		(net "JTAG_BMC_L_TDO")
	)
	(segment
		(start 45.723048 -127.889)
		(end 82.133948 -91.4781)
		(width 0.127)
		(layer "In5.Cu")
		(net "JTAG_BMC_L_TDO")
	)
	(segment
		(start 315.463936 -198.755)
		(end 315.463936 -202.184)
		(width 0.1143)
		(layer "F.Cu")
		(net "JTAG_EXP_IOC_TCK")
	)
	(segment
		(start 96.19361 -76.0095)
		(end 95.97517 -76.22794)
		(width 0.1143)
		(layer "F.Cu")
		(net "JTAG_EXP_IOC_TCK")
	)
	(segment
		(start 98.18497 -76.0095)
		(end 96.19361 -76.0095)
		(width 0.1143)
		(layer "F.Cu")
		(net "JTAG_EXP_IOC_TCK")
	)
	(via
		(at 315.463936 -202.184)
		(size 0.5588)
		(drill 0.3048)
		(layers "F.Cu" "B.Cu")
		(net "JTAG_EXP_IOC_TCK")
	)
	(via
		(at 33.655 -138.938)
		(size 0.5588)
		(drill 0.3048)
		(layers "F.Cu" "B.Cu")
		(net "JTAG_EXP_IOC_TCK")
	)
	(via
		(at 106.045 -64.262)
		(size 0.7112)
		(drill 0.3556)
		(layers "F.Cu" "B.Cu")
		(net "JTAG_EXP_IOC_TCK")
	)
	(via
		(at 95.97517 -76.22794)
		(size 0.5588)
		(drill 0.3048)
		(layers "F.Cu" "B.Cu")
		(net "JTAG_EXP_IOC_TCK")
	)
	(segment
		(start 96.698308 -74.94905)
		(end 97.376996 -74.94905)
		(width 0.1143)
		(layer "B.Cu")
		(net "JTAG_EXP_IOC_TCK")
	)
	(segment
		(start 102.343966 -59.3725)
		(end 102.743 -59.771534)
		(width 0.1143)
		(layer "B.Cu")
		(net "JTAG_EXP_IOC_TCK")
	)
	(segment
		(start 97.376996 -74.94905)
		(end 99.301046 -73.025)
		(width 0.1143)
		(layer "B.Cu")
		(net "JTAG_EXP_IOC_TCK")
	)
	(segment
		(start 95.97517 -75.672188)
		(end 96.698308 -74.94905)
		(width 0.1143)
		(layer "B.Cu")
		(net "JTAG_EXP_IOC_TCK")
	)
	(segment
		(start 108.636054 -64.262)
		(end 106.045 -64.262)
		(width 0.1143)
		(layer "B.Cu")
		(net "JTAG_EXP_IOC_TCK")
	)
	(segment
		(start 99.301046 -73.025)
		(end 103.695246 -73.025)
		(width 0.1143)
		(layer "B.Cu")
		(net "JTAG_EXP_IOC_TCK")
	)
	(segment
		(start 108.96219 -70.48881)
		(end 110.871 -68.58)
		(width 0.1143)
		(layer "B.Cu")
		(net "JTAG_EXP_IOC_TCK")
	)
	(segment
		(start 103.963724 -62.865)
		(end 104.648 -62.865)
		(width 0.1143)
		(layer "B.Cu")
		(net "JTAG_EXP_IOC_TCK")
	)
	(segment
		(start 102.743 -59.771534)
		(end 102.743 -61.644276)
		(width 0.1143)
		(layer "B.Cu")
		(net "JTAG_EXP_IOC_TCK")
	)
	(segment
		(start 102.743 -61.644276)
		(end 103.963724 -62.865)
		(width 0.1143)
		(layer "B.Cu")
		(net "JTAG_EXP_IOC_TCK")
	)
	(segment
		(start 103.695246 -73.025)
		(end 106.231436 -70.48881)
		(width 0.1143)
		(layer "B.Cu")
		(net "JTAG_EXP_IOC_TCK")
	)
	(segment
		(start 104.648 -62.865)
		(end 106.045 -64.262)
		(width 0.1143)
		(layer "B.Cu")
		(net "JTAG_EXP_IOC_TCK")
	)
	(segment
		(start 95.97517 -76.22794)
		(end 95.97517 -75.672188)
		(width 0.1143)
		(layer "B.Cu")
		(net "JTAG_EXP_IOC_TCK")
	)
	(segment
		(start 110.871 -66.496946)
		(end 108.636054 -64.262)
		(width 0.1143)
		(layer "B.Cu")
		(net "JTAG_EXP_IOC_TCK")
	)
	(segment
		(start 106.231436 -70.48881)
		(end 108.96219 -70.48881)
		(width 0.1143)
		(layer "B.Cu")
		(net "JTAG_EXP_IOC_TCK")
	)
	(segment
		(start 110.871 -68.58)
		(end 110.871 -66.496946)
		(width 0.1143)
		(layer "B.Cu")
		(net "JTAG_EXP_IOC_TCK")
	)
	(segment
		(start 31.496 -156.749496)
		(end 31.496 -148.515832)
		(width 0.127)
		(layer "In2.Cu")
		(net "JTAG_EXP_IOC_TCK")
	)
	(segment
		(start 251.084334 -181.7497)
		(end 209.73542 -181.7497)
		(width 0.127)
		(layer "In2.Cu")
		(net "JTAG_EXP_IOC_TCK")
	)
	(segment
		(start 170.561 -183.896)
		(end 163.068 -176.403)
		(width 0.127)
		(layer "In2.Cu")
		(net "JTAG_EXP_IOC_TCK")
	)
	(segment
		(start 290.7919 -210.9089)
		(end 290.576 -210.693)
		(width 0.127)
		(layer "In2.Cu")
		(net "JTAG_EXP_IOC_TCK")
	)
	(segment
		(start 262.363712 -193.029078)
		(end 251.084334 -181.7497)
		(width 0.127)
		(layer "In2.Cu")
		(net "JTAG_EXP_IOC_TCK")
	)
	(segment
		(start 262.363712 -199.536304)
		(end 262.363712 -193.029078)
		(width 0.127)
		(layer "In2.Cu")
		(net "JTAG_EXP_IOC_TCK")
	)
	(segment
		(start 31.2674 -141.3256)
		(end 33.655 -138.938)
		(width 0.127)
		(layer "In2.Cu")
		(net "JTAG_EXP_IOC_TCK")
	)
	(segment
		(start 31.2674 -148.287232)
		(end 31.2674 -141.3256)
		(width 0.127)
		(layer "In2.Cu")
		(net "JTAG_EXP_IOC_TCK")
	)
	(segment
		(start 290.576 -210.693)
		(end 273.520408 -210.693)
		(width 0.127)
		(layer "In2.Cu")
		(net "JTAG_EXP_IOC_TCK")
	)
	(segment
		(start 273.520408 -210.693)
		(end 262.363712 -199.536304)
		(width 0.127)
		(layer "In2.Cu")
		(net "JTAG_EXP_IOC_TCK")
	)
	(segment
		(start 31.496 -148.515832)
		(end 31.2674 -148.287232)
		(width 0.127)
		(layer "In2.Cu")
		(net "JTAG_EXP_IOC_TCK")
	)
	(segment
		(start 66.294 -176.403)
		(end 64.897 -175.006)
		(width 0.127)
		(layer "In2.Cu")
		(net "JTAG_EXP_IOC_TCK")
	)
	(segment
		(start 206.33182 -185.1533)
		(end 196.9643 -185.1533)
		(width 0.127)
		(layer "In2.Cu")
		(net "JTAG_EXP_IOC_TCK")
	)
	(segment
		(start 209.73542 -181.7497)
		(end 206.33182 -185.1533)
		(width 0.127)
		(layer "In2.Cu")
		(net "JTAG_EXP_IOC_TCK")
	)
	(segment
		(start 44.45 -166.878)
		(end 41.624504 -166.878)
		(width 0.127)
		(layer "In2.Cu")
		(net "JTAG_EXP_IOC_TCK")
	)
	(segment
		(start 52.578 -175.006)
		(end 44.45 -166.878)
		(width 0.127)
		(layer "In2.Cu")
		(net "JTAG_EXP_IOC_TCK")
	)
	(segment
		(start 195.707 -183.896)
		(end 170.561 -183.896)
		(width 0.127)
		(layer "In2.Cu")
		(net "JTAG_EXP_IOC_TCK")
	)
	(segment
		(start 315.463936 -202.184)
		(end 306.739036 -210.9089)
		(width 0.127)
		(layer "In2.Cu")
		(net "JTAG_EXP_IOC_TCK")
	)
	(segment
		(start 41.624504 -166.878)
		(end 31.496 -156.749496)
		(width 0.127)
		(layer "In2.Cu")
		(net "JTAG_EXP_IOC_TCK")
	)
	(segment
		(start 64.897 -175.006)
		(end 52.578 -175.006)
		(width 0.127)
		(layer "In2.Cu")
		(net "JTAG_EXP_IOC_TCK")
	)
	(segment
		(start 196.9643 -185.1533)
		(end 195.707 -183.896)
		(width 0.127)
		(layer "In2.Cu")
		(net "JTAG_EXP_IOC_TCK")
	)
	(segment
		(start 306.739036 -210.9089)
		(end 290.7919 -210.9089)
		(width 0.127)
		(layer "In2.Cu")
		(net "JTAG_EXP_IOC_TCK")
	)
	(segment
		(start 163.068 -176.403)
		(end 66.294 -176.403)
		(width 0.127)
		(layer "In2.Cu")
		(net "JTAG_EXP_IOC_TCK")
	)
	(segment
		(start 95.49257 -76.22794)
		(end 87.77351 -83.947)
		(width 0.127)
		(layer "In5.Cu")
		(net "JTAG_EXP_IOC_TCK")
	)
	(segment
		(start 87.77351 -83.947)
		(end 85.864192 -83.947)
		(width 0.127)
		(layer "In5.Cu")
		(net "JTAG_EXP_IOC_TCK")
	)
	(segment
		(start 81.325466 -88.485472)
		(end 81.325466 -91.747594)
		(width 0.127)
		(layer "In5.Cu")
		(net "JTAG_EXP_IOC_TCK")
	)
	(segment
		(start 44.673012 -127.508)
		(end 33.655 -138.526012)
		(width 0.127)
		(layer "In5.Cu")
		(net "JTAG_EXP_IOC_TCK")
	)
	(segment
		(start 85.864192 -83.947)
		(end 81.660238 -88.1507)
		(width 0.127)
		(layer "In5.Cu")
		(net "JTAG_EXP_IOC_TCK")
	)
	(segment
		(start 33.655 -138.526012)
		(end 33.655 -138.938)
		(width 0.127)
		(layer "In5.Cu")
		(net "JTAG_EXP_IOC_TCK")
	)
	(segment
		(start 95.97517 -76.22794)
		(end 95.49257 -76.22794)
		(width 0.127)
		(layer "In5.Cu")
		(net "JTAG_EXP_IOC_TCK")
	)
	(segment
		(start 81.325466 -91.747594)
		(end 45.56506 -127.508)
		(width 0.127)
		(layer "In5.Cu")
		(net "JTAG_EXP_IOC_TCK")
	)
	(segment
		(start 81.660238 -88.1507)
		(end 81.325466 -88.485472)
		(width 0.127)
		(layer "In5.Cu")
		(net "JTAG_EXP_IOC_TCK")
	)
	(segment
		(start 45.56506 -127.508)
		(end 44.673012 -127.508)
		(width 0.127)
		(layer "In5.Cu")
		(net "JTAG_EXP_IOC_TCK")
	)
	(segment
		(start 103.886 -75.86853)
		(end 103.886 -75.057)
		(width 0.1143)
		(layer "F.Cu")
		(net "JTAG_EXP_IOC_TMS")
	)
	(segment
		(start 314.964064 -198.755)
		(end 314.964064 -200.387712)
		(width 0.1143)
		(layer "F.Cu")
		(net "JTAG_EXP_IOC_TMS")
	)
	(segment
		(start 103.92537 -74.167746)
		(end 103.92537 -75.01763)
		(width 0.1143)
		(layer "F.Cu")
		(net "JTAG_EXP_IOC_TMS")
	)
	(segment
		(start 103.125016 -71.519034)
		(end 103.125016 -73.367392)
		(width 0.1143)
		(layer "F.Cu")
		(net "JTAG_EXP_IOC_TMS")
	)
	(segment
		(start 106.81335 -68.25615)
		(end 106.3879 -68.25615)
		(width 0.1143)
		(layer "F.Cu")
		(net "JTAG_EXP_IOC_TMS")
	)
	(segment
		(start 103.92537 -75.01763)
		(end 103.886 -75.057)
		(width 0.1143)
		(layer "F.Cu")
		(net "JTAG_EXP_IOC_TMS")
	)
	(segment
		(start 314.964064 -200.387712)
		(end 314.97143 -200.395078)
		(width 0.1143)
		(layer "F.Cu")
		(net "JTAG_EXP_IOC_TMS")
	)
	(segment
		(start 104.02697 -76.0095)
		(end 103.886 -75.86853)
		(width 0.1143)
		(layer "F.Cu")
		(net "JTAG_EXP_IOC_TMS")
	)
	(segment
		(start 103.798624 -74.041)
		(end 103.92537 -74.167746)
		(width 0.1143)
		(layer "F.Cu")
		(net "JTAG_EXP_IOC_TMS")
	)
	(segment
		(start 106.3879 -68.25615)
		(end 103.125016 -71.519034)
		(width 0.1143)
		(layer "F.Cu")
		(net "JTAG_EXP_IOC_TMS")
	)
	(segment
		(start 103.125016 -73.367392)
		(end 103.798624 -74.041)
		(width 0.1143)
		(layer "F.Cu")
		(net "JTAG_EXP_IOC_TMS")
	)
	(segment
		(start 106.9975 -68.072)
		(end 106.81335 -68.25615)
		(width 0.1143)
		(layer "F.Cu")
		(net "JTAG_EXP_IOC_TMS")
	)
	(via
		(at 103.798624 -74.041)
		(size 0.5588)
		(drill 0.3048)
		(layers "F.Cu" "B.Cu")
		(net "JTAG_EXP_IOC_TMS")
	)
	(via
		(at 103.886 -75.057)
		(size 0.7112)
		(drill 0.3556)
		(layers "F.Cu" "B.Cu")
		(net "JTAG_EXP_IOC_TMS")
	)
	(via
		(at 33.655 -141.224)
		(size 0.5588)
		(drill 0.3048)
		(layers "F.Cu" "B.Cu")
		(net "JTAG_EXP_IOC_TMS")
	)
	(via
		(at 314.97143 -200.395078)
		(size 0.5588)
		(drill 0.3048)
		(layers "F.Cu" "B.Cu")
		(net "JTAG_EXP_IOC_TMS")
	)
	(segment
		(start 263.125712 -192.713102)
		(end 251.40031 -180.9877)
		(width 0.127)
		(layer "In2.Cu")
		(net "JTAG_EXP_IOC_TMS")
	)
	(segment
		(start 196.118988 -183.134)
		(end 171.069 -183.134)
		(width 0.127)
		(layer "In2.Cu")
		(net "JTAG_EXP_IOC_TMS")
	)
	(segment
		(start 263.125712 -199.220328)
		(end 263.125712 -192.713102)
		(width 0.127)
		(layer "In2.Cu")
		(net "JTAG_EXP_IOC_TMS")
	)
	(segment
		(start 53.086 -174.244)
		(end 44.958 -166.116)
		(width 0.127)
		(layer "In2.Cu")
		(net "JTAG_EXP_IOC_TMS")
	)
	(segment
		(start 41.94048 -166.116)
		(end 33.0327 -157.20822)
		(width 0.127)
		(layer "In2.Cu")
		(net "JTAG_EXP_IOC_TMS")
	)
	(segment
		(start 209.042 -180.9877)
		(end 205.6384 -184.3913)
		(width 0.127)
		(layer "In2.Cu")
		(net "JTAG_EXP_IOC_TMS")
	)
	(segment
		(start 65.405 -174.244)
		(end 53.086 -174.244)
		(width 0.127)
		(layer "In2.Cu")
		(net "JTAG_EXP_IOC_TMS")
	)
	(segment
		(start 314.97143 -200.395078)
		(end 314.97143 -201.349102)
		(width 0.127)
		(layer "In2.Cu")
		(net "JTAG_EXP_IOC_TMS")
	)
	(segment
		(start 33.0327 -157.20822)
		(end 33.0327 -141.8463)
		(width 0.127)
		(layer "In2.Cu")
		(net "JTAG_EXP_IOC_TMS")
	)
	(segment
		(start 197.376288 -184.3913)
		(end 196.118988 -183.134)
		(width 0.127)
		(layer "In2.Cu")
		(net "JTAG_EXP_IOC_TMS")
	)
	(segment
		(start 33.0327 -141.8463)
		(end 33.655 -141.224)
		(width 0.127)
		(layer "In2.Cu")
		(net "JTAG_EXP_IOC_TMS")
	)
	(segment
		(start 66.802 -175.641)
		(end 65.405 -174.244)
		(width 0.127)
		(layer "In2.Cu")
		(net "JTAG_EXP_IOC_TMS")
	)
	(segment
		(start 297.8785 -209.7405)
		(end 297.7261 -209.5881)
		(width 0.127)
		(layer "In2.Cu")
		(net "JTAG_EXP_IOC_TMS")
	)
	(segment
		(start 306.580032 -209.7405)
		(end 297.8785 -209.7405)
		(width 0.127)
		(layer "In2.Cu")
		(net "JTAG_EXP_IOC_TMS")
	)
	(segment
		(start 205.6384 -184.3913)
		(end 197.376288 -184.3913)
		(width 0.127)
		(layer "In2.Cu")
		(net "JTAG_EXP_IOC_TMS")
	)
	(segment
		(start 44.958 -166.116)
		(end 41.94048 -166.116)
		(width 0.127)
		(layer "In2.Cu")
		(net "JTAG_EXP_IOC_TMS")
	)
	(segment
		(start 287.4137 -209.9183)
		(end 273.823684 -209.9183)
		(width 0.127)
		(layer "In2.Cu")
		(net "JTAG_EXP_IOC_TMS")
	)
	(segment
		(start 163.576 -175.641)
		(end 66.802 -175.641)
		(width 0.127)
		(layer "In2.Cu")
		(net "JTAG_EXP_IOC_TMS")
	)
	(segment
		(start 273.823684 -209.9183)
		(end 263.125712 -199.220328)
		(width 0.127)
		(layer "In2.Cu")
		(net "JTAG_EXP_IOC_TMS")
	)
	(segment
		(start 314.97143 -201.349102)
		(end 306.580032 -209.7405)
		(width 0.127)
		(layer "In2.Cu")
		(net "JTAG_EXP_IOC_TMS")
	)
	(segment
		(start 297.7261 -209.5881)
		(end 287.7439 -209.5881)
		(width 0.127)
		(layer "In2.Cu")
		(net "JTAG_EXP_IOC_TMS")
	)
	(segment
		(start 251.40031 -180.9877)
		(end 209.042 -180.9877)
		(width 0.127)
		(layer "In2.Cu")
		(net "JTAG_EXP_IOC_TMS")
	)
	(segment
		(start 287.7439 -209.5881)
		(end 287.4137 -209.9183)
		(width 0.127)
		(layer "In2.Cu")
		(net "JTAG_EXP_IOC_TMS")
	)
	(segment
		(start 171.069 -183.134)
		(end 163.576 -175.641)
		(width 0.127)
		(layer "In2.Cu")
		(net "JTAG_EXP_IOC_TMS")
	)
	(segment
		(start 36.195 -137.541)
		(end 40.96385 -132.77215)
		(width 0.127)
		(layer "In5.Cu")
		(net "JTAG_EXP_IOC_TMS")
	)
	(segment
		(start 36.195 -138.684)
		(end 36.195 -137.541)
		(width 0.127)
		(layer "In5.Cu")
		(net "JTAG_EXP_IOC_TMS")
	)
	(segment
		(start 96.36252 -77.216)
		(end 98.01352 -75.565)
		(width 0.127)
		(layer "In5.Cu")
		(net "JTAG_EXP_IOC_TMS")
	)
	(segment
		(start 45.212 -128.524)
		(end 45.627036 -128.524)
		(width 0.127)
		(layer "In5.Cu")
		(net "JTAG_EXP_IOC_TMS")
	)
	(segment
		(start 33.655 -141.224)
		(end 36.195 -138.684)
		(width 0.127)
		(layer "In5.Cu")
		(net "JTAG_EXP_IOC_TMS")
	)
	(segment
		(start 98.01352 -75.565)
		(end 102.695502 -75.565)
		(width 0.127)
		(layer "In5.Cu")
		(net "JTAG_EXP_IOC_TMS")
	)
	(segment
		(start 40.96385 -132.403088)
		(end 41.253918 -132.11302)
		(width 0.127)
		(layer "In5.Cu")
		(net "JTAG_EXP_IOC_TMS")
	)
	(segment
		(start 85.344 -88.807036)
		(end 85.344 -85.979)
		(width 0.127)
		(layer "In5.Cu")
		(net "JTAG_EXP_IOC_TMS")
	)
	(segment
		(start 95.758 -77.216)
		(end 96.36252 -77.216)
		(width 0.127)
		(layer "In5.Cu")
		(net "JTAG_EXP_IOC_TMS")
	)
	(segment
		(start 86.614 -84.709)
		(end 88.265 -84.709)
		(width 0.127)
		(layer "In5.Cu")
		(net "JTAG_EXP_IOC_TMS")
	)
	(segment
		(start 88.265 -84.709)
		(end 95.758 -77.216)
		(width 0.127)
		(layer "In5.Cu")
		(net "JTAG_EXP_IOC_TMS")
	)
	(segment
		(start 85.344 -85.979)
		(end 86.614 -84.709)
		(width 0.127)
		(layer "In5.Cu")
		(net "JTAG_EXP_IOC_TMS")
	)
	(segment
		(start 41.253918 -132.11302)
		(end 41.62298 -132.11302)
		(width 0.127)
		(layer "In5.Cu")
		(net "JTAG_EXP_IOC_TMS")
	)
	(segment
		(start 102.695502 -75.565)
		(end 103.798624 -74.461878)
		(width 0.127)
		(layer "In5.Cu")
		(net "JTAG_EXP_IOC_TMS")
	)
	(segment
		(start 41.62298 -132.11302)
		(end 45.212 -128.524)
		(width 0.127)
		(layer "In5.Cu")
		(net "JTAG_EXP_IOC_TMS")
	)
	(segment
		(start 40.96385 -132.77215)
		(end 40.96385 -132.403088)
		(width 0.127)
		(layer "In5.Cu")
		(net "JTAG_EXP_IOC_TMS")
	)
	(segment
		(start 103.798624 -74.461878)
		(end 103.798624 -74.041)
		(width 0.127)
		(layer "In5.Cu")
		(net "JTAG_EXP_IOC_TMS")
	)
	(segment
		(start 45.627036 -128.524)
		(end 85.344 -88.807036)
		(width 0.127)
		(layer "In5.Cu")
		(net "JTAG_EXP_IOC_TMS")
	)
	(segment
		(start 100.3808 -73.90384)
		(end 100.356416 -73.928224)
		(width 0.1143)
		(layer "F.Cu")
		(net "JTAG_EXP_IOC_RST")
	)
	(segment
		(start 102.489 -71.628)
		(end 102.3112 -71.8058)
		(width 0.1143)
		(layer "F.Cu")
		(net "JTAG_EXP_IOC_RST")
	)
	(segment
		(start 106.788966 -67.201034)
		(end 104.394 -69.596)
		(width 0.1143)
		(layer "F.Cu")
		(net "JTAG_EXP_IOC_RST")
	)
	(segment
		(start 104.394 -69.596)
		(end 104.267 -69.596)
		(width 0.1143)
		(layer "F.Cu")
		(net "JTAG_EXP_IOC_RST")
	)
	(segment
		(start 102.3112 -71.8058)
		(end 100.3808 -73.7362)
		(width 0.1143)
		(layer "F.Cu")
		(net "JTAG_EXP_IOC_RST")
	)
	(segment
		(start 102.489 -71.374)
		(end 102.489 -71.628)
		(width 0.1143)
		(layer "F.Cu")
		(net "JTAG_EXP_IOC_RST")
	)
	(segment
		(start 106.31297 -76.0095)
		(end 105.711498 -75.027028)
		(width 0.1143)
		(layer "F.Cu")
		(net "JTAG_EXP_IOC_RST")
	)
	(segment
		(start 106.788966 -66.3321)
		(end 106.788966 -67.201034)
		(width 0.1143)
		(layer "F.Cu")
		(net "JTAG_EXP_IOC_RST")
	)
	(segment
		(start 314.463938 -198.755)
		(end 314.463938 -201.156062)
		(width 0.1143)
		(layer "F.Cu")
		(net "JTAG_EXP_IOC_RST")
	)
	(segment
		(start 100.3808 -73.7362)
		(end 100.3808 -73.90384)
		(width 0.1143)
		(layer "F.Cu")
		(net "JTAG_EXP_IOC_RST")
	)
	(segment
		(start 105.711498 -75.027028)
		(end 105.711498 -74.856594)
		(width 0.1143)
		(layer "F.Cu")
		(net "JTAG_EXP_IOC_RST")
	)
	(segment
		(start 104.267 -69.596)
		(end 102.489 -71.374)
		(width 0.1143)
		(layer "F.Cu")
		(net "JTAG_EXP_IOC_RST")
	)
	(via
		(at 33.655 -142.1384)
		(size 0.5588)
		(drill 0.3048)
		(layers "F.Cu" "B.Cu")
		(net "JTAG_EXP_IOC_RST")
	)
	(via
		(at 102.3112 -71.8058)
		(size 0.7112)
		(drill 0.3556)
		(layers "F.Cu" "B.Cu")
		(net "JTAG_EXP_IOC_RST")
	)
	(via
		(at 100.356416 -73.928224)
		(size 0.5588)
		(drill 0.3048)
		(layers "F.Cu" "B.Cu")
		(net "JTAG_EXP_IOC_RST")
	)
	(via
		(at 105.711498 -74.856594)
		(size 0.5588)
		(drill 0.3048)
		(layers "F.Cu" "B.Cu")
		(net "JTAG_EXP_IOC_RST")
	)
	(via
		(at 314.463938 -201.156062)
		(size 0.5588)
		(drill 0.3048)
		(layers "F.Cu" "B.Cu")
		(net "JTAG_EXP_IOC_RST")
	)
	(segment
		(start 263.506712 -192.555114)
		(end 251.291598 -180.34)
		(width 0.127)
		(layer "In2.Cu")
		(net "JTAG_EXP_IOC_RST")
	)
	(segment
		(start 314.463938 -201.156062)
		(end 306.2605 -209.3595)
		(width 0.127)
		(layer "In2.Cu")
		(net "JTAG_EXP_IOC_RST")
	)
	(segment
		(start 285.977076 -208.634076)
		(end 276.251924 -208.634076)
		(width 0.127)
		(layer "In2.Cu")
		(net "JTAG_EXP_IOC_RST")
	)
	(segment
		(start 298.1325 -209.3595)
		(end 297.9801 -209.2071)
		(width 0.127)
		(layer "In2.Cu")
		(net "JTAG_EXP_IOC_RST")
	)
	(segment
		(start 215.216232 -179.8447)
		(end 214.805768 -179.8447)
		(width 0.127)
		(layer "In2.Cu")
		(net "JTAG_EXP_IOC_RST")
	)
	(segment
		(start 67.056 -175.26)
		(end 65.659 -173.863)
		(width 0.127)
		(layer "In2.Cu")
		(net "JTAG_EXP_IOC_RST")
	)
	(segment
		(start 65.659 -173.863)
		(end 53.34 -173.863)
		(width 0.127)
		(layer "In2.Cu")
		(net "JTAG_EXP_IOC_RST")
	)
	(segment
		(start 163.83 -175.26)
		(end 67.056 -175.26)
		(width 0.127)
		(layer "In2.Cu")
		(net "JTAG_EXP_IOC_RST")
	)
	(segment
		(start 273.079972 -208.6356)
		(end 263.506712 -199.06234)
		(width 0.127)
		(layer "In2.Cu")
		(net "JTAG_EXP_IOC_RST")
	)
	(segment
		(start 196.784976 -183.261)
		(end 196.276976 -182.753)
		(width 0.127)
		(layer "In2.Cu")
		(net "JTAG_EXP_IOC_RST")
	)
	(segment
		(start 215.343232 -179.9717)
		(end 215.216232 -179.8447)
		(width 0.127)
		(layer "In2.Cu")
		(net "JTAG_EXP_IOC_RST")
	)
	(segment
		(start 42.098468 -165.735)
		(end 33.4137 -157.050232)
		(width 0.127)
		(layer "In2.Cu")
		(net "JTAG_EXP_IOC_RST")
	)
	(segment
		(start 223.979232 -179.8447)
		(end 223.568768 -179.8447)
		(width 0.127)
		(layer "In2.Cu")
		(net "JTAG_EXP_IOC_RST")
	)
	(segment
		(start 216.740232 -179.9717)
		(end 215.343232 -179.9717)
		(width 0.127)
		(layer "In2.Cu")
		(net "JTAG_EXP_IOC_RST")
	)
	(segment
		(start 276.2504 -208.6356)
		(end 273.079972 -208.6356)
		(width 0.127)
		(layer "In2.Cu")
		(net "JTAG_EXP_IOC_RST")
	)
	(segment
		(start 33.4137 -157.050232)
		(end 33.4137 -142.3797)
		(width 0.127)
		(layer "In2.Cu")
		(net "JTAG_EXP_IOC_RST")
	)
	(segment
		(start 306.2605 -209.3595)
		(end 298.1325 -209.3595)
		(width 0.127)
		(layer "In2.Cu")
		(net "JTAG_EXP_IOC_RST")
	)
	(segment
		(start 297.9801 -209.2071)
		(end 287.4899 -209.2071)
		(width 0.127)
		(layer "In2.Cu")
		(net "JTAG_EXP_IOC_RST")
	)
	(segment
		(start 53.34 -173.863)
		(end 45.212 -165.735)
		(width 0.127)
		(layer "In2.Cu")
		(net "JTAG_EXP_IOC_RST")
	)
	(segment
		(start 224.474532 -180.34)
		(end 223.979232 -179.8447)
		(width 0.127)
		(layer "In2.Cu")
		(net "JTAG_EXP_IOC_RST")
	)
	(segment
		(start 223.568768 -179.8447)
		(end 223.073468 -180.34)
		(width 0.127)
		(layer "In2.Cu")
		(net "JTAG_EXP_IOC_RST")
	)
	(segment
		(start 214.310468 -180.34)
		(end 209.150712 -180.34)
		(width 0.127)
		(layer "In2.Cu")
		(net "JTAG_EXP_IOC_RST")
	)
	(segment
		(start 287.4899 -209.2071)
		(end 287.30448 -209.39252)
		(width 0.127)
		(layer "In2.Cu")
		(net "JTAG_EXP_IOC_RST")
	)
	(segment
		(start 276.251924 -208.634076)
		(end 276.2504 -208.6356)
		(width 0.127)
		(layer "In2.Cu")
		(net "JTAG_EXP_IOC_RST")
	)
	(segment
		(start 287.30448 -209.39252)
		(end 286.73552 -209.39252)
		(width 0.127)
		(layer "In2.Cu")
		(net "JTAG_EXP_IOC_RST")
	)
	(segment
		(start 33.4137 -142.3797)
		(end 33.655 -142.1384)
		(width 0.127)
		(layer "In2.Cu")
		(net "JTAG_EXP_IOC_RST")
	)
	(segment
		(start 206.229712 -183.261)
		(end 196.784976 -183.261)
		(width 0.127)
		(layer "In2.Cu")
		(net "JTAG_EXP_IOC_RST")
	)
	(segment
		(start 171.323 -182.753)
		(end 163.83 -175.26)
		(width 0.127)
		(layer "In2.Cu")
		(net "JTAG_EXP_IOC_RST")
	)
	(segment
		(start 217.108532 -180.34)
		(end 216.740232 -179.9717)
		(width 0.127)
		(layer "In2.Cu")
		(net "JTAG_EXP_IOC_RST")
	)
	(segment
		(start 223.073468 -180.34)
		(end 217.108532 -180.34)
		(width 0.127)
		(layer "In2.Cu")
		(net "JTAG_EXP_IOC_RST")
	)
	(segment
		(start 263.506712 -199.06234)
		(end 263.506712 -192.555114)
		(width 0.127)
		(layer "In2.Cu")
		(net "JTAG_EXP_IOC_RST")
	)
	(segment
		(start 45.212 -165.735)
		(end 42.098468 -165.735)
		(width 0.127)
		(layer "In2.Cu")
		(net "JTAG_EXP_IOC_RST")
	)
	(segment
		(start 209.150712 -180.34)
		(end 206.229712 -183.261)
		(width 0.127)
		(layer "In2.Cu")
		(net "JTAG_EXP_IOC_RST")
	)
	(segment
		(start 196.276976 -182.753)
		(end 171.323 -182.753)
		(width 0.127)
		(layer "In2.Cu")
		(net "JTAG_EXP_IOC_RST")
	)
	(segment
		(start 214.805768 -179.8447)
		(end 214.310468 -180.34)
		(width 0.127)
		(layer "In2.Cu")
		(net "JTAG_EXP_IOC_RST")
	)
	(segment
		(start 286.73552 -209.39252)
		(end 285.977076 -208.634076)
		(width 0.127)
		(layer "In2.Cu")
		(net "JTAG_EXP_IOC_RST")
	)
	(segment
		(start 251.291598 -180.34)
		(end 224.474532 -180.34)
		(width 0.127)
		(layer "In2.Cu")
		(net "JTAG_EXP_IOC_RST")
	)
	(segment
		(start 100.356416 -73.928224)
		(end 100.3808 -73.90384)
		(width 0.127)
		(layer "In5.Cu")
		(net "JTAG_EXP_IOC_RST")
	)
	(segment
		(start 100.3808 -73.76287)
		(end 100.73767 -73.406)
		(width 0.127)
		(layer "In5.Cu")
		(net "JTAG_EXP_IOC_RST")
	)
	(segment
		(start 85.019388 -82.7913)
		(end 86.797134 -82.7913)
		(width 0.127)
		(layer "In5.Cu")
		(net "JTAG_EXP_IOC_RST")
	)
	(segment
		(start 34.211768 -129.2987)
		(end 36.407852 -129.2987)
		(width 0.127)
		(layer "In5.Cu")
		(net "JTAG_EXP_IOC_RST")
	)
	(segment
		(start 77.597 -92.837)
		(end 77.597 -90.213688)
		(width 0.127)
		(layer "In5.Cu")
		(net "JTAG_EXP_IOC_RST")
	)
	(segment
		(start 33.655 -142.1384)
		(end 33.655 -142.113)
		(width 0.127)
		(layer "In5.Cu")
		(net "JTAG_EXP_IOC_RST")
	)
	(segment
		(start 77.597 -90.213688)
		(end 85.019388 -82.7913)
		(width 0.127)
		(layer "In5.Cu")
		(net "JTAG_EXP_IOC_RST")
	)
	(segment
		(start 96.393 -73.914)
		(end 100.342192 -73.914)
		(width 0.127)
		(layer "In5.Cu")
		(net "JTAG_EXP_IOC_RST")
	)
	(segment
		(start 100.3808 -73.90384)
		(end 100.3808 -73.76287)
		(width 0.127)
		(layer "In5.Cu")
		(net "JTAG_EXP_IOC_RST")
	)
	(segment
		(start 47.968154 -122.465846)
		(end 77.597 -92.837)
		(width 0.127)
		(layer "In5.Cu")
		(net "JTAG_EXP_IOC_RST")
	)
	(segment
		(start 36.407852 -129.2987)
		(end 43.240706 -122.465846)
		(width 0.127)
		(layer "In5.Cu")
		(net "JTAG_EXP_IOC_RST")
	)
	(segment
		(start 43.240706 -122.465846)
		(end 47.968154 -122.465846)
		(width 0.127)
		(layer "In5.Cu")
		(net "JTAG_EXP_IOC_RST")
	)
	(segment
		(start 104.14 -73.406)
		(end 105.590594 -74.856594)
		(width 0.127)
		(layer "In5.Cu")
		(net "JTAG_EXP_IOC_RST")
	)
	(segment
		(start 88.125046 -82.1817)
		(end 95.699072 -74.607928)
		(width 0.127)
		(layer "In5.Cu")
		(net "JTAG_EXP_IOC_RST")
	)
	(segment
		(start 33.1597 -141.6177)
		(end 33.1597 -130.350768)
		(width 0.127)
		(layer "In5.Cu")
		(net "JTAG_EXP_IOC_RST")
	)
	(segment
		(start 33.655 -142.113)
		(end 33.1597 -141.6177)
		(width 0.127)
		(layer "In5.Cu")
		(net "JTAG_EXP_IOC_RST")
	)
	(segment
		(start 105.590594 -74.856594)
		(end 105.711498 -74.856594)
		(width 0.127)
		(layer "In5.Cu")
		(net "JTAG_EXP_IOC_RST")
	)
	(segment
		(start 86.797134 -82.7913)
		(end 87.406734 -82.1817)
		(width 0.127)
		(layer "In5.Cu")
		(net "JTAG_EXP_IOC_RST")
	)
	(segment
		(start 100.342192 -73.914)
		(end 100.356416 -73.928224)
		(width 0.127)
		(layer "In5.Cu")
		(net "JTAG_EXP_IOC_RST")
	)
	(segment
		(start 95.699072 -74.607928)
		(end 96.393 -73.914)
		(width 0.127)
		(layer "In5.Cu")
		(net "JTAG_EXP_IOC_RST")
	)
	(segment
		(start 33.1597 -130.350768)
		(end 34.211768 -129.2987)
		(width 0.127)
		(layer "In5.Cu")
		(net "JTAG_EXP_IOC_RST")
	)
	(segment
		(start 100.73767 -73.406)
		(end 104.14 -73.406)
		(width 0.127)
		(layer "In5.Cu")
		(net "JTAG_EXP_IOC_RST")
	)
	(segment
		(start 87.406734 -82.1817)
		(end 88.125046 -82.1817)
		(width 0.127)
		(layer "In5.Cu")
		(net "JTAG_EXP_IOC_RST")
	)
	(segment
		(start 220.345 -158.6865)
		(end 220.345 -159.512)
		(width 0.1143)
		(layer "F.Cu")
		(net "JTAG_DT")
	)
	(segment
		(start 219.7735 -166.90975)
		(end 220.05925 -166.624)
		(width 0.1143)
		(layer "F.Cu")
		(net "JTAG_DT")
	)
	(segment
		(start 222.758 -160.1978)
		(end 222.504 -160.4518)
		(width 0.1143)
		(layer "F.Cu")
		(net "JTAG_DT")
	)
	(segment
		(start 220.05925 -166.624)
		(end 220.1418 -166.624)
		(width 0.1143)
		(layer "F.Cu")
		(net "JTAG_DT")
	)
	(segment
		(start 219.7735 -167.62476)
		(end 219.7735 -166.90975)
		(width 0.1143)
		(layer "F.Cu")
		(net "JTAG_DT")
	)
	(segment
		(start 220.1418 -166.624)
		(end 220.345 -166.4208)
		(width 0.1143)
		(layer "F.Cu")
		(net "JTAG_DT")
	)
	(segment
		(start 220.345 -159.512)
		(end 220.726 -159.893)
		(width 0.1143)
		(layer "F.Cu")
		(net "JTAG_DT")
	)
	(segment
		(start 221.2848 -160.4518)
		(end 220.726 -159.893)
		(width 0.1143)
		(layer "F.Cu")
		(net "JTAG_DT")
	)
	(segment
		(start 222.504 -160.4518)
		(end 221.2848 -160.4518)
		(width 0.1143)
		(layer "F.Cu")
		(net "JTAG_DT")
	)
	(segment
		(start 222.758 -158.234888)
		(end 222.758 -160.1978)
		(width 0.1143)
		(layer "F.Cu")
		(net "JTAG_DT")
	)
	(via
		(at 220.345 -166.4208)
		(size 0.5588)
		(drill 0.3048)
		(layers "F.Cu" "B.Cu")
		(net "JTAG_DT")
	)
	(via
		(at 222.504 -160.4518)
		(size 0.5588)
		(drill 0.3048)
		(layers "F.Cu" "B.Cu")
		(net "JTAG_DT")
	)
	(via
		(at 220.726 -159.893)
		(size 0.7112)
		(drill 0.3556)
		(layers "F.Cu" "B.Cu")
		(net "JTAG_DT")
	)
	(segment
		(start 222.504 -164.2618)
		(end 220.345 -166.4208)
		(width 0.1143)
		(layer "B.Cu")
		(net "JTAG_DT")
	)
	(segment
		(start 222.504 -160.4518)
		(end 222.504 -164.2618)
		(width 0.1143)
		(layer "B.Cu")
		(net "JTAG_DT")
	)
	(segment
		(start 101.99497 -78.613)
		(end 101.99497 -79.121)
		(width 0.1143)
		(layer "F.Cu")
		(net "JTAG_EXP_TDO_R")
	)
	(segment
		(start 101.99497 -79.121)
		(end 102.851204 -79.977234)
		(width 0.1143)
		(layer "F.Cu")
		(net "JTAG_EXP_TDO_R")
	)
	(segment
		(start 102.851204 -79.977234)
		(end 102.851204 -80.993234)
		(width 0.1143)
		(layer "F.Cu")
		(net "JTAG_EXP_TDO_R")
	)
	(segment
		(start 106.3498 -85.349842)
		(end 105.849674 -84.849716)
		(width 0.1143)
		(layer "F.Cu")
		(net "JTAG_EXP_TDO_R")
	)
	(segment
		(start 101.74097 -78.359)
		(end 101.99497 -78.613)
		(width 0.1143)
		(layer "F.Cu")
		(net "JTAG_EXP_TDO_R")
	)
	(segment
		(start 101.74097 -76.8985)
		(end 101.74097 -78.359)
		(width 0.1143)
		(layer "F.Cu")
		(net "JTAG_EXP_TDO_R")
	)
	(segment
		(start 102.851204 -80.993234)
		(end 103.26497 -81.407)
		(width 0.1143)
		(layer "F.Cu")
		(net "JTAG_EXP_TDO_R")
	)
	(via
		(at 103.26497 -81.407)
		(size 0.5588)
		(drill 0.3048)
		(layers "F.Cu" "B.Cu")
		(net "JTAG_EXP_TDO_R")
	)
	(via
		(at 105.849674 -84.849716)
		(size 0.508)
		(drill 0.254)
		(layers "F.Cu" "B.Cu")
		(net "JTAG_EXP_TDO_R")
	)
	(segment
		(start 103.26497 -81.407)
		(end 103.862632 -81.407)
		(width 0.1143)
		(layer "B.Cu")
		(net "JTAG_EXP_TDO_R")
	)
	(segment
		(start 105.818686 -84.849716)
		(end 105.849674 -84.849716)
		(width 0.1143)
		(layer "B.Cu")
		(net "JTAG_EXP_TDO_R")
	)
	(segment
		(start 103.862632 -81.407)
		(end 104.78897 -82.333338)
		(width 0.1143)
		(layer "B.Cu")
		(net "JTAG_EXP_TDO_R")
	)
	(segment
		(start 104.78897 -83.205066)
		(end 105.262426 -83.678522)
		(width 0.1143)
		(layer "B.Cu")
		(net "JTAG_EXP_TDO_R")
	)
	(segment
		(start 104.78897 -82.333338)
		(end 104.78897 -83.205066)
		(width 0.1143)
		(layer "B.Cu")
		(net "JTAG_EXP_TDO_R")
	)
	(segment
		(start 105.262426 -83.678522)
		(end 105.262426 -84.293456)
		(width 0.1143)
		(layer "B.Cu")
		(net "JTAG_EXP_TDO_R")
	)
	(segment
		(start 105.262426 -84.293456)
		(end 105.818686 -84.849716)
		(width 0.1143)
		(layer "B.Cu")
		(net "JTAG_EXP_TDO_R")
	)
	(segment
		(start 102.07117 -74.549)
		(end 101.53777 -75.0824)
		(width 0.1143)
		(layer "F.Cu")
		(net "JTAG_EXP_TDO")
	)
	(segment
		(start 314.4774 -217.7669)
		(end 314.4774 -221.3356)
		(width 0.1143)
		(layer "F.Cu")
		(net "JTAG_EXP_TDO")
	)
	(segment
		(start 101.53777 -75.8063)
		(end 101.53777 -75.1078)
		(width 0.1143)
		(layer "F.Cu")
		(net "JTAG_EXP_TDO")
	)
	(segment
		(start 101.53777 -75.0824)
		(end 101.53777 -75.1078)
		(width 0.1143)
		(layer "F.Cu")
		(net "JTAG_EXP_TDO")
	)
	(segment
		(start 101.74097 -76.0095)
		(end 101.53777 -75.8063)
		(width 0.1143)
		(layer "F.Cu")
		(net "JTAG_EXP_TDO")
	)
	(segment
		(start 305.550316 -230.262684)
		(end 278.745442 -230.262684)
		(width 0.1143)
		(layer "F.Cu")
		(net "JTAG_EXP_TDO")
	)
	(segment
		(start 314.4774 -221.3356)
		(end 305.550316 -230.262684)
		(width 0.1143)
		(layer "F.Cu")
		(net "JTAG_EXP_TDO")
	)
	(via
		(at 101.53777 -75.1078)
		(size 0.7112)
		(drill 0.3556)
		(layers "F.Cu" "B.Cu")
		(net "JTAG_EXP_TDO")
	)
	(via
		(at 158.115 -176.911)
		(size 0.508)
		(drill 0.254)
		(layers "F.Cu" "B.Cu")
		(net "JTAG_EXP_TDO")
	)
	(via
		(at 102.07117 -74.549)
		(size 0.5588)
		(drill 0.3048)
		(layers "F.Cu" "B.Cu")
		(net "JTAG_EXP_TDO")
	)
	(via
		(at 278.745442 -230.262684)
		(size 0.5588)
		(drill 0.3048)
		(layers "F.Cu" "B.Cu")
		(net "JTAG_EXP_TDO")
	)
	(segment
		(start 110.97895 -74.701908)
		(end 110.97895 -74.878692)
		(width 0.1143)
		(layer "B.Cu")
		(net "JTAG_EXP_TDO")
	)
	(segment
		(start 158.115 -176.911)
		(end 158.115 -162.687)
		(width 0.1143)
		(layer "B.Cu")
		(net "JTAG_EXP_TDO")
	)
	(segment
		(start 113.411 -73.29805)
		(end 112.382808 -73.29805)
		(width 0.1143)
		(layer "B.Cu")
		(net "JTAG_EXP_TDO")
	)
	(segment
		(start 112.382808 -73.29805)
		(end 110.97895 -74.701908)
		(width 0.1143)
		(layer "B.Cu")
		(net "JTAG_EXP_TDO")
	)
	(segment
		(start 115.80495 -75.692)
		(end 113.411 -73.29805)
		(width 0.1143)
		(layer "B.Cu")
		(net "JTAG_EXP_TDO")
	)
	(segment
		(start 137.209784 -93.902784)
		(end 137.209784 -87.57793)
		(width 0.1143)
		(layer "B.Cu")
		(net "JTAG_EXP_TDO")
	)
	(segment
		(start 118.020084 -75.692)
		(end 115.80495 -75.692)
		(width 0.1143)
		(layer "B.Cu")
		(net "JTAG_EXP_TDO")
	)
	(segment
		(start 158.115 -162.687)
		(end 140.589 -145.161)
		(width 0.1143)
		(layer "B.Cu")
		(net "JTAG_EXP_TDO")
	)
	(segment
		(start 140.589 -145.161)
		(end 140.589 -97.282)
		(width 0.1143)
		(layer "B.Cu")
		(net "JTAG_EXP_TDO")
	)
	(segment
		(start 125.9586 -74.4474)
		(end 120.7516 -74.4474)
		(width 0.1143)
		(layer "B.Cu")
		(net "JTAG_EXP_TDO")
	)
	(segment
		(start 137.209784 -87.57793)
		(end 129.667 -80.035146)
		(width 0.1143)
		(layer "B.Cu")
		(net "JTAG_EXP_TDO")
	)
	(segment
		(start 129.667 -78.1558)
		(end 125.9586 -74.4474)
		(width 0.1143)
		(layer "B.Cu")
		(net "JTAG_EXP_TDO")
	)
	(segment
		(start 110.489492 -75.36815)
		(end 102.89032 -75.36815)
		(width 0.1143)
		(layer "B.Cu")
		(net "JTAG_EXP_TDO")
	)
	(segment
		(start 120.24995 -74.94905)
		(end 118.763034 -74.94905)
		(width 0.1143)
		(layer "B.Cu")
		(net "JTAG_EXP_TDO")
	)
	(segment
		(start 102.89032 -75.36815)
		(end 102.07117 -74.549)
		(width 0.1143)
		(layer "B.Cu")
		(net "JTAG_EXP_TDO")
	)
	(segment
		(start 129.667 -80.035146)
		(end 129.667 -78.1558)
		(width 0.1143)
		(layer "B.Cu")
		(net "JTAG_EXP_TDO")
	)
	(segment
		(start 140.589 -97.282)
		(end 137.209784 -93.902784)
		(width 0.1143)
		(layer "B.Cu")
		(net "JTAG_EXP_TDO")
	)
	(segment
		(start 110.97895 -74.878692)
		(end 110.489492 -75.36815)
		(width 0.1143)
		(layer "B.Cu")
		(net "JTAG_EXP_TDO")
	)
	(segment
		(start 118.763034 -74.94905)
		(end 118.020084 -75.692)
		(width 0.1143)
		(layer "B.Cu")
		(net "JTAG_EXP_TDO")
	)
	(segment
		(start 120.7516 -74.4474)
		(end 120.24995 -74.94905)
		(width 0.1143)
		(layer "B.Cu")
		(net "JTAG_EXP_TDO")
	)
	(segment
		(start 210.6803 -182.1307)
		(end 250.926346 -182.1307)
		(width 0.127)
		(layer "In2.Cu")
		(net "JTAG_EXP_TDO")
	)
	(segment
		(start 262.824468 -204.978)
		(end 264.792968 -204.978)
		(width 0.127)
		(layer "In2.Cu")
		(net "JTAG_EXP_TDO")
	)
	(segment
		(start 261.982712 -204.136244)
		(end 262.824468 -204.978)
		(width 0.127)
		(layer "In2.Cu")
		(net "JTAG_EXP_TDO")
	)
	(segment
		(start 158.115 -176.911)
		(end 162.941 -176.911)
		(width 0.127)
		(layer "In2.Cu")
		(net "JTAG_EXP_TDO")
	)
	(segment
		(start 170.307 -184.277)
		(end 195.453 -184.277)
		(width 0.127)
		(layer "In2.Cu")
		(net "JTAG_EXP_TDO")
	)
	(segment
		(start 264.792968 -204.978)
		(end 278.236172 -218.421204)
		(width 0.127)
		(layer "In2.Cu")
		(net "JTAG_EXP_TDO")
	)
	(segment
		(start 195.453 -184.277)
		(end 196.723 -185.547)
		(width 0.127)
		(layer "In2.Cu")
		(net "JTAG_EXP_TDO")
	)
	(segment
		(start 196.723 -185.547)
		(end 207.264 -185.547)
		(width 0.127)
		(layer "In2.Cu")
		(net "JTAG_EXP_TDO")
	)
	(segment
		(start 278.236172 -229.753414)
		(end 278.745442 -230.262684)
		(width 0.127)
		(layer "In2.Cu")
		(net "JTAG_EXP_TDO")
	)
	(segment
		(start 162.941 -176.911)
		(end 170.307 -184.277)
		(width 0.127)
		(layer "In2.Cu")
		(net "JTAG_EXP_TDO")
	)
	(segment
		(start 261.982712 -193.187066)
		(end 261.982712 -204.136244)
		(width 0.127)
		(layer "In2.Cu")
		(net "JTAG_EXP_TDO")
	)
	(segment
		(start 207.264 -185.547)
		(end 210.6803 -182.1307)
		(width 0.127)
		(layer "In2.Cu")
		(net "JTAG_EXP_TDO")
	)
	(segment
		(start 250.926346 -182.1307)
		(end 261.982712 -193.187066)
		(width 0.127)
		(layer "In2.Cu")
		(net "JTAG_EXP_TDO")
	)
	(segment
		(start 278.236172 -218.421204)
		(end 278.236172 -229.753414)
		(width 0.127)
		(layer "In2.Cu")
		(net "JTAG_EXP_TDO")
	)
	(segment
		(start 109.855 -76.454)
		(end 109.22 -77.089)
		(width 0.1143)
		(layer "F.Cu")
		(net "EXP_LED_12")
	)
	(segment
		(start 107.442 -78.359)
		(end 107.442 -79.25943)
		(width 0.1143)
		(layer "F.Cu")
		(net "EXP_LED_12")
	)
	(segment
		(start 108.06557 -79.883)
		(end 109.356906 -79.883)
		(width 0.1143)
		(layer "F.Cu")
		(net "EXP_LED_12")
	)
	(segment
		(start 108.712 -77.089)
		(end 107.442 -78.359)
		(width 0.1143)
		(layer "F.Cu")
		(net "EXP_LED_12")
	)
	(segment
		(start 109.22 -77.089)
		(end 108.712 -77.089)
		(width 0.1143)
		(layer "F.Cu")
		(net "EXP_LED_12")
	)
	(segment
		(start 110.876842 -82.875882)
		(end 111.34979 -83.34883)
		(width 0.1143)
		(layer "F.Cu")
		(net "EXP_LED_12")
	)
	(segment
		(start 111.34979 -83.34883)
		(end 111.34979 -83.349846)
		(width 0.1143)
		(layer "F.Cu")
		(net "EXP_LED_12")
	)
	(segment
		(start 107.442 -79.25943)
		(end 108.06557 -79.883)
		(width 0.1143)
		(layer "F.Cu")
		(net "EXP_LED_12")
	)
	(segment
		(start 110.876842 -81.402936)
		(end 110.876842 -82.875882)
		(width 0.1143)
		(layer "F.Cu")
		(net "EXP_LED_12")
	)
	(segment
		(start 109.356906 -79.883)
		(end 110.876842 -81.402936)
		(width 0.1143)
		(layer "F.Cu")
		(net "EXP_LED_12")
	)
	(via
		(at 117.696234 -73.754234)
		(size 0.5588)
		(drill 0.3048)
		(layers "F.Cu" "B.Cu")
		(net "EXP_LED_12")
	)
	(via
		(at 109.855 -76.454)
		(size 0.5588)
		(drill 0.3048)
		(layers "F.Cu" "B.Cu")
		(net "EXP_LED_12")
	)
	(segment
		(start 117.4115 -73.4695)
		(end 117.4115 -72.771)
		(width 0.1143)
		(layer "B.Cu")
		(net "EXP_LED_12")
	)
	(segment
		(start 117.696234 -73.754234)
		(end 117.4115 -73.4695)
		(width 0.1143)
		(layer "B.Cu")
		(net "EXP_LED_12")
	)
	(segment
		(start 115.697 -76.454)
		(end 109.855 -76.454)
		(width 0.127)
		(layer "In5.Cu")
		(net "EXP_LED_12")
	)
	(segment
		(start 116.459 -74.991468)
		(end 116.459 -75.692)
		(width 0.127)
		(layer "In5.Cu")
		(net "EXP_LED_12")
	)
	(segment
		(start 117.696234 -73.754234)
		(end 116.459 -74.991468)
		(width 0.127)
		(layer "In5.Cu")
		(net "EXP_LED_12")
	)
	(segment
		(start 116.459 -75.692)
		(end 115.697 -76.454)
		(width 0.127)
		(layer "In5.Cu")
		(net "EXP_LED_12")
	)
	(segment
		(start 111.34979 -85.349842)
		(end 110.849664 -84.849716)
		(width 0.1143)
		(layer "F.Cu")
		(net "EXP_LED_13")
	)
	(via
		(at 110.849664 -84.849716)
		(size 0.508)
		(drill 0.254)
		(layers "F.Cu" "B.Cu")
		(net "EXP_LED_13")
	)
	(segment
		(start 112.02797 -84.328)
		(end 111.633 -84.328)
		(width 0.1143)
		(layer "B.Cu")
		(net "EXP_LED_13")
	)
	(segment
		(start 111.111284 -84.849716)
		(end 110.849664 -84.849716)
		(width 0.1143)
		(layer "B.Cu")
		(net "EXP_LED_13")
	)
	(segment
		(start 111.633 -84.328)
		(end 111.111284 -84.849716)
		(width 0.1143)
		(layer "B.Cu")
		(net "EXP_LED_13")
	)
	(segment
		(start 112.40897 -82.296)
		(end 112.40897 -83.947)
		(width 0.1143)
		(layer "B.Cu")
		(net "EXP_LED_13")
	)
	(segment
		(start 112.40897 -83.947)
		(end 112.02797 -84.328)
		(width 0.1143)
		(layer "B.Cu")
		(net "EXP_LED_13")
	)
	(segment
		(start 112.27435 -86.34984)
		(end 111.90097 -85.852)
		(width 0.1143)
		(layer "F.Cu")
		(net "EXP_LED_14")
	)
	(segment
		(start 112.349788 -86.34984)
		(end 112.27435 -86.34984)
		(width 0.1143)
		(layer "F.Cu")
		(net "EXP_LED_14")
	)
	(via
		(at 111.90097 -85.852)
		(size 0.508)
		(drill 0.254)
		(layers "F.Cu" "B.Cu")
		(net "EXP_LED_14")
	)
	(segment
		(start 110.88497 -86.868)
		(end 111.90097 -85.852)
		(width 0.1143)
		(layer "B.Cu")
		(net "EXP_LED_14")
	)
	(segment
		(start 110.75797 -86.868)
		(end 110.88497 -86.868)
		(width 0.1143)
		(layer "B.Cu")
		(net "EXP_LED_14")
	)
	(segment
		(start 111.34979 -81.534508)
		(end 111.34979 -82.349848)
		(width 0.1143)
		(layer "F.Cu")
		(net "EXP_LED_15")
	)
	(segment
		(start 109.456982 -79.6417)
		(end 111.34979 -81.534508)
		(width 0.1143)
		(layer "F.Cu")
		(net "EXP_LED_15")
	)
	(segment
		(start 108.14177 -79.05877)
		(end 108.7247 -79.6417)
		(width 0.1143)
		(layer "F.Cu")
		(net "EXP_LED_15")
	)
	(segment
		(start 108.14177 -78.6892)
		(end 108.14177 -79.05877)
		(width 0.1143)
		(layer "F.Cu")
		(net "EXP_LED_15")
	)
	(segment
		(start 108.7247 -79.6417)
		(end 109.456982 -79.6417)
		(width 0.1143)
		(layer "F.Cu")
		(net "EXP_LED_15")
	)
	(segment
		(start 36.576 -151.511)
		(end 36.576 -145.415)
		(width 0.1143)
		(layer "F.Cu")
		(net "SAS_HDD_LED23")
	)
	(segment
		(start 30.353 -157.734)
		(end 36.576 -151.511)
		(width 0.1143)
		(layer "F.Cu")
		(net "SAS_HDD_LED23")
	)
	(segment
		(start 112.349788 -81.784698)
		(end 112.09909 -81.534)
		(width 0.1143)
		(layer "F.Cu")
		(net "SAS_HDD_LED23")
	)
	(segment
		(start 26.025348 -170.107356)
		(end 26.025348 -162.061652)
		(width 0.1143)
		(layer "F.Cu")
		(net "SAS_HDD_LED23")
	)
	(segment
		(start 112.349788 -82.349848)
		(end 112.349788 -81.784698)
		(width 0.1143)
		(layer "F.Cu")
		(net "SAS_HDD_LED23")
	)
	(segment
		(start 26.025348 -162.061652)
		(end 30.353 -157.734)
		(width 0.1143)
		(layer "F.Cu")
		(net "SAS_HDD_LED23")
	)
	(via
		(at 36.576 -145.415)
		(size 0.5588)
		(drill 0.3048)
		(layers "F.Cu" "B.Cu")
		(net "SAS_HDD_LED23")
	)
	(via
		(at 30.353 -157.734)
		(size 0.7112)
		(drill 0.3556)
		(layers "F.Cu" "B.Cu")
		(net "SAS_HDD_LED23")
	)
	(via
		(at 112.09909 -81.534)
		(size 0.508)
		(drill 0.254)
		(layers "F.Cu" "B.Cu")
		(net "SAS_HDD_LED23")
	)
	(segment
		(start 94.072202 -82.4103)
		(end 93.8657 -82.4103)
		(width 0.127)
		(layer "In5.Cu")
		(net "SAS_HDD_LED23")
	)
	(segment
		(start 94.36227 -81.91373)
		(end 94.36227 -82.120232)
		(width 0.127)
		(layer "In5.Cu")
		(net "SAS_HDD_LED23")
	)
	(segment
		(start 108.047536 -77.2795)
		(end 98.9965 -77.2795)
		(width 0.127)
		(layer "In5.Cu")
		(net "SAS_HDD_LED23")
	)
	(segment
		(start 38.481 -142.52321)
		(end 38.481 -143.51)
		(width 0.127)
		(layer "In5.Cu")
		(net "SAS_HDD_LED23")
	)
	(segment
		(start 112.09909 -80.60309)
		(end 109.728 -78.232)
		(width 0.127)
		(layer "In5.Cu")
		(net "SAS_HDD_LED23")
	)
	(segment
		(start 93.345 -82.931)
		(end 93.345 -83.088988)
		(width 0.127)
		(layer "In5.Cu")
		(net "SAS_HDD_LED23")
	)
	(segment
		(start 93.8657 -82.4103)
		(end 93.345 -82.931)
		(width 0.127)
		(layer "In5.Cu")
		(net "SAS_HDD_LED23")
	)
	(segment
		(start 94.36227 -82.120232)
		(end 94.072202 -82.4103)
		(width 0.127)
		(layer "In5.Cu")
		(net "SAS_HDD_LED23")
	)
	(segment
		(start 94.99727 -81.358232)
		(end 94.707202 -81.6483)
		(width 0.127)
		(layer "In5.Cu")
		(net "SAS_HDD_LED23")
	)
	(segment
		(start 94.6277 -81.6483)
		(end 94.36227 -81.91373)
		(width 0.127)
		(layer "In5.Cu")
		(net "SAS_HDD_LED23")
	)
	(segment
		(start 46.736 -130.048)
		(end 44.196 -132.588)
		(width 0.127)
		(layer "In5.Cu")
		(net "SAS_HDD_LED23")
	)
	(segment
		(start 44.196 -136.80821)
		(end 38.481 -142.52321)
		(width 0.127)
		(layer "In5.Cu")
		(net "SAS_HDD_LED23")
	)
	(segment
		(start 94.707202 -81.6483)
		(end 94.6277 -81.6483)
		(width 0.127)
		(layer "In5.Cu")
		(net "SAS_HDD_LED23")
	)
	(segment
		(start 44.196 -132.588)
		(end 44.196 -136.80821)
		(width 0.127)
		(layer "In5.Cu")
		(net "SAS_HDD_LED23")
	)
	(segment
		(start 109.728 -78.232)
		(end 109.000036 -78.232)
		(width 0.127)
		(layer "In5.Cu")
		(net "SAS_HDD_LED23")
	)
	(segment
		(start 38.481 -143.51)
		(end 36.576 -145.415)
		(width 0.127)
		(layer "In5.Cu")
		(net "SAS_HDD_LED23")
	)
	(segment
		(start 109.000036 -78.232)
		(end 108.047536 -77.2795)
		(width 0.127)
		(layer "In5.Cu")
		(net "SAS_HDD_LED23")
	)
	(segment
		(start 46.736 -129.697988)
		(end 46.736 -130.048)
		(width 0.127)
		(layer "In5.Cu")
		(net "SAS_HDD_LED23")
	)
	(segment
		(start 112.09909 -81.534)
		(end 112.09909 -80.60309)
		(width 0.127)
		(layer "In5.Cu")
		(net "SAS_HDD_LED23")
	)
	(segment
		(start 98.9965 -77.2795)
		(end 94.99727 -81.27873)
		(width 0.127)
		(layer "In5.Cu")
		(net "SAS_HDD_LED23")
	)
	(segment
		(start 93.345 -83.088988)
		(end 46.736 -129.697988)
		(width 0.127)
		(layer "In5.Cu")
		(net "SAS_HDD_LED23")
	)
	(segment
		(start 94.99727 -81.27873)
		(end 94.99727 -81.358232)
		(width 0.127)
		(layer "In5.Cu")
		(net "SAS_HDD_LED23")
	)
	(segment
		(start 27.051 -160.147)
		(end 35.89655 -151.30145)
		(width 0.1143)
		(layer "F.Cu")
		(net "SAS_HDD_LED22")
	)
	(segment
		(start 35.89655 -144.48155)
		(end 35.687 -144.272)
		(width 0.1143)
		(layer "F.Cu")
		(net "SAS_HDD_LED22")
	)
	(segment
		(start 114.349784 -86.324186)
		(end 114.82197 -85.852)
		(width 0.1143)
		(layer "F.Cu")
		(net "SAS_HDD_LED22")
	)
	(segment
		(start 35.89655 -151.30145)
		(end 35.89655 -144.48155)
		(width 0.1143)
		(layer "F.Cu")
		(net "SAS_HDD_LED22")
	)
	(segment
		(start 114.349784 -86.34984)
		(end 114.349784 -86.324186)
		(width 0.1143)
		(layer "F.Cu")
		(net "SAS_HDD_LED22")
	)
	(segment
		(start 25.625298 -170.107356)
		(end 25.625298 -161.572702)
		(width 0.1143)
		(layer "F.Cu")
		(net "SAS_HDD_LED22")
	)
	(segment
		(start 25.625298 -161.572702)
		(end 27.051 -160.147)
		(width 0.1143)
		(layer "F.Cu")
		(net "SAS_HDD_LED22")
	)
	(via
		(at 35.687 -144.272)
		(size 0.5588)
		(drill 0.3048)
		(layers "F.Cu" "B.Cu")
		(net "SAS_HDD_LED22")
	)
	(via
		(at 27.051 -160.147)
		(size 0.7112)
		(drill 0.3556)
		(layers "F.Cu" "B.Cu")
		(net "SAS_HDD_LED22")
	)
	(via
		(at 114.82197 -85.852)
		(size 0.508)
		(drill 0.254)
		(layers "F.Cu" "B.Cu")
		(net "SAS_HDD_LED22")
	)
	(segment
		(start 45.974 -129.54)
		(end 45.974 -129.255012)
		(width 0.127)
		(layer "In5.Cu")
		(net "SAS_HDD_LED22")
	)
	(segment
		(start 111.887 -78.867)
		(end 112.06099 -78.867)
		(width 0.127)
		(layer "In5.Cu")
		(net "SAS_HDD_LED22")
	)
	(segment
		(start 110.484412 -77.47)
		(end 111.754666 -78.740254)
		(width 0.127)
		(layer "In5.Cu")
		(net "SAS_HDD_LED22")
	)
	(segment
		(start 35.687 -144.272)
		(end 37.719 -142.24)
		(width 0.127)
		(layer "In5.Cu")
		(net "SAS_HDD_LED22")
	)
	(segment
		(start 96.43745 -77.978)
		(end 96.901 -77.978)
		(width 0.127)
		(layer "In5.Cu")
		(net "SAS_HDD_LED22")
	)
	(segment
		(start 115.283742 -82.089752)
		(end 115.283742 -85.390228)
		(width 0.127)
		(layer "In5.Cu")
		(net "SAS_HDD_LED22")
	)
	(segment
		(start 92.456 -82.773012)
		(end 92.456 -81.95945)
		(width 0.127)
		(layer "In5.Cu")
		(net "SAS_HDD_LED22")
	)
	(segment
		(start 111.754666 -78.740254)
		(end 111.760254 -78.740254)
		(width 0.127)
		(layer "In5.Cu")
		(net "SAS_HDD_LED22")
	)
	(segment
		(start 45.974 -129.255012)
		(end 92.456 -82.773012)
		(width 0.127)
		(layer "In5.Cu")
		(net "SAS_HDD_LED22")
	)
	(segment
		(start 37.719 -142.24)
		(end 37.719 -137.795)
		(width 0.127)
		(layer "In5.Cu")
		(net "SAS_HDD_LED22")
	)
	(segment
		(start 108.363512 -76.5175)
		(end 109.316012 -77.47)
		(width 0.127)
		(layer "In5.Cu")
		(net "SAS_HDD_LED22")
	)
	(segment
		(start 37.719 -137.795)
		(end 45.974 -129.54)
		(width 0.127)
		(layer "In5.Cu")
		(net "SAS_HDD_LED22")
	)
	(segment
		(start 98.3615 -76.5175)
		(end 108.363512 -76.5175)
		(width 0.127)
		(layer "In5.Cu")
		(net "SAS_HDD_LED22")
	)
	(segment
		(start 111.760254 -78.740254)
		(end 111.887 -78.867)
		(width 0.127)
		(layer "In5.Cu")
		(net "SAS_HDD_LED22")
	)
	(segment
		(start 109.316012 -77.47)
		(end 110.484412 -77.47)
		(width 0.127)
		(layer "In5.Cu")
		(net "SAS_HDD_LED22")
	)
	(segment
		(start 96.901 -77.978)
		(end 98.3615 -76.5175)
		(width 0.127)
		(layer "In5.Cu")
		(net "SAS_HDD_LED22")
	)
	(segment
		(start 92.456 -81.95945)
		(end 96.43745 -77.978)
		(width 0.127)
		(layer "In5.Cu")
		(net "SAS_HDD_LED22")
	)
	(segment
		(start 112.06099 -78.867)
		(end 115.283742 -82.089752)
		(width 0.127)
		(layer "In5.Cu")
		(net "SAS_HDD_LED22")
	)
	(segment
		(start 115.283742 -85.390228)
		(end 114.82197 -85.852)
		(width 0.127)
		(layer "In5.Cu")
		(net "SAS_HDD_LED22")
	)
	(segment
		(start 115.82019 -85.852)
		(end 115.83797 -85.852)
		(width 0.1143)
		(layer "F.Cu")
		(net "SAS_HDD_LED21")
	)
	(segment
		(start 115.350036 -86.322154)
		(end 115.82019 -85.852)
		(width 0.1143)
		(layer "F.Cu")
		(net "SAS_HDD_LED21")
	)
	(segment
		(start 34.544 -143.885158)
		(end 34.544 -143.764)
		(width 0.1143)
		(layer "F.Cu")
		(net "SAS_HDD_LED21")
	)
	(segment
		(start 25.225248 -170.107356)
		(end 25.225248 -161.083752)
		(width 0.1143)
		(layer "F.Cu")
		(net "SAS_HDD_LED21")
	)
	(segment
		(start 35.52825 -144.869408)
		(end 34.544 -143.885158)
		(width 0.1143)
		(layer "F.Cu")
		(net "SAS_HDD_LED21")
	)
	(segment
		(start 30.734 -155.575)
		(end 35.52825 -150.78075)
		(width 0.1143)
		(layer "F.Cu")
		(net "SAS_HDD_LED21")
	)
	(segment
		(start 115.350036 -86.34984)
		(end 115.350036 -86.322154)
		(width 0.1143)
		(layer "F.Cu")
		(net "SAS_HDD_LED21")
	)
	(segment
		(start 25.225248 -161.083752)
		(end 30.734 -155.575)
		(width 0.1143)
		(layer "F.Cu")
		(net "SAS_HDD_LED21")
	)
	(segment
		(start 35.52825 -150.78075)
		(end 35.52825 -144.869408)
		(width 0.1143)
		(layer "F.Cu")
		(net "SAS_HDD_LED21")
	)
	(via
		(at 34.544 -143.764)
		(size 0.5588)
		(drill 0.3048)
		(layers "F.Cu" "B.Cu")
		(net "SAS_HDD_LED21")
	)
	(via
		(at 30.734 -155.575)
		(size 0.7112)
		(drill 0.3556)
		(layers "F.Cu" "B.Cu")
		(net "SAS_HDD_LED21")
	)
	(via
		(at 115.83797 -85.852)
		(size 0.508)
		(drill 0.254)
		(layers "F.Cu" "B.Cu")
		(net "SAS_HDD_LED21")
	)
	(segment
		(start 36.576 -141.732)
		(end 34.544 -143.764)
		(width 0.127)
		(layer "In5.Cu")
		(net "SAS_HDD_LED21")
	)
	(segment
		(start 108.5215 -76.1365)
		(end 97.981008 -76.1365)
		(width 0.127)
		(layer "In5.Cu")
		(net "SAS_HDD_LED21")
	)
	(segment
		(start 91.94927 -81.927192)
		(end 91.94927 -82.596228)
		(width 0.127)
		(layer "In5.Cu")
		(net "SAS_HDD_LED21")
	)
	(segment
		(start 88.011 -86.679024)
		(end 45.593 -129.097024)
		(width 0.127)
		(layer "In5.Cu")
		(net "SAS_HDD_LED21")
	)
	(segment
		(start 115.83797 -85.852)
		(end 116.269262 -85.420708)
		(width 0.127)
		(layer "In5.Cu")
		(net "SAS_HDD_LED21")
	)
	(segment
		(start 45.593 -129.300224)
		(end 36.576 -138.317224)
		(width 0.127)
		(layer "In5.Cu")
		(net "SAS_HDD_LED21")
	)
	(segment
		(start 96.279462 -77.597)
		(end 91.94927 -81.927192)
		(width 0.127)
		(layer "In5.Cu")
		(net "SAS_HDD_LED21")
	)
	(segment
		(start 88.011 -86.534498)
		(end 88.011 -86.679024)
		(width 0.127)
		(layer "In5.Cu")
		(net "SAS_HDD_LED21")
	)
	(segment
		(start 36.576 -138.317224)
		(end 36.576 -141.732)
		(width 0.127)
		(layer "In5.Cu")
		(net "SAS_HDD_LED21")
	)
	(segment
		(start 96.520508 -77.597)
		(end 96.279462 -77.597)
		(width 0.127)
		(layer "In5.Cu")
		(net "SAS_HDD_LED21")
	)
	(segment
		(start 110.6424 -77.089)
		(end 109.474 -77.089)
		(width 0.127)
		(layer "In5.Cu")
		(net "SAS_HDD_LED21")
	)
	(segment
		(start 116.269262 -85.420708)
		(end 116.269262 -82.715862)
		(width 0.127)
		(layer "In5.Cu")
		(net "SAS_HDD_LED21")
	)
	(segment
		(start 91.94927 -82.596228)
		(end 88.011 -86.534498)
		(width 0.127)
		(layer "In5.Cu")
		(net "SAS_HDD_LED21")
	)
	(segment
		(start 97.981008 -76.1365)
		(end 96.520508 -77.597)
		(width 0.127)
		(layer "In5.Cu")
		(net "SAS_HDD_LED21")
	)
	(segment
		(start 45.593 -129.097024)
		(end 45.593 -129.300224)
		(width 0.127)
		(layer "In5.Cu")
		(net "SAS_HDD_LED21")
	)
	(segment
		(start 109.474 -77.089)
		(end 108.5215 -76.1365)
		(width 0.127)
		(layer "In5.Cu")
		(net "SAS_HDD_LED21")
	)
	(segment
		(start 116.269262 -82.715862)
		(end 110.6424 -77.089)
		(width 0.127)
		(layer "In5.Cu")
		(net "SAS_HDD_LED21")
	)
	(segment
		(start 24.825198 -170.107356)
		(end 24.825198 -160.594802)
		(width 0.1143)
		(layer "F.Cu")
		(net "SAS_HDD_LED20")
	)
	(segment
		(start 113.349786 -85.349842)
		(end 113.349786 -85.268816)
		(width 0.1143)
		(layer "F.Cu")
		(net "SAS_HDD_LED20")
	)
	(segment
		(start 35.15995 -150.26005)
		(end 35.15995 -145.39595)
		(width 0.1143)
		(layer "F.Cu")
		(net "SAS_HDD_LED20")
	)
	(segment
		(start 28.321 -157.099)
		(end 35.15995 -150.26005)
		(width 0.1143)
		(layer "F.Cu")
		(net "SAS_HDD_LED20")
	)
	(segment
		(start 24.825198 -160.594802)
		(end 28.321 -157.099)
		(width 0.1143)
		(layer "F.Cu")
		(net "SAS_HDD_LED20")
	)
	(segment
		(start 113.349786 -85.268816)
		(end 112.91697 -84.836)
		(width 0.1143)
		(layer "F.Cu")
		(net "SAS_HDD_LED20")
	)
	(segment
		(start 35.15995 -145.39595)
		(end 34.671 -144.907)
		(width 0.1143)
		(layer "F.Cu")
		(net "SAS_HDD_LED20")
	)
	(segment
		(start 34.671 -144.907)
		(end 34.671 -144.7038)
		(width 0.1143)
		(layer "F.Cu")
		(net "SAS_HDD_LED20")
	)
	(via
		(at 34.671 -144.7038)
		(size 0.5588)
		(drill 0.3048)
		(layers "F.Cu" "B.Cu")
		(net "SAS_HDD_LED20")
	)
	(via
		(at 112.91697 -84.836)
		(size 0.508)
		(drill 0.254)
		(layers "F.Cu" "B.Cu")
		(net "SAS_HDD_LED20")
	)
	(via
		(at 28.321 -157.099)
		(size 0.7112)
		(drill 0.3556)
		(layers "F.Cu" "B.Cu")
		(net "SAS_HDD_LED20")
	)
	(segment
		(start 46.355 -129.794)
		(end 46.355 -129.54)
		(width 0.127)
		(layer "In5.Cu")
		(net "SAS_HDD_LED20")
	)
	(segment
		(start 38.1 -142.559532)
		(end 38.1 -142.24)
		(width 0.127)
		(layer "In5.Cu")
		(net "SAS_HDD_LED20")
	)
	(segment
		(start 98.7425 -76.8985)
		(end 108.205524 -76.8985)
		(width 0.127)
		(layer "In5.Cu")
		(net "SAS_HDD_LED20")
	)
	(segment
		(start 112.51819 -81.037684)
		(end 112.51819 -81.707736)
		(width 0.127)
		(layer "In5.Cu")
		(net "SAS_HDD_LED20")
	)
	(segment
		(start 109.158024 -77.851)
		(end 110.236 -77.851)
		(width 0.127)
		(layer "In5.Cu")
		(net "SAS_HDD_LED20")
	)
	(segment
		(start 112.43056 -81.795366)
		(end 112.43056 -84.34959)
		(width 0.127)
		(layer "In5.Cu")
		(net "SAS_HDD_LED20")
	)
	(segment
		(start 42.770806 -133.378194)
		(end 46.355 -129.794)
		(width 0.127)
		(layer "In5.Cu")
		(net "SAS_HDD_LED20")
	)
	(segment
		(start 112.43056 -84.34959)
		(end 112.91697 -84.836)
		(width 0.127)
		(layer "In5.Cu")
		(net "SAS_HDD_LED20")
	)
	(segment
		(start 34.671 -144.7038)
		(end 34.7345 -144.7673)
		(width 0.127)
		(layer "In5.Cu")
		(net "SAS_HDD_LED20")
	)
	(segment
		(start 46.355 -129.54)
		(end 92.837 -83.058)
		(width 0.127)
		(layer "In5.Cu")
		(net "SAS_HDD_LED20")
	)
	(segment
		(start 42.770806 -137.569194)
		(end 42.770806 -133.378194)
		(width 0.127)
		(layer "In5.Cu")
		(net "SAS_HDD_LED20")
	)
	(segment
		(start 35.892232 -144.7673)
		(end 38.1 -142.559532)
		(width 0.127)
		(layer "In5.Cu")
		(net "SAS_HDD_LED20")
	)
	(segment
		(start 38.1 -142.24)
		(end 42.770806 -137.569194)
		(width 0.127)
		(layer "In5.Cu")
		(net "SAS_HDD_LED20")
	)
	(segment
		(start 110.236 -77.851)
		(end 112.4585 -80.0735)
		(width 0.127)
		(layer "In5.Cu")
		(net "SAS_HDD_LED20")
	)
	(segment
		(start 92.837 -82.117438)
		(end 96.595438 -78.359)
		(width 0.127)
		(layer "In5.Cu")
		(net "SAS_HDD_LED20")
	)
	(segment
		(start 112.4585 -80.0735)
		(end 112.4585 -80.977994)
		(width 0.127)
		(layer "In5.Cu")
		(net "SAS_HDD_LED20")
	)
	(segment
		(start 108.205524 -76.8985)
		(end 109.158024 -77.851)
		(width 0.127)
		(layer "In5.Cu")
		(net "SAS_HDD_LED20")
	)
	(segment
		(start 34.7345 -144.7673)
		(end 35.892232 -144.7673)
		(width 0.127)
		(layer "In5.Cu")
		(net "SAS_HDD_LED20")
	)
	(segment
		(start 112.51819 -81.707736)
		(end 112.43056 -81.795366)
		(width 0.127)
		(layer "In5.Cu")
		(net "SAS_HDD_LED20")
	)
	(segment
		(start 112.4585 -80.977994)
		(end 112.51819 -81.037684)
		(width 0.127)
		(layer "In5.Cu")
		(net "SAS_HDD_LED20")
	)
	(segment
		(start 92.837 -83.058)
		(end 92.837 -82.117438)
		(width 0.127)
		(layer "In5.Cu")
		(net "SAS_HDD_LED20")
	)
	(segment
		(start 96.595438 -78.359)
		(end 97.282 -78.359)
		(width 0.127)
		(layer "In5.Cu")
		(net "SAS_HDD_LED20")
	)
	(segment
		(start 97.282 -78.359)
		(end 98.7425 -76.8985)
		(width 0.127)
		(layer "In5.Cu")
		(net "SAS_HDD_LED20")
	)
	(segment
		(start 40.4495 -171.0055)
		(end 41.275 -170.18)
		(width 0.1143)
		(layer "F.Cu")
		(net "CPU_EXP_RESET_N")
	)
	(segment
		(start 203.62926 -216.13876)
		(end 203.6445 -216.154)
		(width 0.1143)
		(layer "F.Cu")
		(net "CPU_EXP_RESET_N")
	)
	(segment
		(start 198.501 -212.979)
		(end 196.469 -212.979)
		(width 0.1143)
		(layer "F.Cu")
		(net "CPU_EXP_RESET_N")
	)
	(segment
		(start 212.344 -214.122)
		(end 213.0425 -214.8205)
		(width 0.1143)
		(layer "F.Cu")
		(net "CPU_EXP_RESET_N")
	)
	(segment
		(start 200.4695 -216.13876)
		(end 203.62926 -216.13876)
		(width 0.1143)
		(layer "F.Cu")
		(net "CPU_EXP_RESET_N")
	)
	(segment
		(start 205.6765 -214.122)
		(end 212.344 -214.122)
		(width 0.1143)
		(layer "F.Cu")
		(net "CPU_EXP_RESET_N")
	)
	(segment
		(start 200.4695 -214.9475)
		(end 198.501 -212.979)
		(width 0.1143)
		(layer "F.Cu")
		(net "CPU_EXP_RESET_N")
	)
	(segment
		(start 40.41775 -171.0055)
		(end 40.4495 -171.0055)
		(width 0.1143)
		(layer "F.Cu")
		(net "CPU_EXP_RESET_N")
	)
	(segment
		(start 196.469 -212.979)
		(end 195.072 -211.582)
		(width 0.1143)
		(layer "F.Cu")
		(net "CPU_EXP_RESET_N")
	)
	(segment
		(start 213.0425 -214.8205)
		(end 213.1695 -214.99576)
		(width 0.1143)
		(layer "F.Cu")
		(net "CPU_EXP_RESET_N")
	)
	(segment
		(start 203.6445 -216.154)
		(end 205.6765 -214.122)
		(width 0.1143)
		(layer "F.Cu")
		(net "CPU_EXP_RESET_N")
	)
	(segment
		(start 200.4695 -216.13876)
		(end 200.4695 -214.9475)
		(width 0.1143)
		(layer "F.Cu")
		(net "CPU_EXP_RESET_N")
	)
	(via
		(at 41.275 -170.18)
		(size 0.5588)
		(drill 0.3048)
		(layers "F.Cu" "B.Cu")
		(net "CPU_EXP_RESET_N")
	)
	(via
		(at 195.072 -211.582)
		(size 0.5588)
		(drill 0.3048)
		(layers "F.Cu" "B.Cu")
		(net "CPU_EXP_RESET_N")
	)
	(via
		(at 195.072 -184.912)
		(size 0.5588)
		(drill 0.3048)
		(layers "F.Cu" "B.Cu")
		(net "CPU_EXP_RESET_N")
	)
	(via
		(at 195.072 -193.1924)
		(size 0.7112)
		(drill 0.3556)
		(layers "F.Cu" "B.Cu")
		(net "CPU_EXP_RESET_N")
	)
	(segment
		(start 195.072 -211.582)
		(end 195.072 -193.1924)
		(width 0.1143)
		(layer "B.Cu")
		(net "CPU_EXP_RESET_N")
	)
	(segment
		(start 195.072 -193.1924)
		(end 195.072 -184.912)
		(width 0.1143)
		(layer "B.Cu")
		(net "CPU_EXP_RESET_N")
	)
	(segment
		(start 162.687 -177.927)
		(end 170.0403 -185.2803)
		(width 0.127)
		(layer "In2.Cu")
		(net "CPU_EXP_RESET_N")
	)
	(segment
		(start 46.99 -170.688)
		(end 52.197 -175.895)
		(width 0.127)
		(layer "In2.Cu")
		(net "CPU_EXP_RESET_N")
	)
	(segment
		(start 66.548 -177.927)
		(end 162.687 -177.927)
		(width 0.127)
		(layer "In2.Cu")
		(net "CPU_EXP_RESET_N")
	)
	(segment
		(start 170.0403 -185.2803)
		(end 194.7037 -185.2803)
		(width 0.127)
		(layer "In2.Cu")
		(net "CPU_EXP_RESET_N")
	)
	(segment
		(start 52.197 -175.895)
		(end 64.516 -175.895)
		(width 0.127)
		(layer "In2.Cu")
		(net "CPU_EXP_RESET_N")
	)
	(segment
		(start 41.783 -170.688)
		(end 46.99 -170.688)
		(width 0.127)
		(layer "In2.Cu")
		(net "CPU_EXP_RESET_N")
	)
	(segment
		(start 194.7037 -185.2803)
		(end 195.072 -184.912)
		(width 0.127)
		(layer "In2.Cu")
		(net "CPU_EXP_RESET_N")
	)
	(segment
		(start 64.516 -175.895)
		(end 66.548 -177.927)
		(width 0.127)
		(layer "In2.Cu")
		(net "CPU_EXP_RESET_N")
	)
	(segment
		(start 41.275 -170.18)
		(end 41.783 -170.688)
		(width 0.127)
		(layer "In2.Cu")
		(net "CPU_EXP_RESET_N")
	)
	(segment
		(start 198.247 -224.7265)
		(end 196.7865 -226.187)
		(width 0.1143)
		(layer "F.Cu")
		(net "SYS_RSTBTN_N")
	)
	(segment
		(start 285.75 -161.0995)
		(end 285.760414 -161.089086)
		(width 0.1143)
		(layer "F.Cu")
		(net "SYS_RSTBTN_N")
	)
	(segment
		(start 285.760414 -161.089086)
		(end 285.760414 -160.274)
		(width 0.1143)
		(layer "F.Cu")
		(net "SYS_RSTBTN_N")
	)
	(segment
		(start 196.7865 -226.187)
		(end 196.723 -226.187)
		(width 0.1143)
		(layer "F.Cu")
		(net "SYS_RSTBTN_N")
	)
	(via
		(at 193.952622 -218.044776)
		(size 0.7112)
		(drill 0.3556)
		(layers "F.Cu" "B.Cu")
		(net "SYS_RSTBTN_N")
	)
	(via
		(at 194.818 -164.719)
		(size 0.5588)
		(drill 0.3048)
		(layers "F.Cu" "B.Cu")
		(net "SYS_RSTBTN_N")
	)
	(via
		(at 196.723 -226.187)
		(size 0.5588)
		(drill 0.3048)
		(layers "F.Cu" "B.Cu")
		(net "SYS_RSTBTN_N")
	)
	(via
		(at 285.760414 -160.274)
		(size 0.5588)
		(drill 0.3048)
		(layers "F.Cu" "B.Cu")
		(net "SYS_RSTBTN_N")
	)
	(segment
		(start 193.952622 -213.90102)
		(end 193.952622 -218.044776)
		(width 0.1143)
		(layer "B.Cu")
		(net "SYS_RSTBTN_N")
	)
	(segment
		(start 193.952622 -218.044776)
		(end 193.952622 -225.827082)
		(width 0.1143)
		(layer "B.Cu")
		(net "SYS_RSTBTN_N")
	)
	(segment
		(start 194.41795 -165.11905)
		(end 194.41795 -213.435692)
		(width 0.1143)
		(layer "B.Cu")
		(net "SYS_RSTBTN_N")
	)
	(segment
		(start 194.41795 -213.435692)
		(end 193.952622 -213.90102)
		(width 0.1143)
		(layer "B.Cu")
		(net "SYS_RSTBTN_N")
	)
	(segment
		(start 193.952622 -225.827082)
		(end 194.31254 -226.187)
		(width 0.1143)
		(layer "B.Cu")
		(net "SYS_RSTBTN_N")
	)
	(segment
		(start 194.818 -164.719)
		(end 194.41795 -165.11905)
		(width 0.1143)
		(layer "B.Cu")
		(net "SYS_RSTBTN_N")
	)
	(segment
		(start 194.31254 -226.187)
		(end 196.723 -226.187)
		(width 0.1143)
		(layer "B.Cu")
		(net "SYS_RSTBTN_N")
	)
	(segment
		(start 195.262754 -164.274246)
		(end 199.245474 -164.274246)
		(width 0.127)
		(layer "In2.Cu")
		(net "SYS_RSTBTN_N")
	)
	(segment
		(start 199.245474 -164.274246)
		(end 202.420728 -167.4495)
		(width 0.127)
		(layer "In2.Cu")
		(net "SYS_RSTBTN_N")
	)
	(segment
		(start 285.496 -160.274)
		(end 285.760414 -160.274)
		(width 0.127)
		(layer "In2.Cu")
		(net "SYS_RSTBTN_N")
	)
	(segment
		(start 228.699568 -167.4495)
		(end 232.687368 -163.4617)
		(width 0.127)
		(layer "In2.Cu")
		(net "SYS_RSTBTN_N")
	)
	(segment
		(start 251.201428 -166.3319)
		(end 257.211322 -166.3319)
		(width 0.127)
		(layer "In2.Cu")
		(net "SYS_RSTBTN_N")
	)
	(segment
		(start 202.420728 -167.4495)
		(end 228.699568 -167.4495)
		(width 0.127)
		(layer "In2.Cu")
		(net "SYS_RSTBTN_N")
	)
	(segment
		(start 257.211322 -166.3319)
		(end 257.763772 -165.77945)
		(width 0.127)
		(layer "In2.Cu")
		(net "SYS_RSTBTN_N")
	)
	(segment
		(start 257.763772 -165.77945)
		(end 273.399758 -165.77945)
		(width 0.127)
		(layer "In2.Cu")
		(net "SYS_RSTBTN_N")
	)
	(segment
		(start 273.399758 -165.77945)
		(end 277.127208 -162.052)
		(width 0.127)
		(layer "In2.Cu")
		(net "SYS_RSTBTN_N")
	)
	(segment
		(start 232.687368 -163.4617)
		(end 248.331228 -163.4617)
		(width 0.127)
		(layer "In2.Cu")
		(net "SYS_RSTBTN_N")
	)
	(segment
		(start 277.127208 -162.052)
		(end 283.718 -162.052)
		(width 0.127)
		(layer "In2.Cu")
		(net "SYS_RSTBTN_N")
	)
	(segment
		(start 194.818 -164.719)
		(end 195.262754 -164.274246)
		(width 0.127)
		(layer "In2.Cu")
		(net "SYS_RSTBTN_N")
	)
	(segment
		(start 283.718 -162.052)
		(end 285.496 -160.274)
		(width 0.127)
		(layer "In2.Cu")
		(net "SYS_RSTBTN_N")
	)
	(segment
		(start 248.331228 -163.4617)
		(end 251.201428 -166.3319)
		(width 0.127)
		(layer "In2.Cu")
		(net "SYS_RSTBTN_N")
	)
	(segment
		(start 273.7485 -165.608)
		(end 272.10385 -165.608)
		(width 0.1143)
		(layer "F.Cu")
		(net "BMC_RSTBTN_N")
	)
	(segment
		(start 194.691 -213.233)
		(end 193.929 -213.233)
		(width 0.1143)
		(layer "F.Cu")
		(net "BMC_RSTBTN_N")
	)
	(segment
		(start 195.6435 -214.1855)
		(end 194.691 -213.233)
		(width 0.1143)
		(layer "F.Cu")
		(net "BMC_RSTBTN_N")
	)
	(segment
		(start 195.6435 -216.789)
		(end 195.6435 -214.1855)
		(width 0.1143)
		(layer "F.Cu")
		(net "BMC_RSTBTN_N")
	)
	(segment
		(start 272.10385 -165.608)
		(end 271.78 -165.28415)
		(width 0.1143)
		(layer "F.Cu")
		(net "BMC_RSTBTN_N")
	)
	(segment
		(start 198.8185 -216.789)
		(end 195.6435 -216.789)
		(width 0.1143)
		(layer "F.Cu")
		(net "BMC_RSTBTN_N")
	)
	(via
		(at 193.7766 -195.0212)
		(size 0.7112)
		(drill 0.3556)
		(layers "F.Cu" "B.Cu")
		(net "BMC_RSTBTN_N")
	)
	(via
		(at 193.929 -213.233)
		(size 0.5588)
		(drill 0.3048)
		(layers "F.Cu" "B.Cu")
		(net "BMC_RSTBTN_N")
	)
	(via
		(at 271.78 -165.28415)
		(size 0.5588)
		(drill 0.3048)
		(layers "F.Cu" "B.Cu")
		(net "BMC_RSTBTN_N")
	)
	(via
		(at 193.802 -164.592)
		(size 0.5588)
		(drill 0.3048)
		(layers "F.Cu" "B.Cu")
		(net "BMC_RSTBTN_N")
	)
	(segment
		(start 193.929 -213.233)
		(end 193.7766 -213.0806)
		(width 0.1143)
		(layer "B.Cu")
		(net "BMC_RSTBTN_N")
	)
	(segment
		(start 193.929 -194.8688)
		(end 193.929 -164.719)
		(width 0.1143)
		(layer "B.Cu")
		(net "BMC_RSTBTN_N")
	)
	(segment
		(start 193.929 -164.719)
		(end 193.802 -164.592)
		(width 0.1143)
		(layer "B.Cu")
		(net "BMC_RSTBTN_N")
	)
	(segment
		(start 193.7766 -213.0806)
		(end 193.7766 -195.0212)
		(width 0.1143)
		(layer "B.Cu")
		(net "BMC_RSTBTN_N")
	)
	(segment
		(start 193.7766 -195.0212)
		(end 193.929 -194.8688)
		(width 0.1143)
		(layer "B.Cu")
		(net "BMC_RSTBTN_N")
	)
	(segment
		(start 271.78 -165.28415)
		(end 257.648202 -165.28415)
		(width 0.127)
		(layer "In2.Cu")
		(net "BMC_RSTBTN_N")
	)
	(segment
		(start 248.510298 -163.0299)
		(end 230.659432 -163.0299)
		(width 0.127)
		(layer "In2.Cu")
		(net "BMC_RSTBTN_N")
	)
	(segment
		(start 257.337052 -165.5953)
		(end 256.504948 -165.5953)
		(width 0.127)
		(layer "In2.Cu")
		(net "BMC_RSTBTN_N")
	)
	(segment
		(start 194.551554 -163.842446)
		(end 193.802 -164.592)
		(width 0.127)
		(layer "In2.Cu")
		(net "BMC_RSTBTN_N")
	)
	(segment
		(start 256.205736 -165.296088)
		(end 250.776486 -165.296088)
		(width 0.127)
		(layer "In2.Cu")
		(net "BMC_RSTBTN_N")
	)
	(segment
		(start 204.256132 -165.8366)
		(end 202.261978 -163.842446)
		(width 0.127)
		(layer "In2.Cu")
		(net "BMC_RSTBTN_N")
	)
	(segment
		(start 230.659432 -163.0299)
		(end 227.852732 -165.8366)
		(width 0.127)
		(layer "In2.Cu")
		(net "BMC_RSTBTN_N")
	)
	(segment
		(start 227.852732 -165.8366)
		(end 204.256132 -165.8366)
		(width 0.127)
		(layer "In2.Cu")
		(net "BMC_RSTBTN_N")
	)
	(segment
		(start 257.648202 -165.28415)
		(end 257.337052 -165.5953)
		(width 0.127)
		(layer "In2.Cu")
		(net "BMC_RSTBTN_N")
	)
	(segment
		(start 202.261978 -163.842446)
		(end 194.551554 -163.842446)
		(width 0.127)
		(layer "In2.Cu")
		(net "BMC_RSTBTN_N")
	)
	(segment
		(start 250.776486 -165.296088)
		(end 248.510298 -163.0299)
		(width 0.127)
		(layer "In2.Cu")
		(net "BMC_RSTBTN_N")
	)
	(segment
		(start 256.504948 -165.5953)
		(end 256.205736 -165.296088)
		(width 0.127)
		(layer "In2.Cu")
		(net "BMC_RSTBTN_N")
	)
	(segment
		(start 276.098 -166.116)
		(end 277.206456 -166.116)
		(width 0.1143)
		(layer "F.Cu")
		(net "BMC_RSTBTN_N_R")
	)
	(segment
		(start 277.206456 -166.116)
		(end 278.003 -166.912544)
		(width 0.1143)
		(layer "F.Cu")
		(net "BMC_RSTBTN_N_R")
	)
	(segment
		(start 275.59 -165.608)
		(end 276.098 -166.116)
		(width 0.1143)
		(layer "F.Cu")
		(net "BMC_RSTBTN_N_R")
	)
	(segment
		(start 289.625278 -169.840148)
		(end 289.231832 -169.446702)
		(width 0.1143)
		(layer "F.Cu")
		(net "BMC_RSTBTN_N_R")
	)
	(segment
		(start 274.6375 -165.608)
		(end 275.59 -165.608)
		(width 0.1143)
		(layer "F.Cu")
		(net "BMC_RSTBTN_N_R")
	)
	(segment
		(start 289.63493 -169.840148)
		(end 289.625278 -169.840148)
		(width 0.1143)
		(layer "F.Cu")
		(net "BMC_RSTBTN_N_R")
	)
	(segment
		(start 278.003 -166.912544)
		(end 278.003 -167.005)
		(width 0.1143)
		(layer "F.Cu")
		(net "BMC_RSTBTN_N_R")
	)
	(via
		(at 289.231832 -169.446702)
		(size 0.508)
		(drill 0.254)
		(layers "F.Cu" "B.Cu")
		(net "BMC_RSTBTN_N_R")
	)
	(via
		(at 278.892 -167.386)
		(size 0.7112)
		(drill 0.3556)
		(layers "F.Cu" "B.Cu")
		(net "BMC_RSTBTN_N_R")
	)
	(via
		(at 278.003 -167.005)
		(size 0.5588)
		(drill 0.3048)
		(layers "F.Cu" "B.Cu")
		(net "BMC_RSTBTN_N_R")
	)
	(segment
		(start 278.835104 -167.386)
		(end 278.892 -167.386)
		(width 0.1143)
		(layer "B.Cu")
		(net "BMC_RSTBTN_N_R")
	)
	(segment
		(start 278.454104 -167.005)
		(end 278.835104 -167.386)
		(width 0.1143)
		(layer "B.Cu")
		(net "BMC_RSTBTN_N_R")
	)
	(segment
		(start 278.003 -167.005)
		(end 278.454104 -167.005)
		(width 0.1143)
		(layer "B.Cu")
		(net "BMC_RSTBTN_N_R")
	)
	(segment
		(start 288.844228 -168.80586)
		(end 289.231832 -169.193464)
		(width 0.0889)
		(layer "In2.Cu")
		(net "BMC_RSTBTN_N_R")
	)
	(segment
		(start 281.6479 -163.3601)
		(end 284.0101 -163.3601)
		(width 0.127)
		(layer "In2.Cu")
		(net "BMC_RSTBTN_N_R")
	)
	(segment
		(start 289.231832 -169.193464)
		(end 289.231832 -169.446702)
		(width 0.0889)
		(layer "In2.Cu")
		(net "BMC_RSTBTN_N_R")
	)
	(segment
		(start 288.844228 -168.194228)
		(end 288.844228 -168.80586)
		(width 0.0889)
		(layer "In2.Cu")
		(net "BMC_RSTBTN_N_R")
	)
	(segment
		(start 278.003 -167.005)
		(end 281.6479 -163.3601)
		(width 0.127)
		(layer "In2.Cu")
		(net "BMC_RSTBTN_N_R")
	)
	(segment
		(start 284.0101 -163.3601)
		(end 288.844228 -168.194228)
		(width 0.127)
		(layer "In2.Cu")
		(net "BMC_RSTBTN_N_R")
	)
	(segment
		(start 286.30245 -164.745162)
		(end 286.304736 -164.747448)
		(width 0.1143)
		(layer "F.Cu")
		(net "SYS_RSTBTN_N_R")
	)
	(segment
		(start 286.305498 -164.74821)
		(end 286.305498 -165.110922)
		(width 0.1143)
		(layer "F.Cu")
		(net "SYS_RSTBTN_N_R")
	)
	(segment
		(start 285.75 -161.9885)
		(end 286.30245 -162.54095)
		(width 0.1143)
		(layer "F.Cu")
		(net "SYS_RSTBTN_N_R")
	)
	(segment
		(start 286.30245 -162.54095)
		(end 286.30245 -164.745162)
		(width 0.1143)
		(layer "F.Cu")
		(net "SYS_RSTBTN_N_R")
	)
	(segment
		(start 288.034984 -166.840408)
		(end 288.034984 -167.440102)
		(width 0.1143)
		(layer "F.Cu")
		(net "SYS_RSTBTN_N_R")
	)
	(segment
		(start 286.304736 -164.747448)
		(end 286.305498 -164.74821)
		(width 0.1143)
		(layer "F.Cu")
		(net "SYS_RSTBTN_N_R")
	)
	(segment
		(start 286.305498 -165.110922)
		(end 288.034984 -166.840408)
		(width 0.1143)
		(layer "F.Cu")
		(net "SYS_RSTBTN_N_R")
	)
	(via
		(at 286.304736 -164.747448)
		(size 0.7112)
		(drill 0.3556)
		(layers "F.Cu" "B.Cu")
		(net "SYS_RSTBTN_N_R")
	)
	(segment
		(start 197.21576 -217.43924)
		(end 196.876162 -217.778838)
		(width 0.1143)
		(layer "F.Cu")
		(net "RSTBTN_OUT_N")
	)
	(segment
		(start 198.8185 -217.43924)
		(end 197.21576 -217.43924)
		(width 0.1143)
		(layer "F.Cu")
		(net "RSTBTN_OUT_N")
	)
	(segment
		(start 196.723 -217.932)
		(end 196.876162 -217.778838)
		(width 0.1143)
		(layer "F.Cu")
		(net "RSTBTN_OUT_N")
	)
	(segment
		(start 195.6435 -217.932)
		(end 196.723 -217.932)
		(width 0.1143)
		(layer "F.Cu")
		(net "RSTBTN_OUT_N")
	)
	(segment
		(start 198.86676 -217.4875)
		(end 198.8185 -217.43924)
		(width 0.1143)
		(layer "F.Cu")
		(net "RSTBTN_OUT_N")
	)
	(segment
		(start 198.86676 -219.6465)
		(end 198.86676 -217.4875)
		(width 0.1143)
		(layer "F.Cu")
		(net "RSTBTN_OUT_N")
	)
	(via
		(at 196.876162 -217.778838)
		(size 0.7112)
		(drill 0.3556)
		(layers "F.Cu" "B.Cu")
		(net "RSTBTN_OUT_N")
	)
	(segment
		(start 198.247 -223.8375)
		(end 196.977 -223.8375)
		(width 0.1143)
		(layer "F.Cu")
		(net "RSTBTN_FP_N")
	)
	(segment
		(start 199.39 -223.8375)
		(end 199.517 -223.7105)
		(width 0.1143)
		(layer "F.Cu")
		(net "RSTBTN_FP_N")
	)
	(segment
		(start 194.98945 -223.8375)
		(end 196.977 -223.8375)
		(width 0.1143)
		(layer "F.Cu")
		(net "RSTBTN_FP_N")
	)
	(segment
		(start 198.247 -223.8375)
		(end 199.39 -223.8375)
		(width 0.1143)
		(layer "F.Cu")
		(net "RSTBTN_FP_N")
	)
	(segment
		(start 194.9704 -223.85655)
		(end 194.98945 -223.8375)
		(width 0.1143)
		(layer "F.Cu")
		(net "RSTBTN_FP_N")
	)
	(segment
		(start 199.517 -223.7105)
		(end 199.517 -221.2975)
		(width 0.1143)
		(layer "F.Cu")
		(net "RSTBTN_FP_N")
	)
	(via
		(at 196.977 -223.8375)
		(size 0.7112)
		(drill 0.3556)
		(layers "F.Cu" "B.Cu")
		(net "RSTBTN_FP_N")
	)
	(segment
		(start 193.802 -224.50552)
		(end 193.548 -224.25152)
		(width 0.1143)
		(layer "F.Cu")
		(net "FP_RETBTN_R")
	)
	(segment
		(start 194.9704 -224.50552)
		(end 193.802 -224.50552)
		(width 0.1143)
		(layer "F.Cu")
		(net "FP_RETBTN_R")
	)
	(segment
		(start 192.5955 -222.123)
		(end 193.548 -222.123)
		(width 0.1143)
		(layer "F.Cu")
		(net "FP_RETBTN_R")
	)
	(segment
		(start 193.548 -224.25152)
		(end 193.548 -222.123)
		(width 0.1143)
		(layer "F.Cu")
		(net "FP_RETBTN_R")
	)
	(via
		(at 193.548 -222.123)
		(size 0.7112)
		(drill 0.3556)
		(layers "F.Cu" "B.Cu")
		(net "FP_RETBTN_R")
	)
	(segment
		(start 190.754 -224.12452)
		(end 190.754 -222.123)
		(width 0.1143)
		(layer "F.Cu")
		(net "FP_RETBTN")
	)
	(segment
		(start 191.7065 -222.123)
		(end 190.754 -222.123)
		(width 0.1143)
		(layer "F.Cu")
		(net "FP_RETBTN")
	)
	(segment
		(start 189.3316 -224.50552)
		(end 190.373 -224.50552)
		(width 0.1143)
		(layer "F.Cu")
		(net "FP_RETBTN")
	)
	(segment
		(start 190.373 -224.50552)
		(end 190.754 -224.12452)
		(width 0.1143)
		(layer "F.Cu")
		(net "FP_RETBTN")
	)
	(via
		(at 190.754 -222.123)
		(size 0.7112)
		(drill 0.3556)
		(layers "F.Cu" "B.Cu")
		(net "FP_RETBTN")
	)
	(segment
		(start 300.609 -127.489712)
		(end 294.101012 -133.9977)
		(width 0.1143)
		(layer "F.Cu")
		(net "FP_RESET_RC_N")
	)
	(segment
		(start 326.009 -65.913)
		(end 324.104 -67.818)
		(width 0.1143)
		(layer "F.Cu")
		(net "FP_RESET_RC_N")
	)
	(segment
		(start 326.276208 -16.68018)
		(end 326.009 -16.947388)
		(width 0.1143)
		(layer "F.Cu")
		(net "FP_RESET_RC_N")
	)
	(segment
		(start 340.868 -20.6375)
		(end 339.2805 -20.6375)
		(width 0.1143)
		(layer "F.Cu")
		(net "FP_RESET_RC_N")
	)
	(segment
		(start 305.054 -109.22)
		(end 305.054 -116.84)
		(width 0.1143)
		(layer "F.Cu")
		(net "FP_RESET_RC_N")
	)
	(segment
		(start 338.201 -17.05737)
		(end 337.82381 -16.68018)
		(width 0.1143)
		(layer "F.Cu")
		(net "FP_RESET_RC_N")
	)
	(segment
		(start 305.562 -108.712)
		(end 305.054 -109.22)
		(width 0.1143)
		(layer "F.Cu")
		(net "FP_RESET_RC_N")
	)
	(segment
		(start 294.101012 -133.9977)
		(end 287.255712 -133.9977)
		(width 0.1143)
		(layer "F.Cu")
		(net "FP_RESET_RC_N")
	)
	(segment
		(start 188.07176 -225.15576)
		(end 187.96 -225.044)
		(width 0.1143)
		(layer "F.Cu")
		(net "FP_RESET_RC_N")
	)
	(segment
		(start 324.104 -67.818)
		(end 324.104 -82.169)
		(width 0.1143)
		(layer "F.Cu")
		(net "FP_RESET_RC_N")
	)
	(segment
		(start 339.2805 -20.6375)
		(end 338.201 -19.558)
		(width 0.1143)
		(layer "F.Cu")
		(net "FP_RESET_RC_N")
	)
	(segment
		(start 338.201 -19.558)
		(end 338.201 -17.05737)
		(width 0.1143)
		(layer "F.Cu")
		(net "FP_RESET_RC_N")
	)
	(segment
		(start 300.609 -121.285)
		(end 300.609 -127.489712)
		(width 0.1143)
		(layer "F.Cu")
		(net "FP_RESET_RC_N")
	)
	(segment
		(start 318.262 -88.011)
		(end 318.262 -93.853)
		(width 0.1143)
		(layer "F.Cu")
		(net "FP_RESET_RC_N")
	)
	(segment
		(start 305.562 -106.553)
		(end 305.562 -108.712)
		(width 0.1143)
		(layer "F.Cu")
		(net "FP_RESET_RC_N")
	)
	(segment
		(start 189.3316 -225.15576)
		(end 188.07176 -225.15576)
		(width 0.1143)
		(layer "F.Cu")
		(net "FP_RESET_RC_N")
	)
	(segment
		(start 305.054 -116.84)
		(end 300.609 -121.285)
		(width 0.1143)
		(layer "F.Cu")
		(net "FP_RESET_RC_N")
	)
	(segment
		(start 337.82381 -16.68018)
		(end 326.276208 -16.68018)
		(width 0.1143)
		(layer "F.Cu")
		(net "FP_RESET_RC_N")
	)
	(segment
		(start 326.009 -16.947388)
		(end 326.009 -65.913)
		(width 0.1143)
		(layer "F.Cu")
		(net "FP_RESET_RC_N")
	)
	(segment
		(start 324.104 -82.169)
		(end 318.262 -88.011)
		(width 0.1143)
		(layer "F.Cu")
		(net "FP_RESET_RC_N")
	)
	(segment
		(start 318.262 -93.853)
		(end 305.562 -106.553)
		(width 0.1143)
		(layer "F.Cu")
		(net "FP_RESET_RC_N")
	)
	(via
		(at 187.96 -225.044)
		(size 0.5588)
		(drill 0.3048)
		(layers "F.Cu" "B.Cu")
		(net "FP_RESET_RC_N")
	)
	(via
		(at 190.119 -218.1098)
		(size 0.7112)
		(drill 0.3556)
		(layers "F.Cu" "B.Cu")
		(net "FP_RESET_RC_N")
	)
	(via
		(at 287.255712 -133.9977)
		(size 0.5588)
		(drill 0.3048)
		(layers "F.Cu" "B.Cu")
		(net "FP_RESET_RC_N")
	)
	(via
		(at 208.153 -143.256)
		(size 0.5588)
		(drill 0.3048)
		(layers "F.Cu" "B.Cu")
		(net "FP_RESET_RC_N")
	)
	(segment
		(start 191.77 -203.708)
		(end 191.77 -185.928)
		(width 0.1143)
		(layer "B.Cu")
		(net "FP_RESET_RC_N")
	)
	(segment
		(start 207.645 -149.86)
		(end 207.645 -143.764)
		(width 0.1143)
		(layer "B.Cu")
		(net "FP_RESET_RC_N")
	)
	(segment
		(start 190.119 -223.012)
		(end 190.119 -218.1098)
		(width 0.1143)
		(layer "B.Cu")
		(net "FP_RESET_RC_N")
	)
	(segment
		(start 207.645 -143.764)
		(end 208.153 -143.256)
		(width 0.1143)
		(layer "B.Cu")
		(net "FP_RESET_RC_N")
	)
	(segment
		(start 187.96 -225.044)
		(end 188.087 -225.044)
		(width 0.1143)
		(layer "B.Cu")
		(net "FP_RESET_RC_N")
	)
	(segment
		(start 190.119 -218.1098)
		(end 190.119 -205.359)
		(width 0.1143)
		(layer "B.Cu")
		(net "FP_RESET_RC_N")
	)
	(segment
		(start 188.087 -225.044)
		(end 190.119 -223.012)
		(width 0.1143)
		(layer "B.Cu")
		(net "FP_RESET_RC_N")
	)
	(segment
		(start 192.278 -185.42)
		(end 192.278 -165.227)
		(width 0.1143)
		(layer "B.Cu")
		(net "FP_RESET_RC_N")
	)
	(segment
		(start 192.278 -165.227)
		(end 207.645 -149.86)
		(width 0.1143)
		(layer "B.Cu")
		(net "FP_RESET_RC_N")
	)
	(segment
		(start 190.119 -205.359)
		(end 191.77 -203.708)
		(width 0.1143)
		(layer "B.Cu")
		(net "FP_RESET_RC_N")
	)
	(segment
		(start 191.77 -185.928)
		(end 192.278 -185.42)
		(width 0.1143)
		(layer "B.Cu")
		(net "FP_RESET_RC_N")
	)
	(segment
		(start 274.844002 -143.7513)
		(end 208.6483 -143.7513)
		(width 0.127)
		(layer "In2.Cu")
		(net "FP_RESET_RC_N")
	)
	(segment
		(start 287.255712 -133.985)
		(end 284.610302 -133.985)
		(width 0.127)
		(layer "In2.Cu")
		(net "FP_RESET_RC_N")
	)
	(segment
		(start 208.6483 -143.7513)
		(end 208.153 -143.256)
		(width 0.127)
		(layer "In2.Cu")
		(net "FP_RESET_RC_N")
	)
	(segment
		(start 284.610302 -133.985)
		(end 274.844002 -143.7513)
		(width 0.127)
		(layer "In2.Cu")
		(net "FP_RESET_RC_N")
	)
	(segment
		(start 287.255712 -133.9977)
		(end 287.255712 -133.985)
		(width 0.127)
		(layer "In2.Cu")
		(net "FP_RESET_RC_N")
	)
	(via
		(at 166.116 -115.7986)
		(size 0.7112)
		(drill 0.3556)
		(layers "F.Cu" "B.Cu")
		(net "P3V3_STBY_G4")
	)
	(segment
		(start 166.116 -115.6335)
		(end 166.116 -115.7986)
		(width 0.127)
		(layer "B.Cu")
		(net "P3V3_STBY_G4")
	)
	(segment
		(start 165.354 -114.8715)
		(end 166.116 -115.6335)
		(width 0.127)
		(layer "B.Cu")
		(net "P3V3_STBY_G4")
	)
	(segment
		(start 165.3921 -116.5225)
		(end 166.116 -115.7986)
		(width 0.127)
		(layer "B.Cu")
		(net "P3V3_STBY_G4")
	)
	(segment
		(start 164.94125 -116.5225)
		(end 165.3921 -116.5225)
		(width 0.127)
		(layer "B.Cu")
		(net "P3V3_STBY_G4")
	)
	(segment
		(start 339.725 -19.558)
		(end 340.6775 -19.558)
		(width 0.1143)
		(layer "F.Cu")
		(net "CPU_EXP_RST")
	)
	(segment
		(start 342.138 -19.812)
		(end 340.9315 -19.812)
		(width 0.1143)
		(layer "F.Cu")
		(net "CPU_EXP_RST")
	)
	(segment
		(start 343.408 -19.8755)
		(end 342.2015 -19.8755)
		(width 0.1143)
		(layer "F.Cu")
		(net "CPU_EXP_RST")
	)
	(segment
		(start 340.9315 -19.812)
		(end 340.868 -19.7485)
		(width 0.1143)
		(layer "F.Cu")
		(net "CPU_EXP_RST")
	)
	(segment
		(start 347.160342 -19.8755)
		(end 343.408 -19.8755)
		(width 0.1143)
		(layer "F.Cu")
		(net "CPU_EXP_RST")
	)
	(segment
		(start 347.235018 -19.950176)
		(end 347.160342 -19.8755)
		(width 0.1143)
		(layer "F.Cu")
		(net "CPU_EXP_RST")
	)
	(segment
		(start 353.734878 -19.950176)
		(end 347.235018 -19.950176)
		(width 0.1143)
		(layer "F.Cu")
		(net "CPU_EXP_RST")
	)
	(segment
		(start 342.2015 -19.8755)
		(end 342.138 -19.812)
		(width 0.1143)
		(layer "F.Cu")
		(net "CPU_EXP_RST")
	)
	(segment
		(start 340.6775 -19.558)
		(end 340.868 -19.7485)
		(width 0.1143)
		(layer "F.Cu")
		(net "CPU_EXP_RST")
	)
	(via
		(at 339.725 -19.558)
		(size 0.7112)
		(drill 0.3556)
		(layers "F.Cu" "B.Cu")
		(net "CPU_EXP_RST")
	)
	(segment
		(start 42.79773 -133.25475)
		(end 43.06697 -133.52399)
		(width 0.127)
		(layer "F.Cu")
		(net "P3V3_STBY_G5")
	)
	(segment
		(start 41.98747 -134.62)
		(end 43.06697 -134.62)
		(width 0.127)
		(layer "F.Cu")
		(net "P3V3_STBY_G5")
	)
	(segment
		(start 43.06697 -133.52399)
		(end 43.06697 -134.62)
		(width 0.127)
		(layer "F.Cu")
		(net "P3V3_STBY_G5")
	)
	(via
		(at 43.06697 -134.62)
		(size 0.7112)
		(drill 0.3556)
		(layers "F.Cu" "B.Cu")
		(net "P3V3_STBY_G5")
	)
	(segment
		(start 287.782 -161.9885)
		(end 287.72993 -162.04057)
		(width 0.1143)
		(layer "F.Cu")
		(net "BMC_PWRBTN_N_R")
	)
	(segment
		(start 288.798 -166.74846)
		(end 288.798 -167.259)
		(width 0.1143)
		(layer "F.Cu")
		(net "BMC_PWRBTN_N_R")
	)
	(segment
		(start 288.798 -167.259)
		(end 288.83483 -167.29583)
		(width 0.1143)
		(layer "F.Cu")
		(net "BMC_PWRBTN_N_R")
	)
	(segment
		(start 287.72993 -163.75253)
		(end 287.72993 -165.680136)
		(width 0.1143)
		(layer "F.Cu")
		(net "BMC_PWRBTN_N_R")
	)
	(segment
		(start 288.12744 -166.077646)
		(end 288.798 -166.74846)
		(width 0.1143)
		(layer "F.Cu")
		(net "BMC_PWRBTN_N_R")
	)
	(segment
		(start 288.83483 -167.29583)
		(end 288.83483 -167.440102)
		(width 0.1143)
		(layer "F.Cu")
		(net "BMC_PWRBTN_N_R")
	)
	(segment
		(start 287.72993 -162.04057)
		(end 287.72993 -163.75253)
		(width 0.1143)
		(layer "F.Cu")
		(net "BMC_PWRBTN_N_R")
	)
	(segment
		(start 287.72993 -165.680136)
		(end 288.12744 -166.077646)
		(width 0.1143)
		(layer "F.Cu")
		(net "BMC_PWRBTN_N_R")
	)
	(via
		(at 287.72993 -163.75253)
		(size 0.7112)
		(drill 0.3556)
		(layers "F.Cu" "B.Cu")
		(net "BMC_PWRBTN_N_R")
	)
	(segment
		(start 288.83483 -168.036494)
		(end 288.83483 -168.240202)
		(width 0.1143)
		(layer "F.Cu")
		(net "SYS_PWRBTN_N_R")
	)
	(segment
		(start 288.371534 -166.831518)
		(end 288.371534 -167.573198)
		(width 0.1143)
		(layer "F.Cu")
		(net "SYS_PWRBTN_N_R")
	)
	(segment
		(start 288.371534 -167.573198)
		(end 288.83483 -168.036494)
		(width 0.1143)
		(layer "F.Cu")
		(net "SYS_PWRBTN_N_R")
	)
	(segment
		(start 286.893 -162.7886)
		(end 286.8676 -162.814)
		(width 0.1143)
		(layer "F.Cu")
		(net "SYS_PWRBTN_N_R")
	)
	(segment
		(start 286.766 -161.9885)
		(end 286.893 -162.1155)
		(width 0.1143)
		(layer "F.Cu")
		(net "SYS_PWRBTN_N_R")
	)
	(segment
		(start 286.8676 -162.8902)
		(end 286.8676 -164.510974)
		(width 0.1143)
		(layer "F.Cu")
		(net "SYS_PWRBTN_N_R")
	)
	(segment
		(start 286.869886 -164.51326)
		(end 286.869886 -164.981636)
		(width 0.1143)
		(layer "F.Cu")
		(net "SYS_PWRBTN_N_R")
	)
	(segment
		(start 286.8676 -162.814)
		(end 286.8676 -162.8902)
		(width 0.1143)
		(layer "F.Cu")
		(net "SYS_PWRBTN_N_R")
	)
	(segment
		(start 286.869886 -164.981636)
		(end 286.8676 -164.983922)
		(width 0.1143)
		(layer "F.Cu")
		(net "SYS_PWRBTN_N_R")
	)
	(segment
		(start 286.8676 -165.327584)
		(end 288.371534 -166.831518)
		(width 0.1143)
		(layer "F.Cu")
		(net "SYS_PWRBTN_N_R")
	)
	(segment
		(start 286.893 -162.1155)
		(end 286.893 -162.7886)
		(width 0.1143)
		(layer "F.Cu")
		(net "SYS_PWRBTN_N_R")
	)
	(segment
		(start 286.8676 -164.510974)
		(end 286.869886 -164.51326)
		(width 0.1143)
		(layer "F.Cu")
		(net "SYS_PWRBTN_N_R")
	)
	(segment
		(start 286.8676 -164.983922)
		(end 286.8676 -165.327584)
		(width 0.1143)
		(layer "F.Cu")
		(net "SYS_PWRBTN_N_R")
	)
	(via
		(at 286.8676 -162.8902)
		(size 0.7112)
		(drill 0.3556)
		(layers "F.Cu" "B.Cu")
		(net "SYS_PWRBTN_N_R")
	)
	(segment
		(start 288.34715 -161.67735)
		(end 288.34715 -164.77615)
		(width 0.1143)
		(layer "F.Cu")
		(net "FM_BMC_READY_N_R")
	)
	(segment
		(start 288.34715 -164.77615)
		(end 288.4424 -164.8714)
		(width 0.1143)
		(layer "F.Cu")
		(net "FM_BMC_READY_N_R")
	)
	(segment
		(start 289.052 -165.481)
		(end 288.4424 -164.8714)
		(width 0.1143)
		(layer "F.Cu")
		(net "FM_BMC_READY_N_R")
	)
	(segment
		(start 289.63493 -167.96893)
		(end 289.179 -167.513)
		(width 0.1143)
		(layer "F.Cu")
		(net "FM_BMC_READY_N_R")
	)
	(segment
		(start 288.798 -161.2265)
		(end 288.34715 -161.67735)
		(width 0.1143)
		(layer "F.Cu")
		(net "FM_BMC_READY_N_R")
	)
	(segment
		(start 289.052 -167.132)
		(end 289.052 -165.481)
		(width 0.1143)
		(layer "F.Cu")
		(net "FM_BMC_READY_N_R")
	)
	(segment
		(start 289.63493 -168.240202)
		(end 289.63493 -167.96893)
		(width 0.1143)
		(layer "F.Cu")
		(net "FM_BMC_READY_N_R")
	)
	(segment
		(start 289.179 -167.513)
		(end 289.179 -167.259)
		(width 0.1143)
		(layer "F.Cu")
		(net "FM_BMC_READY_N_R")
	)
	(segment
		(start 289.179 -167.259)
		(end 289.052 -167.132)
		(width 0.1143)
		(layer "F.Cu")
		(net "FM_BMC_READY_N_R")
	)
	(via
		(at 288.4424 -164.8714)
		(size 0.7112)
		(drill 0.3556)
		(layers "F.Cu" "B.Cu")
		(net "FM_BMC_READY_N_R")
	)
	(segment
		(start 189.3316 -226.45624)
		(end 185.42 -226.45624)
		(width 0.1143)
		(layer "F.Cu")
		(net "FP_PWRBTN_R")
	)
	(segment
		(start 184.48274 -226.45624)
		(end 185.42 -226.45624)
		(width 0.1143)
		(layer "F.Cu")
		(net "FP_PWRBTN_R")
	)
	(segment
		(start 184.404 -226.3775)
		(end 184.48274 -226.45624)
		(width 0.1143)
		(layer "F.Cu")
		(net "FP_PWRBTN_R")
	)
	(via
		(at 185.42 -226.45624)
		(size 0.7112)
		(drill 0.3556)
		(layers "F.Cu" "B.Cu")
		(net "FP_PWRBTN_R")
	)
	(segment
		(start 168.471342 -179.874164)
		(end 168.471342 -218.744546)
		(width 0.1143)
		(layer "F.Cu")
		(net "SYS_PWRBTN_N")
	)
	(segment
		(start 176.910746 -227.18395)
		(end 177.27295 -227.18395)
		(width 0.1143)
		(layer "F.Cu")
		(net "SYS_PWRBTN_N")
	)
	(segment
		(start 182.13705 -227.18395)
		(end 177.27295 -227.18395)
		(width 0.1143)
		(layer "F.Cu")
		(net "SYS_PWRBTN_N")
	)
	(segment
		(start 286.766 -159.747204)
		(end 287.14446 -159.368744)
		(width 0.1143)
		(layer "F.Cu")
		(net "SYS_PWRBTN_N")
	)
	(segment
		(start 183.9595 -225.3615)
		(end 182.13705 -227.18395)
		(width 0.1143)
		(layer "F.Cu")
		(net "SYS_PWRBTN_N")
	)
	(segment
		(start 168.471342 -218.744546)
		(end 176.910746 -227.18395)
		(width 0.1143)
		(layer "F.Cu")
		(net "SYS_PWRBTN_N")
	)
	(segment
		(start 171.370752 -176.974754)
		(end 168.471342 -179.874164)
		(width 0.1143)
		(layer "F.Cu")
		(net "SYS_PWRBTN_N")
	)
	(segment
		(start 286.766 -161.0995)
		(end 286.766 -159.747204)
		(width 0.1143)
		(layer "F.Cu")
		(net "SYS_PWRBTN_N")
	)
	(segment
		(start 183.9595 -225.298)
		(end 183.9595 -225.3615)
		(width 0.1143)
		(layer "F.Cu")
		(net "SYS_PWRBTN_N")
	)
	(via
		(at 177.27295 -227.18395)
		(size 0.7112)
		(drill 0.3556)
		(layers "F.Cu" "B.Cu")
		(net "SYS_PWRBTN_N")
	)
	(via
		(at 287.14446 -159.368744)
		(size 0.5588)
		(drill 0.3048)
		(layers "F.Cu" "B.Cu")
		(net "SYS_PWRBTN_N")
	)
	(via
		(at 171.370752 -176.974754)
		(size 0.5588)
		(drill 0.3048)
		(layers "F.Cu" "B.Cu")
		(net "SYS_PWRBTN_N")
	)
	(segment
		(start 171.370752 -176.974754)
		(end 183.728106 -164.6174)
		(width 0.127)
		(layer "In2.Cu")
		(net "SYS_PWRBTN_N")
	)
	(segment
		(start 287.14446 -159.170624)
		(end 287.14446 -159.368744)
		(width 0.127)
		(layer "In2.Cu")
		(net "SYS_PWRBTN_N")
	)
	(segment
		(start 204.14107 -164.4142)
		(end 218.962732 -164.4142)
		(width 0.127)
		(layer "In2.Cu")
		(net "SYS_PWRBTN_N")
	)
	(segment
		(start 227.225098 -164.4523)
		(end 229.511098 -162.1663)
		(width 0.127)
		(layer "In2.Cu")
		(net "SYS_PWRBTN_N")
	)
	(segment
		(start 248.868438 -162.1663)
		(end 250.341638 -163.6395)
		(width 0.127)
		(layer "In2.Cu")
		(net "SYS_PWRBTN_N")
	)
	(segment
		(start 250.341638 -163.6395)
		(end 265.046968 -163.6395)
		(width 0.127)
		(layer "In2.Cu")
		(net "SYS_PWRBTN_N")
	)
	(segment
		(start 202.705716 -162.978846)
		(end 204.14107 -164.4142)
		(width 0.127)
		(layer "In2.Cu")
		(net "SYS_PWRBTN_N")
	)
	(segment
		(start 192.465198 -164.6174)
		(end 194.103752 -162.978846)
		(width 0.127)
		(layer "In2.Cu")
		(net "SYS_PWRBTN_N")
	)
	(segment
		(start 218.962732 -164.4142)
		(end 219.000832 -164.4523)
		(width 0.127)
		(layer "In2.Cu")
		(net "SYS_PWRBTN_N")
	)
	(segment
		(start 265.478768 -164.0713)
		(end 273.886168 -164.0713)
		(width 0.127)
		(layer "In2.Cu")
		(net "SYS_PWRBTN_N")
	)
	(segment
		(start 194.103752 -162.978846)
		(end 202.705716 -162.978846)
		(width 0.127)
		(layer "In2.Cu")
		(net "SYS_PWRBTN_N")
	)
	(segment
		(start 219.000832 -164.4523)
		(end 227.225098 -164.4523)
		(width 0.127)
		(layer "In2.Cu")
		(net "SYS_PWRBTN_N")
	)
	(segment
		(start 229.511098 -162.1663)
		(end 248.868438 -162.1663)
		(width 0.127)
		(layer "In2.Cu")
		(net "SYS_PWRBTN_N")
	)
	(segment
		(start 265.046968 -163.6395)
		(end 265.478768 -164.0713)
		(width 0.127)
		(layer "In2.Cu")
		(net "SYS_PWRBTN_N")
	)
	(segment
		(start 273.886168 -164.0713)
		(end 279.543002 -158.414466)
		(width 0.127)
		(layer "In2.Cu")
		(net "SYS_PWRBTN_N")
	)
	(segment
		(start 279.543002 -158.414466)
		(end 286.388302 -158.414466)
		(width 0.127)
		(layer "In2.Cu")
		(net "SYS_PWRBTN_N")
	)
	(segment
		(start 286.388302 -158.414466)
		(end 287.14446 -159.170624)
		(width 0.127)
		(layer "In2.Cu")
		(net "SYS_PWRBTN_N")
	)
	(segment
		(start 183.728106 -164.6174)
		(end 192.465198 -164.6174)
		(width 0.127)
		(layer "In2.Cu")
		(net "SYS_PWRBTN_N")
	)
	(segment
		(start 288.798 -160.3375)
		(end 288.798 -160.330642)
		(width 0.1143)
		(layer "F.Cu")
		(net "FM_BMC_READY_N")
	)
	(segment
		(start 285.342076 -157.988)
		(end 284.9626 -157.988)
		(width 0.1143)
		(layer "F.Cu")
		(net "FM_BMC_READY_N")
	)
	(segment
		(start 184.8485 -221.09176)
		(end 187.98794 -221.09176)
		(width 0.1143)
		(layer "F.Cu")
		(net "FM_BMC_READY_N")
	)
	(segment
		(start 184.8485 -219.456)
		(end 184.8485 -221.09176)
		(width 0.1143)
		(layer "F.Cu")
		(net "FM_BMC_READY_N")
	)
	(segment
		(start 200.533 -223.8375)
		(end 200.152 -223.4565)
		(width 0.1143)
		(layer "F.Cu")
		(net "FM_BMC_READY_N")
	)
	(segment
		(start 200.16724 -220.874336)
		(end 200.16724 -221.2975)
		(width 0.1143)
		(layer "F.Cu")
		(net "FM_BMC_READY_N")
	)
	(segment
		(start 200.152 -223.4565)
		(end 200.152 -221.31274)
		(width 0.1143)
		(layer "F.Cu")
		(net "FM_BMC_READY_N")
	)
	(segment
		(start 187.98794 -221.09176)
		(end 188.2267 -220.853)
		(width 0.1143)
		(layer "F.Cu")
		(net "FM_BMC_READY_N")
	)
	(segment
		(start 287.347152 -158.879794)
		(end 286.23387 -158.879794)
		(width 0.1143)
		(layer "F.Cu")
		(net "FM_BMC_READY_N")
	)
	(segment
		(start 188.2267 -220.853)
		(end 188.57595 -220.50375)
		(width 0.1143)
		(layer "F.Cu")
		(net "FM_BMC_READY_N")
	)
	(segment
		(start 199.796654 -220.50375)
		(end 200.16724 -220.874336)
		(width 0.1143)
		(layer "F.Cu")
		(net "FM_BMC_READY_N")
	)
	(segment
		(start 188.57595 -220.50375)
		(end 199.796654 -220.50375)
		(width 0.1143)
		(layer "F.Cu")
		(net "FM_BMC_READY_N")
	)
	(segment
		(start 200.152 -221.31274)
		(end 200.16724 -221.2975)
		(width 0.1143)
		(layer "F.Cu")
		(net "FM_BMC_READY_N")
	)
	(segment
		(start 288.798 -160.330642)
		(end 287.347152 -158.879794)
		(width 0.1143)
		(layer "F.Cu")
		(net "FM_BMC_READY_N")
	)
	(segment
		(start 284.9626 -157.988)
		(end 284.861 -157.8864)
		(width 0.1143)
		(layer "F.Cu")
		(net "FM_BMC_READY_N")
	)
	(segment
		(start 286.23387 -158.879794)
		(end 285.342076 -157.988)
		(width 0.1143)
		(layer "F.Cu")
		(net "FM_BMC_READY_N")
	)
	(via
		(at 189.93485 -180.40985)
		(size 0.7112)
		(drill 0.3556)
		(layers "F.Cu" "B.Cu")
		(net "FM_BMC_READY_N")
	)
	(via
		(at 284.861 -157.8864)
		(size 0.5588)
		(drill 0.3048)
		(layers "F.Cu" "B.Cu")
		(net "FM_BMC_READY_N")
	)
	(via
		(at 188.2267 -220.853)
		(size 0.5588)
		(drill 0.3048)
		(layers "F.Cu" "B.Cu")
		(net "FM_BMC_READY_N")
	)
	(via
		(at 194.564 -161.29)
		(size 0.5588)
		(drill 0.3048)
		(layers "F.Cu" "B.Cu")
		(net "FM_BMC_READY_N")
	)
	(segment
		(start 189.93485 -165.91915)
		(end 189.93485 -180.40985)
		(width 0.1143)
		(layer "B.Cu")
		(net "FM_BMC_READY_N")
	)
	(segment
		(start 194.564 -161.29)
		(end 189.93485 -165.91915)
		(width 0.1143)
		(layer "B.Cu")
		(net "FM_BMC_READY_N")
	)
	(segment
		(start 189.93485 -180.40985)
		(end 189.93485 -204.01915)
		(width 0.1143)
		(layer "B.Cu")
		(net "FM_BMC_READY_N")
	)
	(segment
		(start 189.93485 -204.01915)
		(end 188.2267 -205.7273)
		(width 0.1143)
		(layer "B.Cu")
		(net "FM_BMC_READY_N")
	)
	(segment
		(start 188.2267 -205.7273)
		(end 188.2267 -220.853)
		(width 0.1143)
		(layer "B.Cu")
		(net "FM_BMC_READY_N")
	)
	(segment
		(start 270.345154 -160.565846)
		(end 273.0246 -157.8864)
		(width 0.127)
		(layer "In2.Cu")
		(net "FM_BMC_READY_N")
	)
	(segment
		(start 219.63253 -162.9283)
		(end 226.5934 -162.9283)
		(width 0.127)
		(layer "In2.Cu")
		(net "FM_BMC_READY_N")
	)
	(segment
		(start 218.37523 -161.671)
		(end 219.63253 -162.9283)
		(width 0.127)
		(layer "In2.Cu")
		(net "FM_BMC_READY_N")
	)
	(segment
		(start 194.564 -161.29)
		(end 194.6021 -161.3281)
		(width 0.127)
		(layer "In2.Cu")
		(net "FM_BMC_READY_N")
	)
	(segment
		(start 273.0246 -157.8864)
		(end 284.861 -157.8864)
		(width 0.127)
		(layer "In2.Cu")
		(net "FM_BMC_READY_N")
	)
	(segment
		(start 226.5934 -162.9283)
		(end 228.955854 -160.565846)
		(width 0.127)
		(layer "In2.Cu")
		(net "FM_BMC_READY_N")
	)
	(segment
		(start 203.210668 -161.3281)
		(end 203.553568 -161.671)
		(width 0.127)
		(layer "In2.Cu")
		(net "FM_BMC_READY_N")
	)
	(segment
		(start 194.6021 -161.3281)
		(end 203.210668 -161.3281)
		(width 0.127)
		(layer "In2.Cu")
		(net "FM_BMC_READY_N")
	)
	(segment
		(start 203.553568 -161.671)
		(end 218.37523 -161.671)
		(width 0.127)
		(layer "In2.Cu")
		(net "FM_BMC_READY_N")
	)
	(segment
		(start 228.955854 -160.565846)
		(end 270.345154 -160.565846)
		(width 0.127)
		(layer "In2.Cu")
		(net "FM_BMC_READY_N")
	)
	(segment
		(start 179.46624 -222.6945)
		(end 180.5305 -222.6945)
		(width 0.1143)
		(layer "F.Cu")
		(net "PWRBTN_OUT_N")
	)
	(segment
		(start 181.356 -222.1865)
		(end 181.56174 -222.39224)
		(width 0.1143)
		(layer "F.Cu")
		(net "PWRBTN_OUT_N")
	)
	(segment
		(start 180.5305 -222.6945)
		(end 181.0385 -222.1865)
		(width 0.1143)
		(layer "F.Cu")
		(net "PWRBTN_OUT_N")
	)
	(segment
		(start 181.0385 -222.1865)
		(end 181.356 -222.1865)
		(width 0.1143)
		(layer "F.Cu")
		(net "PWRBTN_OUT_N")
	)
	(segment
		(start 181.56174 -222.39224)
		(end 183.1975 -222.39224)
		(width 0.1143)
		(layer "F.Cu")
		(net "PWRBTN_OUT_N")
	)
	(segment
		(start 181.356 -223.266)
		(end 181.356 -222.1865)
		(width 0.1143)
		(layer "F.Cu")
		(net "PWRBTN_OUT_N")
	)
	(via
		(at 181.356 -223.266)
		(size 0.7112)
		(drill 0.3556)
		(layers "F.Cu" "B.Cu")
		(net "PWRBTN_OUT_N")
	)
	(segment
		(start 184.023 -221.869)
		(end 184.15 -221.742)
		(width 0.1143)
		(layer "F.Cu")
		(net "PWRBTN_FP_N")
	)
	(segment
		(start 184.15 -221.742)
		(end 184.8485 -221.742)
		(width 0.1143)
		(layer "F.Cu")
		(net "PWRBTN_FP_N")
	)
	(segment
		(start 184.8485 -225.298)
		(end 184.8485 -224.155)
		(width 0.1143)
		(layer "F.Cu")
		(net "PWRBTN_FP_N")
	)
	(segment
		(start 186.563 -225.298)
		(end 187.071 -225.806)
		(width 0.1143)
		(layer "F.Cu")
		(net "PWRBTN_FP_N")
	)
	(segment
		(start 187.071 -225.806)
		(end 187.452 -225.806)
		(width 0.1143)
		(layer "F.Cu")
		(net "PWRBTN_FP_N")
	)
	(segment
		(start 184.8485 -225.298)
		(end 186.563 -225.298)
		(width 0.1143)
		(layer "F.Cu")
		(net "PWRBTN_FP_N")
	)
	(segment
		(start 189.3316 -225.806)
		(end 187.452 -225.806)
		(width 0.1143)
		(layer "F.Cu")
		(net "PWRBTN_FP_N")
	)
	(segment
		(start 184.8485 -223.5835)
		(end 184.023 -222.758)
		(width 0.1143)
		(layer "F.Cu")
		(net "PWRBTN_FP_N")
	)
	(segment
		(start 184.8485 -224.155)
		(end 184.8485 -223.5835)
		(width 0.1143)
		(layer "F.Cu")
		(net "PWRBTN_FP_N")
	)
	(segment
		(start 184.023 -222.758)
		(end 184.023 -221.869)
		(width 0.1143)
		(layer "F.Cu")
		(net "PWRBTN_FP_N")
	)
	(via
		(at 187.452 -225.806)
		(size 0.7112)
		(drill 0.3556)
		(layers "F.Cu" "B.Cu")
		(net "PWRBTN_FP_N")
	)
	(segment
		(start 287.782 -160.782)
		(end 287.274 -160.274)
		(width 0.1143)
		(layer "F.Cu")
		(net "BMC_PWRBTN_N")
	)
	(segment
		(start 168.890442 -218.57081)
		(end 175.046132 -224.7265)
		(width 0.1143)
		(layer "F.Cu")
		(net "BMC_PWRBTN_N")
	)
	(segment
		(start 287.782 -161.0995)
		(end 287.782 -160.782)
		(width 0.1143)
		(layer "F.Cu")
		(net "BMC_PWRBTN_N")
	)
	(segment
		(start 168.890442 -185.063638)
		(end 168.890442 -218.57081)
		(width 0.1143)
		(layer "F.Cu")
		(net "BMC_PWRBTN_N")
	)
	(segment
		(start 172.10405 -177.56505)
		(end 172.10405 -181.85003)
		(width 0.1143)
		(layer "F.Cu")
		(net "BMC_PWRBTN_N")
	)
	(segment
		(start 172.085 -177.546)
		(end 172.10405 -177.56505)
		(width 0.1143)
		(layer "F.Cu")
		(net "BMC_PWRBTN_N")
	)
	(segment
		(start 172.10405 -181.85003)
		(end 168.890442 -185.063638)
		(width 0.1143)
		(layer "F.Cu")
		(net "BMC_PWRBTN_N")
	)
	(segment
		(start 178.816 -224.7265)
		(end 176.4665 -224.7265)
		(width 0.1143)
		(layer "F.Cu")
		(net "BMC_PWRBTN_N")
	)
	(segment
		(start 175.046132 -224.7265)
		(end 176.4665 -224.7265)
		(width 0.1143)
		(layer "F.Cu")
		(net "BMC_PWRBTN_N")
	)
	(segment
		(start 178.816 -222.6945)
		(end 178.816 -224.7265)
		(width 0.1143)
		(layer "F.Cu")
		(net "BMC_PWRBTN_N")
	)
	(via
		(at 172.085 -177.546)
		(size 0.5588)
		(drill 0.3048)
		(layers "F.Cu" "B.Cu")
		(net "BMC_PWRBTN_N")
	)
	(via
		(at 176.4665 -224.7265)
		(size 0.7112)
		(drill 0.3556)
		(layers "F.Cu" "B.Cu")
		(net "BMC_PWRBTN_N")
	)
	(via
		(at 287.274 -160.274)
		(size 0.5588)
		(drill 0.3048)
		(layers "F.Cu" "B.Cu")
		(net "BMC_PWRBTN_N")
	)
	(segment
		(start 226.883468 -165.4048)
		(end 229.690168 -162.5981)
		(width 0.127)
		(layer "In2.Cu")
		(net "BMC_PWRBTN_N")
	)
	(segment
		(start 194.282822 -163.410646)
		(end 202.526646 -163.410646)
		(width 0.127)
		(layer "In2.Cu")
		(net "BMC_PWRBTN_N")
	)
	(segment
		(start 248.689368 -162.5981)
		(end 250.302268 -164.211)
		(width 0.127)
		(layer "In2.Cu")
		(net "BMC_PWRBTN_N")
	)
	(segment
		(start 286.209232 -158.846266)
		(end 286.4993 -159.136334)
		(width 0.127)
		(layer "In2.Cu")
		(net "BMC_PWRBTN_N")
	)
	(segment
		(start 286.4993 -159.4993)
		(end 287.274 -160.274)
		(width 0.127)
		(layer "In2.Cu")
		(net "BMC_PWRBTN_N")
	)
	(segment
		(start 192.644268 -165.0492)
		(end 194.282822 -163.410646)
		(width 0.127)
		(layer "In2.Cu")
		(net "BMC_PWRBTN_N")
	)
	(segment
		(start 274.065238 -164.5031)
		(end 279.722072 -158.846266)
		(width 0.127)
		(layer "In2.Cu")
		(net "BMC_PWRBTN_N")
	)
	(segment
		(start 184.5818 -165.0492)
		(end 192.644268 -165.0492)
		(width 0.127)
		(layer "In2.Cu")
		(net "BMC_PWRBTN_N")
	)
	(segment
		(start 172.085 -177.546)
		(end 184.5818 -165.0492)
		(width 0.127)
		(layer "In2.Cu")
		(net "BMC_PWRBTN_N")
	)
	(segment
		(start 202.526646 -163.410646)
		(end 204.5208 -165.4048)
		(width 0.127)
		(layer "In2.Cu")
		(net "BMC_PWRBTN_N")
	)
	(segment
		(start 229.690168 -162.5981)
		(end 248.689368 -162.5981)
		(width 0.127)
		(layer "In2.Cu")
		(net "BMC_PWRBTN_N")
	)
	(segment
		(start 256.684018 -165.1635)
		(end 257.157982 -165.1635)
		(width 0.127)
		(layer "In2.Cu")
		(net "BMC_PWRBTN_N")
	)
	(segment
		(start 255.731518 -164.211)
		(end 256.684018 -165.1635)
		(width 0.127)
		(layer "In2.Cu")
		(net "BMC_PWRBTN_N")
	)
	(segment
		(start 204.5208 -165.4048)
		(end 226.883468 -165.4048)
		(width 0.127)
		(layer "In2.Cu")
		(net "BMC_PWRBTN_N")
	)
	(segment
		(start 279.722072 -158.846266)
		(end 286.209232 -158.846266)
		(width 0.127)
		(layer "In2.Cu")
		(net "BMC_PWRBTN_N")
	)
	(segment
		(start 250.302268 -164.211)
		(end 255.731518 -164.211)
		(width 0.127)
		(layer "In2.Cu")
		(net "BMC_PWRBTN_N")
	)
	(segment
		(start 258.097782 -164.2237)
		(end 265.020298 -164.2237)
		(width 0.127)
		(layer "In2.Cu")
		(net "BMC_PWRBTN_N")
	)
	(segment
		(start 257.157982 -165.1635)
		(end 258.097782 -164.2237)
		(width 0.127)
		(layer "In2.Cu")
		(net "BMC_PWRBTN_N")
	)
	(segment
		(start 265.020298 -164.2237)
		(end 265.299698 -164.5031)
		(width 0.127)
		(layer "In2.Cu")
		(net "BMC_PWRBTN_N")
	)
	(segment
		(start 286.4993 -159.136334)
		(end 286.4993 -159.4993)
		(width 0.127)
		(layer "In2.Cu")
		(net "BMC_PWRBTN_N")
	)
	(segment
		(start 265.299698 -164.5031)
		(end 274.065238 -164.5031)
		(width 0.127)
		(layer "In2.Cu")
		(net "BMC_PWRBTN_N")
	)
	(segment
		(start 187.78855 -227.75545)
		(end 187.198 -228.346)
		(width 0.1143)
		(layer "F.Cu")
		(net "FP_PWRBTN_RC_N")
	)
	(segment
		(start 186.055 -228.346)
		(end 184.8485 -228.346)
		(width 0.1143)
		(layer "F.Cu")
		(net "FP_PWRBTN_RC_N")
	)
	(segment
		(start 189.3316 -227.75545)
		(end 187.78855 -227.75545)
		(width 0.1143)
		(layer "F.Cu")
		(net "FP_PWRBTN_RC_N")
	)
	(segment
		(start 187.198 -228.346)
		(end 186.055 -228.346)
		(width 0.1143)
		(layer "F.Cu")
		(net "FP_PWRBTN_RC_N")
	)
	(via
		(at 186.055 -228.346)
		(size 0.7112)
		(drill 0.3556)
		(layers "F.Cu" "B.Cu")
		(net "FP_PWRBTN_RC_N")
	)
	(segment
		(start 186.8805 -227.2665)
		(end 187.039758 -227.107242)
		(width 0.1143)
		(layer "F.Cu")
		(net "FP_PWRBTN")
	)
	(segment
		(start 189.3316 -227.10648)
		(end 187.04052 -227.10648)
		(width 0.1143)
		(layer "F.Cu")
		(net "FP_PWRBTN")
	)
	(segment
		(start 184.404 -227.2665)
		(end 186.8805 -227.2665)
		(width 0.1143)
		(layer "F.Cu")
		(net "FP_PWRBTN")
	)
	(segment
		(start 187.04052 -227.10648)
		(end 187.039758 -227.107242)
		(width 0.1143)
		(layer "F.Cu")
		(net "FP_PWRBTN")
	)
	(via
		(at 187.039758 -227.107242)
		(size 0.7112)
		(drill 0.3556)
		(layers "F.Cu" "B.Cu")
		(net "FP_PWRBTN")
	)
	(segment
		(start 205.613 -92.964)
		(end 205.613 -104.267)
		(width 0.1143)
		(layer "F.Cu")
		(net "CPU_RESET_N")
	)
	(segment
		(start 210.8835 -155.3845)
		(end 210.8835 -184.7215)
		(width 0.1143)
		(layer "F.Cu")
		(net "CPU_RESET_N")
	)
	(segment
		(start 208.180686 -78.712314)
		(end 207.719676 -79.173324)
		(width 0.1143)
		(layer "F.Cu")
		(net "CPU_RESET_N")
	)
	(segment
		(start 213.0425 -219.31376)
		(end 213.0425 -217.932)
		(width 0.1143)
		(layer "F.Cu")
		(net "CPU_RESET_N")
	)
	(segment
		(start 218.29395 -147.97405)
		(end 210.8835 -155.3845)
		(width 0.1143)
		(layer "F.Cu")
		(net "CPU_RESET_N")
	)
	(segment
		(start 213.0425 -217.932)
		(end 214.503 -216.4715)
		(width 0.1143)
		(layer "F.Cu")
		(net "CPU_RESET_N")
	)
	(segment
		(start 209.931 -69.38645)
		(end 209.931 -74.676)
		(width 0.1143)
		(layer "F.Cu")
		(net "CPU_RESET_N")
	)
	(segment
		(start 208.180686 -76.426314)
		(end 208.180686 -78.712314)
		(width 0.1143)
		(layer "F.Cu")
		(net "CPU_RESET_N")
	)
	(segment
		(start 205.613 -104.267)
		(end 211.074 -109.728)
		(width 0.1143)
		(layer "F.Cu")
		(net "CPU_RESET_N")
	)
	(segment
		(start 207.719676 -90.857324)
		(end 205.613 -92.964)
		(width 0.1143)
		(layer "F.Cu")
		(net "CPU_RESET_N")
	)
	(segment
		(start 209.931 -74.676)
		(end 208.180686 -76.426314)
		(width 0.1143)
		(layer "F.Cu")
		(net "CPU_RESET_N")
	)
	(segment
		(start 211.074 -109.728)
		(end 212.725 -109.728)
		(width 0.1143)
		(layer "F.Cu")
		(net "CPU_RESET_N")
	)
	(segment
		(start 210.57997 -68.73748)
		(end 209.931 -69.38645)
		(width 0.1143)
		(layer "F.Cu")
		(net "CPU_RESET_N")
	)
	(segment
		(start 214.503 -213.148164)
		(end 210.8835 -209.528664)
		(width 0.1143)
		(layer "F.Cu")
		(net "CPU_RESET_N")
	)
	(segment
		(start 207.719676 -79.173324)
		(end 207.719676 -90.857324)
		(width 0.1143)
		(layer "F.Cu")
		(net "CPU_RESET_N")
	)
	(segment
		(start 214.503 -216.4715)
		(end 214.503 -213.148164)
		(width 0.1143)
		(layer "F.Cu")
		(net "CPU_RESET_N")
	)
	(segment
		(start 210.8835 -209.528664)
		(end 210.8835 -184.7215)
		(width 0.1143)
		(layer "F.Cu")
		(net "CPU_RESET_N")
	)
	(segment
		(start 218.29395 -115.29695)
		(end 218.29395 -147.97405)
		(width 0.1143)
		(layer "F.Cu")
		(net "CPU_RESET_N")
	)
	(segment
		(start 210.57997 -68.6435)
		(end 210.57997 -68.73748)
		(width 0.1143)
		(layer "F.Cu")
		(net "CPU_RESET_N")
	)
	(segment
		(start 212.725 -109.728)
		(end 218.29395 -115.29695)
		(width 0.1143)
		(layer "F.Cu")
		(net "CPU_RESET_N")
	)
	(via
		(at 210.8835 -184.7215)
		(size 0.7112)
		(drill 0.3556)
		(layers "F.Cu" "B.Cu")
		(net "CPU_RESET_N")
	)
	(segment
		(start 306.07 -161.544)
		(end 305.435 -162.179)
		(width 0.1143)
		(layer "F.Cu")
		(net "DP_BMC_CPU_RST_N_R")
	)
	(segment
		(start 301.176436 -165.34511)
		(end 299.23486 -167.28694)
		(width 0.1143)
		(layer "F.Cu")
		(net "DP_BMC_CPU_RST_N_R")
	)
	(segment
		(start 306.07 -161.0995)
		(end 306.07 -161.544)
		(width 0.1143)
		(layer "F.Cu")
		(net "DP_BMC_CPU_RST_N_R")
	)
	(segment
		(start 299.23486 -167.28694)
		(end 299.23486 -167.440102)
		(width 0.1143)
		(layer "F.Cu")
		(net "DP_BMC_CPU_RST_N_R")
	)
	(segment
		(start 303.057052 -162.75685)
		(end 301.176436 -164.647626)
		(width 0.1143)
		(layer "F.Cu")
		(net "DP_BMC_CPU_RST_N_R")
	)
	(segment
		(start 305.435 -162.179)
		(end 304.85715 -162.75685)
		(width 0.1143)
		(layer "F.Cu")
		(net "DP_BMC_CPU_RST_N_R")
	)
	(segment
		(start 301.176436 -164.647626)
		(end 301.176436 -165.34511)
		(width 0.1143)
		(layer "F.Cu")
		(net "DP_BMC_CPU_RST_N_R")
	)
	(segment
		(start 304.85715 -162.75685)
		(end 303.057052 -162.75685)
		(width 0.1143)
		(layer "F.Cu")
		(net "DP_BMC_CPU_RST_N_R")
	)
	(via
		(at 305.435 -162.179)
		(size 0.7112)
		(drill 0.3556)
		(layers "F.Cu" "B.Cu")
		(net "DP_BMC_CPU_RST_N_R")
	)
	(segment
		(start 209.719418 -215.667082)
		(end 209.804 -215.646)
		(width 0.1143)
		(layer "F.Cu")
		(net "DP_BMC_CPU_RST_N")
	)
	(segment
		(start 209.804 -215.646)
		(end 213.1695 -215.646)
		(width 0.1143)
		(layer "F.Cu")
		(net "DP_BMC_CPU_RST_N")
	)
	(segment
		(start 209.931 -197.21322)
		(end 209.931 -209.169)
		(width 0.1143)
		(layer "F.Cu")
		(net "DP_BMC_CPU_RST_N")
	)
	(segment
		(start 306.07 -160.2105)
		(end 306.07 -159.131)
		(width 0.1143)
		(layer "F.Cu")
		(net "DP_BMC_CPU_RST_N")
	)
	(segment
		(start 213.995 -215.392)
		(end 213.741 -215.646)
		(width 0.1143)
		(layer "F.Cu")
		(net "DP_BMC_CPU_RST_N")
	)
	(segment
		(start 209.931 -188.722)
		(end 209.931 -197.21322)
		(width 0.1143)
		(layer "F.Cu")
		(net "DP_BMC_CPU_RST_N")
	)
	(segment
		(start 306.07 -159.131)
		(end 306.959 -158.242)
		(width 0.1143)
		(layer "F.Cu")
		(net "DP_BMC_CPU_RST_N")
	)
	(segment
		(start 208.5975 -216.789)
		(end 209.719418 -215.667082)
		(width 0.1143)
		(layer "F.Cu")
		(net "DP_BMC_CPU_RST_N")
	)
	(segment
		(start 213.995 -213.233)
		(end 213.995 -215.392)
		(width 0.1143)
		(layer "F.Cu")
		(net "DP_BMC_CPU_RST_N")
	)
	(segment
		(start 213.741 -215.646)
		(end 213.1695 -215.646)
		(width 0.1143)
		(layer "F.Cu")
		(net "DP_BMC_CPU_RST_N")
	)
	(segment
		(start 209.931 -209.169)
		(end 213.995 -213.233)
		(width 0.1143)
		(layer "F.Cu")
		(net "DP_BMC_CPU_RST_N")
	)
	(via
		(at 329.184 -162.179)
		(size 0.5588)
		(drill 0.3048)
		(layers "F.Cu" "B.Cu")
		(net "DP_BMC_CPU_RST_N")
	)
	(via
		(at 209.931 -188.722)
		(size 0.5588)
		(drill 0.3048)
		(layers "F.Cu" "B.Cu")
		(net "DP_BMC_CPU_RST_N")
	)
	(via
		(at 306.959 -158.242)
		(size 0.5588)
		(drill 0.3048)
		(layers "F.Cu" "B.Cu")
		(net "DP_BMC_CPU_RST_N")
	)
	(via
		(at 209.931 -197.21322)
		(size 0.7112)
		(drill 0.3556)
		(layers "F.Cu" "B.Cu")
		(net "DP_BMC_CPU_RST_N")
	)
	(segment
		(start 306.451 -222.057468)
		(end 306.893468 -221.615)
		(width 0.127)
		(layer "In2.Cu")
		(net "DP_BMC_CPU_RST_N")
	)
	(segment
		(start 329.3618 -164.6428)
		(end 329.3618 -162.3568)
		(width 0.127)
		(layer "In2.Cu")
		(net "DP_BMC_CPU_RST_N")
	)
	(segment
		(start 330.1238 -165.4048)
		(end 329.3618 -164.6428)
		(width 0.127)
		(layer "In2.Cu")
		(net "DP_BMC_CPU_RST_N")
	)
	(segment
		(start 209.931 -188.722)
		(end 227.963476 -188.722)
		(width 0.127)
		(layer "In2.Cu")
		(net "DP_BMC_CPU_RST_N")
	)
	(segment
		(start 329.4888 -181.4322)
		(end 329.4888 -170.129708)
		(width 0.127)
		(layer "In2.Cu")
		(net "DP_BMC_CPU_RST_N")
	)
	(segment
		(start 260.9469 -217.98661)
		(end 260.9469 -226.019106)
		(width 0.127)
		(layer "In2.Cu")
		(net "DP_BMC_CPU_RST_N")
	)
	(segment
		(start 325.882 -185.039)
		(end 329.4888 -181.4322)
		(width 0.127)
		(layer "In2.Cu")
		(net "DP_BMC_CPU_RST_N")
	)
	(segment
		(start 230.020876 -186.6646)
		(end 253.304802 -186.6646)
		(width 0.127)
		(layer "In2.Cu")
		(net "DP_BMC_CPU_RST_N")
	)
	(segment
		(start 329.4888 -170.129708)
		(end 330.1238 -169.494708)
		(width 0.127)
		(layer "In2.Cu")
		(net "DP_BMC_CPU_RST_N")
	)
	(segment
		(start 227.963476 -188.722)
		(end 230.020876 -186.6646)
		(width 0.127)
		(layer "In2.Cu")
		(net "DP_BMC_CPU_RST_N")
	)
	(segment
		(start 307.278532 -221.615)
		(end 325.882 -203.011532)
		(width 0.127)
		(layer "In2.Cu")
		(net "DP_BMC_CPU_RST_N")
	)
	(segment
		(start 329.3618 -162.3568)
		(end 329.184 -162.179)
		(width 0.127)
		(layer "In2.Cu")
		(net "DP_BMC_CPU_RST_N")
	)
	(segment
		(start 260.544564 -233.539792)
		(end 264.050272 -237.0455)
		(width 0.127)
		(layer "In2.Cu")
		(net "DP_BMC_CPU_RST_N")
	)
	(segment
		(start 264.050272 -237.0455)
		(end 291.605716 -237.0455)
		(width 0.127)
		(layer "In2.Cu")
		(net "DP_BMC_CPU_RST_N")
	)
	(segment
		(start 306.893468 -221.615)
		(end 307.278532 -221.615)
		(width 0.127)
		(layer "In2.Cu")
		(net "DP_BMC_CPU_RST_N")
	)
	(segment
		(start 260.9469 -226.019106)
		(end 260.544564 -226.421442)
		(width 0.127)
		(layer "In2.Cu")
		(net "DP_BMC_CPU_RST_N")
	)
	(segment
		(start 253.304802 -186.6646)
		(end 260.294628 -193.654426)
		(width 0.127)
		(layer "In2.Cu")
		(net "DP_BMC_CPU_RST_N")
	)
	(segment
		(start 260.544564 -226.421442)
		(end 260.544564 -233.539792)
		(width 0.127)
		(layer "In2.Cu")
		(net "DP_BMC_CPU_RST_N")
	)
	(segment
		(start 330.1238 -169.494708)
		(end 330.1238 -165.4048)
		(width 0.127)
		(layer "In2.Cu")
		(net "DP_BMC_CPU_RST_N")
	)
	(segment
		(start 260.294628 -193.654426)
		(end 260.294628 -217.334338)
		(width 0.127)
		(layer "In2.Cu")
		(net "DP_BMC_CPU_RST_N")
	)
	(segment
		(start 291.605716 -237.0455)
		(end 306.451 -222.200216)
		(width 0.127)
		(layer "In2.Cu")
		(net "DP_BMC_CPU_RST_N")
	)
	(segment
		(start 306.451 -222.200216)
		(end 306.451 -222.057468)
		(width 0.127)
		(layer "In2.Cu")
		(net "DP_BMC_CPU_RST_N")
	)
	(segment
		(start 325.882 -203.011532)
		(end 325.882 -185.039)
		(width 0.127)
		(layer "In2.Cu")
		(net "DP_BMC_CPU_RST_N")
	)
	(segment
		(start 260.294628 -217.334338)
		(end 260.9469 -217.98661)
		(width 0.127)
		(layer "In2.Cu")
		(net "DP_BMC_CPU_RST_N")
	)
	(segment
		(start 327.560432 -160.4899)
		(end 329.184 -162.113468)
		(width 0.127)
		(layer "In5.Cu")
		(net "DP_BMC_CPU_RST_N")
	)
	(segment
		(start 314.771532 -158.242)
		(end 317.019432 -160.4899)
		(width 0.127)
		(layer "In5.Cu")
		(net "DP_BMC_CPU_RST_N")
	)
	(segment
		(start 329.184 -162.113468)
		(end 329.184 -162.179)
		(width 0.127)
		(layer "In5.Cu")
		(net "DP_BMC_CPU_RST_N")
	)
	(segment
		(start 306.959 -158.242)
		(end 314.771532 -158.242)
		(width 0.127)
		(layer "In5.Cu")
		(net "DP_BMC_CPU_RST_N")
	)
	(segment
		(start 317.019432 -160.4899)
		(end 327.560432 -160.4899)
		(width 0.127)
		(layer "In5.Cu")
		(net "DP_BMC_CPU_RST_N")
	)
	(segment
		(start 272.885916 -187.452)
		(end 272.193766 -186.75985)
		(width 0.1143)
		(layer "F.Cu")
		(net "DP_RST_N_R")
	)
	(segment
		(start 275.298408 -187.452)
		(end 273.123406 -187.452)
		(width 0.1143)
		(layer "F.Cu")
		(net "DP_RST_N_R")
	)
	(segment
		(start 271.97685 -186.75985)
		(end 271.526 -186.309)
		(width 0.1143)
		(layer "F.Cu")
		(net "DP_RST_N_R")
	)
	(segment
		(start 271.526 -186.309)
		(end 271.2085 -186.309)
		(width 0.1143)
		(layer "F.Cu")
		(net "DP_RST_N_R")
	)
	(segment
		(start 273.123406 -187.452)
		(end 272.885916 -187.452)
		(width 0.1143)
		(layer "F.Cu")
		(net "DP_RST_N_R")
	)
	(segment
		(start 284.411166 -183.44007)
		(end 281.980386 -185.87085)
		(width 0.1143)
		(layer "F.Cu")
		(net "DP_RST_N_R")
	)
	(segment
		(start 276.879558 -185.87085)
		(end 275.298408 -187.452)
		(width 0.1143)
		(layer "F.Cu")
		(net "DP_RST_N_R")
	)
	(segment
		(start 284.834838 -183.44007)
		(end 284.411166 -183.44007)
		(width 0.1143)
		(layer "F.Cu")
		(net "DP_RST_N_R")
	)
	(segment
		(start 272.193766 -186.75985)
		(end 271.97685 -186.75985)
		(width 0.1143)
		(layer "F.Cu")
		(net "DP_RST_N_R")
	)
	(segment
		(start 281.980386 -185.87085)
		(end 276.879558 -185.87085)
		(width 0.1143)
		(layer "F.Cu")
		(net "DP_RST_N_R")
	)
	(via
		(at 273.123406 -187.452)
		(size 0.7112)
		(drill 0.3556)
		(layers "F.Cu" "B.Cu")
		(net "DP_RST_N_R")
	)
	(segment
		(start 268.986 -186.69)
		(end 267.716 -186.69)
		(width 0.1143)
		(layer "F.Cu")
		(net "DP_RST_N")
	)
	(segment
		(start 270.3195 -187.325)
		(end 270.3195 -188.341)
		(width 0.1143)
		(layer "F.Cu")
		(net "DP_RST_N")
	)
	(segment
		(start 269.367 -186.309)
		(end 268.986 -186.69)
		(width 0.1143)
		(layer "F.Cu")
		(net "DP_RST_N")
	)
	(segment
		(start 270.3195 -186.309)
		(end 270.3195 -187.325)
		(width 0.1143)
		(layer "F.Cu")
		(net "DP_RST_N")
	)
	(segment
		(start 270.3195 -186.309)
		(end 269.367 -186.309)
		(width 0.1143)
		(layer "F.Cu")
		(net "DP_RST_N")
	)
	(via
		(at 275.817584 -140.081)
		(size 0.7112)
		(drill 0.3556)
		(layers "F.Cu" "B.Cu")
		(net "DP_RST_N")
	)
	(via
		(at 268.986 -141.78026)
		(size 0.5588)
		(drill 0.3048)
		(layers "F.Cu" "B.Cu")
		(net "DP_RST_N")
	)
	(via
		(at 267.716 -186.69)
		(size 0.5588)
		(drill 0.3048)
		(layers "F.Cu" "B.Cu")
		(net "DP_RST_N")
	)
	(via
		(at 305.181 -135.89)
		(size 0.5588)
		(drill 0.3048)
		(layers "F.Cu" "B.Cu")
		(net "DP_RST_N")
	)
	(segment
		(start 268.986 -141.78026)
		(end 274.118324 -141.78026)
		(width 0.1143)
		(layer "B.Cu")
		(net "DP_RST_N")
	)
	(segment
		(start 302.208692 -135.1026)
		(end 303.008792 -135.9027)
		(width 0.1143)
		(layer "B.Cu")
		(net "DP_RST_N")
	)
	(segment
		(start 303.008792 -135.9027)
		(end 305.1683 -135.9027)
		(width 0.1143)
		(layer "B.Cu")
		(net "DP_RST_N")
	)
	(segment
		(start 275.817584 -140.081)
		(end 280.795984 -135.1026)
		(width 0.1143)
		(layer "B.Cu")
		(net "DP_RST_N")
	)
	(segment
		(start 280.795984 -135.1026)
		(end 302.208692 -135.1026)
		(width 0.1143)
		(layer "B.Cu")
		(net "DP_RST_N")
	)
	(segment
		(start 274.118324 -141.78026)
		(end 275.817584 -140.081)
		(width 0.1143)
		(layer "B.Cu")
		(net "DP_RST_N")
	)
	(segment
		(start 305.1683 -135.9027)
		(end 305.181 -135.89)
		(width 0.1143)
		(layer "B.Cu")
		(net "DP_RST_N")
	)
	(segment
		(start 267.716 -181.483)
		(end 267.716 -186.69)
		(width 0.127)
		(layer "In5.Cu")
		(net "DP_RST_N")
	)
	(segment
		(start 333.836518 -12.446)
		(end 325.247 -21.035518)
		(width 0.127)
		(layer "In5.Cu")
		(net "DP_RST_N")
	)
	(segment
		(start 313.113166 -92.329)
		(end 310.957468 -92.329)
		(width 0.127)
		(layer "In5.Cu")
		(net "DP_RST_N")
	)
	(segment
		(start 267.867892 -179.91836)
		(end 267.867892 -181.331108)
		(width 0.127)
		(layer "In5.Cu")
		(net "DP_RST_N")
	)
	(segment
		(start 267.867892 -181.331108)
		(end 267.716 -181.483)
		(width 0.127)
		(layer "In5.Cu")
		(net "DP_RST_N")
	)
	(segment
		(start 314.256166 -91.186)
		(end 313.113166 -92.329)
		(width 0.127)
		(layer "In5.Cu")
		(net "DP_RST_N")
	)
	(segment
		(start 266.8397 -168.0083)
		(end 266.8397 -178.997356)
		(width 0.127)
		(layer "In5.Cu")
		(net "DP_RST_N")
	)
	(segment
		(start 318.004698 -91.186)
		(end 314.256166 -91.186)
		(width 0.127)
		(layer "In5.Cu")
		(net "DP_RST_N")
	)
	(segment
		(start 305.562 -134.2644)
		(end 305.181 -134.6454)
		(width 0.127)
		(layer "In5.Cu")
		(net "DP_RST_N")
	)
	(segment
		(start 324.739 -84.451698)
		(end 318.004698 -91.186)
		(width 0.127)
		(layer "In5.Cu")
		(net "DP_RST_N")
	)
	(segment
		(start 268.605 -143.764)
		(end 268.605 -151.257)
		(width 0.127)
		(layer "In5.Cu")
		(net "DP_RST_N")
	)
	(segment
		(start 325.247 -21.035518)
		(end 325.247 -21.336)
		(width 0.127)
		(layer "In5.Cu")
		(net "DP_RST_N")
	)
	(segment
		(start 267.420344 -179.578)
		(end 267.527532 -179.578)
		(width 0.127)
		(layer "In5.Cu")
		(net "DP_RST_N")
	)
	(segment
		(start 341.984584 -7.499604)
		(end 341.984584 -7.900416)
		(width 0.127)
		(layer "In5.Cu")
		(net "DP_RST_N")
	)
	(segment
		(start 269.748 -152.4)
		(end 269.748 -157.58287)
		(width 0.127)
		(layer "In5.Cu")
		(net "DP_RST_N")
	)
	(segment
		(start 323.7357 -59.659266)
		(end 324.739 -60.662566)
		(width 0.127)
		(layer "In5.Cu")
		(net "DP_RST_N")
	)
	(segment
		(start 266.8397 -178.997356)
		(end 267.420344 -179.578)
		(width 0.127)
		(layer "In5.Cu")
		(net "DP_RST_N")
	)
	(segment
		(start 268.986 -141.78026)
		(end 268.986 -143.383)
		(width 0.127)
		(layer "In5.Cu")
		(net "DP_RST_N")
	)
	(segment
		(start 325.247 -21.336)
		(end 323.7357 -22.8473)
		(width 0.127)
		(layer "In5.Cu")
		(net "DP_RST_N")
	)
	(segment
		(start 267.527532 -179.578)
		(end 267.867892 -179.91836)
		(width 0.127)
		(layer "In5.Cu")
		(net "DP_RST_N")
	)
	(segment
		(start 268.224 -159.10687)
		(end 268.224 -166.624)
		(width 0.127)
		(layer "In5.Cu")
		(net "DP_RST_N")
	)
	(segment
		(start 269.748 -157.58287)
		(end 268.224 -159.10687)
		(width 0.127)
		(layer "In5.Cu")
		(net "DP_RST_N")
	)
	(segment
		(start 324.739 -60.662566)
		(end 324.739 -84.451698)
		(width 0.127)
		(layer "In5.Cu")
		(net "DP_RST_N")
	)
	(segment
		(start 268.224 -166.624)
		(end 266.8397 -168.0083)
		(width 0.127)
		(layer "In5.Cu")
		(net "DP_RST_N")
	)
	(segment
		(start 268.986 -143.383)
		(end 268.605 -143.764)
		(width 0.127)
		(layer "In5.Cu")
		(net "DP_RST_N")
	)
	(segment
		(start 305.181 -134.6454)
		(end 305.181 -135.89)
		(width 0.127)
		(layer "In5.Cu")
		(net "DP_RST_N")
	)
	(segment
		(start 310.957468 -92.329)
		(end 305.6763 -97.610168)
		(width 0.127)
		(layer "In5.Cu")
		(net "DP_RST_N")
	)
	(segment
		(start 337.439 -12.446)
		(end 333.836518 -12.446)
		(width 0.127)
		(layer "In5.Cu")
		(net "DP_RST_N")
	)
	(segment
		(start 268.605 -151.257)
		(end 269.748 -152.4)
		(width 0.127)
		(layer "In5.Cu")
		(net "DP_RST_N")
	)
	(segment
		(start 323.7357 -22.8473)
		(end 323.7357 -59.659266)
		(width 0.127)
		(layer "In5.Cu")
		(net "DP_RST_N")
	)
	(segment
		(start 305.562 -109.198664)
		(end 305.562 -134.2644)
		(width 0.127)
		(layer "In5.Cu")
		(net "DP_RST_N")
	)
	(segment
		(start 305.6763 -97.610168)
		(end 305.6763 -109.084364)
		(width 0.127)
		(layer "In5.Cu")
		(net "DP_RST_N")
	)
	(segment
		(start 305.6763 -109.084364)
		(end 305.562 -109.198664)
		(width 0.127)
		(layer "In5.Cu")
		(net "DP_RST_N")
	)
	(segment
		(start 341.984584 -7.900416)
		(end 337.439 -12.446)
		(width 0.127)
		(layer "In5.Cu")
		(net "DP_RST_N")
	)
	(segment
		(start 275.674836 -186.23915)
		(end 276.462236 -185.45175)
		(width 0.1143)
		(layer "F.Cu")
		(net "DP_BMC_EXP_RST_N_R")
	)
	(segment
		(start 281.582114 -185.45175)
		(end 283.968444 -183.06542)
		(width 0.1143)
		(layer "F.Cu")
		(net "DP_BMC_EXP_RST_N_R")
	)
	(segment
		(start 285.209742 -183.06542)
		(end 285.634938 -182.640224)
		(width 0.1143)
		(layer "F.Cu")
		(net "DP_BMC_EXP_RST_N_R")
	)
	(segment
		(start 271.69745 -185.84545)
		(end 272.09115 -186.23915)
		(width 0.1143)
		(layer "F.Cu")
		(net "DP_BMC_EXP_RST_N_R")
	)
	(segment
		(start 37.2745 -169.291)
		(end 37.2745 -166.0525)
		(width 0.1143)
		(layer "F.Cu")
		(net "DP_BMC_EXP_RST_N_R")
	)
	(segment
		(start 42.291 -165.227)
		(end 38.1 -165.227)
		(width 0.1143)
		(layer "F.Cu")
		(net "DP_BMC_EXP_RST_N_R")
	)
	(segment
		(start 276.462236 -185.45175)
		(end 281.582114 -185.45175)
		(width 0.1143)
		(layer "F.Cu")
		(net "DP_BMC_EXP_RST_N_R")
	)
	(segment
		(start 260.194298 -187.51042)
		(end 261.859268 -185.84545)
		(width 0.1143)
		(layer "F.Cu")
		(net "DP_BMC_EXP_RST_N_R")
	)
	(segment
		(start 283.968444 -183.06542)
		(end 285.209742 -183.06542)
		(width 0.1143)
		(layer "F.Cu")
		(net "DP_BMC_EXP_RST_N_R")
	)
	(segment
		(start 272.09115 -186.23915)
		(end 275.674836 -186.23915)
		(width 0.1143)
		(layer "F.Cu")
		(net "DP_BMC_EXP_RST_N_R")
	)
	(segment
		(start 37.2745 -166.0525)
		(end 38.1 -165.227)
		(width 0.1143)
		(layer "F.Cu")
		(net "DP_BMC_EXP_RST_N_R")
	)
	(segment
		(start 261.859268 -185.84545)
		(end 271.69745 -185.84545)
		(width 0.1143)
		(layer "F.Cu")
		(net "DP_BMC_EXP_RST_N_R")
	)
	(via
		(at 38.1 -165.227)
		(size 0.7112)
		(drill 0.3556)
		(layers "F.Cu" "B.Cu")
		(net "DP_BMC_EXP_RST_N_R")
	)
	(via
		(at 42.291 -165.227)
		(size 0.5588)
		(drill 0.3048)
		(layers "F.Cu" "B.Cu")
		(net "DP_BMC_EXP_RST_N_R")
	)
	(via
		(at 260.194298 -187.51042)
		(size 0.5588)
		(drill 0.3048)
		(layers "F.Cu" "B.Cu")
		(net "DP_BMC_EXP_RST_N_R")
	)
	(segment
		(start 164.084 -174.244)
		(end 171.7802 -181.9402)
		(width 0.127)
		(layer "In2.Cu")
		(net "DP_BMC_EXP_RST_N_R")
	)
	(segment
		(start 224.31629 -179.0319)
		(end 224.73539 -179.451)
		(width 0.127)
		(layer "In2.Cu")
		(net "DP_BMC_EXP_RST_N_R")
	)
	(segment
		(start 217.07729 -179.1589)
		(end 217.36939 -179.451)
		(width 0.127)
		(layer "In2.Cu")
		(net "DP_BMC_EXP_RST_N_R")
	)
	(segment
		(start 197.122034 -182.4482)
		(end 205.892654 -182.4482)
		(width 0.127)
		(layer "In2.Cu")
		(net "DP_BMC_EXP_RST_N_R")
	)
	(segment
		(start 67.437 -171.958)
		(end 69.723 -174.244)
		(width 0.127)
		(layer "In2.Cu")
		(net "DP_BMC_EXP_RST_N_R")
	)
	(segment
		(start 223.23171 -179.0319)
		(end 224.31629 -179.0319)
		(width 0.127)
		(layer "In2.Cu")
		(net "DP_BMC_EXP_RST_N_R")
	)
	(segment
		(start 42.291 -165.227)
		(end 45.339 -165.227)
		(width 0.127)
		(layer "In2.Cu")
		(net "DP_BMC_EXP_RST_N_R")
	)
	(segment
		(start 196.614034 -181.9402)
		(end 197.122034 -182.4482)
		(width 0.127)
		(layer "In2.Cu")
		(net "DP_BMC_EXP_RST_N_R")
	)
	(segment
		(start 69.723 -174.244)
		(end 164.084 -174.244)
		(width 0.127)
		(layer "In2.Cu")
		(net "DP_BMC_EXP_RST_N_R")
	)
	(segment
		(start 222.81261 -179.451)
		(end 223.23171 -179.0319)
		(width 0.127)
		(layer "In2.Cu")
		(net "DP_BMC_EXP_RST_N_R")
	)
	(segment
		(start 214.04961 -179.451)
		(end 214.46871 -179.0319)
		(width 0.127)
		(layer "In2.Cu")
		(net "DP_BMC_EXP_RST_N_R")
	)
	(segment
		(start 215.68029 -179.1589)
		(end 217.07729 -179.1589)
		(width 0.127)
		(layer "In2.Cu")
		(net "DP_BMC_EXP_RST_N_R")
	)
	(segment
		(start 224.73539 -179.451)
		(end 252.134878 -179.451)
		(width 0.127)
		(layer "In2.Cu")
		(net "DP_BMC_EXP_RST_N_R")
	)
	(segment
		(start 171.7802 -181.9402)
		(end 196.614034 -181.9402)
		(width 0.127)
		(layer "In2.Cu")
		(net "DP_BMC_EXP_RST_N_R")
	)
	(segment
		(start 252.134878 -179.451)
		(end 260.194298 -187.51042)
		(width 0.127)
		(layer "In2.Cu")
		(net "DP_BMC_EXP_RST_N_R")
	)
	(segment
		(start 205.892654 -182.4482)
		(end 208.889854 -179.451)
		(width 0.127)
		(layer "In2.Cu")
		(net "DP_BMC_EXP_RST_N_R")
	)
	(segment
		(start 208.889854 -179.451)
		(end 214.04961 -179.451)
		(width 0.127)
		(layer "In2.Cu")
		(net "DP_BMC_EXP_RST_N_R")
	)
	(segment
		(start 45.339 -165.227)
		(end 52.07 -171.958)
		(width 0.127)
		(layer "In2.Cu")
		(net "DP_BMC_EXP_RST_N_R")
	)
	(segment
		(start 217.36939 -179.451)
		(end 222.81261 -179.451)
		(width 0.127)
		(layer "In2.Cu")
		(net "DP_BMC_EXP_RST_N_R")
	)
	(segment
		(start 214.46871 -179.0319)
		(end 215.55329 -179.0319)
		(width 0.127)
		(layer "In2.Cu")
		(net "DP_BMC_EXP_RST_N_R")
	)
	(segment
		(start 215.55329 -179.0319)
		(end 215.68029 -179.1589)
		(width 0.127)
		(layer "In2.Cu")
		(net "DP_BMC_EXP_RST_N_R")
	)
	(segment
		(start 52.07 -171.958)
		(end 67.437 -171.958)
		(width 0.127)
		(layer "In2.Cu")
		(net "DP_BMC_EXP_RST_N_R")
	)
	(segment
		(start 53.98897 -142.748)
		(end 54.49697 -143.256)
		(width 0.1143)
		(layer "F.Cu")
		(net "DP_EXP_RST")
	)
	(segment
		(start 55.44947 -143.383)
		(end 54.62397 -143.383)
		(width 0.1143)
		(layer "F.Cu")
		(net "DP_EXP_RST")
	)
	(segment
		(start 53.98897 -141.3891)
		(end 53.98897 -142.748)
		(width 0.1143)
		(layer "F.Cu")
		(net "DP_EXP_RST")
	)
	(segment
		(start 53.69687 -141.097)
		(end 53.98897 -141.3891)
		(width 0.1143)
		(layer "F.Cu")
		(net "DP_EXP_RST")
	)
	(segment
		(start 54.62397 -143.383)
		(end 54.49697 -143.256)
		(width 0.1143)
		(layer "F.Cu")
		(net "DP_EXP_RST")
	)
	(segment
		(start 52.90947 -141.097)
		(end 53.69687 -141.097)
		(width 0.1143)
		(layer "F.Cu")
		(net "DP_EXP_RST")
	)
	(via
		(at 54.49697 -143.256)
		(size 0.7112)
		(drill 0.3556)
		(layers "F.Cu" "B.Cu")
		(net "DP_EXP_RST")
	)
	(segment
		(start 38.21684 -176.784)
		(end 38.608 -176.784)
		(width 0.1143)
		(layer "F.Cu")
		(net "DP_EXP_RST_R")
	)
	(segment
		(start 38.20668 -176.77384)
		(end 38.21684 -176.784)
		(width 0.1143)
		(layer "F.Cu")
		(net "DP_EXP_RST_R")
	)
	(segment
		(start 56.33847 -143.383)
		(end 56.33847 -144.7165)
		(width 0.1143)
		(layer "F.Cu")
		(net "DP_EXP_RST_R")
	)
	(segment
		(start 56.33847 -163.047172)
		(end 56.33847 -144.7165)
		(width 0.1143)
		(layer "F.Cu")
		(net "DP_EXP_RST_R")
	)
	(segment
		(start 38.608 -176.784)
		(end 39.497 -175.895)
		(width 0.1143)
		(layer "F.Cu")
		(net "DP_EXP_RST_R")
	)
	(segment
		(start 39.497 -175.895)
		(end 43.490642 -175.895)
		(width 0.1143)
		(layer "F.Cu")
		(net "DP_EXP_RST_R")
	)
	(segment
		(start 36.449 -176.77384)
		(end 38.20668 -176.77384)
		(width 0.1143)
		(layer "F.Cu")
		(net "DP_EXP_RST_R")
	)
	(segment
		(start 43.490642 -175.895)
		(end 56.33847 -163.047172)
		(width 0.1143)
		(layer "F.Cu")
		(net "DP_EXP_RST_R")
	)
	(segment
		(start 36.449 -178.4985)
		(end 36.449 -176.77384)
		(width 0.1143)
		(layer "F.Cu")
		(net "DP_EXP_RST_R")
	)
	(via
		(at 56.33847 -144.7165)
		(size 0.7112)
		(drill 0.3556)
		(layers "F.Cu" "B.Cu")
		(net "DP_EXP_RST_R")
	)
	(segment
		(start 35.2425 -169.291)
		(end 35.2425 -167.9575)
		(width 0.1143)
		(layer "F.Cu")
		(net "DP_BMC_EXP_RST_N")
	)
	(segment
		(start 35.2425 -170.78325)
		(end 35.2425 -169.291)
		(width 0.1143)
		(layer "F.Cu")
		(net "DP_BMC_EXP_RST_N")
	)
	(segment
		(start 34.29 -167.005)
		(end 33.909 -167.005)
		(width 0.1143)
		(layer "F.Cu")
		(net "DP_BMC_EXP_RST_N")
	)
	(segment
		(start 35.46475 -171.0055)
		(end 35.2425 -170.78325)
		(width 0.1143)
		(layer "F.Cu")
		(net "DP_BMC_EXP_RST_N")
	)
	(segment
		(start 35.2425 -167.9575)
		(end 34.29 -167.005)
		(width 0.1143)
		(layer "F.Cu")
		(net "DP_BMC_EXP_RST_N")
	)
	(segment
		(start 36.3855 -169.291)
		(end 35.2425 -169.291)
		(width 0.1143)
		(layer "F.Cu")
		(net "DP_BMC_EXP_RST_N")
	)
	(via
		(at 33.909 -167.005)
		(size 0.7112)
		(drill 0.3556)
		(layers "F.Cu" "B.Cu")
		(net "DP_BMC_EXP_RST_N")
	)
	(segment
		(start 311.785 -165.481)
		(end 314.96 -162.306)
		(width 0.1143)
		(layer "F.Cu")
		(net "PU_BMC0_SDA13")
	)
	(segment
		(start 301.864522 -167.440102)
		(end 302.820324 -166.4843)
		(width 0.1143)
		(layer "F.Cu")
		(net "PU_BMC0_SDA13")
	)
	(segment
		(start 311.2643 -166.0017)
		(end 311.785 -165.481)
		(width 0.1143)
		(layer "F.Cu")
		(net "PU_BMC0_SDA13")
	)
	(segment
		(start 304.0761 -166.0017)
		(end 311.2643 -166.0017)
		(width 0.1143)
		(layer "F.Cu")
		(net "PU_BMC0_SDA13")
	)
	(segment
		(start 302.820324 -166.4843)
		(end 303.5935 -166.4843)
		(width 0.1143)
		(layer "F.Cu")
		(net "PU_BMC0_SDA13")
	)
	(segment
		(start 301.634906 -167.440102)
		(end 301.864522 -167.440102)
		(width 0.1143)
		(layer "F.Cu")
		(net "PU_BMC0_SDA13")
	)
	(segment
		(start 314.96 -162.306)
		(end 317.5635 -162.306)
		(width 0.1143)
		(layer "F.Cu")
		(net "PU_BMC0_SDA13")
	)
	(segment
		(start 303.5935 -166.4843)
		(end 304.0761 -166.0017)
		(width 0.1143)
		(layer "F.Cu")
		(net "PU_BMC0_SDA13")
	)
	(via
		(at 311.785 -165.481)
		(size 0.7112)
		(drill 0.3556)
		(layers "F.Cu" "B.Cu")
		(net "PU_BMC0_SDA13")
	)
	(segment
		(start 317.5635 -161.29)
		(end 314.579 -161.29)
		(width 0.1143)
		(layer "F.Cu")
		(net "PU_BMC0_SCL13")
	)
	(segment
		(start 302.387 -166.116)
		(end 301.244 -167.259)
		(width 0.1143)
		(layer "F.Cu")
		(net "PU_BMC0_SCL13")
	)
	(segment
		(start 303.870868 -165.5064)
		(end 303.261268 -166.116)
		(width 0.1143)
		(layer "F.Cu")
		(net "PU_BMC0_SCL13")
	)
	(segment
		(start 301.244 -167.64)
		(end 300.834806 -168.049194)
		(width 0.1143)
		(layer "F.Cu")
		(net "PU_BMC0_SCL13")
	)
	(segment
		(start 312.547 -163.322)
		(end 310.3626 -165.5064)
		(width 0.1143)
		(layer "F.Cu")
		(net "PU_BMC0_SCL13")
	)
	(segment
		(start 301.244 -167.259)
		(end 301.244 -167.64)
		(width 0.1143)
		(layer "F.Cu")
		(net "PU_BMC0_SCL13")
	)
	(segment
		(start 303.261268 -166.116)
		(end 302.387 -166.116)
		(width 0.1143)
		(layer "F.Cu")
		(net "PU_BMC0_SCL13")
	)
	(segment
		(start 300.834806 -168.049194)
		(end 300.834806 -168.240202)
		(width 0.1143)
		(layer "F.Cu")
		(net "PU_BMC0_SCL13")
	)
	(segment
		(start 314.579 -161.29)
		(end 312.547 -163.322)
		(width 0.1143)
		(layer "F.Cu")
		(net "PU_BMC0_SCL13")
	)
	(segment
		(start 310.3626 -165.5064)
		(end 303.870868 -165.5064)
		(width 0.1143)
		(layer "F.Cu")
		(net "PU_BMC0_SCL13")
	)
	(via
		(at 312.547 -163.322)
		(size 0.7112)
		(drill 0.3556)
		(layers "F.Cu" "B.Cu")
		(net "PU_BMC0_SCL13")
	)
	(segment
		(start 52.05222 -141.48943)
		(end 52.05222 -138.09091)
		(width 0.1143)
		(layer "F.Cu")
		(net "EXP_RST_2")
	)
	(segment
		(start 49.67097 -141.74724)
		(end 51.25847 -141.74724)
		(width 0.1143)
		(layer "F.Cu")
		(net "EXP_RST_2")
	)
	(segment
		(start 52.05222 -138.09091)
		(end 51.75631 -137.795)
		(width 0.1143)
		(layer "F.Cu")
		(net "EXP_RST_2")
	)
	(segment
		(start 51.79441 -141.74724)
		(end 52.05222 -141.48943)
		(width 0.1143)
		(layer "F.Cu")
		(net "EXP_RST_2")
	)
	(segment
		(start 51.75631 -137.795)
		(end 51.25847 -137.795)
		(width 0.1143)
		(layer "F.Cu")
		(net "EXP_RST_2")
	)
	(segment
		(start 51.25847 -141.74724)
		(end 51.79441 -141.74724)
		(width 0.1143)
		(layer "F.Cu")
		(net "EXP_RST_2")
	)
	(via
		(at 49.67097 -141.74724)
		(size 0.7112)
		(drill 0.3556)
		(layers "F.Cu" "B.Cu")
		(net "EXP_RST_2")
	)
	(segment
		(start 48.27143 -138.44524)
		(end 49.05121 -138.44524)
		(width 0.1143)
		(layer "F.Cu")
		(net "EXP_RST_1")
	)
	(segment
		(start 51.6128 -136.16813)
		(end 48.2854 -136.16813)
		(width 0.1143)
		(layer "F.Cu")
		(net "EXP_RST_1")
	)
	(segment
		(start 52.34559 -133.96976)
		(end 52.05222 -134.26313)
		(width 0.1143)
		(layer "F.Cu")
		(net "EXP_RST_1")
	)
	(segment
		(start 47.88027 -136.57326)
		(end 47.88027 -138.05408)
		(width 0.1143)
		(layer "F.Cu")
		(net "EXP_RST_1")
	)
	(segment
		(start 52.05222 -134.26313)
		(end 52.05222 -135.72871)
		(width 0.1143)
		(layer "F.Cu")
		(net "EXP_RST_1")
	)
	(segment
		(start 47.88027 -138.05408)
		(end 48.27143 -138.44524)
		(width 0.1143)
		(layer "F.Cu")
		(net "EXP_RST_1")
	)
	(segment
		(start 48.2854 -136.16813)
		(end 47.88027 -136.57326)
		(width 0.1143)
		(layer "F.Cu")
		(net "EXP_RST_1")
	)
	(segment
		(start 52.05222 -135.72871)
		(end 51.6128 -136.16813)
		(width 0.1143)
		(layer "F.Cu")
		(net "EXP_RST_1")
	)
	(segment
		(start 51.25847 -138.44524)
		(end 49.05121 -138.44524)
		(width 0.1143)
		(layer "F.Cu")
		(net "EXP_RST_1")
	)
	(segment
		(start 52.90947 -133.96976)
		(end 52.34559 -133.96976)
		(width 0.1143)
		(layer "F.Cu")
		(net "EXP_RST_1")
	)
	(via
		(at 49.05121 -138.44524)
		(size 0.7112)
		(drill 0.3556)
		(layers "F.Cu" "B.Cu")
		(net "EXP_RST_1")
	)
	(segment
		(start 211.449666 -77.997304)
		(end 211.449666 -78.24978)
		(width 0.1143)
		(layer "F.Cu")
		(net "CPU_RESET_N_R")
	)
	(segment
		(start 211.201 -74.15403)
		(end 211.201 -74.422)
		(width 0.1143)
		(layer "F.Cu")
		(net "CPU_RESET_N_R")
	)
	(segment
		(start 210.57997 -69.5325)
		(end 210.57997 -73.533)
		(width 0.1143)
		(layer "F.Cu")
		(net "CPU_RESET_N_R")
	)
	(segment
		(start 212.61197 -76.835)
		(end 211.449666 -77.997304)
		(width 0.1143)
		(layer "F.Cu")
		(net "CPU_RESET_N_R")
	)
	(segment
		(start 210.57997 -73.533)
		(end 211.201 -74.15403)
		(width 0.1143)
		(layer "F.Cu")
		(net "CPU_RESET_N_R")
	)
	(segment
		(start 211.201 -74.422)
		(end 212.61197 -75.83297)
		(width 0.1143)
		(layer "F.Cu")
		(net "CPU_RESET_N_R")
	)
	(segment
		(start 212.61197 -75.83297)
		(end 212.61197 -76.835)
		(width 0.1143)
		(layer "F.Cu")
		(net "CPU_RESET_N_R")
	)
	(segment
		(start 53.71973 -140.44676)
		(end 54.62397 -141.351)
		(width 0.1143)
		(layer "F.Cu")
		(net "RST_BTN_N")
	)
	(segment
		(start 52.90947 -140.44676)
		(end 53.71973 -140.44676)
		(width 0.1143)
		(layer "F.Cu")
		(net "RST_BTN_N")
	)
	(segment
		(start 55.44947 -142.1765)
		(end 54.62397 -141.351)
		(width 0.1143)
		(layer "F.Cu")
		(net "RST_BTN_N")
	)
	(segment
		(start 55.44947 -142.24)
		(end 55.44947 -142.1765)
		(width 0.1143)
		(layer "F.Cu")
		(net "RST_BTN_N")
	)
	(via
		(at 54.62397 -141.351)
		(size 0.7112)
		(drill 0.3556)
		(layers "F.Cu" "B.Cu")
		(net "RST_BTN_N")
	)
	(segment
		(start 56.933592 -163.044886)
		(end 43.664378 -176.3141)
		(width 0.1143)
		(layer "F.Cu")
		(net "RST_BTN_R")
	)
	(segment
		(start 43.664378 -176.3141)
		(end 43.6499 -176.3141)
		(width 0.1143)
		(layer "F.Cu")
		(net "RST_BTN_R")
	)
	(segment
		(start 41.402 -178.4985)
		(end 41.402 -176.90084)
		(width 0.1143)
		(layer "F.Cu")
		(net "RST_BTN_R")
	)
	(segment
		(start 56.933592 -142.835122)
		(end 56.933592 -146.6596)
		(width 0.1143)
		(layer "F.Cu")
		(net "RST_BTN_R")
	)
	(segment
		(start 43.561 -176.403)
		(end 41.89984 -176.403)
		(width 0.1143)
		(layer "F.Cu")
		(net "RST_BTN_R")
	)
	(segment
		(start 43.6499 -176.3141)
		(end 43.561 -176.403)
		(width 0.1143)
		(layer "F.Cu")
		(net "RST_BTN_R")
	)
	(segment
		(start 41.89984 -176.403)
		(end 41.402 -176.90084)
		(width 0.1143)
		(layer "F.Cu")
		(net "RST_BTN_R")
	)
	(segment
		(start 56.933592 -146.6596)
		(end 56.933592 -163.044886)
		(width 0.1143)
		(layer "F.Cu")
		(net "RST_BTN_R")
	)
	(segment
		(start 56.33847 -142.24)
		(end 56.933592 -142.835122)
		(width 0.1143)
		(layer "F.Cu")
		(net "RST_BTN_R")
	)
	(via
		(at 56.933592 -146.6596)
		(size 0.7112)
		(drill 0.3556)
		(layers "F.Cu" "B.Cu")
		(net "RST_BTN_R")
	)
	(segment
		(start 33.0835 -172.4025)
		(end 34.036 -172.4025)
		(width 0.127)
		(layer "F.Cu")
		(net "P3V3_STBY_R8")
	)
	(segment
		(start 33.02 -172.339)
		(end 33.0835 -172.4025)
		(width 0.127)
		(layer "F.Cu")
		(net "P3V3_STBY_R8")
	)
	(segment
		(start 35.306 -172.9105)
		(end 36.449 -172.9105)
		(width 0.127)
		(layer "F.Cu")
		(net "P3V3_STBY_R8")
	)
	(segment
		(start 34.036 -172.4025)
		(end 34.798 -172.4025)
		(width 0.127)
		(layer "F.Cu")
		(net "P3V3_STBY_R8")
	)
	(segment
		(start 34.798 -172.4025)
		(end 35.306 -172.9105)
		(width 0.127)
		(layer "F.Cu")
		(net "P3V3_STBY_R8")
	)
	(segment
		(start 34.036 -172.4025)
		(end 34.036 -171.3865)
		(width 0.127)
		(layer "F.Cu")
		(net "P3V3_STBY_R8")
	)
	(via
		(at 33.02 -172.339)
		(size 0.7112)
		(drill 0.3556)
		(layers "F.Cu" "B.Cu")
		(net "P3V3_STBY_R8")
	)
	(segment
		(start 38.989 -171.2595)
		(end 38.989 -172.4025)
		(width 0.127)
		(layer "F.Cu")
		(net "P3V3_STBY_R7")
	)
	(segment
		(start 40.005 -172.4025)
		(end 40.513 -172.9105)
		(width 0.127)
		(layer "F.Cu")
		(net "P3V3_STBY_R7")
	)
	(segment
		(start 41.5925 -173.101)
		(end 41.402 -172.9105)
		(width 0.127)
		(layer "F.Cu")
		(net "P3V3_STBY_R7")
	)
	(segment
		(start 43.561 -173.101)
		(end 41.5925 -173.101)
		(width 0.127)
		(layer "F.Cu")
		(net "P3V3_STBY_R7")
	)
	(segment
		(start 38.989 -172.4025)
		(end 40.005 -172.4025)
		(width 0.127)
		(layer "F.Cu")
		(net "P3V3_STBY_R7")
	)
	(segment
		(start 40.513 -172.9105)
		(end 41.402 -172.9105)
		(width 0.127)
		(layer "F.Cu")
		(net "P3V3_STBY_R7")
	)
	(via
		(at 43.561 -173.101)
		(size 0.7112)
		(drill 0.3556)
		(layers "F.Cu" "B.Cu")
		(net "P3V3_STBY_R7")
	)
	(segment
		(start 34.036 -174.371)
		(end 34.036 -173.2915)
		(width 0.127)
		(layer "F.Cu")
		(net "P3V3_STBY_G8")
	)
	(segment
		(start 34.53384 -174.86884)
		(end 34.036 -174.371)
		(width 0.127)
		(layer "F.Cu")
		(net "P3V3_STBY_G8")
	)
	(segment
		(start 35.46475 -174.86884)
		(end 34.53384 -174.86884)
		(width 0.127)
		(layer "F.Cu")
		(net "P3V3_STBY_G8")
	)
	(via
		(at 34.036 -174.371)
		(size 0.7112)
		(drill 0.3556)
		(layers "F.Cu" "B.Cu")
		(net "P3V3_STBY_G8")
	)
	(segment
		(start 39.86784 -174.99584)
		(end 39.243 -174.371)
		(width 0.127)
		(layer "F.Cu")
		(net "P3V3_STBY_G7")
	)
	(segment
		(start 40.41775 -174.99584)
		(end 39.86784 -174.99584)
		(width 0.127)
		(layer "F.Cu")
		(net "P3V3_STBY_G7")
	)
	(segment
		(start 38.989 -174.117)
		(end 39.243 -174.371)
		(width 0.127)
		(layer "F.Cu")
		(net "P3V3_STBY_G7")
	)
	(segment
		(start 38.989 -173.2915)
		(end 38.989 -174.117)
		(width 0.127)
		(layer "F.Cu")
		(net "P3V3_STBY_G7")
	)
	(via
		(at 39.243 -174.371)
		(size 0.7112)
		(drill 0.3556)
		(layers "F.Cu" "B.Cu")
		(net "P3V3_STBY_G7")
	)
	(segment
		(start 219.00388 -88.60409)
		(end 219.00388 -89.40292)
		(width 0.1143)
		(layer "F.Cu")
		(net "IOC_UART_R_RX")
	)
	(segment
		(start 219.00388 -89.40292)
		(end 218.64828 -89.75852)
		(width 0.1143)
		(layer "F.Cu")
		(net "IOC_UART_R_RX")
	)
	(segment
		(start 218.64828 -89.82202)
		(end 218.64828 -89.75852)
		(width 0.1143)
		(layer "F.Cu")
		(net "IOC_UART_R_RX")
	)
	(segment
		(start 219.41028 -90.58402)
		(end 218.64828 -89.82202)
		(width 0.1143)
		(layer "F.Cu")
		(net "IOC_UART_R_RX")
	)
	(via
		(at 218.64828 -89.75852)
		(size 0.7112)
		(drill 0.3556)
		(layers "F.Cu" "B.Cu")
		(net "IOC_UART_R_RX")
	)
	(segment
		(start 221.44228 -89.82202)
		(end 221.44228 -89.75852)
		(width 0.1143)
		(layer "F.Cu")
		(net "IOC_UART_R_TX")
	)
	(segment
		(start 221.34068 -88.60409)
		(end 221.34068 -89.65692)
		(width 0.1143)
		(layer "F.Cu")
		(net "IOC_UART_R_TX")
	)
	(segment
		(start 220.68028 -90.58402)
		(end 221.44228 -89.82202)
		(width 0.1143)
		(layer "F.Cu")
		(net "IOC_UART_R_TX")
	)
	(segment
		(start 221.34068 -89.65692)
		(end 221.44228 -89.75852)
		(width 0.1143)
		(layer "F.Cu")
		(net "IOC_UART_R_TX")
	)
	(via
		(at 221.44228 -89.75852)
		(size 0.7112)
		(drill 0.3556)
		(layers "F.Cu" "B.Cu")
		(net "IOC_UART_R_TX")
	)
	(segment
		(start 325.5645 -143.383)
		(end 326.033384 -142.914116)
		(width 0.1143)
		(layer "F.Cu")
		(net "RTC_OSCO")
	)
	(segment
		(start 323.85 -149.352)
		(end 324.612 -149.352)
		(width 0.1143)
		(layer "F.Cu")
		(net "RTC_OSCO")
	)
	(segment
		(start 325.2343 -145.923)
		(end 325.2343 -144.9197)
		(width 0.1143)
		(layer "F.Cu")
		(net "RTC_OSCO")
	)
	(segment
		(start 325.93915 -147.193254)
		(end 325.93915 -146.62785)
		(width 0.1143)
		(layer "F.Cu")
		(net "RTC_OSCO")
	)
	(segment
		(start 325.2343 -144.9197)
		(end 325.628 -144.526)
		(width 0.1143)
		(layer "F.Cu")
		(net "RTC_OSCO")
	)
	(segment
		(start 325.628 -144.526)
		(end 325.5645 -144.4625)
		(width 0.1143)
		(layer "F.Cu")
		(net "RTC_OSCO")
	)
	(segment
		(start 324.612 -149.352)
		(end 325.93915 -148.02485)
		(width 0.1143)
		(layer "F.Cu")
		(net "RTC_OSCO")
	)
	(segment
		(start 325.93915 -146.62785)
		(end 325.2343 -145.923)
		(width 0.1143)
		(layer "F.Cu")
		(net "RTC_OSCO")
	)
	(segment
		(start 326.033384 -142.914116)
		(end 326.033384 -141.478)
		(width 0.1143)
		(layer "F.Cu")
		(net "RTC_OSCO")
	)
	(segment
		(start 325.5645 -144.4625)
		(end 325.5645 -143.383)
		(width 0.1143)
		(layer "F.Cu")
		(net "RTC_OSCO")
	)
	(segment
		(start 325.93915 -148.02485)
		(end 325.93915 -147.193254)
		(width 0.1143)
		(layer "F.Cu")
		(net "RTC_OSCO")
	)
	(via
		(at 325.93915 -147.193254)
		(size 0.7112)
		(drill 0.3556)
		(layers "F.Cu" "B.Cu")
		(net "RTC_OSCO")
	)
	(segment
		(start 323.85 -148.082)
		(end 325.12 -148.082)
		(width 0.1143)
		(layer "F.Cu")
		(net "RTC_OSCI")
	)
	(segment
		(start 324.104 -144.526)
		(end 324.0405 -144.4625)
		(width 0.1143)
		(layer "F.Cu")
		(net "RTC_OSCI")
	)
	(segment
		(start 324.612 -145.5928)
		(end 324.612 -145.034)
		(width 0.1143)
		(layer "F.Cu")
		(net "RTC_OSCI")
	)
	(segment
		(start 324.0405 -143.383)
		(end 323.444616 -142.787116)
		(width 0.1143)
		(layer "F.Cu")
		(net "RTC_OSCI")
	)
	(segment
		(start 323.444616 -142.787116)
		(end 323.444616 -141.478)
		(width 0.1143)
		(layer "F.Cu")
		(net "RTC_OSCI")
	)
	(segment
		(start 324.0405 -144.4625)
		(end 324.0405 -143.383)
		(width 0.1143)
		(layer "F.Cu")
		(net "RTC_OSCI")
	)
	(segment
		(start 325.374 -147.066)
		(end 324.612 -146.304)
		(width 0.1143)
		(layer "F.Cu")
		(net "RTC_OSCI")
	)
	(segment
		(start 325.374 -147.828)
		(end 325.374 -147.066)
		(width 0.1143)
		(layer "F.Cu")
		(net "RTC_OSCI")
	)
	(segment
		(start 324.612 -145.034)
		(end 324.104 -144.526)
		(width 0.1143)
		(layer "F.Cu")
		(net "RTC_OSCI")
	)
	(segment
		(start 325.12 -148.082)
		(end 325.374 -147.828)
		(width 0.1143)
		(layer "F.Cu")
		(net "RTC_OSCI")
	)
	(segment
		(start 324.612 -146.304)
		(end 324.612 -145.5928)
		(width 0.1143)
		(layer "F.Cu")
		(net "RTC_OSCI")
	)
	(via
		(at 324.612 -145.5928)
		(size 0.7112)
		(drill 0.3556)
		(layers "F.Cu" "B.Cu")
		(net "RTC_OSCI")
	)
	(segment
		(start 329.057 -7.8105)
		(end 329.057 -6.731)
		(width 0.1143)
		(layer "F.Cu")
		(net "DEBUG_PORT_GND")
	)
	(segment
		(start 329.10018 -4.550156)
		(end 329.10018 -6.68782)
		(width 0.1143)
		(layer "F.Cu")
		(net "DEBUG_PORT_GND")
	)
	(segment
		(start 329.10018 -6.68782)
		(end 329.057 -6.731)
		(width 0.1143)
		(layer "F.Cu")
		(net "DEBUG_PORT_GND")
	)
	(via
		(at 329.057 -6.731)
		(size 0.7112)
		(drill 0.3556)
		(layers "F.Cu" "B.Cu")
		(net "DEBUG_PORT_GND")
	)
	(segment
		(start 304.8635 -153.797)
		(end 303.8602 -153.797)
		(width 0.1143)
		(layer "F.Cu")
		(net "BMC_MAC2_RGMIICK")
	)
	(segment
		(start 303.8602 -153.797)
		(end 303.784 -153.8732)
		(width 0.1143)
		(layer "F.Cu")
		(net "BMC_MAC2_RGMIICK")
	)
	(segment
		(start 296.034968 -168.2496)
		(end 295.642284 -168.642284)
		(width 0.1143)
		(layer "F.Cu")
		(net "BMC_MAC2_RGMIICK")
	)
	(segment
		(start 296.034968 -168.240202)
		(end 296.034968 -168.2496)
		(width 0.1143)
		(layer "F.Cu")
		(net "BMC_MAC2_RGMIICK")
	)
	(via
		(at 296.94505 -155.829)
		(size 0.5588)
		(drill 0.3048)
		(layers "F.Cu" "B.Cu")
		(net "BMC_MAC2_RGMIICK")
	)
	(via
		(at 295.642284 -168.642284)
		(size 0.508)
		(drill 0.254)
		(layers "F.Cu" "B.Cu")
		(net "BMC_MAC2_RGMIICK")
	)
	(via
		(at 303.784 -153.8732)
		(size 0.5588)
		(drill 0.3048)
		(layers "F.Cu" "B.Cu")
		(net "BMC_MAC2_RGMIICK")
	)
	(via
		(at 296.94505 -156.845)
		(size 0.7112)
		(drill 0.3556)
		(layers "F.Cu" "B.Cu")
		(net "BMC_MAC2_RGMIICK")
	)
	(segment
		(start 296.291 -166.990776)
		(end 296.291 -167.894)
		(width 0.1143)
		(layer "B.Cu")
		(net "BMC_MAC2_RGMIICK")
	)
	(segment
		(start 296.291 -167.894)
		(end 295.642284 -168.542716)
		(width 0.1143)
		(layer "B.Cu")
		(net "BMC_MAC2_RGMIICK")
	)
	(segment
		(start 295.642284 -168.542716)
		(end 295.642284 -168.642284)
		(width 0.1143)
		(layer "B.Cu")
		(net "BMC_MAC2_RGMIICK")
	)
	(segment
		(start 296.94505 -156.845)
		(end 296.94505 -166.336726)
		(width 0.1143)
		(layer "B.Cu")
		(net "BMC_MAC2_RGMIICK")
	)
	(segment
		(start 296.94505 -155.829)
		(end 296.94505 -156.845)
		(width 0.1143)
		(layer "B.Cu")
		(net "BMC_MAC2_RGMIICK")
	)
	(segment
		(start 296.94505 -166.336726)
		(end 296.291 -166.990776)
		(width 0.1143)
		(layer "B.Cu")
		(net "BMC_MAC2_RGMIICK")
	)
	(segment
		(start 298.90085 -153.8732)
		(end 296.94505 -155.829)
		(width 0.127)
		(layer "In5.Cu")
		(net "BMC_MAC2_RGMIICK")
	)
	(segment
		(start 303.784 -153.8732)
		(end 298.90085 -153.8732)
		(width 0.127)
		(layer "In5.Cu")
		(net "BMC_MAC2_RGMIICK")
	)
	(segment
		(start 319.489582 -10.0965)
		(end 319.786 -9.800082)
		(width 0.1778)
		(layer "F.Cu")
		(net "LED_SL_SW_ON")
	)
	(segment
		(start 319.786 -9.800082)
		(end 320.512948 -9.800082)
		(width 0.1778)
		(layer "F.Cu")
		(net "LED_SL_SW_ON")
	)
	(segment
		(start 322.232274 -9.800082)
		(end 320.512948 -9.800082)
		(width 0.1778)
		(layer "F.Cu")
		(net "LED_SL_SW_ON")
	)
	(segment
		(start 319.278 -10.0965)
		(end 319.489582 -10.0965)
		(width 0.1778)
		(layer "F.Cu")
		(net "LED_SL_SW_ON")
	)
	(via
		(at 320.512948 -9.800082)
		(size 0.7112)
		(drill 0.3556)
		(layers "F.Cu" "B.Cu")
		(net "LED_SL_SW_ON")
	)
	(segment
		(start 288.29 -69.088)
		(end 288.29 -69.723)
		(width 0.1143)
		(layer "F.Cu")
		(net "HS_ADR")
	)
	(segment
		(start 286.160972 -68.017136)
		(end 287.219136 -68.017136)
		(width 0.1143)
		(layer "F.Cu")
		(net "HS_ADR")
	)
	(segment
		(start 287.219136 -68.017136)
		(end 288.29 -69.088)
		(width 0.1143)
		(layer "F.Cu")
		(net "HS_ADR")
	)
	(segment
		(start 288.29 -69.723)
		(end 289.2425 -69.723)
		(width 0.1143)
		(layer "F.Cu")
		(net "HS_ADR")
	)
	(segment
		(start 289.2425 -69.723)
		(end 289.2425 -70.739)
		(width 0.1143)
		(layer "F.Cu")
		(net "HS_ADR")
	)
	(via
		(at 288.29 -69.723)
		(size 0.7112)
		(drill 0.3556)
		(layers "F.Cu" "B.Cu")
		(net "HS_ADR")
	)
	(segment
		(start 18.385028 -170.107356)
		(end 18.385028 -167.669972)
		(width 0.1143)
		(layer "F.Cu")
		(net "SAS_HDD_LED10")
	)
	(segment
		(start 34.036 -149.78507)
		(end 34.036 -149.098)
		(width 0.1143)
		(layer "F.Cu")
		(net "SAS_HDD_LED10")
	)
	(segment
		(start 21.844 -161.97707)
		(end 34.036 -149.78507)
		(width 0.1143)
		(layer "F.Cu")
		(net "SAS_HDD_LED10")
	)
	(segment
		(start 108.146342 -82.146394)
		(end 108.146342 -81.034382)
		(width 0.1143)
		(layer "F.Cu")
		(net "SAS_HDD_LED10")
	)
	(segment
		(start 107.88396 -80.772)
		(end 107.83697 -80.772)
		(width 0.1143)
		(layer "F.Cu")
		(net "SAS_HDD_LED10")
	)
	(segment
		(start 108.349796 -82.349848)
		(end 108.146342 -82.146394)
		(width 0.1143)
		(layer "F.Cu")
		(net "SAS_HDD_LED10")
	)
	(segment
		(start 18.385028 -167.669972)
		(end 20.828 -165.227)
		(width 0.1143)
		(layer "F.Cu")
		(net "SAS_HDD_LED10")
	)
	(segment
		(start 20.828 -165.227)
		(end 21.844 -164.211)
		(width 0.1143)
		(layer "F.Cu")
		(net "SAS_HDD_LED10")
	)
	(segment
		(start 108.146342 -81.034382)
		(end 107.88396 -80.772)
		(width 0.1143)
		(layer "F.Cu")
		(net "SAS_HDD_LED10")
	)
	(segment
		(start 21.844 -164.211)
		(end 21.844 -161.97707)
		(width 0.1143)
		(layer "F.Cu")
		(net "SAS_HDD_LED10")
	)
	(via
		(at 107.83697 -80.772)
		(size 0.508)
		(drill 0.254)
		(layers "F.Cu" "B.Cu")
		(net "SAS_HDD_LED10")
	)
	(via
		(at 34.036 -149.098)
		(size 0.5588)
		(drill 0.3048)
		(layers "F.Cu" "B.Cu")
		(net "SAS_HDD_LED10")
	)
	(via
		(at 20.828 -165.227)
		(size 0.7112)
		(drill 0.3556)
		(layers "F.Cu" "B.Cu")
		(net "SAS_HDD_LED10")
	)
	(segment
		(start 47.117 -138.269472)
		(end 36.288472 -149.098)
		(width 0.127)
		(layer "In5.Cu")
		(net "SAS_HDD_LED10")
	)
	(segment
		(start 105.54589 -79.5909)
		(end 101.649022 -79.5909)
		(width 0.127)
		(layer "In5.Cu")
		(net "SAS_HDD_LED10")
	)
	(segment
		(start 47.117 -136.909048)
		(end 47.117 -138.269472)
		(width 0.127)
		(layer "In5.Cu")
		(net "SAS_HDD_LED10")
	)
	(segment
		(start 98.327464 -81.534)
		(end 49.022 -130.839464)
		(width 0.127)
		(layer "In5.Cu")
		(net "SAS_HDD_LED10")
	)
	(segment
		(start 107.83697 -80.772)
		(end 106.50347 -79.4385)
		(width 0.127)
		(layer "In5.Cu")
		(net "SAS_HDD_LED10")
	)
	(segment
		(start 99.705922 -81.534)
		(end 98.327464 -81.534)
		(width 0.127)
		(layer "In5.Cu")
		(net "SAS_HDD_LED10")
	)
	(segment
		(start 49.022 -135.004048)
		(end 47.117 -136.909048)
		(width 0.127)
		(layer "In5.Cu")
		(net "SAS_HDD_LED10")
	)
	(segment
		(start 36.288472 -149.098)
		(end 34.036 -149.098)
		(width 0.127)
		(layer "In5.Cu")
		(net "SAS_HDD_LED10")
	)
	(segment
		(start 106.50347 -79.4385)
		(end 105.69829 -79.4385)
		(width 0.127)
		(layer "In5.Cu")
		(net "SAS_HDD_LED10")
	)
	(segment
		(start 105.69829 -79.4385)
		(end 105.54589 -79.5909)
		(width 0.127)
		(layer "In5.Cu")
		(net "SAS_HDD_LED10")
	)
	(segment
		(start 49.022 -130.839464)
		(end 49.022 -135.004048)
		(width 0.127)
		(layer "In5.Cu")
		(net "SAS_HDD_LED10")
	)
	(segment
		(start 101.649022 -79.5909)
		(end 99.705922 -81.534)
		(width 0.127)
		(layer "In5.Cu")
		(net "SAS_HDD_LED10")
	)
	(segment
		(start 38.848792 -150.127208)
		(end 38.848792 -149.098)
		(width 0.1143)
		(layer "F.Cu")
		(net "SAS_HDD_LED0")
	)
	(segment
		(start 105.923842 -82.923888)
		(end 105.923842 -81.751424)
		(width 0.1143)
		(layer "F.Cu")
		(net "SAS_HDD_LED0")
	)
	(segment
		(start 26.424128 -170.107356)
		(end 26.424128 -162.551872)
		(width 0.1143)
		(layer "F.Cu")
		(net "SAS_HDD_LED0")
	)
	(segment
		(start 105.923842 -81.751424)
		(end 105.9053 -81.732882)
		(width 0.1143)
		(layer "F.Cu")
		(net "SAS_HDD_LED0")
	)
	(segment
		(start 106.3498 -83.349846)
		(end 105.923842 -82.923888)
		(width 0.1143)
		(layer "F.Cu")
		(net "SAS_HDD_LED0")
	)
	(segment
		(start 26.424128 -162.551872)
		(end 29.464 -159.512)
		(width 0.1143)
		(layer "F.Cu")
		(net "SAS_HDD_LED0")
	)
	(segment
		(start 29.464 -159.512)
		(end 38.848792 -150.127208)
		(width 0.1143)
		(layer "F.Cu")
		(net "SAS_HDD_LED0")
	)
	(via
		(at 105.9053 -81.732882)
		(size 0.508)
		(drill 0.254)
		(layers "F.Cu" "B.Cu")
		(net "SAS_HDD_LED0")
	)
	(via
		(at 38.848792 -149.098)
		(size 0.5588)
		(drill 0.3048)
		(layers "F.Cu" "B.Cu")
		(net "SAS_HDD_LED0")
	)
	(via
		(at 29.464 -159.512)
		(size 0.7112)
		(drill 0.3556)
		(layers "F.Cu" "B.Cu")
		(net "SAS_HDD_LED0")
	)
	(segment
		(start 44.069 -147.447)
		(end 49.21885 -142.29715)
		(width 0.127)
		(layer "In5.Cu")
		(net "SAS_HDD_LED0")
	)
	(segment
		(start 43.161204 -148.717)
		(end 44.069 -147.809204)
		(width 0.127)
		(layer "In5.Cu")
		(net "SAS_HDD_LED0")
	)
	(segment
		(start 100.065332 -84.04098)
		(end 100.794312 -83.312)
		(width 0.127)
		(layer "In5.Cu")
		(net "SAS_HDD_LED0")
	)
	(segment
		(start 95.758 -88.218264)
		(end 99.935284 -84.04098)
		(width 0.127)
		(layer "In5.Cu")
		(net "SAS_HDD_LED0")
	)
	(segment
		(start 49.21885 -139.12215)
		(end 53.269642 -135.071358)
		(width 0.127)
		(layer "In5.Cu")
		(net "SAS_HDD_LED0")
	)
	(segment
		(start 99.935284 -84.04098)
		(end 100.065332 -84.04098)
		(width 0.127)
		(layer "In5.Cu")
		(net "SAS_HDD_LED0")
	)
	(segment
		(start 39.7383 -149.8473)
		(end 41.58742 -149.8473)
		(width 0.127)
		(layer "In5.Cu")
		(net "SAS_HDD_LED0")
	)
	(segment
		(start 49.21885 -142.29715)
		(end 49.21885 -139.12215)
		(width 0.127)
		(layer "In5.Cu")
		(net "SAS_HDD_LED0")
	)
	(segment
		(start 38.848792 -149.098)
		(end 38.989 -149.098)
		(width 0.127)
		(layer "In5.Cu")
		(net "SAS_HDD_LED0")
	)
	(segment
		(start 53.269642 -135.071358)
		(end 53.269642 -130.447796)
		(width 0.127)
		(layer "In5.Cu")
		(net "SAS_HDD_LED0")
	)
	(segment
		(start 94.883478 -89.535)
		(end 95.758 -88.660478)
		(width 0.127)
		(layer "In5.Cu")
		(net "SAS_HDD_LED0")
	)
	(segment
		(start 38.989 -149.098)
		(end 39.7383 -149.8473)
		(width 0.127)
		(layer "In5.Cu")
		(net "SAS_HDD_LED0")
	)
	(segment
		(start 95.758 -88.660478)
		(end 95.758 -88.218264)
		(width 0.127)
		(layer "In5.Cu")
		(net "SAS_HDD_LED0")
	)
	(segment
		(start 104.326182 -83.312)
		(end 105.9053 -81.732882)
		(width 0.127)
		(layer "In5.Cu")
		(net "SAS_HDD_LED0")
	)
	(segment
		(start 44.069 -147.809204)
		(end 44.069 -147.447)
		(width 0.127)
		(layer "In5.Cu")
		(net "SAS_HDD_LED0")
	)
	(segment
		(start 94.182438 -89.535)
		(end 94.883478 -89.535)
		(width 0.127)
		(layer "In5.Cu")
		(net "SAS_HDD_LED0")
	)
	(segment
		(start 53.269642 -130.447796)
		(end 94.182438 -89.535)
		(width 0.127)
		(layer "In5.Cu")
		(net "SAS_HDD_LED0")
	)
	(segment
		(start 41.58742 -149.8473)
		(end 42.71772 -148.717)
		(width 0.127)
		(layer "In5.Cu")
		(net "SAS_HDD_LED0")
	)
	(segment
		(start 100.794312 -83.312)
		(end 104.326182 -83.312)
		(width 0.127)
		(layer "In5.Cu")
		(net "SAS_HDD_LED0")
	)
	(segment
		(start 42.71772 -148.717)
		(end 43.161204 -148.717)
		(width 0.127)
		(layer "In5.Cu")
		(net "SAS_HDD_LED0")
	)
	(segment
		(start 49.7332 -134.62)
		(end 47.06747 -134.62)
		(width 0.1143)
		(layer "F.Cu")
		(net "BMC_EXP_RESET_N")
	)
	(segment
		(start 51.25847 -134.62)
		(end 49.7332 -134.62)
		(width 0.1143)
		(layer "F.Cu")
		(net "BMC_EXP_RESET_N")
	)
	(via
		(at 49.7332 -134.62)
		(size 0.7112)
		(drill 0.3556)
		(layers "F.Cu" "B.Cu")
		(net "BMC_EXP_RESET_N")
	)
	(segment
		(start 109.860842 -82.621882)
		(end 109.860842 -81.097882)
		(width 0.1143)
		(layer "F.Cu")
		(net "SAS_HDD_LED11")
	)
	(segment
		(start 109.479842 -80.716882)
		(end 109.479842 -80.589882)
		(width 0.1143)
		(layer "F.Cu")
		(net "SAS_HDD_LED11")
	)
	(segment
		(start 110.349792 -83.110832)
		(end 109.860842 -82.621882)
		(width 0.1143)
		(layer "F.Cu")
		(net "SAS_HDD_LED11")
	)
	(segment
		(start 34.671 -149.671024)
		(end 34.671 -147.447)
		(width 0.1143)
		(layer "F.Cu")
		(net "SAS_HDD_LED11")
	)
	(segment
		(start 18.785078 -170.107356)
		(end 18.785078 -168.158922)
		(width 0.1143)
		(layer "F.Cu")
		(net "SAS_HDD_LED11")
	)
	(segment
		(start 20.193 -166.751)
		(end 22.606 -164.338)
		(width 0.1143)
		(layer "F.Cu")
		(net "SAS_HDD_LED11")
	)
	(segment
		(start 109.860842 -81.097882)
		(end 109.479842 -80.716882)
		(width 0.1143)
		(layer "F.Cu")
		(net "SAS_HDD_LED11")
	)
	(segment
		(start 22.606 -164.338)
		(end 22.606 -161.736024)
		(width 0.1143)
		(layer "F.Cu")
		(net "SAS_HDD_LED11")
	)
	(segment
		(start 22.606 -161.736024)
		(end 34.671 -149.671024)
		(width 0.1143)
		(layer "F.Cu")
		(net "SAS_HDD_LED11")
	)
	(segment
		(start 110.349792 -83.349846)
		(end 110.349792 -83.110832)
		(width 0.1143)
		(layer "F.Cu")
		(net "SAS_HDD_LED11")
	)
	(segment
		(start 18.785078 -168.158922)
		(end 20.193 -166.751)
		(width 0.1143)
		(layer "F.Cu")
		(net "SAS_HDD_LED11")
	)
	(via
		(at 34.671 -147.447)
		(size 0.5588)
		(drill 0.3048)
		(layers "F.Cu" "B.Cu")
		(net "SAS_HDD_LED11")
	)
	(via
		(at 109.479842 -80.589882)
		(size 0.508)
		(drill 0.254)
		(layers "F.Cu" "B.Cu")
		(net "SAS_HDD_LED11")
	)
	(via
		(at 20.193 -166.751)
		(size 0.7112)
		(drill 0.3556)
		(layers "F.Cu" "B.Cu")
		(net "SAS_HDD_LED11")
	)
	(segment
		(start 36.322508 -147.447)
		(end 34.671 -147.447)
		(width 0.127)
		(layer "In5.Cu")
		(net "SAS_HDD_LED11")
	)
	(segment
		(start 109.164882 -80.589882)
		(end 106.9975 -78.4225)
		(width 0.127)
		(layer "In5.Cu")
		(net "SAS_HDD_LED11")
	)
	(segment
		(start 47.879 -130.81)
		(end 45.974 -132.715)
		(width 0.127)
		(layer "In5.Cu")
		(net "SAS_HDD_LED11")
	)
	(segment
		(start 99.822 -78.4225)
		(end 47.879 -130.3655)
		(width 0.127)
		(layer "In5.Cu")
		(net "SAS_HDD_LED11")
	)
	(segment
		(start 45.974 -137.795508)
		(end 36.322508 -147.447)
		(width 0.127)
		(layer "In5.Cu")
		(net "SAS_HDD_LED11")
	)
	(segment
		(start 106.9975 -78.4225)
		(end 99.822 -78.4225)
		(width 0.127)
		(layer "In5.Cu")
		(net "SAS_HDD_LED11")
	)
	(segment
		(start 45.974 -132.715)
		(end 45.974 -137.795508)
		(width 0.127)
		(layer "In5.Cu")
		(net "SAS_HDD_LED11")
	)
	(segment
		(start 47.879 -130.3655)
		(end 47.879 -130.81)
		(width 0.127)
		(layer "In5.Cu")
		(net "SAS_HDD_LED11")
	)
	(segment
		(start 109.479842 -80.589882)
		(end 109.164882 -80.589882)
		(width 0.127)
		(layer "In5.Cu")
		(net "SAS_HDD_LED11")
	)
	(segment
		(start 108.349796 -96.350074)
		(end 107.84967 -96.8502)
		(width 0.1143)
		(layer "F.Cu")
		(net "EXP_GPIO_9")
	)
	(segment
		(start 83.74253 -133.272276)
		(end 83.944714 -133.47446)
		(width 0.1143)
		(layer "F.Cu")
		(net "EXP_GPIO_9")
	)
	(segment
		(start 83.74253 -131.5466)
		(end 83.74253 -133.272276)
		(width 0.1143)
		(layer "F.Cu")
		(net "EXP_GPIO_9")
	)
	(via
		(at 107.84967 -96.8502)
		(size 0.508)
		(drill 0.254)
		(layers "F.Cu" "B.Cu")
		(net "EXP_GPIO_9")
	)
	(via
		(at 83.944714 -133.47446)
		(size 0.5588)
		(drill 0.3048)
		(layers "F.Cu" "B.Cu")
		(net "EXP_GPIO_9")
	)
	(via
		(at 98.429826 -96.36125)
		(size 0.7112)
		(drill 0.3556)
		(layers "F.Cu" "B.Cu")
		(net "EXP_GPIO_9")
	)
	(segment
		(start 98.429826 -96.36125)
		(end 101.13772 -96.36125)
		(width 0.1143)
		(layer "B.Cu")
		(net "EXP_GPIO_9")
	)
	(segment
		(start 106.02087 -96.43745)
		(end 106.32821 -96.74479)
		(width 0.1143)
		(layer "B.Cu")
		(net "EXP_GPIO_9")
	)
	(segment
		(start 106.32821 -97.18421)
		(end 106.553 -97.409)
		(width 0.1143)
		(layer "B.Cu")
		(net "EXP_GPIO_9")
	)
	(segment
		(start 102.50297 -95.437452)
		(end 105.020872 -95.437452)
		(width 0.1143)
		(layer "B.Cu")
		(net "EXP_GPIO_9")
	)
	(segment
		(start 107.442 -97.155)
		(end 107.54487 -97.155)
		(width 0.1143)
		(layer "B.Cu")
		(net "EXP_GPIO_9")
	)
	(segment
		(start 105.262426 -95.679006)
		(end 105.262426 -95.8469)
		(width 0.1143)
		(layer "B.Cu")
		(net "EXP_GPIO_9")
	)
	(segment
		(start 98.057716 -96.36125)
		(end 84.594192 -109.824774)
		(width 0.1143)
		(layer "B.Cu")
		(net "EXP_GPIO_9")
	)
	(segment
		(start 105.852976 -96.43745)
		(end 106.02087 -96.43745)
		(width 0.1143)
		(layer "B.Cu")
		(net "EXP_GPIO_9")
	)
	(segment
		(start 105.020872 -95.437452)
		(end 105.262426 -95.679006)
		(width 0.1143)
		(layer "B.Cu")
		(net "EXP_GPIO_9")
	)
	(segment
		(start 98.429826 -96.36125)
		(end 98.057716 -96.36125)
		(width 0.1143)
		(layer "B.Cu")
		(net "EXP_GPIO_9")
	)
	(segment
		(start 107.54487 -97.155)
		(end 107.84967 -96.8502)
		(width 0.1143)
		(layer "B.Cu")
		(net "EXP_GPIO_9")
	)
	(segment
		(start 107.188 -97.409)
		(end 107.442 -97.155)
		(width 0.1143)
		(layer "B.Cu")
		(net "EXP_GPIO_9")
	)
	(segment
		(start 84.594192 -109.824774)
		(end 84.594192 -132.824982)
		(width 0.1143)
		(layer "B.Cu")
		(net "EXP_GPIO_9")
	)
	(segment
		(start 101.74732 -95.75165)
		(end 102.188772 -95.75165)
		(width 0.1143)
		(layer "B.Cu")
		(net "EXP_GPIO_9")
	)
	(segment
		(start 105.262426 -95.8469)
		(end 105.852976 -96.43745)
		(width 0.1143)
		(layer "B.Cu")
		(net "EXP_GPIO_9")
	)
	(segment
		(start 106.553 -97.409)
		(end 107.188 -97.409)
		(width 0.1143)
		(layer "B.Cu")
		(net "EXP_GPIO_9")
	)
	(segment
		(start 101.13772 -96.36125)
		(end 101.74732 -95.75165)
		(width 0.1143)
		(layer "B.Cu")
		(net "EXP_GPIO_9")
	)
	(segment
		(start 102.188772 -95.75165)
		(end 102.50297 -95.437452)
		(width 0.1143)
		(layer "B.Cu")
		(net "EXP_GPIO_9")
	)
	(segment
		(start 84.594192 -132.824982)
		(end 83.944714 -133.47446)
		(width 0.1143)
		(layer "B.Cu")
		(net "EXP_GPIO_9")
	)
	(segment
		(start 106.32821 -96.74479)
		(end 106.32821 -97.18421)
		(width 0.1143)
		(layer "B.Cu")
		(net "EXP_GPIO_9")
	)
	(segment
		(start 114.349784 -102.350062)
		(end 113.849658 -102.850188)
		(width 0.1016)
		(layer "F.Cu")
		(net "SAS_HDD_CONN_RX8_N")
	)
	(via
		(at 113.849658 -102.850188)
		(size 0.508)
		(drill 0.254)
		(layers "F.Cu" "B.Cu")
		(net "SAS_HDD_CONN_RX8_N")
	)
	(segment
		(start 115.189 -190.373)
		(end 115.189 -113.875058)
		(width 0.1016)
		(layer "B.Cu")
		(net "SAS_HDD_CONN_RX8_N")
	)
	(segment
		(start 109.150658 -197.990968)
		(end 109.169708 -197.971664)
		(width 0.1016)
		(layer "B.Cu")
		(net "SAS_HDD_CONN_RX8_N")
	)
	(segment
		(start 113.073942 -104.964738)
		(end 113.073942 -104.614472)
		(width 0.1016)
		(layer "B.Cu")
		(net "SAS_HDD_CONN_RX8_N")
	)
	(segment
		(start 114.805968 -113.299748)
		(end 114.13236 -112.626394)
		(width 0.1016)
		(layer "B.Cu")
		(net "SAS_HDD_CONN_RX8_N")
	)
	(segment
		(start 109.169708 -197.971664)
		(end 114.072162 -193.06921)
		(width 0.1016)
		(layer "B.Cu")
		(net "SAS_HDD_CONN_RX8_N")
	)
	(segment
		(start 115.05311 -113.54689)
		(end 114.805968 -113.299748)
		(width 0.1016)
		(layer "B.Cu")
		(net "SAS_HDD_CONN_RX8_N")
	)
	(segment
		(start 113.806986 -102.89286)
		(end 113.849658 -102.850188)
		(width 0.1016)
		(layer "B.Cu")
		(net "SAS_HDD_CONN_RX8_N")
	)
	(segment
		(start 113.459514 -103.578406)
		(end 113.677446 -103.192834)
		(width 0.1016)
		(layer "B.Cu")
		(net "SAS_HDD_CONN_RX8_N")
	)
	(segment
		(start 113.710974 -103.124254)
		(end 113.806986 -102.89286)
		(width 0.1016)
		(layer "B.Cu")
		(net "SAS_HDD_CONN_RX8_N")
	)
	(segment
		(start 108.681012 -204.34808)
		(end 108.681012 -199.125586)
		(width 0.1016)
		(layer "B.Cu")
		(net "SAS_HDD_CONN_RX8_N")
	)
	(segment
		(start 113.289842 -110.5916)
		(end 113.289842 -105.77576)
		(width 0.1016)
		(layer "B.Cu")
		(net "SAS_HDD_CONN_RX8_N")
	)
	(segment
		(start 113.289588 -110.5916)
		(end 113.289842 -110.5916)
		(width 0.1016)
		(layer "B.Cu")
		(net "SAS_HDD_CONN_RX8_N")
	)
	(arc
		(start 115.189 -113.875058)
		(mid 115.153676 -113.697471)
		(end 115.05311 -113.54689)
		(width 0.1016)
		(layer "B.Cu")
		(net "SAS_HDD_CONN_RX8_N")
	)
	(arc
		(start 113.677446 -103.192834)
		(mid 113.69524 -103.159048)
		(end 113.710974 -103.124254)
		(width 0.1016)
		(layer "B.Cu")
		(net "SAS_HDD_CONN_RX8_N")
	)
	(arc
		(start 113.073942 -104.614472)
		(mid 113.124823 -104.302851)
		(end 113.272316 -104.023668)
		(width 0.1016)
		(layer "B.Cu")
		(net "SAS_HDD_CONN_RX8_N")
	)
	(arc
		(start 113.208562 -105.460292)
		(mid 113.201097 -105.447394)
		(end 113.19383 -105.434384)
		(width 0.1016)
		(layer "B.Cu")
		(net "SAS_HDD_CONN_RX8_N")
	)
	(arc
		(start 108.450634 -205.059788)
		(mid 108.62204 -204.722125)
		(end 108.681012 -204.34808)
		(width 0.1016)
		(layer "B.Cu")
		(net "SAS_HDD_CONN_RX8_N")
	)
	(arc
		(start 114.072162 -193.06921)
		(mid 114.89872 -191.832178)
		(end 115.189 -190.373)
		(width 0.1016)
		(layer "B.Cu")
		(net "SAS_HDD_CONN_RX8_N")
	)
	(arc
		(start 113.272316 -104.023668)
		(mid 113.357988 -103.91111)
		(end 113.388394 -103.77297)
		(width 0.1016)
		(layer "B.Cu")
		(net "SAS_HDD_CONN_RX8_N")
	)
	(arc
		(start 108.681012 -199.125586)
		(mid 108.803107 -198.511615)
		(end 109.150658 -197.990968)
		(width 0.1016)
		(layer "B.Cu")
		(net "SAS_HDD_CONN_RX8_N")
	)
	(arc
		(start 113.388394 -103.77297)
		(mid 113.395326 -103.741021)
		(end 113.403888 -103.70947)
		(width 0.1016)
		(layer "B.Cu")
		(net "SAS_HDD_CONN_RX8_N")
	)
	(arc
		(start 114.13236 -112.626394)
		(mid 113.508568 -111.692823)
		(end 113.289588 -110.5916)
		(width 0.1016)
		(layer "B.Cu")
		(net "SAS_HDD_CONN_RX8_N")
	)
	(arc
		(start 113.403888 -103.70947)
		(mid 113.428021 -103.642376)
		(end 113.459514 -103.578406)
		(width 0.1016)
		(layer "B.Cu")
		(net "SAS_HDD_CONN_RX8_N")
	)
	(arc
		(start 108.020612 -205.4225)
		(mid 108.257835 -205.267479)
		(end 108.450634 -205.059788)
		(width 0.1016)
		(layer "B.Cu")
		(net "SAS_HDD_CONN_RX8_N")
	)
	(arc
		(start 113.289842 -105.77576)
		(mid 113.269194 -105.612876)
		(end 113.208562 -105.460292)
		(width 0.1016)
		(layer "B.Cu")
		(net "SAS_HDD_CONN_RX8_N")
	)
	(arc
		(start 113.19383 -105.434384)
		(mid 113.104376 -105.207099)
		(end 113.073942 -104.964738)
		(width 0.1016)
		(layer "B.Cu")
		(net "SAS_HDD_CONN_RX8_N")
	)
	(segment
		(start 287.64103 -168.636696)
		(end 287.635442 -168.631108)
		(width 0.1143)
		(layer "F.Cu")
		(net "BMC_EN_0V955_R")
	)
	(segment
		(start 287.64103 -168.646094)
		(end 287.64103 -168.636696)
		(width 0.1143)
		(layer "F.Cu")
		(net "BMC_EN_0V955_R")
	)
	(segment
		(start 288.034984 -169.040048)
		(end 287.64103 -168.646094)
		(width 0.1143)
		(layer "F.Cu")
		(net "BMC_EN_0V955_R")
	)
	(via
		(at 283.21 -165.1)
		(size 0.7112)
		(drill 0.3556)
		(layers "F.Cu" "B.Cu")
		(net "BMC_EN_0V955_R")
	)
	(via
		(at 287.635442 -168.631108)
		(size 0.508)
		(drill 0.254)
		(layers "F.Cu" "B.Cu")
		(net "BMC_EN_0V955_R")
	)
	(segment
		(start 287.528508 -168.631108)
		(end 284.24632 -165.34892)
		(width 0.1143)
		(layer "B.Cu")
		(net "BMC_EN_0V955_R")
	)
	(segment
		(start 284.24632 -165.34892)
		(end 283.45892 -165.34892)
		(width 0.1143)
		(layer "B.Cu")
		(net "BMC_EN_0V955_R")
	)
	(segment
		(start 283.45892 -165.34892)
		(end 283.21 -165.1)
		(width 0.1143)
		(layer "B.Cu")
		(net "BMC_EN_0V955_R")
	)
	(segment
		(start 287.635442 -168.631108)
		(end 287.528508 -168.631108)
		(width 0.1143)
		(layer "B.Cu")
		(net "BMC_EN_0V955_R")
	)
	(segment
		(start 278.13 -160.02)
		(end 276.7965 -160.02)
		(width 0.1143)
		(layer "B.Cu")
		(net "BMC_EN_0V955_R")
	)
	(segment
		(start 283.21 -165.1)
		(end 278.13 -160.02)
		(width 0.1143)
		(layer "B.Cu")
		(net "BMC_EN_0V955_R")
	)
	(segment
		(start 87.14867 -135.3693)
		(end 87.54237 -135.763)
		(width 0.1143)
		(layer "F.Cu")
		(net "EXP_GPIO_7")
	)
	(segment
		(start 86.869016 -135.255)
		(end 86.983316 -135.3693)
		(width 0.1143)
		(layer "F.Cu")
		(net "EXP_GPIO_7")
	)
	(segment
		(start 83.34248 -133.563868)
		(end 85.033612 -135.255)
		(width 0.1143)
		(layer "F.Cu")
		(net "EXP_GPIO_7")
	)
	(segment
		(start 103.349806 -99.350068)
		(end 102.84968 -99.850194)
		(width 0.1143)
		(layer "F.Cu")
		(net "EXP_GPIO_7")
	)
	(segment
		(start 86.983316 -135.3693)
		(end 87.14867 -135.3693)
		(width 0.1143)
		(layer "F.Cu")
		(net "EXP_GPIO_7")
	)
	(segment
		(start 85.033612 -135.255)
		(end 86.869016 -135.255)
		(width 0.1143)
		(layer "F.Cu")
		(net "EXP_GPIO_7")
	)
	(segment
		(start 83.34248 -131.5466)
		(end 83.34248 -133.563868)
		(width 0.1143)
		(layer "F.Cu")
		(net "EXP_GPIO_7")
	)
	(via
		(at 89.640918 -112.6998)
		(size 0.7112)
		(drill 0.3556)
		(layers "F.Cu" "B.Cu")
		(net "EXP_GPIO_7")
	)
	(via
		(at 102.84968 -99.850194)
		(size 0.508)
		(drill 0.254)
		(layers "F.Cu" "B.Cu")
		(net "EXP_GPIO_7")
	)
	(via
		(at 87.54237 -135.763)
		(size 0.5588)
		(drill 0.3048)
		(layers "F.Cu" "B.Cu")
		(net "EXP_GPIO_7")
	)
	(segment
		(start 101.170232 -100.65004)
		(end 100.42652 -101.393752)
		(width 0.1143)
		(layer "B.Cu")
		(net "EXP_GPIO_7")
	)
	(segment
		(start 89.640918 -112.6998)
		(end 89.6366 -112.704118)
		(width 0.1143)
		(layer "B.Cu")
		(net "EXP_GPIO_7")
	)
	(segment
		(start 89.34196 -113.00841)
		(end 89.34196 -120.992392)
		(width 0.1143)
		(layer "B.Cu")
		(net "EXP_GPIO_7")
	)
	(segment
		(start 89.6366 -112.71377)
		(end 89.34196 -113.00841)
		(width 0.1143)
		(layer "B.Cu")
		(net "EXP_GPIO_7")
	)
	(segment
		(start 100.42652 -101.914198)
		(end 89.640918 -112.6998)
		(width 0.1143)
		(layer "B.Cu")
		(net "EXP_GPIO_7")
	)
	(segment
		(start 100.42652 -101.393752)
		(end 100.42652 -101.914198)
		(width 0.1143)
		(layer "B.Cu")
		(net "EXP_GPIO_7")
	)
	(segment
		(start 88.3031 -121.996454)
		(end 88.890602 -122.583956)
		(width 0.1143)
		(layer "B.Cu")
		(net "EXP_GPIO_7")
	)
	(segment
		(start 88.61552 -121.27865)
		(end 88.3031 -121.59107)
		(width 0.1143)
		(layer "B.Cu")
		(net "EXP_GPIO_7")
	)
	(segment
		(start 101.170232 -100.60432)
		(end 101.170232 -100.65004)
		(width 0.1143)
		(layer "B.Cu")
		(net "EXP_GPIO_7")
	)
	(segment
		(start 89.34196 -120.992392)
		(end 89.055702 -121.27865)
		(width 0.1143)
		(layer "B.Cu")
		(net "EXP_GPIO_7")
	)
	(segment
		(start 102.529132 -100.170742)
		(end 101.60381 -100.170742)
		(width 0.1143)
		(layer "B.Cu")
		(net "EXP_GPIO_7")
	)
	(segment
		(start 89.6366 -112.704118)
		(end 89.6366 -112.71377)
		(width 0.1143)
		(layer "B.Cu")
		(net "EXP_GPIO_7")
	)
	(segment
		(start 89.055702 -121.27865)
		(end 88.61552 -121.27865)
		(width 0.1143)
		(layer "B.Cu")
		(net "EXP_GPIO_7")
	)
	(segment
		(start 88.890602 -134.414768)
		(end 87.54237 -135.763)
		(width 0.1143)
		(layer "B.Cu")
		(net "EXP_GPIO_7")
	)
	(segment
		(start 88.890602 -122.583956)
		(end 88.890602 -134.414768)
		(width 0.1143)
		(layer "B.Cu")
		(net "EXP_GPIO_7")
	)
	(segment
		(start 88.3031 -121.59107)
		(end 88.3031 -121.996454)
		(width 0.1143)
		(layer "B.Cu")
		(net "EXP_GPIO_7")
	)
	(segment
		(start 102.84968 -99.850194)
		(end 102.529132 -100.170742)
		(width 0.1143)
		(layer "B.Cu")
		(net "EXP_GPIO_7")
	)
	(segment
		(start 101.60381 -100.170742)
		(end 101.170232 -100.60432)
		(width 0.1143)
		(layer "B.Cu")
		(net "EXP_GPIO_7")
	)
	(segment
		(start 111.23803 -32.476694)
		(end 111.23803 -32.298386)
		(width 0.1143)
		(layer "F.Cu")
		(net "IOC_GPIO_14")
	)
	(segment
		(start 111.181642 -33.828482)
		(end 111.181642 -33.24733)
		(width 0.1143)
		(layer "F.Cu")
		(net "IOC_GPIO_14")
	)
	(segment
		(start 111.18596 -33.243012)
		(end 111.18596 -32.528764)
		(width 0.1143)
		(layer "F.Cu")
		(net "IOC_GPIO_14")
	)
	(segment
		(start 111.549942 -34.196782)
		(end 111.181642 -33.828482)
		(width 0.1143)
		(layer "F.Cu")
		(net "IOC_GPIO_14")
	)
	(segment
		(start 111.18596 -32.528764)
		(end 111.23803 -32.476694)
		(width 0.1143)
		(layer "F.Cu")
		(net "IOC_GPIO_14")
	)
	(segment
		(start 111.181642 -33.24733)
		(end 111.18596 -33.243012)
		(width 0.1143)
		(layer "F.Cu")
		(net "IOC_GPIO_14")
	)
	(segment
		(start 111.549942 -34.19983)
		(end 111.549942 -34.196782)
		(width 0.1143)
		(layer "F.Cu")
		(net "IOC_GPIO_14")
	)
	(via
		(at 111.23803 -32.298386)
		(size 0.508)
		(drill 0.254)
		(layers "F.Cu" "B.Cu")
		(net "IOC_GPIO_14")
	)
	(segment
		(start 111.024416 -32.512)
		(end 111.23803 -32.298386)
		(width 0.1143)
		(layer "B.Cu")
		(net "IOC_GPIO_14")
	)
	(segment
		(start 110.50016 -32.512)
		(end 111.024416 -32.512)
		(width 0.1143)
		(layer "B.Cu")
		(net "IOC_GPIO_14")
	)
	(segment
		(start 274.6375 -166.624)
		(end 275.2217 -166.7002)
		(width 0.1143)
		(layer "F.Cu")
		(net "PWGD_P0V955_C_PG_R")
	)
	(segment
		(start 275.2217 -166.7002)
		(end 275.8948 -166.7002)
		(width 0.1143)
		(layer "F.Cu")
		(net "PWGD_P0V955_C_PG_R")
	)
	(segment
		(start 281.259026 -170.976798)
		(end 285.810452 -170.976798)
		(width 0.1143)
		(layer "F.Cu")
		(net "PWGD_P0V955_C_PG_R")
	)
	(segment
		(start 286.147002 -170.640248)
		(end 286.434784 -170.640248)
		(width 0.1143)
		(layer "F.Cu")
		(net "PWGD_P0V955_C_PG_R")
	)
	(segment
		(start 285.810452 -170.976798)
		(end 286.147002 -170.640248)
		(width 0.1143)
		(layer "F.Cu")
		(net "PWGD_P0V955_C_PG_R")
	)
	(segment
		(start 275.8948 -166.7002)
		(end 276.982428 -166.7002)
		(width 0.1143)
		(layer "F.Cu")
		(net "PWGD_P0V955_C_PG_R")
	)
	(segment
		(start 276.982428 -166.7002)
		(end 281.259026 -170.976798)
		(width 0.1143)
		(layer "F.Cu")
		(net "PWGD_P0V955_C_PG_R")
	)
	(via
		(at 275.8948 -166.7002)
		(size 0.7112)
		(drill 0.3556)
		(layers "F.Cu" "B.Cu")
		(net "PWGD_P0V955_C_PG_R")
	)
	(segment
		(start 275.463 -164.592)
		(end 276.098 -165.227)
		(width 0.1143)
		(layer "F.Cu")
		(net "PWGD_P0V9_E_PG_R")
	)
	(segment
		(start 281.707082 -169.566082)
		(end 281.752548 -169.611548)
		(width 0.1143)
		(layer "F.Cu")
		(net "PWGD_P0V9_E_PG_R")
	)
	(segment
		(start 286.147002 -169.040048)
		(end 286.434784 -169.040048)
		(width 0.1143)
		(layer "F.Cu")
		(net "PWGD_P0V9_E_PG_R")
	)
	(segment
		(start 284.684978 -169.477944)
		(end 285.709106 -169.477944)
		(width 0.1143)
		(layer "F.Cu")
		(net "PWGD_P0V9_E_PG_R")
	)
	(segment
		(start 285.709106 -169.477944)
		(end 286.147002 -169.040048)
		(width 0.1143)
		(layer "F.Cu")
		(net "PWGD_P0V9_E_PG_R")
	)
	(segment
		(start 274.6375 -164.592)
		(end 275.463 -164.592)
		(width 0.1143)
		(layer "F.Cu")
		(net "PWGD_P0V9_E_PG_R")
	)
	(segment
		(start 277.1902 -165.227)
		(end 277.364952 -165.227)
		(width 0.1143)
		(layer "F.Cu")
		(net "PWGD_P0V9_E_PG_R")
	)
	(segment
		(start 277.364952 -165.227)
		(end 281.704034 -169.566082)
		(width 0.1143)
		(layer "F.Cu")
		(net "PWGD_P0V9_E_PG_R")
	)
	(segment
		(start 284.551374 -169.611548)
		(end 284.684978 -169.477944)
		(width 0.1143)
		(layer "F.Cu")
		(net "PWGD_P0V9_E_PG_R")
	)
	(segment
		(start 276.098 -165.227)
		(end 277.1902 -165.227)
		(width 0.1143)
		(layer "F.Cu")
		(net "PWGD_P0V9_E_PG_R")
	)
	(segment
		(start 281.704034 -169.566082)
		(end 281.707082 -169.566082)
		(width 0.1143)
		(layer "F.Cu")
		(net "PWGD_P0V9_E_PG_R")
	)
	(segment
		(start 281.752548 -169.611548)
		(end 284.551374 -169.611548)
		(width 0.1143)
		(layer "F.Cu")
		(net "PWGD_P0V9_E_PG_R")
	)
	(via
		(at 277.1902 -165.227)
		(size 0.7112)
		(drill 0.3556)
		(layers "F.Cu" "B.Cu")
		(net "PWGD_P0V9_E_PG_R")
	)
	(segment
		(start 84.14258 -131.5466)
		(end 84.14258 -132.89661)
		(width 0.1143)
		(layer "F.Cu")
		(net "EXP_GPIO_10")
	)
	(segment
		(start 84.14258 -132.89661)
		(end 84.84997 -133.604)
		(width 0.1143)
		(layer "F.Cu")
		(net "EXP_GPIO_10")
	)
	(segment
		(start 106.3498 -97.350072)
		(end 105.849674 -97.850198)
		(width 0.1143)
		(layer "F.Cu")
		(net "EXP_GPIO_10")
	)
	(via
		(at 84.84997 -133.604)
		(size 0.5588)
		(drill 0.3048)
		(layers "F.Cu" "B.Cu")
		(net "EXP_GPIO_10")
	)
	(via
		(at 105.849674 -97.850198)
		(size 0.508)
		(drill 0.254)
		(layers "F.Cu" "B.Cu")
		(net "EXP_GPIO_10")
	)
	(via
		(at 85.56117 -116.5606)
		(size 0.7112)
		(drill 0.3556)
		(layers "F.Cu" "B.Cu")
		(net "EXP_GPIO_10")
	)
	(segment
		(start 103.238554 -97.536)
		(end 101.53777 -97.536)
		(width 0.1143)
		(layer "B.Cu")
		(net "EXP_GPIO_10")
	)
	(segment
		(start 105.849674 -97.850198)
		(end 105.433622 -97.850198)
		(width 0.1143)
		(layer "B.Cu")
		(net "EXP_GPIO_10")
	)
	(segment
		(start 84.962492 -133.491478)
		(end 84.962492 -117.159278)
		(width 0.1143)
		(layer "B.Cu")
		(net "EXP_GPIO_10")
	)
	(segment
		(start 97.42424 -98.306128)
		(end 97.113598 -98.306128)
		(width 0.1143)
		(layer "B.Cu")
		(net "EXP_GPIO_10")
	)
	(segment
		(start 100.367846 -96.9264)
		(end 98.413062 -96.9264)
		(width 0.1143)
		(layer "B.Cu")
		(net "EXP_GPIO_10")
	)
	(segment
		(start 103.578406 -97.196148)
		(end 103.238554 -97.536)
		(width 0.1143)
		(layer "B.Cu")
		(net "EXP_GPIO_10")
	)
	(segment
		(start 104.36225 -97.437448)
		(end 104.12095 -97.196148)
		(width 0.1143)
		(layer "B.Cu")
		(net "EXP_GPIO_10")
	)
	(segment
		(start 97.113598 -98.306128)
		(end 85.9282 -109.491526)
		(width 0.1143)
		(layer "B.Cu")
		(net "EXP_GPIO_10")
	)
	(segment
		(start 97.90176 -97.828354)
		(end 97.42424 -98.306128)
		(width 0.1143)
		(layer "B.Cu")
		(net "EXP_GPIO_10")
	)
	(segment
		(start 98.413062 -96.9264)
		(end 97.90176 -97.437702)
		(width 0.1143)
		(layer "B.Cu")
		(net "EXP_GPIO_10")
	)
	(segment
		(start 84.962492 -117.159278)
		(end 85.56117 -116.5606)
		(width 0.1143)
		(layer "B.Cu")
		(net "EXP_GPIO_10")
	)
	(segment
		(start 85.9282 -109.491526)
		(end 85.9282 -116.19357)
		(width 0.1143)
		(layer "B.Cu")
		(net "EXP_GPIO_10")
	)
	(segment
		(start 97.90176 -97.437702)
		(end 97.90176 -97.828354)
		(width 0.1143)
		(layer "B.Cu")
		(net "EXP_GPIO_10")
	)
	(segment
		(start 105.020872 -97.437448)
		(end 104.36225 -97.437448)
		(width 0.1143)
		(layer "B.Cu")
		(net "EXP_GPIO_10")
	)
	(segment
		(start 100.374196 -96.93275)
		(end 100.367846 -96.9264)
		(width 0.1143)
		(layer "B.Cu")
		(net "EXP_GPIO_10")
	)
	(segment
		(start 101.53777 -97.536)
		(end 100.93452 -96.93275)
		(width 0.1143)
		(layer "B.Cu")
		(net "EXP_GPIO_10")
	)
	(segment
		(start 104.12095 -97.196148)
		(end 103.578406 -97.196148)
		(width 0.1143)
		(layer "B.Cu")
		(net "EXP_GPIO_10")
	)
	(segment
		(start 100.93452 -96.93275)
		(end 100.374196 -96.93275)
		(width 0.1143)
		(layer "B.Cu")
		(net "EXP_GPIO_10")
	)
	(segment
		(start 85.9282 -116.19357)
		(end 85.56117 -116.5606)
		(width 0.1143)
		(layer "B.Cu")
		(net "EXP_GPIO_10")
	)
	(segment
		(start 105.433622 -97.850198)
		(end 105.020872 -97.437448)
		(width 0.1143)
		(layer "B.Cu")
		(net "EXP_GPIO_10")
	)
	(segment
		(start 84.84997 -133.604)
		(end 84.962492 -133.491478)
		(width 0.1143)
		(layer "B.Cu")
		(net "EXP_GPIO_10")
	)
	(segment
		(start 102.349808 -100.350066)
		(end 101.849682 -100.850192)
		(width 0.1143)
		(layer "F.Cu")
		(net "EXP_GPIO_11")
	)
	(segment
		(start 87.69477 -135.001)
		(end 88.45677 -135.763)
		(width 0.1143)
		(layer "F.Cu")
		(net "EXP_GPIO_11")
	)
	(segment
		(start 84.54136 -131.5466)
		(end 84.54136 -132.40639)
		(width 0.1143)
		(layer "F.Cu")
		(net "EXP_GPIO_11")
	)
	(segment
		(start 84.54136 -132.40639)
		(end 87.13597 -135.001)
		(width 0.1143)
		(layer "F.Cu")
		(net "EXP_GPIO_11")
	)
	(segment
		(start 87.13597 -135.001)
		(end 87.69477 -135.001)
		(width 0.1143)
		(layer "F.Cu")
		(net "EXP_GPIO_11")
	)
	(via
		(at 88.45677 -135.763)
		(size 0.5588)
		(drill 0.3048)
		(layers "F.Cu" "B.Cu")
		(net "EXP_GPIO_11")
	)
	(via
		(at 101.849682 -100.850192)
		(size 0.508)
		(drill 0.254)
		(layers "F.Cu" "B.Cu")
		(net "EXP_GPIO_11")
	)
	(via
		(at 93.345 -110.83417)
		(size 0.7112)
		(drill 0.3556)
		(layers "F.Cu" "B.Cu")
		(net "EXP_GPIO_11")
	)
	(segment
		(start 90.07856 -114.10061)
		(end 90.07856 -121.2977)
		(width 0.1143)
		(layer "B.Cu")
		(net "EXP_GPIO_11")
	)
	(segment
		(start 101.849682 -100.850192)
		(end 100.996496 -101.703378)
		(width 0.1143)
		(layer "B.Cu")
		(net "EXP_GPIO_11")
	)
	(segment
		(start 94.281498 -109.897672)
		(end 93.345 -110.83417)
		(width 0.1143)
		(layer "B.Cu")
		(net "EXP_GPIO_11")
	)
	(segment
		(start 100.687632 -102.694994)
		(end 94.281498 -109.101128)
		(width 0.1143)
		(layer "B.Cu")
		(net "EXP_GPIO_11")
	)
	(segment
		(start 100.996496 -101.703378)
		(end 100.996496 -102.059486)
		(width 0.1143)
		(layer "B.Cu")
		(net "EXP_GPIO_11")
	)
	(segment
		(start 100.996496 -102.059486)
		(end 100.687632 -102.36835)
		(width 0.1143)
		(layer "B.Cu")
		(net "EXP_GPIO_11")
	)
	(segment
		(start 89.92108 -134.29869)
		(end 88.45677 -135.763)
		(width 0.1143)
		(layer "B.Cu")
		(net "EXP_GPIO_11")
	)
	(segment
		(start 89.86012 -130.118104)
		(end 89.92108 -130.179064)
		(width 0.1143)
		(layer "B.Cu")
		(net "EXP_GPIO_11")
	)
	(segment
		(start 93.345 -110.83417)
		(end 90.07856 -114.10061)
		(width 0.1143)
		(layer "B.Cu")
		(net "EXP_GPIO_11")
	)
	(segment
		(start 89.86012 -121.51614)
		(end 89.86012 -130.118104)
		(width 0.1143)
		(layer "B.Cu")
		(net "EXP_GPIO_11")
	)
	(segment
		(start 100.687632 -102.36835)
		(end 100.687632 -102.694994)
		(width 0.1143)
		(layer "B.Cu")
		(net "EXP_GPIO_11")
	)
	(segment
		(start 90.07856 -121.2977)
		(end 89.86012 -121.51614)
		(width 0.1143)
		(layer "B.Cu")
		(net "EXP_GPIO_11")
	)
	(segment
		(start 94.281498 -109.101128)
		(end 94.281498 -109.897672)
		(width 0.1143)
		(layer "B.Cu")
		(net "EXP_GPIO_11")
	)
	(segment
		(start 89.92108 -130.179064)
		(end 89.92108 -134.29869)
		(width 0.1143)
		(layer "B.Cu")
		(net "EXP_GPIO_11")
	)
	(segment
		(start 115.345464 -103.35006)
		(end 114.864642 -103.830882)
		(width 0.1016)
		(layer "F.Cu")
		(net "SAS_HDD_CONN_RX7_P")
	)
	(segment
		(start 115.350036 -103.35006)
		(end 115.345464 -103.35006)
		(width 0.1016)
		(layer "F.Cu")
		(net "SAS_HDD_CONN_RX7_P")
	)
	(via
		(at 114.864642 -103.830882)
		(size 0.508)
		(drill 0.254)
		(layers "F.Cu" "B.Cu")
		(net "SAS_HDD_CONN_RX7_P")
	)
	(segment
		(start 117.861842 -181.845458)
		(end 117.861842 -176.932082)
		(width 0.1016)
		(layer "B.Cu")
		(net "SAS_HDD_CONN_RX7_P")
	)
	(segment
		(start 118.100602 -187.321698)
		(end 118.100602 -187.016898)
		(width 0.1016)
		(layer "B.Cu")
		(net "SAS_HDD_CONN_RX7_P")
	)
	(segment
		(start 116.885212 -204.4954)
		(end 116.885212 -198.166228)
		(width 0.1016)
		(layer "B.Cu")
		(net "SAS_HDD_CONN_RX7_P")
	)
	(segment
		(start 118.100602 -173.325282)
		(end 118.100602 -173.020482)
		(width 0.1016)
		(layer "B.Cu")
		(net "SAS_HDD_CONN_RX7_P")
	)
	(segment
		(start 117.861842 -183.410098)
		(end 117.861842 -183.105298)
		(width 0.1016)
		(layer "B.Cu")
		(net "SAS_HDD_CONN_RX7_P")
	)
	(segment
		(start 117.861842 -175.672242)
		(end 117.861842 -175.367442)
		(width 0.1016)
		(layer "B.Cu")
		(net "SAS_HDD_CONN_RX7_P")
	)
	(segment
		(start 118.100602 -184.192418)
		(end 118.100602 -183.887618)
		(width 0.1016)
		(layer "B.Cu")
		(net "SAS_HDD_CONN_RX7_P")
	)
	(segment
		(start 114.85499 -107.20578)
		(end 114.61877 -106.96956)
		(width 0.1016)
		(layer "B.Cu")
		(net "SAS_HDD_CONN_RX7_P")
	)
	(segment
		(start 114.432842 -106.520488)
		(end 114.432842 -105.663492)
		(width 0.1016)
		(layer "B.Cu")
		(net "SAS_HDD_CONN_RX7_P")
	)
	(segment
		(start 115.32997 -110.568994)
		(end 115.32997 -108.14558)
		(width 0.1016)
		(layer "B.Cu")
		(net "SAS_HDD_CONN_RX7_P")
	)
	(segment
		(start 117.559328 -113.916968)
		(end 116.12118 -112.47882)
		(width 0.1016)
		(layer "B.Cu")
		(net "SAS_HDD_CONN_RX7_P")
	)
	(segment
		(start 118.100602 -185.757058)
		(end 118.100602 -185.452258)
		(width 0.1016)
		(layer "B.Cu")
		(net "SAS_HDD_CONN_RX7_P")
	)
	(segment
		(start 117.861842 -172.542962)
		(end 117.861842 -114.64798)
		(width 0.1016)
		(layer "B.Cu")
		(net "SAS_HDD_CONN_RX7_P")
	)
	(segment
		(start 117.861842 -186.539378)
		(end 117.861842 -186.234578)
		(width 0.1016)
		(layer "B.Cu")
		(net "SAS_HDD_CONN_RX7_P")
	)
	(segment
		(start 118.100602 -176.454562)
		(end 118.100602 -176.149762)
		(width 0.1016)
		(layer "B.Cu")
		(net "SAS_HDD_CONN_RX7_P")
	)
	(segment
		(start 117.861842 -195.834)
		(end 117.861842 -187.799218)
		(width 0.1016)
		(layer "B.Cu")
		(net "SAS_HDD_CONN_RX7_P")
	)
	(segment
		(start 115.001802 -107.352846)
		(end 114.85499 -107.20578)
		(width 0.1016)
		(layer "B.Cu")
		(net "SAS_HDD_CONN_RX7_P")
	)
	(segment
		(start 117.374162 -196.98589)
		(end 117.39245 -196.967602)
		(width 0.1016)
		(layer "B.Cu")
		(net "SAS_HDD_CONN_RX7_P")
	)
	(segment
		(start 117.861842 -174.107602)
		(end 117.861842 -173.802802)
		(width 0.1016)
		(layer "B.Cu")
		(net "SAS_HDD_CONN_RX7_P")
	)
	(segment
		(start 114.610642 -105.01884)
		(end 114.610642 -104.444038)
		(width 0.1016)
		(layer "B.Cu")
		(net "SAS_HDD_CONN_RX7_P")
	)
	(segment
		(start 117.861842 -184.974738)
		(end 117.861842 -184.669938)
		(width 0.1016)
		(layer "B.Cu")
		(net "SAS_HDD_CONN_RX7_P")
	)
	(segment
		(start 118.100602 -174.889922)
		(end 118.100602 -174.585122)
		(width 0.1016)
		(layer "B.Cu")
		(net "SAS_HDD_CONN_RX7_P")
	)
	(segment
		(start 118.100602 -182.627778)
		(end 118.100602 -182.322978)
		(width 0.1016)
		(layer "B.Cu")
		(net "SAS_HDD_CONN_RX7_P")
	)
	(arc
		(start 114.476276 -105.47985)
		(mid 114.525434 -105.391624)
		(end 114.563906 -105.29824)
		(width 0.1016)
		(layer "B.Cu")
		(net "SAS_HDD_CONN_RX7_P")
	)
	(arc
		(start 117.981222 -175.128682)
		(mid 118.070016 -175.023868)
		(end 118.100602 -174.889922)
		(width 0.1016)
		(layer "B.Cu")
		(net "SAS_HDD_CONN_RX7_P")
	)
	(arc
		(start 117.861842 -186.234578)
		(mid 117.892334 -186.100585)
		(end 117.981222 -185.995818)
		(width 0.1016)
		(layer "B.Cu")
		(net "SAS_HDD_CONN_RX7_P")
	)
	(arc
		(start 118.100602 -185.452258)
		(mid 118.07011 -185.318265)
		(end 117.981222 -185.213498)
		(width 0.1016)
		(layer "B.Cu")
		(net "SAS_HDD_CONN_RX7_P")
	)
	(arc
		(start 115.32997 -108.14558)
		(mid 115.244729 -107.716576)
		(end 115.001802 -107.352846)
		(width 0.1016)
		(layer "B.Cu")
		(net "SAS_HDD_CONN_RX7_P")
	)
	(arc
		(start 117.981222 -173.564042)
		(mid 118.070016 -173.459228)
		(end 118.100602 -173.325282)
		(width 0.1016)
		(layer "B.Cu")
		(net "SAS_HDD_CONN_RX7_P")
	)
	(arc
		(start 114.563906 -105.29824)
		(mid 114.580751 -105.243243)
		(end 114.593878 -105.187242)
		(width 0.1016)
		(layer "B.Cu")
		(net "SAS_HDD_CONN_RX7_P")
	)
	(arc
		(start 117.981222 -185.213498)
		(mid 117.892428 -185.108684)
		(end 117.861842 -184.974738)
		(width 0.1016)
		(layer "B.Cu")
		(net "SAS_HDD_CONN_RX7_P")
	)
	(arc
		(start 116.885212 -198.166228)
		(mid 117.012279 -197.527419)
		(end 117.374162 -196.98589)
		(width 0.1016)
		(layer "B.Cu")
		(net "SAS_HDD_CONN_RX7_P")
	)
	(arc
		(start 118.100602 -176.149762)
		(mid 118.07011 -176.015769)
		(end 117.981222 -175.911002)
		(width 0.1016)
		(layer "B.Cu")
		(net "SAS_HDD_CONN_RX7_P")
	)
	(arc
		(start 118.100602 -187.016898)
		(mid 118.07011 -186.882905)
		(end 117.981222 -186.778138)
		(width 0.1016)
		(layer "B.Cu")
		(net "SAS_HDD_CONN_RX7_P")
	)
	(arc
		(start 117.981222 -183.648858)
		(mid 117.892428 -183.544044)
		(end 117.861842 -183.410098)
		(width 0.1016)
		(layer "B.Cu")
		(net "SAS_HDD_CONN_RX7_P")
	)
	(arc
		(start 117.981222 -186.778138)
		(mid 117.892428 -186.673324)
		(end 117.861842 -186.539378)
		(width 0.1016)
		(layer "B.Cu")
		(net "SAS_HDD_CONN_RX7_P")
	)
	(arc
		(start 117.981222 -182.084218)
		(mid 117.892428 -181.979404)
		(end 117.861842 -181.845458)
		(width 0.1016)
		(layer "B.Cu")
		(net "SAS_HDD_CONN_RX7_P")
	)
	(arc
		(start 116.948966 -204.981302)
		(mid 116.901235 -204.740432)
		(end 116.885212 -204.4954)
		(width 0.1016)
		(layer "B.Cu")
		(net "SAS_HDD_CONN_RX7_P")
	)
	(arc
		(start 117.861842 -184.669938)
		(mid 117.892334 -184.535945)
		(end 117.981222 -184.431178)
		(width 0.1016)
		(layer "B.Cu")
		(net "SAS_HDD_CONN_RX7_P")
	)
	(arc
		(start 117.981222 -172.781722)
		(mid 117.892428 -172.676908)
		(end 117.861842 -172.542962)
		(width 0.1016)
		(layer "B.Cu")
		(net "SAS_HDD_CONN_RX7_P")
	)
	(arc
		(start 118.100602 -174.585122)
		(mid 118.07011 -174.451129)
		(end 117.981222 -174.346362)
		(width 0.1016)
		(layer "B.Cu")
		(net "SAS_HDD_CONN_RX7_P")
	)
	(arc
		(start 117.39245 -196.967602)
		(mid 117.739887 -196.447486)
		(end 117.861842 -195.834)
		(width 0.1016)
		(layer "B.Cu")
		(net "SAS_HDD_CONN_RX7_P")
	)
	(arc
		(start 117.545612 -205.4225)
		(mid 117.224144 -205.337592)
		(end 116.986558 -205.105)
		(width 0.1016)
		(layer "B.Cu")
		(net "SAS_HDD_CONN_RX7_P")
	)
	(arc
		(start 117.861842 -175.367442)
		(mid 117.892334 -175.233449)
		(end 117.981222 -175.128682)
		(width 0.1016)
		(layer "B.Cu")
		(net "SAS_HDD_CONN_RX7_P")
	)
	(arc
		(start 118.100602 -173.020482)
		(mid 118.07011 -172.886489)
		(end 117.981222 -172.781722)
		(width 0.1016)
		(layer "B.Cu")
		(net "SAS_HDD_CONN_RX7_P")
	)
	(arc
		(start 116.986558 -205.105)
		(mid 116.966701 -205.043473)
		(end 116.948966 -204.981302)
		(width 0.1016)
		(layer "B.Cu")
		(net "SAS_HDD_CONN_RX7_P")
	)
	(arc
		(start 117.861842 -114.64798)
		(mid 117.78332 -114.252374)
		(end 117.559328 -113.916968)
		(width 0.1016)
		(layer "B.Cu")
		(net "SAS_HDD_CONN_RX7_P")
	)
	(arc
		(start 117.861842 -176.932082)
		(mid 117.892334 -176.798089)
		(end 117.981222 -176.693322)
		(width 0.1016)
		(layer "B.Cu")
		(net "SAS_HDD_CONN_RX7_P")
	)
	(arc
		(start 117.981222 -182.866538)
		(mid 118.070016 -182.761724)
		(end 118.100602 -182.627778)
		(width 0.1016)
		(layer "B.Cu")
		(net "SAS_HDD_CONN_RX7_P")
	)
	(arc
		(start 117.861842 -187.799218)
		(mid 117.892334 -187.665225)
		(end 117.981222 -187.560458)
		(width 0.1016)
		(layer "B.Cu")
		(net "SAS_HDD_CONN_RX7_P")
	)
	(arc
		(start 114.610642 -104.444038)
		(mid 114.67665 -104.112192)
		(end 114.864642 -103.830882)
		(width 0.1016)
		(layer "B.Cu")
		(net "SAS_HDD_CONN_RX7_P")
	)
	(arc
		(start 117.981222 -174.346362)
		(mid 117.892428 -174.241548)
		(end 117.861842 -174.107602)
		(width 0.1016)
		(layer "B.Cu")
		(net "SAS_HDD_CONN_RX7_P")
	)
	(arc
		(start 117.981222 -175.911002)
		(mid 117.892428 -175.806188)
		(end 117.861842 -175.672242)
		(width 0.1016)
		(layer "B.Cu")
		(net "SAS_HDD_CONN_RX7_P")
	)
	(arc
		(start 117.981222 -187.560458)
		(mid 118.070016 -187.455644)
		(end 118.100602 -187.321698)
		(width 0.1016)
		(layer "B.Cu")
		(net "SAS_HDD_CONN_RX7_P")
	)
	(arc
		(start 116.12118 -112.47882)
		(mid 115.535615 -111.602599)
		(end 115.32997 -110.568994)
		(width 0.1016)
		(layer "B.Cu")
		(net "SAS_HDD_CONN_RX7_P")
	)
	(arc
		(start 117.981222 -184.431178)
		(mid 118.070016 -184.326364)
		(end 118.100602 -184.192418)
		(width 0.1016)
		(layer "B.Cu")
		(net "SAS_HDD_CONN_RX7_P")
	)
	(arc
		(start 118.100602 -182.322978)
		(mid 118.07011 -182.188985)
		(end 117.981222 -182.084218)
		(width 0.1016)
		(layer "B.Cu")
		(net "SAS_HDD_CONN_RX7_P")
	)
	(arc
		(start 114.61877 -106.96956)
		(mid 114.481155 -106.76351)
		(end 114.432842 -106.520488)
		(width 0.1016)
		(layer "B.Cu")
		(net "SAS_HDD_CONN_RX7_P")
	)
	(arc
		(start 117.981222 -176.693322)
		(mid 118.070016 -176.588508)
		(end 118.100602 -176.454562)
		(width 0.1016)
		(layer "B.Cu")
		(net "SAS_HDD_CONN_RX7_P")
	)
	(arc
		(start 114.593878 -105.187242)
		(mid 114.60641 -105.103455)
		(end 114.610642 -105.01884)
		(width 0.1016)
		(layer "B.Cu")
		(net "SAS_HDD_CONN_RX7_P")
	)
	(arc
		(start 117.861842 -183.105298)
		(mid 117.892334 -182.971305)
		(end 117.981222 -182.866538)
		(width 0.1016)
		(layer "B.Cu")
		(net "SAS_HDD_CONN_RX7_P")
	)
	(arc
		(start 114.432842 -105.663492)
		(mid 114.443848 -105.569138)
		(end 114.476276 -105.47985)
		(width 0.1016)
		(layer "B.Cu")
		(net "SAS_HDD_CONN_RX7_P")
	)
	(arc
		(start 118.100602 -183.887618)
		(mid 118.07011 -183.753625)
		(end 117.981222 -183.648858)
		(width 0.1016)
		(layer "B.Cu")
		(net "SAS_HDD_CONN_RX7_P")
	)
	(arc
		(start 117.981222 -185.995818)
		(mid 118.070016 -185.891004)
		(end 118.100602 -185.757058)
		(width 0.1016)
		(layer "B.Cu")
		(net "SAS_HDD_CONN_RX7_P")
	)
	(arc
		(start 117.861842 -173.802802)
		(mid 117.892334 -173.668809)
		(end 117.981222 -173.564042)
		(width 0.1016)
		(layer "B.Cu")
		(net "SAS_HDD_CONN_RX7_P")
	)
	(segment
		(start 112.350042 -40.599868)
		(end 112.350042 -40.595804)
		(width 0.1143)
		(layer "F.Cu")
		(net "IOC_GPIO_36")
	)
	(segment
		(start 112.350042 -40.595804)
		(end 112.743234 -40.202612)
		(width 0.1143)
		(layer "F.Cu")
		(net "IOC_GPIO_36")
	)
	(via
		(at 112.743234 -40.202612)
		(size 0.508)
		(drill 0.254)
		(layers "F.Cu" "B.Cu")
		(net "IOC_GPIO_36")
	)
	(segment
		(start 113.570766 -39.878)
		(end 113.065306 -39.88054)
		(width 0.1143)
		(layer "B.Cu")
		(net "IOC_GPIO_36")
	)
	(segment
		(start 113.065306 -39.88054)
		(end 112.743234 -40.202612)
		(width 0.1143)
		(layer "B.Cu")
		(net "IOC_GPIO_36")
	)
	(segment
		(start 83.34248 -137.1854)
		(end 83.34248 -139.08151)
		(width 0.1143)
		(layer "F.Cu")
		(net "FAN_PWM_PCIE_R")
	)
	(segment
		(start 83.57997 -140.3985)
		(end 83.57997 -139.319)
		(width 0.1143)
		(layer "F.Cu")
		(net "FAN_PWM_PCIE_R")
	)
	(segment
		(start 83.34248 -139.08151)
		(end 83.57997 -139.319)
		(width 0.1143)
		(layer "F.Cu")
		(net "FAN_PWM_PCIE_R")
	)
	(via
		(at 83.57997 -139.319)
		(size 0.7112)
		(drill 0.3556)
		(layers "F.Cu" "B.Cu")
		(net "FAN_PWM_PCIE_R")
	)
	(segment
		(start 104.349804 -100.350066)
		(end 103.849678 -100.850192)
		(width 0.1143)
		(layer "F.Cu")
		(net "EXP_GPIO_1")
	)
	(segment
		(start 89.525602 -128.420368)
		(end 90.43797 -127.508)
		(width 0.1143)
		(layer "F.Cu")
		(net "EXP_GPIO_1")
	)
	(segment
		(start 89.525602 -131.570476)
		(end 89.525602 -128.420368)
		(width 0.1143)
		(layer "F.Cu")
		(net "EXP_GPIO_1")
	)
	(via
		(at 91.30157 -113.8682)
		(size 0.7112)
		(drill 0.3556)
		(layers "F.Cu" "B.Cu")
		(net "EXP_GPIO_1")
	)
	(via
		(at 90.43797 -127.508)
		(size 0.508)
		(drill 0.254)
		(layers "F.Cu" "B.Cu")
		(net "EXP_GPIO_1")
	)
	(via
		(at 103.849678 -100.850192)
		(size 0.508)
		(drill 0.254)
		(layers "F.Cu" "B.Cu")
		(net "EXP_GPIO_1")
	)
	(segment
		(start 90.50782 -114.66195)
		(end 91.30157 -113.8682)
		(width 0.1143)
		(layer "B.Cu")
		(net "EXP_GPIO_1")
	)
	(segment
		(start 95.06077 -110.109)
		(end 95.06077 -108.84281)
		(width 0.1143)
		(layer "B.Cu")
		(net "EXP_GPIO_1")
	)
	(segment
		(start 91.30157 -113.8682)
		(end 95.06077 -110.109)
		(width 0.1143)
		(layer "B.Cu")
		(net "EXP_GPIO_1")
	)
	(segment
		(start 100.928932 -102.974648)
		(end 100.928932 -102.468426)
		(width 0.1143)
		(layer "B.Cu")
		(net "EXP_GPIO_1")
	)
	(segment
		(start 101.827584 -101.288342)
		(end 103.322374 -101.288342)
		(width 0.1143)
		(layer "B.Cu")
		(net "EXP_GPIO_1")
	)
	(segment
		(start 101.237796 -101.87813)
		(end 101.827584 -101.288342)
		(width 0.1143)
		(layer "B.Cu")
		(net "EXP_GPIO_1")
	)
	(segment
		(start 103.761032 -100.850192)
		(end 103.849678 -100.850192)
		(width 0.1143)
		(layer "B.Cu")
		(net "EXP_GPIO_1")
	)
	(segment
		(start 90.43797 -127.508)
		(end 90.50782 -127.43815)
		(width 0.1143)
		(layer "B.Cu")
		(net "EXP_GPIO_1")
	)
	(segment
		(start 101.237796 -102.159562)
		(end 101.237796 -101.87813)
		(width 0.1143)
		(layer "B.Cu")
		(net "EXP_GPIO_1")
	)
	(segment
		(start 95.06077 -108.84281)
		(end 100.928932 -102.974648)
		(width 0.1143)
		(layer "B.Cu")
		(net "EXP_GPIO_1")
	)
	(segment
		(start 100.928932 -102.468426)
		(end 101.237796 -102.159562)
		(width 0.1143)
		(layer "B.Cu")
		(net "EXP_GPIO_1")
	)
	(segment
		(start 103.322374 -101.288342)
		(end 103.761032 -100.850192)
		(width 0.1143)
		(layer "B.Cu")
		(net "EXP_GPIO_1")
	)
	(segment
		(start 90.50782 -127.43815)
		(end 90.50782 -114.66195)
		(width 0.1143)
		(layer "B.Cu")
		(net "EXP_GPIO_1")
	)
	(segment
		(start 89.63533 -48.03394)
		(end 89.339674 -48.329596)
		(width 0.1143)
		(layer "F.Cu")
		(net "SIO_CLK_0")
	)
	(segment
		(start 90.08872 -47.800006)
		(end 89.854786 -48.03394)
		(width 0.1143)
		(layer "F.Cu")
		(net "SIO_CLK_0")
	)
	(segment
		(start 90.750136 -47.800006)
		(end 90.08872 -47.800006)
		(width 0.1143)
		(layer "F.Cu")
		(net "SIO_CLK_0")
	)
	(segment
		(start 89.854786 -48.03394)
		(end 89.63533 -48.03394)
		(width 0.1143)
		(layer "F.Cu")
		(net "SIO_CLK_0")
	)
	(via
		(at 89.339674 -48.329596)
		(size 0.508)
		(drill 0.254)
		(layers "F.Cu" "B.Cu")
		(net "SIO_CLK_0")
	)
	(segment
		(start 86.56066 -49.022)
		(end 87.77986 -47.8028)
		(width 0.1143)
		(layer "B.Cu")
		(net "SIO_CLK_0")
	)
	(segment
		(start 88.812878 -47.8028)
		(end 89.339674 -48.329596)
		(width 0.1143)
		(layer "B.Cu")
		(net "SIO_CLK_0")
	)
	(segment
		(start 87.916766 -47.8028)
		(end 88.812878 -47.8028)
		(width 0.1143)
		(layer "B.Cu")
		(net "SIO_CLK_0")
	)
	(segment
		(start 87.77986 -47.8028)
		(end 87.916766 -47.8028)
		(width 0.1143)
		(layer "B.Cu")
		(net "SIO_CLK_0")
	)
	(segment
		(start 106.31805 -81.56194)
		(end 106.31805 -81.561686)
		(width 0.1143)
		(layer "F.Cu")
		(net "SAS_HDD_LED1")
	)
	(segment
		(start 26.824178 -163.167822)
		(end 28.448 -161.544)
		(width 0.1143)
		(layer "F.Cu")
		(net "SAS_HDD_LED1")
	)
	(segment
		(start 106.3498 -82.349848)
		(end 106.3498 -81.59369)
		(width 0.1143)
		(layer "F.Cu")
		(net "SAS_HDD_LED1")
	)
	(segment
		(start 39.8526 -150.1394)
		(end 39.8526 -148.971)
		(width 0.1143)
		(layer "F.Cu")
		(net "SAS_HDD_LED1")
	)
	(segment
		(start 106.076242 -81.320132)
		(end 105.787698 -81.031588)
		(width 0.1143)
		(layer "F.Cu")
		(net "SAS_HDD_LED1")
	)
	(segment
		(start 26.824178 -170.107356)
		(end 26.824178 -163.167822)
		(width 0.1143)
		(layer "F.Cu")
		(net "SAS_HDD_LED1")
	)
	(segment
		(start 106.076496 -81.320132)
		(end 106.076242 -81.320132)
		(width 0.1143)
		(layer "F.Cu")
		(net "SAS_HDD_LED1")
	)
	(segment
		(start 105.787698 -81.031588)
		(end 105.786428 -81.031588)
		(width 0.1143)
		(layer "F.Cu")
		(net "SAS_HDD_LED1")
	)
	(segment
		(start 28.448 -161.544)
		(end 39.8526 -150.1394)
		(width 0.1143)
		(layer "F.Cu")
		(net "SAS_HDD_LED1")
	)
	(segment
		(start 106.31805 -81.561686)
		(end 106.076496 -81.320132)
		(width 0.1143)
		(layer "F.Cu")
		(net "SAS_HDD_LED1")
	)
	(segment
		(start 106.3498 -81.59369)
		(end 106.31805 -81.56194)
		(width 0.1143)
		(layer "F.Cu")
		(net "SAS_HDD_LED1")
	)
	(via
		(at 105.786428 -81.031588)
		(size 0.508)
		(drill 0.254)
		(layers "F.Cu" "B.Cu")
		(net "SAS_HDD_LED1")
	)
	(via
		(at 39.8526 -148.971)
		(size 0.5588)
		(drill 0.3048)
		(layers "F.Cu" "B.Cu")
		(net "SAS_HDD_LED1")
	)
	(via
		(at 28.448 -161.544)
		(size 0.7112)
		(drill 0.3556)
		(layers "F.Cu" "B.Cu")
		(net "SAS_HDD_LED1")
	)
	(segment
		(start 103.760016 -83.058)
		(end 105.786428 -81.031588)
		(width 0.127)
		(layer "In5.Cu")
		(net "SAS_HDD_LED1")
	)
	(segment
		(start 100.509324 -83.058)
		(end 103.760016 -83.058)
		(width 0.127)
		(layer "In5.Cu")
		(net "SAS_HDD_LED1")
	)
	(segment
		(start 50.546 -132.63245)
		(end 94.02445 -89.154)
		(width 0.127)
		(layer "In5.Cu")
		(net "SAS_HDD_LED1")
	)
	(segment
		(start 94.72549 -89.154)
		(end 95.377 -88.50249)
		(width 0.127)
		(layer "In5.Cu")
		(net "SAS_HDD_LED1")
	)
	(segment
		(start 43.003216 -148.336)
		(end 43.688 -147.651216)
		(width 0.127)
		(layer "In5.Cu")
		(net "SAS_HDD_LED1")
	)
	(segment
		(start 95.377 -88.50249)
		(end 95.377 -88.060276)
		(width 0.127)
		(layer "In5.Cu")
		(net "SAS_HDD_LED1")
	)
	(segment
		(start 95.377 -88.060276)
		(end 99.777296 -83.65998)
		(width 0.127)
		(layer "In5.Cu")
		(net "SAS_HDD_LED1")
	)
	(segment
		(start 42.559732 -148.336)
		(end 43.003216 -148.336)
		(width 0.127)
		(layer "In5.Cu")
		(net "SAS_HDD_LED1")
	)
	(segment
		(start 94.02445 -89.154)
		(end 94.72549 -89.154)
		(width 0.127)
		(layer "In5.Cu")
		(net "SAS_HDD_LED1")
	)
	(segment
		(start 41.429432 -149.4663)
		(end 42.559732 -148.336)
		(width 0.127)
		(layer "In5.Cu")
		(net "SAS_HDD_LED1")
	)
	(segment
		(start 39.8526 -148.971)
		(end 40.3479 -149.4663)
		(width 0.127)
		(layer "In5.Cu")
		(net "SAS_HDD_LED1")
	)
	(segment
		(start 43.688 -147.193)
		(end 48.768 -142.113)
		(width 0.127)
		(layer "In5.Cu")
		(net "SAS_HDD_LED1")
	)
	(segment
		(start 43.688 -147.651216)
		(end 43.688 -147.193)
		(width 0.127)
		(layer "In5.Cu")
		(net "SAS_HDD_LED1")
	)
	(segment
		(start 48.768 -137.414)
		(end 50.546 -135.636)
		(width 0.127)
		(layer "In5.Cu")
		(net "SAS_HDD_LED1")
	)
	(segment
		(start 48.768 -142.113)
		(end 48.768 -137.414)
		(width 0.127)
		(layer "In5.Cu")
		(net "SAS_HDD_LED1")
	)
	(segment
		(start 50.546 -135.636)
		(end 50.546 -132.63245)
		(width 0.127)
		(layer "In5.Cu")
		(net "SAS_HDD_LED1")
	)
	(segment
		(start 40.3479 -149.4663)
		(end 41.429432 -149.4663)
		(width 0.127)
		(layer "In5.Cu")
		(net "SAS_HDD_LED1")
	)
	(segment
		(start 99.907344 -83.65998)
		(end 100.509324 -83.058)
		(width 0.127)
		(layer "In5.Cu")
		(net "SAS_HDD_LED1")
	)
	(segment
		(start 99.777296 -83.65998)
		(end 99.907344 -83.65998)
		(width 0.127)
		(layer "In5.Cu")
		(net "SAS_HDD_LED1")
	)
	(segment
		(start 115.996974 -39.578026)
		(end 116.603526 -38.971474)
		(width 0.1143)
		(layer "F.Cu")
		(net "IOC_GPIO_37")
	)
	(segment
		(start 115.42649 -40.513)
		(end 115.996974 -39.942516)
		(width 0.1143)
		(layer "F.Cu")
		(net "IOC_GPIO_37")
	)
	(segment
		(start 116.603526 -38.971474)
		(end 116.603526 -38.60292)
		(width 0.1143)
		(layer "F.Cu")
		(net "IOC_GPIO_37")
	)
	(segment
		(start 114.036856 -40.513)
		(end 115.42649 -40.513)
		(width 0.1143)
		(layer "F.Cu")
		(net "IOC_GPIO_37")
	)
	(segment
		(start 115.996974 -39.942516)
		(end 115.996974 -39.578026)
		(width 0.1143)
		(layer "F.Cu")
		(net "IOC_GPIO_37")
	)
	(segment
		(start 113.949988 -40.599868)
		(end 114.036856 -40.513)
		(width 0.1143)
		(layer "F.Cu")
		(net "IOC_GPIO_37")
	)
	(via
		(at 116.603526 -38.60292)
		(size 0.508)
		(drill 0.254)
		(layers "F.Cu" "B.Cu")
		(net "IOC_GPIO_37")
	)
	(segment
		(start 116.545106 -38.5445)
		(end 116.603526 -38.60292)
		(width 0.1143)
		(layer "B.Cu")
		(net "IOC_GPIO_37")
	)
	(segment
		(start 116.545106 -37.5666)
		(end 116.545106 -38.5445)
		(width 0.1143)
		(layer "B.Cu")
		(net "IOC_GPIO_37")
	)
	(segment
		(start 106.199178 -80.860392)
		(end 106.199178 -81.026762)
		(width 0.1143)
		(layer "F.Cu")
		(net "SAS_HDD_LED2")
	)
	(segment
		(start 106.0831 -80.3656)
		(end 106.0831 -80.431132)
		(width 0.1143)
		(layer "F.Cu")
		(net "SAS_HDD_LED2")
	)
	(segment
		(start 106.199178 -81.026762)
		(end 106.812842 -81.640426)
		(width 0.1143)
		(layer "F.Cu")
		(net "SAS_HDD_LED2")
	)
	(segment
		(start 33.909 -157.099)
		(end 40.767 -150.241)
		(width 0.1143)
		(layer "F.Cu")
		(net "SAS_HDD_LED2")
	)
	(segment
		(start 106.077766 -80.73898)
		(end 106.199178 -80.860392)
		(width 0.1143)
		(layer "F.Cu")
		(net "SAS_HDD_LED2")
	)
	(segment
		(start 27.224228 -163.783772)
		(end 33.909 -157.099)
		(width 0.1143)
		(layer "F.Cu")
		(net "SAS_HDD_LED2")
	)
	(segment
		(start 27.224228 -170.107356)
		(end 27.224228 -163.783772)
		(width 0.1143)
		(layer "F.Cu")
		(net "SAS_HDD_LED2")
	)
	(segment
		(start 106.812842 -81.640426)
		(end 106.812842 -82.81289)
		(width 0.1143)
		(layer "F.Cu")
		(net "SAS_HDD_LED2")
	)
	(segment
		(start 106.077766 -80.436466)
		(end 106.077766 -80.73898)
		(width 0.1143)
		(layer "F.Cu")
		(net "SAS_HDD_LED2")
	)
	(segment
		(start 40.767 -150.241)
		(end 40.767 -148.971)
		(width 0.1143)
		(layer "F.Cu")
		(net "SAS_HDD_LED2")
	)
	(segment
		(start 106.812842 -82.81289)
		(end 107.349798 -83.349846)
		(width 0.1143)
		(layer "F.Cu")
		(net "SAS_HDD_LED2")
	)
	(segment
		(start 106.0831 -80.431132)
		(end 106.077766 -80.436466)
		(width 0.1143)
		(layer "F.Cu")
		(net "SAS_HDD_LED2")
	)
	(via
		(at 33.909 -157.099)
		(size 0.7112)
		(drill 0.3556)
		(layers "F.Cu" "B.Cu")
		(net "SAS_HDD_LED2")
	)
	(via
		(at 106.0831 -80.3656)
		(size 0.508)
		(drill 0.254)
		(layers "F.Cu" "B.Cu")
		(net "SAS_HDD_LED2")
	)
	(via
		(at 40.767 -148.971)
		(size 0.5588)
		(drill 0.3048)
		(layers "F.Cu" "B.Cu")
		(net "SAS_HDD_LED2")
	)
	(segment
		(start 41.275 -148.971)
		(end 40.767 -148.971)
		(width 0.127)
		(layer "In5.Cu")
		(net "SAS_HDD_LED2")
	)
	(segment
		(start 42.908728 -147.8915)
		(end 42.3545 -147.8915)
		(width 0.127)
		(layer "In5.Cu")
		(net "SAS_HDD_LED2")
	)
	(segment
		(start 94.87027 -88.028018)
		(end 94.87027 -88.470232)
		(width 0.127)
		(layer "In5.Cu")
		(net "SAS_HDD_LED2")
	)
	(segment
		(start 43.2435 -147.556728)
		(end 42.908728 -147.8915)
		(width 0.127)
		(layer "In5.Cu")
		(net "SAS_HDD_LED2")
	)
	(segment
		(start 43.2435 -147.0025)
		(end 43.2435 -147.556728)
		(width 0.127)
		(layer "In5.Cu")
		(net "SAS_HDD_LED2")
	)
	(segment
		(start 50.165 -132.474462)
		(end 50.165 -135.478012)
		(width 0.127)
		(layer "In5.Cu")
		(net "SAS_HDD_LED2")
	)
	(segment
		(start 100.97897 -82.677)
		(end 100.351336 -82.677)
		(width 0.127)
		(layer "In5.Cu")
		(net "SAS_HDD_LED2")
	)
	(segment
		(start 42.3545 -147.8915)
		(end 41.275 -148.971)
		(width 0.127)
		(layer "In5.Cu")
		(net "SAS_HDD_LED2")
	)
	(segment
		(start 94.87027 -88.470232)
		(end 94.580202 -88.7603)
		(width 0.127)
		(layer "In5.Cu")
		(net "SAS_HDD_LED2")
	)
	(segment
		(start 94.580202 -88.7603)
		(end 93.879162 -88.7603)
		(width 0.127)
		(layer "In5.Cu")
		(net "SAS_HDD_LED2")
	)
	(segment
		(start 93.879162 -88.7603)
		(end 50.165 -132.474462)
		(width 0.127)
		(layer "In5.Cu")
		(net "SAS_HDD_LED2")
	)
	(segment
		(start 103.17607 -80.4799)
		(end 100.97897 -82.677)
		(width 0.127)
		(layer "In5.Cu")
		(net "SAS_HDD_LED2")
	)
	(segment
		(start 100.351336 -82.677)
		(end 99.749356 -83.27898)
		(width 0.127)
		(layer "In5.Cu")
		(net "SAS_HDD_LED2")
	)
	(segment
		(start 48.387 -137.256012)
		(end 48.387 -141.859)
		(width 0.127)
		(layer "In5.Cu")
		(net "SAS_HDD_LED2")
	)
	(segment
		(start 50.165 -135.478012)
		(end 48.387 -137.256012)
		(width 0.127)
		(layer "In5.Cu")
		(net "SAS_HDD_LED2")
	)
	(segment
		(start 48.387 -141.859)
		(end 43.2435 -147.0025)
		(width 0.127)
		(layer "In5.Cu")
		(net "SAS_HDD_LED2")
	)
	(segment
		(start 99.749356 -83.27898)
		(end 99.619308 -83.27898)
		(width 0.127)
		(layer "In5.Cu")
		(net "SAS_HDD_LED2")
	)
	(segment
		(start 105.9688 -80.4799)
		(end 103.17607 -80.4799)
		(width 0.127)
		(layer "In5.Cu")
		(net "SAS_HDD_LED2")
	)
	(segment
		(start 106.0831 -80.3656)
		(end 105.9688 -80.4799)
		(width 0.127)
		(layer "In5.Cu")
		(net "SAS_HDD_LED2")
	)
	(segment
		(start 99.619308 -83.27898)
		(end 94.87027 -88.028018)
		(width 0.127)
		(layer "In5.Cu")
		(net "SAS_HDD_LED2")
	)
	(segment
		(start 42.537126 -149.598126)
		(end 42.537126 -149.613874)
		(width 0.1143)
		(layer "F.Cu")
		(net "SAS_HDD_LED3")
	)
	(segment
		(start 27.624278 -170.107356)
		(end 27.624278 -164.526722)
		(width 0.1143)
		(layer "F.Cu")
		(net "SAS_HDD_LED3")
	)
	(segment
		(start 27.624278 -164.526722)
		(end 35.941 -156.21)
		(width 0.1143)
		(layer "F.Cu")
		(net "SAS_HDD_LED3")
	)
	(segment
		(start 108.349796 -87.349838)
		(end 107.84967 -86.849712)
		(width 0.1143)
		(layer "F.Cu")
		(net "SAS_HDD_LED3")
	)
	(segment
		(start 42.537126 -149.613874)
		(end 35.941 -156.21)
		(width 0.1143)
		(layer "F.Cu")
		(net "SAS_HDD_LED3")
	)
	(via
		(at 107.84967 -86.849712)
		(size 0.508)
		(drill 0.254)
		(layers "F.Cu" "B.Cu")
		(net "SAS_HDD_LED3")
	)
	(via
		(at 35.941 -156.21)
		(size 0.7112)
		(drill 0.3556)
		(layers "F.Cu" "B.Cu")
		(net "SAS_HDD_LED3")
	)
	(via
		(at 42.537126 -149.598126)
		(size 0.5588)
		(drill 0.3048)
		(layers "F.Cu" "B.Cu")
		(net "SAS_HDD_LED3")
	)
	(segment
		(start 96.139 -88.818466)
		(end 95.041466 -89.916)
		(width 0.127)
		(layer "In5.Cu")
		(net "SAS_HDD_LED3")
	)
	(segment
		(start 53.975 -131.143502)
		(end 53.975 -137.16)
		(width 0.127)
		(layer "In5.Cu")
		(net "SAS_HDD_LED3")
	)
	(segment
		(start 43.037252 -149.098)
		(end 42.537126 -149.598126)
		(width 0.127)
		(layer "In5.Cu")
		(net "SAS_HDD_LED3")
	)
	(segment
		(start 106.405172 -85.99805)
		(end 106.405172 -84.812378)
		(width 0.127)
		(layer "In5.Cu")
		(net "SAS_HDD_LED3")
	)
	(segment
		(start 106.009186 -84.416392)
		(end 100.228908 -84.416392)
		(width 0.127)
		(layer "In5.Cu")
		(net "SAS_HDD_LED3")
	)
	(segment
		(start 44.45 -147.685252)
		(end 44.45 -147.967192)
		(width 0.127)
		(layer "In5.Cu")
		(net "SAS_HDD_LED3")
	)
	(segment
		(start 100.228908 -84.416392)
		(end 100.22332 -84.42198)
		(width 0.127)
		(layer "In5.Cu")
		(net "SAS_HDD_LED3")
	)
	(segment
		(start 53.975 -137.16)
		(end 50.292 -140.843)
		(width 0.127)
		(layer "In5.Cu")
		(net "SAS_HDD_LED3")
	)
	(segment
		(start 43.319192 -149.098)
		(end 43.037252 -149.098)
		(width 0.127)
		(layer "In5.Cu")
		(net "SAS_HDD_LED3")
	)
	(segment
		(start 100.22332 -84.42198)
		(end 100.093272 -84.42198)
		(width 0.127)
		(layer "In5.Cu")
		(net "SAS_HDD_LED3")
	)
	(segment
		(start 96.139 -88.376252)
		(end 96.139 -88.818466)
		(width 0.127)
		(layer "In5.Cu")
		(net "SAS_HDD_LED3")
	)
	(segment
		(start 50.292 -140.843)
		(end 50.292 -141.843252)
		(width 0.127)
		(layer "In5.Cu")
		(net "SAS_HDD_LED3")
	)
	(segment
		(start 95.041466 -89.916)
		(end 94.745302 -89.916)
		(width 0.127)
		(layer "In5.Cu")
		(net "SAS_HDD_LED3")
	)
	(segment
		(start 50.292 -141.843252)
		(end 44.45 -147.685252)
		(width 0.127)
		(layer "In5.Cu")
		(net "SAS_HDD_LED3")
	)
	(segment
		(start 106.405172 -84.812378)
		(end 106.009186 -84.416392)
		(width 0.127)
		(layer "In5.Cu")
		(net "SAS_HDD_LED3")
	)
	(segment
		(start 106.713782 -86.30666)
		(end 106.405172 -85.99805)
		(width 0.127)
		(layer "In5.Cu")
		(net "SAS_HDD_LED3")
	)
	(segment
		(start 44.45 -147.967192)
		(end 43.319192 -149.098)
		(width 0.127)
		(layer "In5.Cu")
		(net "SAS_HDD_LED3")
	)
	(segment
		(start 107.84967 -86.849712)
		(end 107.306618 -86.30666)
		(width 0.127)
		(layer "In5.Cu")
		(net "SAS_HDD_LED3")
	)
	(segment
		(start 100.093272 -84.42198)
		(end 96.139 -88.376252)
		(width 0.127)
		(layer "In5.Cu")
		(net "SAS_HDD_LED3")
	)
	(segment
		(start 107.306618 -86.30666)
		(end 106.713782 -86.30666)
		(width 0.127)
		(layer "In5.Cu")
		(net "SAS_HDD_LED3")
	)
	(segment
		(start 94.745302 -89.916)
		(end 58.67527 -125.986032)
		(width 0.127)
		(layer "In5.Cu")
		(net "SAS_HDD_LED3")
	)
	(segment
		(start 58.67527 -126.443232)
		(end 53.975 -131.143502)
		(width 0.127)
		(layer "In5.Cu")
		(net "SAS_HDD_LED3")
	)
	(segment
		(start 58.67527 -125.986032)
		(end 58.67527 -126.443232)
		(width 0.127)
		(layer "In5.Cu")
		(net "SAS_HDD_LED3")
	)
	(segment
		(start 112.350042 -42.199814)
		(end 112.350042 -42.190924)
		(width 0.1143)
		(layer "F.Cu")
		(net "IOC_GPIO_38")
	)
	(segment
		(start 112.350042 -42.190924)
		(end 112.750346 -41.79062)
		(width 0.1143)
		(layer "F.Cu")
		(net "IOC_GPIO_38")
	)
	(via
		(at 112.750346 -41.79062)
		(size 0.508)
		(drill 0.254)
		(layers "F.Cu" "B.Cu")
		(net "IOC_GPIO_38")
	)
	(segment
		(start 113.662206 -41.19626)
		(end 113.067846 -41.79062)
		(width 0.1143)
		(layer "B.Cu")
		(net "IOC_GPIO_38")
	)
	(segment
		(start 113.067846 -41.79062)
		(end 112.750346 -41.79062)
		(width 0.1143)
		(layer "B.Cu")
		(net "IOC_GPIO_38")
	)
	(via
		(at 166.2684 -113.7158)
		(size 0.7112)
		(drill 0.3556)
		(layers "F.Cu" "B.Cu")
		(net "P3V3_STBY_R4")
	)
	(segment
		(start 166.0017 -113.9825)
		(end 165.354 -113.9825)
		(width 0.127)
		(layer "B.Cu")
		(net "P3V3_STBY_R4")
	)
	(segment
		(start 166.2684 -113.2459)
		(end 166.2684 -113.7158)
		(width 0.127)
		(layer "B.Cu")
		(net "P3V3_STBY_R4")
	)
	(segment
		(start 166.2684 -113.7158)
		(end 166.0017 -113.9825)
		(width 0.127)
		(layer "B.Cu")
		(net "P3V3_STBY_R4")
	)
	(segment
		(start 165.354 -113.9825)
		(end 164.211 -113.9825)
		(width 0.127)
		(layer "B.Cu")
		(net "P3V3_STBY_R4")
	)
	(segment
		(start 165.354 -112.3315)
		(end 166.2684 -113.2459)
		(width 0.127)
		(layer "B.Cu")
		(net "P3V3_STBY_R4")
	)
	(segment
		(start 87.305134 -133.731)
		(end 87.114634 -133.5405)
		(width 0.1143)
		(layer "F.Cu")
		(net "EXP_GPIO_8")
	)
	(segment
		(start 91.524582 -132.48767)
		(end 90.281252 -133.731)
		(width 0.1143)
		(layer "F.Cu")
		(net "EXP_GPIO_8")
	)
	(segment
		(start 91.524582 -131.570476)
		(end 91.524582 -132.48767)
		(width 0.1143)
		(layer "F.Cu")
		(net "EXP_GPIO_8")
	)
	(segment
		(start 90.281252 -133.731)
		(end 87.305134 -133.731)
		(width 0.1143)
		(layer "F.Cu")
		(net "EXP_GPIO_8")
	)
	(segment
		(start 105.349802 -98.35007)
		(end 104.849676 -98.850196)
		(width 0.1143)
		(layer "F.Cu")
		(net "EXP_GPIO_8")
	)
	(via
		(at 98.15957 -99.568)
		(size 0.7112)
		(drill 0.3556)
		(layers "F.Cu" "B.Cu")
		(net "EXP_GPIO_8")
	)
	(via
		(at 104.849676 -98.850196)
		(size 0.508)
		(drill 0.254)
		(layers "F.Cu" "B.Cu")
		(net "EXP_GPIO_8")
	)
	(via
		(at 87.114634 -133.5405)
		(size 0.508)
		(drill 0.254)
		(layers "F.Cu" "B.Cu")
		(net "EXP_GPIO_8")
	)
	(segment
		(start 104.031288 -98.412046)
		(end 103.39832 -98.412046)
		(width 0.1143)
		(layer "B.Cu")
		(net "EXP_GPIO_8")
	)
	(segment
		(start 87.1982 -120.190006)
		(end 87.1982 -122.45467)
		(width 0.1143)
		(layer "B.Cu")
		(net "EXP_GPIO_8")
	)
	(segment
		(start 103.39832 -98.412046)
		(end 103.18242 -98.196146)
		(width 0.1143)
		(layer "B.Cu")
		(net "EXP_GPIO_8")
	)
	(segment
		(start 100.512626 -99.09175)
		(end 98.63582 -99.09175)
		(width 0.1143)
		(layer "B.Cu")
		(net "EXP_GPIO_8")
	)
	(segment
		(start 98.63582 -99.09175)
		(end 98.15957 -99.568)
		(width 0.1143)
		(layer "B.Cu")
		(net "EXP_GPIO_8")
	)
	(segment
		(start 87.785702 -123.042172)
		(end 87.785702 -132.869432)
		(width 0.1143)
		(layer "B.Cu")
		(net "EXP_GPIO_8")
	)
	(segment
		(start 98.15957 -99.568)
		(end 98.157538 -99.570032)
		(width 0.1143)
		(layer "B.Cu")
		(net "EXP_GPIO_8")
	)
	(segment
		(start 96.891602 -99.570032)
		(end 87.63508 -108.826554)
		(width 0.1143)
		(layer "B.Cu")
		(net "EXP_GPIO_8")
	)
	(segment
		(start 100.879656 -99.116388)
		(end 100.537264 -99.116388)
		(width 0.1143)
		(layer "B.Cu")
		(net "EXP_GPIO_8")
	)
	(segment
		(start 104.469438 -98.850196)
		(end 104.031288 -98.412046)
		(width 0.1143)
		(layer "B.Cu")
		(net "EXP_GPIO_8")
	)
	(segment
		(start 87.63508 -108.826554)
		(end 87.63508 -119.753126)
		(width 0.1143)
		(layer "B.Cu")
		(net "EXP_GPIO_8")
	)
	(segment
		(start 101.835712 -98.196146)
		(end 100.940108 -99.09175)
		(width 0.1143)
		(layer "B.Cu")
		(net "EXP_GPIO_8")
	)
	(segment
		(start 104.849676 -98.850196)
		(end 104.469438 -98.850196)
		(width 0.1143)
		(layer "B.Cu")
		(net "EXP_GPIO_8")
	)
	(segment
		(start 100.940108 -99.09175)
		(end 100.904294 -99.09175)
		(width 0.1143)
		(layer "B.Cu")
		(net "EXP_GPIO_8")
	)
	(segment
		(start 103.18242 -98.196146)
		(end 101.835712 -98.196146)
		(width 0.1143)
		(layer "B.Cu")
		(net "EXP_GPIO_8")
	)
	(segment
		(start 87.1982 -122.45467)
		(end 87.785702 -123.042172)
		(width 0.1143)
		(layer "B.Cu")
		(net "EXP_GPIO_8")
	)
	(segment
		(start 98.157538 -99.570032)
		(end 96.891602 -99.570032)
		(width 0.1143)
		(layer "B.Cu")
		(net "EXP_GPIO_8")
	)
	(segment
		(start 87.63508 -119.753126)
		(end 87.1982 -120.190006)
		(width 0.1143)
		(layer "B.Cu")
		(net "EXP_GPIO_8")
	)
	(segment
		(start 100.904294 -99.09175)
		(end 100.879656 -99.116388)
		(width 0.1143)
		(layer "B.Cu")
		(net "EXP_GPIO_8")
	)
	(segment
		(start 87.785702 -132.869432)
		(end 87.114634 -133.5405)
		(width 0.1143)
		(layer "B.Cu")
		(net "EXP_GPIO_8")
	)
	(segment
		(start 100.537264 -99.116388)
		(end 100.512626 -99.09175)
		(width 0.1143)
		(layer "B.Cu")
		(net "EXP_GPIO_8")
	)
	(segment
		(start 18.452338 -161.835338)
		(end 30.90799 -149.379686)
		(width 0.1143)
		(layer "F.Cu")
		(net "SAS_HDD_LED4")
	)
	(segment
		(start 106.789728 -80.754982)
		(end 107.130342 -80.754982)
		(width 0.1143)
		(layer "F.Cu")
		(net "SAS_HDD_LED4")
	)
	(segment
		(start 106.657902 -80.784954)
		(end 106.759756 -80.784954)
		(width 0.1143)
		(layer "F.Cu")
		(net "SAS_HDD_LED4")
	)
	(segment
		(start 107.257342 -80.881982)
		(end 107.257342 -82.257392)
		(width 0.1143)
		(layer "F.Cu")
		(net "SAS_HDD_LED4")
	)
	(segment
		(start 18.452338 -162.395662)
		(end 18.452338 -161.835338)
		(width 0.1143)
		(layer "F.Cu")
		(net "SAS_HDD_LED4")
	)
	(segment
		(start 30.90799 -149.379686)
		(end 30.90799 -149.331426)
		(width 0.1143)
		(layer "F.Cu")
		(net "SAS_HDD_LED4")
	)
	(segment
		(start 107.257342 -82.257392)
		(end 107.349798 -82.349848)
		(width 0.1143)
		(layer "F.Cu")
		(net "SAS_HDD_LED4")
	)
	(segment
		(start 15.985998 -170.107356)
		(end 15.985998 -164.862002)
		(width 0.1143)
		(layer "F.Cu")
		(net "SAS_HDD_LED4")
	)
	(segment
		(start 15.985998 -164.862002)
		(end 17.653 -163.195)
		(width 0.1143)
		(layer "F.Cu")
		(net "SAS_HDD_LED4")
	)
	(segment
		(start 106.759756 -80.784954)
		(end 106.789728 -80.754982)
		(width 0.1143)
		(layer "F.Cu")
		(net "SAS_HDD_LED4")
	)
	(segment
		(start 17.653 -163.195)
		(end 18.452338 -162.395662)
		(width 0.1143)
		(layer "F.Cu")
		(net "SAS_HDD_LED4")
	)
	(segment
		(start 107.130342 -80.754982)
		(end 107.257342 -80.881982)
		(width 0.1143)
		(layer "F.Cu")
		(net "SAS_HDD_LED4")
	)
	(via
		(at 106.657902 -80.784954)
		(size 0.508)
		(drill 0.254)
		(layers "F.Cu" "B.Cu")
		(net "SAS_HDD_LED4")
	)
	(via
		(at 30.90799 -149.331426)
		(size 0.5588)
		(drill 0.3048)
		(layers "F.Cu" "B.Cu")
		(net "SAS_HDD_LED4")
	)
	(via
		(at 17.653 -163.195)
		(size 0.7112)
		(drill 0.3556)
		(layers "F.Cu" "B.Cu")
		(net "SAS_HDD_LED4")
	)
	(segment
		(start 46.066202 -142.8623)
		(end 45.35805 -142.8623)
		(width 0.127)
		(layer "In5.Cu")
		(net "SAS_HDD_LED4")
	)
	(segment
		(start 106.657902 -80.784954)
		(end 106.657902 -80.347566)
		(width 0.127)
		(layer "In5.Cu")
		(net "SAS_HDD_LED4")
	)
	(segment
		(start 95.714058 -86.162388)
		(end 49.784 -132.092446)
		(width 0.127)
		(layer "In5.Cu")
		(net "SAS_HDD_LED4")
	)
	(segment
		(start 101.91242 -80.2259)
		(end 100.457 -81.68132)
		(width 0.127)
		(layer "In5.Cu")
		(net "SAS_HDD_LED4")
	)
	(segment
		(start 42.930826 -144.277334)
		(end 37.130482 -150.077678)
		(width 0.127)
		(layer "In5.Cu")
		(net "SAS_HDD_LED4")
	)
	(segment
		(start 106.256836 -79.9465)
		(end 105.909364 -79.9465)
		(width 0.127)
		(layer "In5.Cu")
		(net "SAS_HDD_LED4")
	)
	(segment
		(start 45.35805 -142.8623)
		(end 43.943016 -144.277334)
		(width 0.127)
		(layer "In5.Cu")
		(net "SAS_HDD_LED4")
	)
	(segment
		(start 47.94123 -140.987272)
		(end 46.066202 -142.8623)
		(width 0.127)
		(layer "In5.Cu")
		(net "SAS_HDD_LED4")
	)
	(segment
		(start 105.909364 -79.9465)
		(end 105.62971 -80.2259)
		(width 0.127)
		(layer "In5.Cu")
		(net "SAS_HDD_LED4")
	)
	(segment
		(start 99.297236 -83.062064)
		(end 99.209606 -83.062064)
		(width 0.127)
		(layer "In5.Cu")
		(net "SAS_HDD_LED4")
	)
	(segment
		(start 99.209606 -83.062064)
		(end 96.109282 -86.162388)
		(width 0.127)
		(layer "In5.Cu")
		(net "SAS_HDD_LED4")
	)
	(segment
		(start 105.62971 -80.2259)
		(end 101.91242 -80.2259)
		(width 0.127)
		(layer "In5.Cu")
		(net "SAS_HDD_LED4")
	)
	(segment
		(start 37.130482 -150.077678)
		(end 31.654242 -150.077678)
		(width 0.127)
		(layer "In5.Cu")
		(net "SAS_HDD_LED4")
	)
	(segment
		(start 43.943016 -144.277334)
		(end 42.930826 -144.277334)
		(width 0.127)
		(layer "In5.Cu")
		(net "SAS_HDD_LED4")
	)
	(segment
		(start 99.591368 -82.89798)
		(end 99.46132 -82.89798)
		(width 0.127)
		(layer "In5.Cu")
		(net "SAS_HDD_LED4")
	)
	(segment
		(start 49.784 -135.320024)
		(end 47.94123 -137.162794)
		(width 0.127)
		(layer "In5.Cu")
		(net "SAS_HDD_LED4")
	)
	(segment
		(start 106.657902 -80.347566)
		(end 106.256836 -79.9465)
		(width 0.127)
		(layer "In5.Cu")
		(net "SAS_HDD_LED4")
	)
	(segment
		(start 47.94123 -137.162794)
		(end 47.94123 -140.987272)
		(width 0.127)
		(layer "In5.Cu")
		(net "SAS_HDD_LED4")
	)
	(segment
		(start 31.654242 -150.077678)
		(end 30.90799 -149.331426)
		(width 0.127)
		(layer "In5.Cu")
		(net "SAS_HDD_LED4")
	)
	(segment
		(start 99.46132 -82.89798)
		(end 99.297236 -83.062064)
		(width 0.127)
		(layer "In5.Cu")
		(net "SAS_HDD_LED4")
	)
	(segment
		(start 100.457 -82.032348)
		(end 99.591368 -82.89798)
		(width 0.127)
		(layer "In5.Cu")
		(net "SAS_HDD_LED4")
	)
	(segment
		(start 49.784 -132.092446)
		(end 49.784 -135.320024)
		(width 0.127)
		(layer "In5.Cu")
		(net "SAS_HDD_LED4")
	)
	(segment
		(start 100.457 -81.68132)
		(end 100.457 -82.032348)
		(width 0.127)
		(layer "In5.Cu")
		(net "SAS_HDD_LED4")
	)
	(segment
		(start 96.109282 -86.162388)
		(end 95.714058 -86.162388)
		(width 0.127)
		(layer "In5.Cu")
		(net "SAS_HDD_LED4")
	)
	(segment
		(start 117.22227 -194.96913)
		(end 116.915438 -194.662552)
		(width 0.1016)
		(layer "F.Cu")
		(net "SAS_HDD_REDV_TX7_P")
	)
	(segment
		(start 119.80037 -197.54723)
		(end 117.22227 -194.96913)
		(width 0.1016)
		(layer "F.Cu")
		(net "SAS_HDD_REDV_TX7_P")
	)
	(segment
		(start 116.45392 -193.548)
		(end 116.45392 -114.931952)
		(width 0.1016)
		(layer "F.Cu")
		(net "SAS_HDD_REDV_TX7_P")
	)
	(segment
		(start 120.847612 -205.4225)
		(end 120.669558 -205.4225)
		(width 0.1016)
		(layer "F.Cu")
		(net "SAS_HDD_REDV_TX7_P")
	)
	(segment
		(start 120.187212 -204.928978)
		(end 120.187212 -198.481188)
		(width 0.1016)
		(layer "F.Cu")
		(net "SAS_HDD_REDV_TX7_P")
	)
	(arc
		(start 116.915438 -194.662552)
		(mid 116.573841 -194.151176)
		(end 116.45392 -193.548)
		(width 0.1016)
		(layer "F.Cu")
		(net "SAS_HDD_REDV_TX7_P")
	)
	(arc
		(start 116.559584 -114.676936)
		(mid 116.589485 -114.632186)
		(end 116.59997 -114.5794)
		(width 0.1016)
		(layer "F.Cu")
		(net "SAS_HDD_REDV_TX7_P")
	)
	(arc
		(start 120.669558 -205.4225)
		(mid 120.497287 -205.393162)
		(end 120.344438 -205.308454)
		(width 0.1016)
		(layer "F.Cu")
		(net "SAS_HDD_REDV_TX7_P")
	)
	(arc
		(start 120.344438 -205.308454)
		(mid 120.228105 -205.134349)
		(end 120.187212 -204.928978)
		(width 0.1016)
		(layer "F.Cu")
		(net "SAS_HDD_REDV_TX7_P")
	)
	(arc
		(start 116.45392 -114.931952)
		(mid 116.481375 -114.793926)
		(end 116.559584 -114.676936)
		(width 0.1016)
		(layer "F.Cu")
		(net "SAS_HDD_REDV_TX7_P")
	)
	(arc
		(start 120.187212 -198.481188)
		(mid 120.086687 -197.975725)
		(end 119.80037 -197.54723)
		(width 0.1016)
		(layer "F.Cu")
		(net "SAS_HDD_REDV_TX7_P")
	)
	(segment
		(start 107.54995 -33.399984)
		(end 107.54995 -32.124904)
		(width 0.1143)
		(layer "F.Cu")
		(net "SYS_ERROR1")
	)
	(segment
		(start 107.54995 -32.124904)
		(end 107.616244 -32.05861)
		(width 0.1143)
		(layer "F.Cu")
		(net "SYS_ERROR1")
	)
	(via
		(at 107.616244 -32.05861)
		(size 0.508)
		(drill 0.254)
		(layers "F.Cu" "B.Cu")
		(net "SYS_ERROR1")
	)
	(segment
		(start 107.616244 -30.644084)
		(end 107.616244 -32.05861)
		(width 0.1143)
		(layer "B.Cu")
		(net "SYS_ERROR1")
	)
	(segment
		(start 107.07116 -30.099)
		(end 107.616244 -30.644084)
		(width 0.1143)
		(layer "B.Cu")
		(net "SYS_ERROR1")
	)
	(segment
		(start 113.882424 -36.9824)
		(end 113.464848 -37.399976)
		(width 0.1143)
		(layer "F.Cu")
		(net "IOC_GPIO_39")
	)
	(segment
		(start 114.553238 -36.9824)
		(end 113.882424 -36.9824)
		(width 0.1143)
		(layer "F.Cu")
		(net "IOC_GPIO_39")
	)
	(segment
		(start 113.464848 -37.399976)
		(end 113.150142 -37.399976)
		(width 0.1143)
		(layer "F.Cu")
		(net "IOC_GPIO_39")
	)
	(segment
		(start 117.456966 -34.078672)
		(end 114.553238 -36.9824)
		(width 0.1143)
		(layer "F.Cu")
		(net "IOC_GPIO_39")
	)
	(segment
		(start 117.456966 -33.909)
		(end 117.456966 -34.078672)
		(width 0.1143)
		(layer "F.Cu")
		(net "IOC_GPIO_39")
	)
	(via
		(at 164.8714 -119.8118)
		(size 0.7112)
		(drill 0.3556)
		(layers "F.Cu" "B.Cu")
		(net "EXP_RST")
	)
	(segment
		(start 163.957 -118.4275)
		(end 164.8714 -119.3419)
		(width 0.1143)
		(layer "B.Cu")
		(net "EXP_RST")
	)
	(segment
		(start 163.957 -119.9515)
		(end 164.7317 -119.9515)
		(width 0.1143)
		(layer "B.Cu")
		(net "EXP_RST")
	)
	(segment
		(start 162.814 -119.9515)
		(end 163.957 -119.9515)
		(width 0.1143)
		(layer "B.Cu")
		(net "EXP_RST")
	)
	(segment
		(start 164.7317 -119.9515)
		(end 164.8714 -119.8118)
		(width 0.1143)
		(layer "B.Cu")
		(net "EXP_RST")
	)
	(segment
		(start 164.8714 -119.3419)
		(end 164.8714 -119.8118)
		(width 0.1143)
		(layer "B.Cu")
		(net "EXP_RST")
	)
	(segment
		(start 46.355 -169.418)
		(end 46.355 -172.085)
		(width 0.1143)
		(layer "F.Cu")
		(net "EXP_RESET_MR_N")
	)
	(segment
		(start 44.47667 -143.5227)
		(end 43.97502 -144.02435)
		(width 0.1143)
		(layer "F.Cu")
		(net "EXP_RESET_MR_N")
	)
	(segment
		(start 43.97502 -167.03802)
		(end 46.355 -169.418)
		(width 0.1143)
		(layer "F.Cu")
		(net "EXP_RESET_MR_N")
	)
	(segment
		(start 43.97502 -144.02435)
		(end 43.97502 -167.03802)
		(width 0.1143)
		(layer "F.Cu")
		(net "EXP_RESET_MR_N")
	)
	(segment
		(start 45.337984 -143.5227)
		(end 44.47667 -143.5227)
		(width 0.1143)
		(layer "F.Cu")
		(net "EXP_RESET_MR_N")
	)
	(via
		(at 158.75 -179.324)
		(size 0.508)
		(drill 0.254)
		(layers "F.Cu" "B.Cu")
		(net "EXP_RESET_MR_N")
	)
	(via
		(at 46.355 -172.085)
		(size 0.508)
		(drill 0.254)
		(layers "F.Cu" "B.Cu")
		(net "EXP_RESET_MR_N")
	)
	(via
		(at 159.004 -171.704)
		(size 0.7112)
		(drill 0.3556)
		(layers "F.Cu" "B.Cu")
		(net "EXP_RESET_MR_N")
	)
	(segment
		(start 158.75 -179.324)
		(end 159.004 -179.07)
		(width 0.1143)
		(layer "B.Cu")
		(net "EXP_RESET_MR_N")
	)
	(segment
		(start 159.004 -168.91)
		(end 159.004 -171.704)
		(width 0.1143)
		(layer "B.Cu")
		(net "EXP_RESET_MR_N")
	)
	(segment
		(start 162.814 -120.8405)
		(end 162.814 -165.1)
		(width 0.1143)
		(layer "B.Cu")
		(net "EXP_RESET_MR_N")
	)
	(segment
		(start 162.814 -165.1)
		(end 159.004 -168.91)
		(width 0.1143)
		(layer "B.Cu")
		(net "EXP_RESET_MR_N")
	)
	(segment
		(start 159.004 -179.07)
		(end 159.004 -171.704)
		(width 0.1143)
		(layer "B.Cu")
		(net "EXP_RESET_MR_N")
	)
	(segment
		(start 46.355 -172.085)
		(end 51.562 -177.292)
		(width 0.127)
		(layer "In2.Cu")
		(net "EXP_RESET_MR_N")
	)
	(segment
		(start 66.04 -179.324)
		(end 158.75 -179.324)
		(width 0.127)
		(layer "In2.Cu")
		(net "EXP_RESET_MR_N")
	)
	(segment
		(start 51.562 -177.292)
		(end 64.008 -177.292)
		(width 0.127)
		(layer "In2.Cu")
		(net "EXP_RESET_MR_N")
	)
	(segment
		(start 64.008 -177.292)
		(end 66.04 -179.324)
		(width 0.127)
		(layer "In2.Cu")
		(net "EXP_RESET_MR_N")
	)
	(segment
		(start 91.549982 -47.800006)
		(end 91.226132 -47.800006)
		(width 0.1143)
		(layer "F.Cu")
		(net "SIO_DOUT_1")
	)
	(segment
		(start 90.889582 -48.136556)
		(end 90.353642 -48.136556)
		(width 0.1143)
		(layer "F.Cu")
		(net "SIO_DOUT_1")
	)
	(segment
		(start 91.226132 -47.800006)
		(end 90.889582 -48.136556)
		(width 0.1143)
		(layer "F.Cu")
		(net "SIO_DOUT_1")
	)
	(segment
		(start 90.353642 -48.136556)
		(end 90.205306 -48.285146)
		(width 0.1143)
		(layer "F.Cu")
		(net "SIO_DOUT_1")
	)
	(via
		(at 90.205306 -48.285146)
		(size 0.508)
		(drill 0.254)
		(layers "F.Cu" "B.Cu")
		(net "SIO_DOUT_1")
	)
	(segment
		(start 87.00516 -50.165)
		(end 88.14816 -49.022)
		(width 0.1143)
		(layer "B.Cu")
		(net "SIO_DOUT_1")
	)
	(segment
		(start 86.56066 -50.165)
		(end 87.00516 -50.165)
		(width 0.1143)
		(layer "B.Cu")
		(net "SIO_DOUT_1")
	)
	(segment
		(start 90.205306 -48.285146)
		(end 89.595452 -48.895)
		(width 0.1143)
		(layer "B.Cu")
		(net "SIO_DOUT_1")
	)
	(segment
		(start 88.27516 -48.895)
		(end 88.14816 -49.022)
		(width 0.1143)
		(layer "B.Cu")
		(net "SIO_DOUT_1")
	)
	(segment
		(start 89.595452 -48.895)
		(end 88.27516 -48.895)
		(width 0.1143)
		(layer "B.Cu")
		(net "SIO_DOUT_1")
	)
	(segment
		(start 114.349784 -103.35006)
		(end 113.849658 -103.850186)
		(width 0.1016)
		(layer "F.Cu")
		(net "SAS_HDD_CONN_RX8_P")
	)
	(via
		(at 113.849658 -103.850186)
		(size 0.508)
		(drill 0.254)
		(layers "F.Cu" "B.Cu")
		(net "SAS_HDD_CONN_RX8_P")
	)
	(segment
		(start 109.023658 -204.33538)
		(end 109.023912 -204.33538)
		(width 0.1016)
		(layer "B.Cu")
		(net "SAS_HDD_CONN_RX8_P")
	)
	(segment
		(start 115.5319 -173.452282)
		(end 115.5319 -173.147482)
		(width 0.1016)
		(layer "B.Cu")
		(net "SAS_HDD_CONN_RX8_P")
	)
	(segment
		(start 115.29568 -113.30432)
		(end 115.048538 -113.057178)
		(width 0.1016)
		(layer "B.Cu")
		(net "SAS_HDD_CONN_RX8_P")
	)
	(segment
		(start 109.023912 -204.33538)
		(end 109.023912 -199.12584)
		(width 0.1016)
		(layer "B.Cu")
		(net "SAS_HDD_CONN_RX8_P")
	)
	(segment
		(start 115.77066 -171.105322)
		(end 115.77066 -170.800522)
		(width 0.1016)
		(layer "B.Cu")
		(net "SAS_HDD_CONN_RX8_P")
	)
	(segment
		(start 115.048538 -113.057178)
		(end 114.37493 -112.383824)
		(width 0.1016)
		(layer "B.Cu")
		(net "SAS_HDD_CONN_RX8_P")
	)
	(segment
		(start 115.5319 -186.502802)
		(end 115.5319 -186.198002)
		(width 0.1016)
		(layer "B.Cu")
		(net "SAS_HDD_CONN_RX8_P")
	)
	(segment
		(start 115.77066 -148.73351)
		(end 115.77066 -148.42871)
		(width 0.1016)
		(layer "B.Cu")
		(net "SAS_HDD_CONN_RX8_P")
	)
	(segment
		(start 115.77066 -187.285122)
		(end 115.77066 -186.980322)
		(width 0.1016)
		(layer "B.Cu")
		(net "SAS_HDD_CONN_RX8_P")
	)
	(segment
		(start 113.54562 -104.230678)
		(end 113.545874 -104.230678)
		(width 0.1016)
		(layer "B.Cu")
		(net "SAS_HDD_CONN_RX8_P")
	)
	(segment
		(start 113.632742 -110.5916)
		(end 113.632742 -105.77576)
		(width 0.1016)
		(layer "B.Cu")
		(net "SAS_HDD_CONN_RX8_P")
	)
	(segment
		(start 115.5319 -147.95119)
		(end 115.5319 -113.875058)
		(width 0.1016)
		(layer "B.Cu")
		(net "SAS_HDD_CONN_RX8_P")
	)
	(segment
		(start 115.77066 -172.669962)
		(end 115.77066 -172.365162)
		(width 0.1016)
		(layer "B.Cu")
		(net "SAS_HDD_CONN_RX8_P")
	)
	(segment
		(start 115.77066 -174.234602)
		(end 115.77066 -173.929802)
		(width 0.1016)
		(layer "B.Cu")
		(net "SAS_HDD_CONN_RX8_P")
	)
	(segment
		(start 115.5319 -171.887642)
		(end 115.5319 -171.582842)
		(width 0.1016)
		(layer "B.Cu")
		(net "SAS_HDD_CONN_RX8_P")
	)
	(segment
		(start 109.39399 -198.232776)
		(end 109.413802 -198.21271)
		(width 0.1016)
		(layer "B.Cu")
		(net "SAS_HDD_CONN_RX8_P")
	)
	(segment
		(start 113.602516 -104.165908)
		(end 113.685828 -104.082596)
		(width 0.1016)
		(layer "B.Cu")
		(net "SAS_HDD_CONN_RX8_P")
	)
	(segment
		(start 115.5319 -183.373522)
		(end 115.5319 -174.712122)
		(width 0.1016)
		(layer "B.Cu")
		(net "SAS_HDD_CONN_RX8_P")
	)
	(segment
		(start 115.77066 -185.720482)
		(end 115.77066 -185.415682)
		(width 0.1016)
		(layer "B.Cu")
		(net "SAS_HDD_CONN_RX8_P")
	)
	(segment
		(start 113.727484 -104.031034)
		(end 113.849658 -103.850186)
		(width 0.1016)
		(layer "B.Cu")
		(net "SAS_HDD_CONN_RX8_P")
	)
	(segment
		(start 113.416842 -104.964738)
		(end 113.416842 -104.614218)
		(width 0.1016)
		(layer "B.Cu")
		(net "SAS_HDD_CONN_RX8_P")
	)
	(segment
		(start 109.671612 -205.4225)
		(end 109.334554 -205.085696)
		(width 0.1016)
		(layer "B.Cu")
		(net "SAS_HDD_CONN_RX8_P")
	)
	(segment
		(start 109.413802 -198.21271)
		(end 114.314732 -193.31178)
		(width 0.1016)
		(layer "B.Cu")
		(net "SAS_HDD_CONN_RX8_P")
	)
	(segment
		(start 115.5319 -184.938162)
		(end 115.5319 -184.633362)
		(width 0.1016)
		(layer "B.Cu")
		(net "SAS_HDD_CONN_RX8_P")
	)
	(segment
		(start 113.685828 -104.082596)
		(end 113.686844 -104.080056)
		(width 0.1016)
		(layer "B.Cu")
		(net "SAS_HDD_CONN_RX8_P")
	)
	(segment
		(start 113.416842 -104.614218)
		(end 113.417096 -104.614472)
		(width 0.1016)
		(layer "B.Cu")
		(net "SAS_HDD_CONN_RX8_P")
	)
	(segment
		(start 115.5319 -170.323002)
		(end 115.5319 -149.21103)
		(width 0.1016)
		(layer "B.Cu")
		(net "SAS_HDD_CONN_RX8_P")
	)
	(segment
		(start 115.5319 -190.373254)
		(end 115.5319 -187.762642)
		(width 0.1016)
		(layer "B.Cu")
		(net "SAS_HDD_CONN_RX8_P")
	)
	(segment
		(start 115.77066 -184.155842)
		(end 115.77066 -183.851042)
		(width 0.1016)
		(layer "B.Cu")
		(net "SAS_HDD_CONN_RX8_P")
	)
	(arc
		(start 113.632742 -105.77576)
		(mid 113.601292 -105.527233)
		(end 113.50879 -105.29443)
		(width 0.1016)
		(layer "B.Cu")
		(net "SAS_HDD_CONN_RX8_P")
	)
	(arc
		(start 115.77066 -185.415682)
		(mid 115.740168 -185.281689)
		(end 115.65128 -185.176922)
		(width 0.1016)
		(layer "B.Cu")
		(net "SAS_HDD_CONN_RX8_P")
	)
	(arc
		(start 115.77066 -173.929802)
		(mid 115.740168 -173.795809)
		(end 115.65128 -173.691042)
		(width 0.1016)
		(layer "B.Cu")
		(net "SAS_HDD_CONN_RX8_P")
	)
	(arc
		(start 114.314732 -193.31178)
		(mid 115.215522 -191.963559)
		(end 115.5319 -190.373254)
		(width 0.1016)
		(layer "B.Cu")
		(net "SAS_HDD_CONN_RX8_P")
	)
	(arc
		(start 115.65128 -171.344082)
		(mid 115.740074 -171.239268)
		(end 115.77066 -171.105322)
		(width 0.1016)
		(layer "B.Cu")
		(net "SAS_HDD_CONN_RX8_P")
	)
	(arc
		(start 115.65128 -170.561762)
		(mid 115.562486 -170.456948)
		(end 115.5319 -170.323002)
		(width 0.1016)
		(layer "B.Cu")
		(net "SAS_HDD_CONN_RX8_P")
	)
	(arc
		(start 113.417096 -104.614472)
		(mid 113.449952 -104.412054)
		(end 113.54562 -104.230678)
		(width 0.1016)
		(layer "B.Cu")
		(net "SAS_HDD_CONN_RX8_P")
	)
	(arc
		(start 115.65128 -148.97227)
		(mid 115.740074 -148.867456)
		(end 115.77066 -148.73351)
		(width 0.1016)
		(layer "B.Cu")
		(net "SAS_HDD_CONN_RX8_P")
	)
	(arc
		(start 115.77066 -148.42871)
		(mid 115.740168 -148.294717)
		(end 115.65128 -148.18995)
		(width 0.1016)
		(layer "B.Cu")
		(net "SAS_HDD_CONN_RX8_P")
	)
	(arc
		(start 109.023912 -199.12584)
		(mid 109.120146 -198.64251)
		(end 109.39399 -198.232776)
		(width 0.1016)
		(layer "B.Cu")
		(net "SAS_HDD_CONN_RX8_P")
	)
	(arc
		(start 109.334554 -205.085696)
		(mid 109.104535 -204.741448)
		(end 109.023658 -204.33538)
		(width 0.1016)
		(layer "B.Cu")
		(net "SAS_HDD_CONN_RX8_P")
	)
	(arc
		(start 115.5319 -186.198002)
		(mid 115.562392 -186.064009)
		(end 115.65128 -185.959242)
		(width 0.1016)
		(layer "B.Cu")
		(net "SAS_HDD_CONN_RX8_P")
	)
	(arc
		(start 115.77066 -172.365162)
		(mid 115.740168 -172.231169)
		(end 115.65128 -172.126402)
		(width 0.1016)
		(layer "B.Cu")
		(net "SAS_HDD_CONN_RX8_P")
	)
	(arc
		(start 115.65128 -174.473362)
		(mid 115.740074 -174.368548)
		(end 115.77066 -174.234602)
		(width 0.1016)
		(layer "B.Cu")
		(net "SAS_HDD_CONN_RX8_P")
	)
	(arc
		(start 115.77066 -186.980322)
		(mid 115.740168 -186.846329)
		(end 115.65128 -186.741562)
		(width 0.1016)
		(layer "B.Cu")
		(net "SAS_HDD_CONN_RX8_P")
	)
	(arc
		(start 115.65128 -173.691042)
		(mid 115.562486 -173.586228)
		(end 115.5319 -173.452282)
		(width 0.1016)
		(layer "B.Cu")
		(net "SAS_HDD_CONN_RX8_P")
	)
	(arc
		(start 115.5319 -173.147482)
		(mid 115.562392 -173.013489)
		(end 115.65128 -172.908722)
		(width 0.1016)
		(layer "B.Cu")
		(net "SAS_HDD_CONN_RX8_P")
	)
	(arc
		(start 113.545874 -104.230678)
		(mid 113.573095 -104.197331)
		(end 113.602516 -104.165908)
		(width 0.1016)
		(layer "B.Cu")
		(net "SAS_HDD_CONN_RX8_P")
	)
	(arc
		(start 115.5319 -187.762642)
		(mid 115.562392 -187.628649)
		(end 115.65128 -187.523882)
		(width 0.1016)
		(layer "B.Cu")
		(net "SAS_HDD_CONN_RX8_P")
	)
	(arc
		(start 115.65128 -187.523882)
		(mid 115.740074 -187.419068)
		(end 115.77066 -187.285122)
		(width 0.1016)
		(layer "B.Cu")
		(net "SAS_HDD_CONN_RX8_P")
	)
	(arc
		(start 115.5319 -171.582842)
		(mid 115.562392 -171.448849)
		(end 115.65128 -171.344082)
		(width 0.1016)
		(layer "B.Cu")
		(net "SAS_HDD_CONN_RX8_P")
	)
	(arc
		(start 115.65128 -148.18995)
		(mid 115.562486 -148.085136)
		(end 115.5319 -147.95119)
		(width 0.1016)
		(layer "B.Cu")
		(net "SAS_HDD_CONN_RX8_P")
	)
	(arc
		(start 115.65128 -172.126402)
		(mid 115.562486 -172.021588)
		(end 115.5319 -171.887642)
		(width 0.1016)
		(layer "B.Cu")
		(net "SAS_HDD_CONN_RX8_P")
	)
	(arc
		(start 115.65128 -185.176922)
		(mid 115.562486 -185.072108)
		(end 115.5319 -184.938162)
		(width 0.1016)
		(layer "B.Cu")
		(net "SAS_HDD_CONN_RX8_P")
	)
	(arc
		(start 115.65128 -172.908722)
		(mid 115.740074 -172.803908)
		(end 115.77066 -172.669962)
		(width 0.1016)
		(layer "B.Cu")
		(net "SAS_HDD_CONN_RX8_P")
	)
	(arc
		(start 115.65128 -184.394602)
		(mid 115.740074 -184.289788)
		(end 115.77066 -184.155842)
		(width 0.1016)
		(layer "B.Cu")
		(net "SAS_HDD_CONN_RX8_P")
	)
	(arc
		(start 115.65128 -183.612282)
		(mid 115.562486 -183.507468)
		(end 115.5319 -183.373522)
		(width 0.1016)
		(layer "B.Cu")
		(net "SAS_HDD_CONN_RX8_P")
	)
	(arc
		(start 113.50879 -105.29443)
		(mid 113.501877 -105.28207)
		(end 113.49482 -105.269792)
		(width 0.1016)
		(layer "B.Cu")
		(net "SAS_HDD_CONN_RX8_P")
	)
	(arc
		(start 115.5319 -149.21103)
		(mid 115.562392 -149.077037)
		(end 115.65128 -148.97227)
		(width 0.1016)
		(layer "B.Cu")
		(net "SAS_HDD_CONN_RX8_P")
	)
	(arc
		(start 115.5319 -174.712122)
		(mid 115.562392 -174.578129)
		(end 115.65128 -174.473362)
		(width 0.1016)
		(layer "B.Cu")
		(net "SAS_HDD_CONN_RX8_P")
	)
	(arc
		(start 115.65128 -185.959242)
		(mid 115.740074 -185.854428)
		(end 115.77066 -185.720482)
		(width 0.1016)
		(layer "B.Cu")
		(net "SAS_HDD_CONN_RX8_P")
	)
	(arc
		(start 115.5319 -184.633362)
		(mid 115.562392 -184.499369)
		(end 115.65128 -184.394602)
		(width 0.1016)
		(layer "B.Cu")
		(net "SAS_HDD_CONN_RX8_P")
	)
	(arc
		(start 115.77066 -170.800522)
		(mid 115.740168 -170.666529)
		(end 115.65128 -170.561762)
		(width 0.1016)
		(layer "B.Cu")
		(net "SAS_HDD_CONN_RX8_P")
	)
	(arc
		(start 115.77066 -183.851042)
		(mid 115.740168 -183.717049)
		(end 115.65128 -183.612282)
		(width 0.1016)
		(layer "B.Cu")
		(net "SAS_HDD_CONN_RX8_P")
	)
	(arc
		(start 115.5319 -113.875058)
		(mid 115.470557 -113.566195)
		(end 115.29568 -113.30432)
		(width 0.1016)
		(layer "B.Cu")
		(net "SAS_HDD_CONN_RX8_P")
	)
	(arc
		(start 114.37493 -112.383824)
		(mid 113.825583 -111.56153)
		(end 113.632742 -110.5916)
		(width 0.1016)
		(layer "B.Cu")
		(net "SAS_HDD_CONN_RX8_P")
	)
	(arc
		(start 113.49482 -105.269792)
		(mid 113.436606 -105.122176)
		(end 113.416842 -104.964738)
		(width 0.1016)
		(layer "B.Cu")
		(net "SAS_HDD_CONN_RX8_P")
	)
	(arc
		(start 113.686844 -104.080056)
		(mid 113.708334 -104.056515)
		(end 113.727484 -104.031034)
		(width 0.1016)
		(layer "B.Cu")
		(net "SAS_HDD_CONN_RX8_P")
	)
	(arc
		(start 115.65128 -186.741562)
		(mid 115.562486 -186.636748)
		(end 115.5319 -186.502802)
		(width 0.1016)
		(layer "B.Cu")
		(net "SAS_HDD_CONN_RX8_P")
	)
	(segment
		(start 90.750136 -49.399952)
		(end 90.490548 -49.399952)
		(width 0.1143)
		(layer "F.Cu")
		(net "SIO_LOAD_1")
	)
	(segment
		(start 90.490548 -49.399952)
		(end 90.19286 -49.69764)
		(width 0.1143)
		(layer "F.Cu")
		(net "SIO_LOAD_1")
	)
	(via
		(at 90.19286 -49.69764)
		(size 0.508)
		(drill 0.254)
		(layers "F.Cu" "B.Cu")
		(net "SIO_LOAD_1")
	)
	(segment
		(start 89.64041 -50.25009)
		(end 90.19286 -49.69764)
		(width 0.1143)
		(layer "B.Cu")
		(net "SIO_LOAD_1")
	)
	(segment
		(start 89.67216 -52.6415)
		(end 89.67216 -51.435)
		(width 0.1143)
		(layer "B.Cu")
		(net "SIO_LOAD_1")
	)
	(segment
		(start 89.64041 -51.40325)
		(end 89.64041 -50.25009)
		(width 0.1143)
		(layer "B.Cu")
		(net "SIO_LOAD_1")
	)
	(segment
		(start 89.67216 -51.435)
		(end 89.64041 -51.40325)
		(width 0.1143)
		(layer "B.Cu")
		(net "SIO_LOAD_1")
	)
	(segment
		(start 193.1035 -122.174)
		(end 191.8462 -122.174)
		(width 0.254)
		(layer "F.Cu")
		(net "P1V8_E_B")
	)
	(segment
		(start 194.183 -122.682)
		(end 193.7385 -122.2375)
		(width 0.254)
		(layer "F.Cu")
		(net "P1V8_E_B")
	)
	(segment
		(start 193.167 -122.2375)
		(end 193.1035 -122.174)
		(width 0.254)
		(layer "F.Cu")
		(net "P1V8_E_B")
	)
	(segment
		(start 193.7385 -122.2375)
		(end 193.167 -122.2375)
		(width 0.254)
		(layer "F.Cu")
		(net "P1V8_E_B")
	)
	(via
		(at 194.183 -122.682)
		(size 0.7112)
		(drill 0.3556)
		(layers "F.Cu" "B.Cu")
		(net "P1V8_E_B")
	)
	(segment
		(start 127.913892 -90.754708)
		(end 127.09017 -90.754708)
		(width 0.1016)
		(layer "F.Cu")
		(net "3X24_SAS_TX19_P")
	)
	(segment
		(start 130.517392 -91.221052)
		(end 130.508756 -91.212416)
		(width 0.1016)
		(layer "F.Cu")
		(net "3X24_SAS_TX19_P")
	)
	(segment
		(start 130.946652 -91.3511)
		(end 130.809746 -91.3511)
		(width 0.1016)
		(layer "F.Cu")
		(net "3X24_SAS_TX19_P")
	)
	(segment
		(start 129.768854 -90.907108)
		(end 128.281684 -90.907108)
		(width 0.1016)
		(layer "F.Cu")
		(net "3X24_SAS_TX19_P")
	)
	(segment
		(start 130.532378 -91.235784)
		(end 130.517392 -91.221052)
		(width 0.1016)
		(layer "F.Cu")
		(net "3X24_SAS_TX19_P")
	)
	(segment
		(start 126.517654 -90.517726)
		(end 126.350014 -90.349832)
		(width 0.1016)
		(layer "F.Cu")
		(net "3X24_SAS_TX19_P")
	)
	(arc
		(start 131.0386 -91.313)
		(mid 130.996414 -91.341188)
		(end 130.946652 -91.3511)
		(width 0.1016)
		(layer "F.Cu")
		(net "3X24_SAS_TX19_P")
	)
	(arc
		(start 128.09474 -90.829638)
		(mid 128.011766 -90.774197)
		(end 127.913892 -90.754708)
		(width 0.1016)
		(layer "F.Cu")
		(net "3X24_SAS_TX19_P")
	)
	(arc
		(start 128.281684 -90.907108)
		(mid 128.180497 -90.886981)
		(end 128.09474 -90.829638)
		(width 0.1016)
		(layer "F.Cu")
		(net "3X24_SAS_TX19_P")
	)
	(arc
		(start 127.09017 -90.754708)
		(mid 126.780335 -90.693172)
		(end 126.517654 -90.517726)
		(width 0.1016)
		(layer "F.Cu")
		(net "3X24_SAS_TX19_P")
	)
	(arc
		(start 130.809746 -91.3511)
		(mid 130.659633 -91.32096)
		(end 130.532378 -91.235784)
		(width 0.1016)
		(layer "F.Cu")
		(net "3X24_SAS_TX19_P")
	)
	(arc
		(start 130.508756 -91.212416)
		(mid 130.169059 -90.986446)
		(end 129.768854 -90.907108)
		(width 0.1016)
		(layer "F.Cu")
		(net "3X24_SAS_TX19_P")
	)
	(segment
		(start 112.350042 -42.999914)
		(end 112.35055 -42.999914)
		(width 0.1143)
		(layer "F.Cu")
		(net "IOC_SCL_2")
	)
	(segment
		(start 112.35055 -42.999914)
		(end 112.745266 -42.605198)
		(width 0.1143)
		(layer "F.Cu")
		(net "IOC_SCL_2")
	)
	(segment
		(start 112.745266 -42.605198)
		(end 112.746028 -42.605198)
		(width 0.1143)
		(layer "F.Cu")
		(net "IOC_SCL_2")
	)
	(via
		(at 117.163088 -40.460422)
		(size 0.7112)
		(drill 0.3556)
		(layers "F.Cu" "B.Cu")
		(net "IOC_SCL_2")
	)
	(via
		(at 112.746028 -42.605198)
		(size 0.508)
		(drill 0.254)
		(layers "F.Cu" "B.Cu")
		(net "IOC_SCL_2")
	)
	(segment
		(start 115.051332 -42.605198)
		(end 116.925852 -40.730678)
		(width 0.1143)
		(layer "B.Cu")
		(net "IOC_SCL_2")
	)
	(segment
		(start 119.552466 -37.938964)
		(end 117.163088 -40.328342)
		(width 0.1143)
		(layer "B.Cu")
		(net "IOC_SCL_2")
	)
	(segment
		(start 116.925852 -40.697658)
		(end 117.163088 -40.460422)
		(width 0.1143)
		(layer "B.Cu")
		(net "IOC_SCL_2")
	)
	(segment
		(start 116.925852 -40.730678)
		(end 116.925852 -40.697658)
		(width 0.1143)
		(layer "B.Cu")
		(net "IOC_SCL_2")
	)
	(segment
		(start 117.163088 -40.328342)
		(end 117.163088 -40.460422)
		(width 0.1143)
		(layer "B.Cu")
		(net "IOC_SCL_2")
	)
	(segment
		(start 112.746028 -42.605198)
		(end 115.051332 -42.605198)
		(width 0.1143)
		(layer "B.Cu")
		(net "IOC_SCL_2")
	)
	(segment
		(start 119.552466 -37.846)
		(end 119.552466 -37.938964)
		(width 0.1143)
		(layer "B.Cu")
		(net "IOC_SCL_2")
	)
	(segment
		(start 112.350042 -41.399968)
		(end 112.74679 -41.00322)
		(width 0.1143)
		(layer "F.Cu")
		(net "IOC_SDA_2")
	)
	(segment
		(start 112.74679 -41.00322)
		(end 112.750346 -41.00322)
		(width 0.1143)
		(layer "F.Cu")
		(net "IOC_SDA_2")
	)
	(via
		(at 112.750346 -41.00322)
		(size 0.508)
		(drill 0.254)
		(layers "F.Cu" "B.Cu")
		(net "IOC_SDA_2")
	)
	(via
		(at 116.364766 -42.6466)
		(size 0.7112)
		(drill 0.3556)
		(layers "F.Cu" "B.Cu")
		(net "IOC_SDA_2")
	)
	(segment
		(start 119.552466 -38.989)
		(end 119.323358 -38.989)
		(width 0.1143)
		(layer "B.Cu")
		(net "IOC_SDA_2")
	)
	(segment
		(start 112.333278 -41.420288)
		(end 112.750346 -41.00322)
		(width 0.1143)
		(layer "B.Cu")
		(net "IOC_SDA_2")
	)
	(segment
		(start 119.323358 -38.989)
		(end 117.728238 -40.58412)
		(width 0.1143)
		(layer "B.Cu")
		(net "IOC_SDA_2")
	)
	(segment
		(start 112.581182 -43.024298)
		(end 112.333278 -42.776394)
		(width 0.1143)
		(layer "B.Cu")
		(net "IOC_SDA_2")
	)
	(segment
		(start 117.728238 -40.69461)
		(end 117.397276 -41.025572)
		(width 0.1143)
		(layer "B.Cu")
		(net "IOC_SDA_2")
	)
	(segment
		(start 112.333278 -42.776394)
		(end 112.333278 -41.420288)
		(width 0.1143)
		(layer "B.Cu")
		(net "IOC_SDA_2")
	)
	(segment
		(start 117.30609 -41.025572)
		(end 116.364766 -41.966896)
		(width 0.1143)
		(layer "B.Cu")
		(net "IOC_SDA_2")
	)
	(segment
		(start 117.728238 -40.58412)
		(end 117.728238 -40.69461)
		(width 0.1143)
		(layer "B.Cu")
		(net "IOC_SDA_2")
	)
	(segment
		(start 116.364766 -42.6466)
		(end 115.987068 -43.024298)
		(width 0.1143)
		(layer "B.Cu")
		(net "IOC_SDA_2")
	)
	(segment
		(start 116.364766 -41.966896)
		(end 116.364766 -42.6466)
		(width 0.1143)
		(layer "B.Cu")
		(net "IOC_SDA_2")
	)
	(segment
		(start 115.987068 -43.024298)
		(end 112.581182 -43.024298)
		(width 0.1143)
		(layer "B.Cu")
		(net "IOC_SDA_2")
	)
	(segment
		(start 117.397276 -41.025572)
		(end 117.30609 -41.025572)
		(width 0.1143)
		(layer "B.Cu")
		(net "IOC_SDA_2")
	)
	(segment
		(start 198.935848 -142.503652)
		(end 198.131938 -142.503652)
		(width 0.1143)
		(layer "F.Cu")
		(net "EXP_EEPROM_A2")
	)
	(segment
		(start 198.9455 -142.494)
		(end 198.935848 -142.503652)
		(width 0.1143)
		(layer "F.Cu")
		(net "EXP_EEPROM_A2")
	)
	(segment
		(start 198.9455 -143.0655)
		(end 198.9455 -142.494)
		(width 0.1143)
		(layer "F.Cu")
		(net "EXP_EEPROM_A2")
	)
	(segment
		(start 202.1205 -142.494)
		(end 201.3585 -143.256)
		(width 0.1143)
		(layer "F.Cu")
		(net "EXP_EEPROM_A2")
	)
	(segment
		(start 195.956936 -141.856714)
		(end 197.485 -141.856714)
		(width 0.1143)
		(layer "F.Cu")
		(net "EXP_EEPROM_A2")
	)
	(segment
		(start 199.136 -143.256)
		(end 198.9455 -143.0655)
		(width 0.1143)
		(layer "F.Cu")
		(net "EXP_EEPROM_A2")
	)
	(segment
		(start 201.3585 -143.256)
		(end 199.136 -143.256)
		(width 0.1143)
		(layer "F.Cu")
		(net "EXP_EEPROM_A2")
	)
	(segment
		(start 198.131938 -142.503652)
		(end 197.727316 -142.09903)
		(width 0.1143)
		(layer "F.Cu")
		(net "EXP_EEPROM_A2")
	)
	(segment
		(start 197.485 -141.856714)
		(end 197.727316 -142.09903)
		(width 0.1143)
		(layer "F.Cu")
		(net "EXP_EEPROM_A2")
	)
	(via
		(at 197.727316 -142.09903)
		(size 0.7112)
		(drill 0.3556)
		(layers "F.Cu" "B.Cu")
		(net "EXP_EEPROM_A2")
	)
	(segment
		(start 112.351312 -204.951838)
		(end 112.351312 -201.7014)
		(width 0.1016)
		(layer "F.Cu")
		(net "SAS_HDD_REDV_TX8_P")
	)
	(segment
		(start 112.973612 -205.4225)
		(end 112.817148 -205.4225)
		(width 0.1016)
		(layer "F.Cu")
		(net "SAS_HDD_REDV_TX8_P")
	)
	(segment
		(start 114.67592 -196.08927)
		(end 114.67592 -114.931952)
		(width 0.1016)
		(layer "F.Cu")
		(net "SAS_HDD_REDV_TX8_P")
	)
	(arc
		(start 112.50549 -205.323948)
		(mid 112.391415 -205.153222)
		(end 112.351312 -204.951838)
		(width 0.1016)
		(layer "F.Cu")
		(net "SAS_HDD_REDV_TX8_P")
	)
	(arc
		(start 114.750088 -114.752882)
		(mid 114.803271 -114.673288)
		(end 114.82197 -114.5794)
		(width 0.1016)
		(layer "F.Cu")
		(net "SAS_HDD_REDV_TX8_P")
	)
	(arc
		(start 112.817148 -205.4225)
		(mid 112.653714 -205.397274)
		(end 112.50549 -205.323948)
		(width 0.1016)
		(layer "F.Cu")
		(net "SAS_HDD_REDV_TX8_P")
	)
	(arc
		(start 112.351312 -201.7014)
		(mid 112.716562 -199.865165)
		(end 113.756694 -198.308468)
		(width 0.1016)
		(layer "F.Cu")
		(net "SAS_HDD_REDV_TX8_P")
	)
	(arc
		(start 114.67592 -114.931952)
		(mid 114.695197 -114.835042)
		(end 114.750088 -114.752882)
		(width 0.1016)
		(layer "F.Cu")
		(net "SAS_HDD_REDV_TX8_P")
	)
	(arc
		(start 113.756694 -198.308468)
		(mid 114.437047 -197.290292)
		(end 114.67592 -196.08927)
		(width 0.1016)
		(layer "F.Cu")
		(net "SAS_HDD_REDV_TX8_P")
	)
	(segment
		(start 117.037104 -39.31285)
		(end 117.830346 -38.519608)
		(width 0.1143)
		(layer "F.Cu")
		(net "IOC_GPIO_15")
	)
	(segment
		(start 117.830346 -38.519608)
		(end 117.830346 -37.51072)
		(width 0.1143)
		(layer "F.Cu")
		(net "IOC_GPIO_15")
	)
	(segment
		(start 116.986812 -39.31285)
		(end 117.037104 -39.31285)
		(width 0.1143)
		(layer "F.Cu")
		(net "IOC_GPIO_15")
	)
	(segment
		(start 117.830346 -37.51072)
		(end 117.848126 -37.49294)
		(width 0.1143)
		(layer "F.Cu")
		(net "IOC_GPIO_15")
	)
	(segment
		(start 116.479574 -40.142668)
		(end 116.479574 -39.820088)
		(width 0.1143)
		(layer "F.Cu")
		(net "IOC_GPIO_15")
	)
	(segment
		(start 114.075718 -41.399968)
		(end 114.114326 -41.36136)
		(width 0.1143)
		(layer "F.Cu")
		(net "IOC_GPIO_15")
	)
	(segment
		(start 113.949988 -41.399968)
		(end 114.075718 -41.399968)
		(width 0.1143)
		(layer "F.Cu")
		(net "IOC_GPIO_15")
	)
	(segment
		(start 114.114326 -41.36136)
		(end 115.260882 -41.36136)
		(width 0.1143)
		(layer "F.Cu")
		(net "IOC_GPIO_15")
	)
	(segment
		(start 116.479574 -39.820088)
		(end 116.986812 -39.31285)
		(width 0.1143)
		(layer "F.Cu")
		(net "IOC_GPIO_15")
	)
	(segment
		(start 115.260882 -41.36136)
		(end 116.479574 -40.142668)
		(width 0.1143)
		(layer "F.Cu")
		(net "IOC_GPIO_15")
	)
	(via
		(at 117.848126 -37.49294)
		(size 0.508)
		(drill 0.254)
		(layers "F.Cu" "B.Cu")
		(net "IOC_GPIO_15")
	)
	(segment
		(start 117.848126 -38.735)
		(end 117.848126 -37.49294)
		(width 0.1143)
		(layer "B.Cu")
		(net "IOC_GPIO_15")
	)
	(segment
		(start 117.475 -39.116)
		(end 117.475 -39.108126)
		(width 0.1143)
		(layer "B.Cu")
		(net "IOC_GPIO_15")
	)
	(segment
		(start 117.475 -39.108126)
		(end 117.848126 -38.735)
		(width 0.1143)
		(layer "B.Cu")
		(net "IOC_GPIO_15")
	)
	(segment
		(start 114.342926 -36.599876)
		(end 115.297966 -35.644836)
		(width 0.1143)
		(layer "F.Cu")
		(net "IOC_GPIO_16")
	)
	(segment
		(start 113.949988 -36.599876)
		(end 114.342926 -36.599876)
		(width 0.1143)
		(layer "F.Cu")
		(net "IOC_GPIO_16")
	)
	(via
		(at 115.297966 -35.644836)
		(size 0.508)
		(drill 0.254)
		(layers "F.Cu" "B.Cu")
		(net "IOC_GPIO_16")
	)
	(segment
		(start 116.420646 -34.991548)
		(end 116.003832 -34.991548)
		(width 0.1143)
		(layer "B.Cu")
		(net "IOC_GPIO_16")
	)
	(segment
		(start 116.003832 -34.991548)
		(end 115.350544 -35.644836)
		(width 0.1143)
		(layer "B.Cu")
		(net "IOC_GPIO_16")
	)
	(segment
		(start 115.350544 -35.644836)
		(end 115.297966 -35.644836)
		(width 0.1143)
		(layer "B.Cu")
		(net "IOC_GPIO_16")
	)
	(segment
		(start 201.37755 -141.33195)
		(end 199.68845 -141.33195)
		(width 0.1143)
		(layer "F.Cu")
		(net "EXP_EEPROM_A1")
	)
	(segment
		(start 195.956936 -140.586714)
		(end 197.612 -140.586714)
		(width 0.1143)
		(layer "F.Cu")
		(net "EXP_EEPROM_A1")
	)
	(segment
		(start 198.943214 -140.586714)
		(end 197.612 -140.586714)
		(width 0.1143)
		(layer "F.Cu")
		(net "EXP_EEPROM_A1")
	)
	(segment
		(start 198.9455 -140.589)
		(end 198.943214 -140.586714)
		(width 0.1143)
		(layer "F.Cu")
		(net "EXP_EEPROM_A1")
	)
	(segment
		(start 202.1205 -140.589)
		(end 201.37755 -141.33195)
		(width 0.1143)
		(layer "F.Cu")
		(net "EXP_EEPROM_A1")
	)
	(segment
		(start 199.68845 -141.33195)
		(end 198.9455 -140.589)
		(width 0.1143)
		(layer "F.Cu")
		(net "EXP_EEPROM_A1")
	)
	(via
		(at 197.612 -140.586714)
		(size 0.7112)
		(drill 0.3556)
		(layers "F.Cu" "B.Cu")
		(net "EXP_EEPROM_A1")
	)
	(segment
		(start 190.876936 -143.126714)
		(end 190.864998 -143.138652)
		(width 0.1143)
		(layer "F.Cu")
		(net "EXP_EEPROM_SDA")
	)
	(segment
		(start 190.864998 -143.138652)
		(end 188.985652 -143.138652)
		(width 0.1143)
		(layer "F.Cu")
		(net "EXP_EEPROM_SDA")
	)
	(segment
		(start 188.966348 -143.138652)
		(end 188.976 -143.129)
		(width 0.1143)
		(layer "F.Cu")
		(net "EXP_EEPROM_SDA")
	)
	(segment
		(start 188.985652 -143.138652)
		(end 188.976 -143.129)
		(width 0.1143)
		(layer "F.Cu")
		(net "EXP_EEPROM_SDA")
	)
	(segment
		(start 187.887356 -143.138652)
		(end 188.966348 -143.138652)
		(width 0.1143)
		(layer "F.Cu")
		(net "EXP_EEPROM_SDA")
	)
	(via
		(at 188.976 -143.129)
		(size 0.7112)
		(drill 0.3556)
		(layers "F.Cu" "B.Cu")
		(net "EXP_EEPROM_SDA")
	)
	(segment
		(start 94.750128 -44.609512)
		(end 94.35719 -45.00245)
		(width 0.1143)
		(layer "F.Cu")
		(net "SIO_DIN_0")
	)
	(segment
		(start 94.750128 -44.59986)
		(end 94.750128 -44.609512)
		(width 0.1143)
		(layer "F.Cu")
		(net "SIO_DIN_0")
	)
	(via
		(at 94.35719 -45.00245)
		(size 0.508)
		(drill 0.254)
		(layers "F.Cu" "B.Cu")
		(net "SIO_DIN_0")
	)
	(segment
		(start 88.104726 -46.863)
		(end 88.91016 -46.863)
		(width 0.1143)
		(layer "B.Cu")
		(net "SIO_DIN_0")
	)
	(segment
		(start 89.770966 -46.863)
		(end 88.91016 -46.863)
		(width 0.1143)
		(layer "B.Cu")
		(net "SIO_DIN_0")
	)
	(segment
		(start 94.35719 -45.00245)
		(end 94.298516 -45.00245)
		(width 0.1143)
		(layer "B.Cu")
		(net "SIO_DIN_0")
	)
	(segment
		(start 86.532466 -48.006)
		(end 87.618316 -46.92015)
		(width 0.1143)
		(layer "B.Cu")
		(net "SIO_DIN_0")
	)
	(segment
		(start 88.047576 -46.92015)
		(end 88.104726 -46.863)
		(width 0.1143)
		(layer "B.Cu")
		(net "SIO_DIN_0")
	)
	(segment
		(start 94.298516 -45.00245)
		(end 91.929966 -47.371)
		(width 0.1143)
		(layer "B.Cu")
		(net "SIO_DIN_0")
	)
	(segment
		(start 90.278966 -47.371)
		(end 89.770966 -46.863)
		(width 0.1143)
		(layer "B.Cu")
		(net "SIO_DIN_0")
	)
	(segment
		(start 91.929966 -47.371)
		(end 90.278966 -47.371)
		(width 0.1143)
		(layer "B.Cu")
		(net "SIO_DIN_0")
	)
	(segment
		(start 87.618316 -46.92015)
		(end 88.047576 -46.92015)
		(width 0.1143)
		(layer "B.Cu")
		(net "SIO_DIN_0")
	)
	(segment
		(start 113.652046 -43.457114)
		(end 113.309146 -43.800014)
		(width 0.1143)
		(layer "F.Cu")
		(net "IOC_SDA_3")
	)
	(segment
		(start 118.2624 -41.148)
		(end 118.218966 -41.148)
		(width 0.1143)
		(layer "F.Cu")
		(net "IOC_SDA_3")
	)
	(segment
		(start 117.025166 -41.785286)
		(end 117.025166 -41.879012)
		(width 0.1143)
		(layer "F.Cu")
		(net "IOC_SDA_3")
	)
	(segment
		(start 115.293648 -43.457114)
		(end 113.652046 -43.457114)
		(width 0.1143)
		(layer "F.Cu")
		(net "IOC_SDA_3")
	)
	(segment
		(start 117.825266 -41.5417)
		(end 117.268752 -41.5417)
		(width 0.1143)
		(layer "F.Cu")
		(net "IOC_SDA_3")
	)
	(segment
		(start 118.218966 -41.148)
		(end 117.825266 -41.5417)
		(width 0.1143)
		(layer "F.Cu")
		(net "IOC_SDA_3")
	)
	(segment
		(start 116.507768 -42.39641)
		(end 116.354352 -42.39641)
		(width 0.1143)
		(layer "F.Cu")
		(net "IOC_SDA_3")
	)
	(segment
		(start 117.025166 -41.879012)
		(end 116.507768 -42.39641)
		(width 0.1143)
		(layer "F.Cu")
		(net "IOC_SDA_3")
	)
	(segment
		(start 116.354352 -42.39641)
		(end 115.293648 -43.457114)
		(width 0.1143)
		(layer "F.Cu")
		(net "IOC_SDA_3")
	)
	(segment
		(start 113.309146 -43.800014)
		(end 113.150142 -43.800014)
		(width 0.1143)
		(layer "F.Cu")
		(net "IOC_SDA_3")
	)
	(segment
		(start 117.268752 -41.5417)
		(end 117.025166 -41.785286)
		(width 0.1143)
		(layer "F.Cu")
		(net "IOC_SDA_3")
	)
	(via
		(at 118.2624 -41.148)
		(size 0.5588)
		(drill 0.3048)
		(layers "F.Cu" "B.Cu")
		(net "IOC_SDA_3")
	)
	(via
		(at 117.475 -41.656)
		(size 0.7112)
		(drill 0.3556)
		(layers "F.Cu" "B.Cu")
		(net "IOC_SDA_3")
	)
	(segment
		(start 119.5705 -41.148)
		(end 118.2624 -41.148)
		(width 0.1143)
		(layer "B.Cu")
		(net "IOC_SDA_3")
	)
	(segment
		(start 117.983 -41.148)
		(end 117.475 -41.656)
		(width 0.1143)
		(layer "B.Cu")
		(net "IOC_SDA_3")
	)
	(segment
		(start 118.2624 -41.148)
		(end 117.983 -41.148)
		(width 0.1143)
		(layer "B.Cu")
		(net "IOC_SDA_3")
	)
	(segment
		(start 129.716022 -90.069162)
		(end 129.678684 -90.032078)
		(width 0.1016)
		(layer "F.Cu")
		(net "3X24_SAS_TX18_N")
	)
	(segment
		(start 130.7338 -90.2589)
		(end 130.174746 -90.2589)
		(width 0.1016)
		(layer "F.Cu")
		(net "3X24_SAS_TX18_N")
	)
	(segment
		(start 129.654046 -90.02141)
		(end 128.820926 -90.02141)
		(width 0.1016)
		(layer "F.Cu")
		(net "3X24_SAS_TX18_N")
	)
	(segment
		(start 128.768348 -89.968832)
		(end 127.73406 -89.968832)
		(width 0.1016)
		(layer "F.Cu")
		(net "3X24_SAS_TX18_N")
	)
	(segment
		(start 129.678684 -90.032078)
		(end 129.67843 -90.03157)
		(width 0.1016)
		(layer "F.Cu")
		(net "3X24_SAS_TX18_N")
	)
	(segment
		(start 127.293116 -89.786206)
		(end 127.048768 -89.786206)
		(width 0.1016)
		(layer "F.Cu")
		(net "3X24_SAS_TX18_N")
	)
	(segment
		(start 131.0386 -90.424)
		(end 130.972306 -90.357706)
		(width 0.1016)
		(layer "F.Cu")
		(net "3X24_SAS_TX18_N")
	)
	(segment
		(start 128.820926 -90.02141)
		(end 128.768348 -89.968832)
		(width 0.1016)
		(layer "F.Cu")
		(net "3X24_SAS_TX18_N")
	)
	(segment
		(start 126.600712 -89.600786)
		(end 126.350014 -89.349834)
		(width 0.1016)
		(layer "F.Cu")
		(net "3X24_SAS_TX18_N")
	)
	(arc
		(start 130.174746 -90.2589)
		(mid 129.926533 -90.209599)
		(end 129.716022 -90.069162)
		(width 0.1016)
		(layer "F.Cu")
		(net "3X24_SAS_TX18_N")
	)
	(arc
		(start 129.67843 -90.03157)
		(mid 129.667257 -90.024041)
		(end 129.654046 -90.02141)
		(width 0.1016)
		(layer "F.Cu")
		(net "3X24_SAS_TX18_N")
	)
	(arc
		(start 127.048768 -89.786206)
		(mid 126.806294 -89.738068)
		(end 126.600712 -89.600786)
		(width 0.1016)
		(layer "F.Cu")
		(net "3X24_SAS_TX18_N")
	)
	(arc
		(start 127.73406 -89.968832)
		(mid 127.525951 -89.927437)
		(end 127.349504 -89.809574)
		(width 0.1016)
		(layer "F.Cu")
		(net "3X24_SAS_TX18_N")
	)
	(arc
		(start 130.972306 -90.357706)
		(mid 130.862879 -90.284589)
		(end 130.7338 -90.2589)
		(width 0.1016)
		(layer "F.Cu")
		(net "3X24_SAS_TX18_N")
	)
	(arc
		(start 127.349504 -89.809574)
		(mid 127.323633 -89.792288)
		(end 127.293116 -89.786206)
		(width 0.1016)
		(layer "F.Cu")
		(net "3X24_SAS_TX18_N")
	)
	(segment
		(start 91.153234 -49.7967)
		(end 91.1479 -49.7967)
		(width 0.1143)
		(layer "F.Cu")
		(net "SIO_DOUT_0")
	)
	(segment
		(start 91.549982 -49.399952)
		(end 91.153234 -49.7967)
		(width 0.1143)
		(layer "F.Cu")
		(net "SIO_DOUT_0")
	)
	(via
		(at 91.1479 -49.7967)
		(size 0.508)
		(drill 0.254)
		(layers "F.Cu" "B.Cu")
		(net "SIO_DOUT_0")
	)
	(segment
		(start 90.81516 -52.5145)
		(end 90.68816 -52.6415)
		(width 0.1143)
		(layer "B.Cu")
		(net "SIO_DOUT_0")
	)
	(segment
		(start 90.81516 -50.12944)
		(end 90.81516 -50.673)
		(width 0.1143)
		(layer "B.Cu")
		(net "SIO_DOUT_0")
	)
	(segment
		(start 91.1479 -49.7967)
		(end 90.81516 -50.12944)
		(width 0.1143)
		(layer "B.Cu")
		(net "SIO_DOUT_0")
	)
	(segment
		(start 90.81516 -50.673)
		(end 90.81516 -52.5145)
		(width 0.1143)
		(layer "B.Cu")
		(net "SIO_DOUT_0")
	)
	(segment
		(start 198.8185 -138.811)
		(end 199.7329 -139.7254)
		(width 0.1143)
		(layer "F.Cu")
		(net "EXP_EEPROM_A0")
	)
	(segment
		(start 197.612 -139.319)
		(end 198.3105 -139.319)
		(width 0.1143)
		(layer "F.Cu")
		(net "EXP_EEPROM_A0")
	)
	(segment
		(start 195.956936 -139.316714)
		(end 195.959222 -139.319)
		(width 0.1143)
		(layer "F.Cu")
		(net "EXP_EEPROM_A0")
	)
	(segment
		(start 199.7329 -139.7254)
		(end 201.2061 -139.7254)
		(width 0.1143)
		(layer "F.Cu")
		(net "EXP_EEPROM_A0")
	)
	(segment
		(start 195.959222 -139.319)
		(end 197.612 -139.319)
		(width 0.1143)
		(layer "F.Cu")
		(net "EXP_EEPROM_A0")
	)
	(segment
		(start 201.2061 -139.7254)
		(end 202.1205 -138.811)
		(width 0.1143)
		(layer "F.Cu")
		(net "EXP_EEPROM_A0")
	)
	(segment
		(start 198.3105 -139.319)
		(end 198.8185 -138.811)
		(width 0.1143)
		(layer "F.Cu")
		(net "EXP_EEPROM_A0")
	)
	(via
		(at 197.612 -139.319)
		(size 0.7112)
		(drill 0.3556)
		(layers "F.Cu" "B.Cu")
		(net "EXP_EEPROM_A0")
	)
	(segment
		(start 97.5995 -70.40753)
		(end 97.5995 -68.88353)
		(width 0.1143)
		(layer "F.Cu")
		(net "PWRGD_P0V955_C")
	)
	(segment
		(start 96.20123 -71.8058)
		(end 97.5995 -70.40753)
		(width 0.1143)
		(layer "F.Cu")
		(net "PWRGD_P0V955_C")
	)
	(segment
		(start 101.18725 -60.496196)
		(end 101.18725 -60.16625)
		(width 0.1143)
		(layer "F.Cu")
		(net "PWRGD_P0V955_C")
	)
	(segment
		(start 90.2208 -72.39)
		(end 90.805 -71.8058)
		(width 0.1143)
		(layer "F.Cu")
		(net "PWRGD_P0V955_C")
	)
	(segment
		(start 98.660966 -66.058034)
		(end 98.425 -66.294)
		(width 0.1143)
		(layer "F.Cu")
		(net "PWRGD_P0V955_C")
	)
	(segment
		(start 100.369116 -56.618886)
		(end 100.350066 -56.599836)
		(width 0.1143)
		(layer "F.Cu")
		(net "PWRGD_P0V955_C")
	)
	(segment
		(start 100.369116 -59.348116)
		(end 100.369116 -56.618886)
		(width 0.1143)
		(layer "F.Cu")
		(net "PWRGD_P0V955_C")
	)
	(segment
		(start 83.312 -72.39)
		(end 90.2208 -72.39)
		(width 0.1143)
		(layer "F.Cu")
		(net "PWRGD_P0V955_C")
	)
	(segment
		(start 101.473 -61.087)
		(end 101.473 -60.781946)
		(width 0.1143)
		(layer "F.Cu")
		(net "PWRGD_P0V955_C")
	)
	(segment
		(start 97.625916 -67.354196)
		(end 98.425 -66.555112)
		(width 0.1143)
		(layer "F.Cu")
		(net "PWRGD_P0V955_C")
	)
	(segment
		(start 98.425 -66.555112)
		(end 98.425 -66.294)
		(width 0.1143)
		(layer "F.Cu")
		(net "PWRGD_P0V955_C")
	)
	(segment
		(start 97.5995 -68.88353)
		(end 97.625916 -68.857114)
		(width 0.1143)
		(layer "F.Cu")
		(net "PWRGD_P0V955_C")
	)
	(segment
		(start 101.18725 -60.16625)
		(end 100.369116 -59.348116)
		(width 0.1143)
		(layer "F.Cu")
		(net "PWRGD_P0V955_C")
	)
	(segment
		(start 101.473 -60.781946)
		(end 101.18725 -60.496196)
		(width 0.1143)
		(layer "F.Cu")
		(net "PWRGD_P0V955_C")
	)
	(segment
		(start 90.805 -71.8058)
		(end 96.20123 -71.8058)
		(width 0.1143)
		(layer "F.Cu")
		(net "PWRGD_P0V955_C")
	)
	(segment
		(start 98.660966 -65.1383)
		(end 98.660966 -66.058034)
		(width 0.1143)
		(layer "F.Cu")
		(net "PWRGD_P0V955_C")
	)
	(segment
		(start 97.625916 -68.857114)
		(end 97.625916 -67.354196)
		(width 0.1143)
		(layer "F.Cu")
		(net "PWRGD_P0V955_C")
	)
	(via
		(at 83.312 -72.39)
		(size 0.5588)
		(drill 0.3048)
		(layers "F.Cu" "B.Cu")
		(net "PWRGD_P0V955_C")
	)
	(via
		(at 101.473 -61.087)
		(size 0.5588)
		(drill 0.3048)
		(layers "F.Cu" "B.Cu")
		(net "PWRGD_P0V955_C")
	)
	(via
		(at 99.187 -63.5)
		(size 0.7112)
		(drill 0.3556)
		(layers "F.Cu" "B.Cu")
		(net "PWRGD_P0V955_C")
	)
	(via
		(at 98.425 -66.294)
		(size 0.5588)
		(drill 0.3048)
		(layers "F.Cu" "B.Cu")
		(net "PWRGD_P0V955_C")
	)
	(segment
		(start 83.312 -72.263)
		(end 83.312 -72.39)
		(width 0.1143)
		(layer "B.Cu")
		(net "PWRGD_P0V955_C")
	)
	(segment
		(start 82.6135 -72.4535)
		(end 82.931 -72.136)
		(width 0.1143)
		(layer "B.Cu")
		(net "PWRGD_P0V955_C")
	)
	(segment
		(start 101.473 -61.087)
		(end 101.346 -61.214)
		(width 0.1143)
		(layer "B.Cu")
		(net "PWRGD_P0V955_C")
	)
	(segment
		(start 98.425 -66.294)
		(end 98.425 -64.262)
		(width 0.1143)
		(layer "B.Cu")
		(net "PWRGD_P0V955_C")
	)
	(segment
		(start 100.8507 -61.214)
		(end 99.695 -62.3697)
		(width 0.1143)
		(layer "B.Cu")
		(net "PWRGD_P0V955_C")
	)
	(segment
		(start 99.695 -62.3697)
		(end 99.695 -62.992)
		(width 0.1143)
		(layer "B.Cu")
		(net "PWRGD_P0V955_C")
	)
	(segment
		(start 82.931 -72.136)
		(end 83.185 -72.136)
		(width 0.1143)
		(layer "B.Cu")
		(net "PWRGD_P0V955_C")
	)
	(segment
		(start 83.185 -72.136)
		(end 83.312 -72.263)
		(width 0.1143)
		(layer "B.Cu")
		(net "PWRGD_P0V955_C")
	)
	(segment
		(start 99.695 -62.992)
		(end 99.187 -63.5)
		(width 0.1143)
		(layer "B.Cu")
		(net "PWRGD_P0V955_C")
	)
	(segment
		(start 82.05724 -72.4535)
		(end 82.6135 -72.4535)
		(width 0.1143)
		(layer "B.Cu")
		(net "PWRGD_P0V955_C")
	)
	(segment
		(start 101.346 -61.214)
		(end 100.8507 -61.214)
		(width 0.1143)
		(layer "B.Cu")
		(net "PWRGD_P0V955_C")
	)
	(segment
		(start 98.425 -64.262)
		(end 99.187 -63.5)
		(width 0.1143)
		(layer "B.Cu")
		(net "PWRGD_P0V955_C")
	)
	(segment
		(start 56.547512 -132.380482)
		(end 54.648862 -132.380482)
		(width 0.1143)
		(layer "F.Cu")
		(net "EXP_WP_N")
	)
	(segment
		(start 56.558942 -132.391912)
		(end 56.547512 -132.380482)
		(width 0.1143)
		(layer "F.Cu")
		(net "EXP_WP_N")
	)
	(segment
		(start 54.648862 -132.380482)
		(end 53.663342 -132.380482)
		(width 0.1143)
		(layer "F.Cu")
		(net "EXP_WP_N")
	)
	(via
		(at 54.648862 -132.380482)
		(size 0.7112)
		(drill 0.3556)
		(layers "F.Cu" "B.Cu")
		(net "EXP_WP_N")
	)
	(segment
		(start 189.093348 -141.868652)
		(end 189.103 -141.859)
		(width 0.1143)
		(layer "F.Cu")
		(net "EXP_EEPROM_SCL")
	)
	(segment
		(start 189.867286 -141.856714)
		(end 189.865 -141.859)
		(width 0.1143)
		(layer "F.Cu")
		(net "EXP_EEPROM_SCL")
	)
	(segment
		(start 189.865 -141.859)
		(end 189.103 -141.859)
		(width 0.1143)
		(layer "F.Cu")
		(net "EXP_EEPROM_SCL")
	)
	(segment
		(start 187.887356 -141.868652)
		(end 189.093348 -141.868652)
		(width 0.1143)
		(layer "F.Cu")
		(net "EXP_EEPROM_SCL")
	)
	(segment
		(start 190.876936 -141.856714)
		(end 189.867286 -141.856714)
		(width 0.1143)
		(layer "F.Cu")
		(net "EXP_EEPROM_SCL")
	)
	(via
		(at 189.103 -141.859)
		(size 0.7112)
		(drill 0.3556)
		(layers "F.Cu" "B.Cu")
		(net "EXP_EEPROM_SCL")
	)
	(segment
		(start 92.34043 -47.800006)
		(end 91.944698 -48.195738)
		(width 0.1143)
		(layer "F.Cu")
		(net "SIO_LOAD_0")
	)
	(segment
		(start 92.350082 -47.800006)
		(end 92.34043 -47.800006)
		(width 0.1143)
		(layer "F.Cu")
		(net "SIO_LOAD_0")
	)
	(via
		(at 91.944698 -48.195738)
		(size 0.508)
		(drill 0.254)
		(layers "F.Cu" "B.Cu")
		(net "SIO_LOAD_0")
	)
	(segment
		(start 91.04376 -48.237394)
		(end 91.04376 -48.0822)
		(width 0.1143)
		(layer "B.Cu")
		(net "SIO_LOAD_0")
	)
	(segment
		(start 91.866466 -50.644806)
		(end 91.701366 -50.479706)
		(width 0.1143)
		(layer "B.Cu")
		(net "SIO_LOAD_0")
	)
	(segment
		(start 91.944698 -48.195738)
		(end 91.83116 -48.0822)
		(width 0.1143)
		(layer "B.Cu")
		(net "SIO_LOAD_0")
	)
	(segment
		(start 91.701366 -50.479706)
		(end 91.701366 -48.895)
		(width 0.1143)
		(layer "B.Cu")
		(net "SIO_LOAD_0")
	)
	(segment
		(start 91.701366 -48.895)
		(end 91.04376 -48.237394)
		(width 0.1143)
		(layer "B.Cu")
		(net "SIO_LOAD_0")
	)
	(segment
		(start 91.83116 -48.0822)
		(end 91.04376 -48.0822)
		(width 0.1143)
		(layer "B.Cu")
		(net "SIO_LOAD_0")
	)
	(segment
		(start 112.752886 -46.60392)
		(end 112.755426 -46.60392)
		(width 0.1143)
		(layer "F.Cu")
		(net "IOC_SCL_3")
	)
	(segment
		(start 112.350042 -46.199806)
		(end 112.350042 -46.201076)
		(width 0.1143)
		(layer "F.Cu")
		(net "IOC_SCL_3")
	)
	(segment
		(start 112.350042 -46.201076)
		(end 112.752886 -46.60392)
		(width 0.1143)
		(layer "F.Cu")
		(net "IOC_SCL_3")
	)
	(via
		(at 112.755426 -46.60392)
		(size 0.508)
		(drill 0.254)
		(layers "F.Cu" "B.Cu")
		(net "IOC_SCL_3")
	)
	(via
		(at 115.678966 -47.117)
		(size 0.7112)
		(drill 0.3556)
		(layers "F.Cu" "B.Cu")
		(net "IOC_SCL_3")
	)
	(segment
		(start 113.014506 -46.863)
		(end 113.837466 -46.863)
		(width 0.1143)
		(layer "B.Cu")
		(net "IOC_SCL_3")
	)
	(segment
		(start 113.837466 -46.863)
		(end 113.837466 -47.0535)
		(width 0.1143)
		(layer "B.Cu")
		(net "IOC_SCL_3")
	)
	(segment
		(start 115.297966 -47.498)
		(end 115.678966 -47.117)
		(width 0.1143)
		(layer "B.Cu")
		(net "IOC_SCL_3")
	)
	(segment
		(start 113.837466 -47.0535)
		(end 114.281966 -47.498)
		(width 0.1143)
		(layer "B.Cu")
		(net "IOC_SCL_3")
	)
	(segment
		(start 114.281966 -47.498)
		(end 115.297966 -47.498)
		(width 0.1143)
		(layer "B.Cu")
		(net "IOC_SCL_3")
	)
	(segment
		(start 112.755426 -46.60392)
		(end 113.014506 -46.863)
		(width 0.1143)
		(layer "B.Cu")
		(net "IOC_SCL_3")
	)
	(segment
		(start 94.27337 -117.856)
		(end 94.01937 -117.602)
		(width 0.1143)
		(layer "F.Cu")
		(net "SIO_LOAD_OUT")
	)
	(segment
		(start 95.26397 -117.856)
		(end 94.27337 -117.856)
		(width 0.1143)
		(layer "F.Cu")
		(net "SIO_LOAD_OUT")
	)
	(segment
		(start 96.363282 -114.540792)
		(end 97.907602 -114.540792)
		(width 0.1143)
		(layer "F.Cu")
		(net "SIO_LOAD_OUT")
	)
	(segment
		(start 94.01937 -117.602)
		(end 94.01937 -116.80571)
		(width 0.1143)
		(layer "F.Cu")
		(net "SIO_LOAD_OUT")
	)
	(segment
		(start 108.349796 -98.35007)
		(end 107.84967 -98.850196)
		(width 0.1143)
		(layer "F.Cu")
		(net "SIO_LOAD_OUT")
	)
	(segment
		(start 94.01937 -116.80571)
		(end 96.363282 -114.540792)
		(width 0.1143)
		(layer "F.Cu")
		(net "SIO_LOAD_OUT")
	)
	(via
		(at 97.907602 -114.540792)
		(size 0.5588)
		(drill 0.3048)
		(layers "F.Cu" "B.Cu")
		(net "SIO_LOAD_OUT")
	)
	(via
		(at 107.84967 -98.850196)
		(size 0.508)
		(drill 0.254)
		(layers "F.Cu" "B.Cu")
		(net "SIO_LOAD_OUT")
	)
	(segment
		(start 99.630738 -115.0493)
		(end 100.041202 -115.0493)
		(width 0.127)
		(layer "In2.Cu")
		(net "SIO_LOAD_OUT")
	)
	(segment
		(start 100.041202 -115.0493)
		(end 100.33127 -114.759232)
		(width 0.127)
		(layer "In2.Cu")
		(net "SIO_LOAD_OUT")
	)
	(segment
		(start 100.33127 -114.42573)
		(end 102.3366 -112.4204)
		(width 0.127)
		(layer "In2.Cu")
		(net "SIO_LOAD_OUT")
	)
	(segment
		(start 98.071178 -114.540792)
		(end 98.18497 -114.427)
		(width 0.127)
		(layer "In2.Cu")
		(net "SIO_LOAD_OUT")
	)
	(segment
		(start 102.3366 -112.4204)
		(end 102.626922 -112.4204)
		(width 0.127)
		(layer "In2.Cu")
		(net "SIO_LOAD_OUT")
	)
	(segment
		(start 107.315 -99.384866)
		(end 107.84967 -98.850196)
		(width 0.127)
		(layer "In2.Cu")
		(net "SIO_LOAD_OUT")
	)
	(segment
		(start 106.802174 -105.033826)
		(end 107.315 -104.521)
		(width 0.127)
		(layer "In2.Cu")
		(net "SIO_LOAD_OUT")
	)
	(segment
		(start 99.008438 -114.427)
		(end 99.630738 -115.0493)
		(width 0.127)
		(layer "In2.Cu")
		(net "SIO_LOAD_OUT")
	)
	(segment
		(start 102.626922 -112.4204)
		(end 106.802174 -108.245148)
		(width 0.127)
		(layer "In2.Cu")
		(net "SIO_LOAD_OUT")
	)
	(segment
		(start 107.315 -104.521)
		(end 107.315 -99.384866)
		(width 0.127)
		(layer "In2.Cu")
		(net "SIO_LOAD_OUT")
	)
	(segment
		(start 106.802174 -108.245148)
		(end 106.802174 -105.033826)
		(width 0.127)
		(layer "In2.Cu")
		(net "SIO_LOAD_OUT")
	)
	(segment
		(start 97.907602 -114.540792)
		(end 98.071178 -114.540792)
		(width 0.127)
		(layer "In2.Cu")
		(net "SIO_LOAD_OUT")
	)
	(segment
		(start 98.18497 -114.427)
		(end 99.008438 -114.427)
		(width 0.127)
		(layer "In2.Cu")
		(net "SIO_LOAD_OUT")
	)
	(segment
		(start 100.33127 -114.759232)
		(end 100.33127 -114.42573)
		(width 0.127)
		(layer "In2.Cu")
		(net "SIO_LOAD_OUT")
	)
	(segment
		(start 113.80216 -35.433)
		(end 114.037872 -35.433)
		(width 0.1143)
		(layer "F.Cu")
		(net "IOC_GPIO_18")
	)
	(segment
		(start 113.43513 -35.80003)
		(end 113.80216 -35.433)
		(width 0.1143)
		(layer "F.Cu")
		(net "IOC_GPIO_18")
	)
	(segment
		(start 114.814604 -34.656268)
		(end 114.814604 -34.644584)
		(width 0.1143)
		(layer "F.Cu")
		(net "IOC_GPIO_18")
	)
	(segment
		(start 115.804188 -33.655)
		(end 116.313966 -33.655)
		(width 0.1143)
		(layer "F.Cu")
		(net "IOC_GPIO_18")
	)
	(segment
		(start 114.037872 -35.433)
		(end 114.814604 -34.656268)
		(width 0.1143)
		(layer "F.Cu")
		(net "IOC_GPIO_18")
	)
	(segment
		(start 113.150142 -35.80003)
		(end 113.43513 -35.80003)
		(width 0.1143)
		(layer "F.Cu")
		(net "IOC_GPIO_18")
	)
	(segment
		(start 114.814604 -34.644584)
		(end 115.804188 -33.655)
		(width 0.1143)
		(layer "F.Cu")
		(net "IOC_GPIO_18")
	)
	(via
		(at 116.313966 -33.655)
		(size 0.508)
		(drill 0.254)
		(layers "F.Cu" "B.Cu")
		(net "IOC_GPIO_18")
	)
	(segment
		(start 116.821966 -32.639)
		(end 116.821966 -33.147)
		(width 0.1143)
		(layer "B.Cu")
		(net "IOC_GPIO_18")
	)
	(segment
		(start 116.821966 -33.147)
		(end 116.313966 -33.655)
		(width 0.1143)
		(layer "B.Cu")
		(net "IOC_GPIO_18")
	)
	(segment
		(start 98.05797 -117.856)
		(end 98.648266 -117.856)
		(width 0.1143)
		(layer "F.Cu")
		(net "SIO_LOAD_IN")
	)
	(segment
		(start 106.3498 -101.350064)
		(end 105.849674 -101.85019)
		(width 0.1143)
		(layer "F.Cu")
		(net "SIO_LOAD_IN")
	)
	(segment
		(start 98.648266 -117.856)
		(end 99.20097 -117.303296)
		(width 0.1143)
		(layer "F.Cu")
		(net "SIO_LOAD_IN")
	)
	(segment
		(start 99.20097 -117.303296)
		(end 99.20097 -115.697)
		(width 0.1143)
		(layer "F.Cu")
		(net "SIO_LOAD_IN")
	)
	(segment
		(start 99.20097 -114.274346)
		(end 99.20097 -115.697)
		(width 0.1143)
		(layer "F.Cu")
		(net "SIO_LOAD_IN")
	)
	(segment
		(start 99.83597 -113.6396)
		(end 99.20097 -114.274346)
		(width 0.1143)
		(layer "F.Cu")
		(net "SIO_LOAD_IN")
	)
	(via
		(at 105.849674 -101.85019)
		(size 0.508)
		(drill 0.254)
		(layers "F.Cu" "B.Cu")
		(net "SIO_LOAD_IN")
	)
	(via
		(at 99.83597 -113.6396)
		(size 0.5588)
		(drill 0.3048)
		(layers "F.Cu" "B.Cu")
		(net "SIO_LOAD_IN")
	)
	(segment
		(start 105.283 -102.416864)
		(end 105.849674 -101.85019)
		(width 0.127)
		(layer "In2.Cu")
		(net "SIO_LOAD_IN")
	)
	(segment
		(start 106.294174 -104.770174)
		(end 106.268774 -104.744774)
		(width 0.127)
		(layer "In2.Cu")
		(net "SIO_LOAD_IN")
	)
	(segment
		(start 105.283 -103.759)
		(end 105.283 -102.416864)
		(width 0.127)
		(layer "In2.Cu")
		(net "SIO_LOAD_IN")
	)
	(segment
		(start 106.02341 -104.431084)
		(end 105.955084 -104.431084)
		(width 0.127)
		(layer "In2.Cu")
		(net "SIO_LOAD_IN")
	)
	(segment
		(start 106.268774 -104.744774)
		(end 106.268774 -104.676448)
		(width 0.127)
		(layer "In2.Cu")
		(net "SIO_LOAD_IN")
	)
	(segment
		(start 106.294174 -108.034328)
		(end 106.294174 -104.770174)
		(width 0.127)
		(layer "In2.Cu")
		(net "SIO_LOAD_IN")
	)
	(segment
		(start 99.83597 -113.6396)
		(end 101.56317 -111.9124)
		(width 0.127)
		(layer "In2.Cu")
		(net "SIO_LOAD_IN")
	)
	(segment
		(start 101.56317 -111.9124)
		(end 102.416102 -111.9124)
		(width 0.127)
		(layer "In2.Cu")
		(net "SIO_LOAD_IN")
	)
	(segment
		(start 102.416102 -111.9124)
		(end 106.294174 -108.034328)
		(width 0.127)
		(layer "In2.Cu")
		(net "SIO_LOAD_IN")
	)
	(segment
		(start 106.268774 -104.676448)
		(end 106.02341 -104.431084)
		(width 0.127)
		(layer "In2.Cu")
		(net "SIO_LOAD_IN")
	)
	(segment
		(start 105.955084 -104.431084)
		(end 105.283 -103.759)
		(width 0.127)
		(layer "In2.Cu")
		(net "SIO_LOAD_IN")
	)
	(segment
		(start 90.750136 -48.599852)
		(end 90.327988 -49.022)
		(width 0.1143)
		(layer "F.Cu")
		(net "SIO_CLK_1")
	)
	(segment
		(start 89.621106 -49.022)
		(end 89.23528 -49.40808)
		(width 0.1143)
		(layer "F.Cu")
		(net "SIO_CLK_1")
	)
	(segment
		(start 90.327988 -49.022)
		(end 89.621106 -49.022)
		(width 0.1143)
		(layer "F.Cu")
		(net "SIO_CLK_1")
	)
	(via
		(at 89.23528 -49.40808)
		(size 0.508)
		(drill 0.254)
		(layers "F.Cu" "B.Cu")
		(net "SIO_CLK_1")
	)
	(segment
		(start 88.77808 -49.40808)
		(end 87.865966 -50.320194)
		(width 0.1143)
		(layer "B.Cu")
		(net "SIO_CLK_1")
	)
	(segment
		(start 87.38616 -51.689)
		(end 87.76716 -51.308)
		(width 0.1143)
		(layer "B.Cu")
		(net "SIO_CLK_1")
	)
	(segment
		(start 87.865966 -51.209194)
		(end 87.76716 -51.308)
		(width 0.1143)
		(layer "B.Cu")
		(net "SIO_CLK_1")
	)
	(segment
		(start 89.23528 -49.40808)
		(end 88.77808 -49.40808)
		(width 0.1143)
		(layer "B.Cu")
		(net "SIO_CLK_1")
	)
	(segment
		(start 87.865966 -50.320194)
		(end 87.865966 -51.209194)
		(width 0.1143)
		(layer "B.Cu")
		(net "SIO_CLK_1")
	)
	(segment
		(start 87.38616 -52.6415)
		(end 87.38616 -51.689)
		(width 0.1143)
		(layer "B.Cu")
		(net "SIO_CLK_1")
	)
	(segment
		(start 113.349786 -96.350074)
		(end 112.84966 -96.8502)
		(width 0.4572)
		(layer "F.Cu")
		(net "P0V9_E")
	)
	(segment
		(start 161.4805 -116.09705)
		(end 161.37255 -116.205)
		(width 0.508)
		(layer "F.Cu")
		(net "P0V9_E")
	)
	(segment
		(start 111.34979 -96.350074)
		(end 110.849664 -96.8502)
		(width 0.4572)
		(layer "F.Cu")
		(net "P0V9_E")
	)
	(segment
		(start 113.849658 -92.8497)
		(end 113.349786 -92.349828)
		(width 0.4572)
		(layer "F.Cu")
		(net "P0V9_E")
	)
	(segment
		(start 114.349784 -97.350072)
		(end 113.849658 -97.850198)
		(width 0.4572)
		(layer "F.Cu")
		(net "P0V9_E")
	)
	(segment
		(start 115.350036 -96.350074)
		(end 115.850162 -96.8502)
		(width 0.4572)
		(layer "F.Cu")
		(net "P0V9_E")
	)
	(segment
		(start 112.349788 -97.350072)
		(end 112.84966 -96.8502)
		(width 0.4572)
		(layer "F.Cu")
		(net "P0V9_E")
	)
	(segment
		(start 161.4805 -115.062)
		(end 161.4805 -116.09705)
		(width 0.508)
		(layer "F.Cu")
		(net "P0V9_E")
	)
	(segment
		(start 116.350034 -93.349826)
		(end 116.85016 -92.8497)
		(width 0.4572)
		(layer "F.Cu")
		(net "P0V9_E")
	)
	(segment
		(start 114.349784 -93.349826)
		(end 113.849658 -92.8497)
		(width 0.4572)
		(layer "F.Cu")
		(net "P0V9_E")
	)
	(segment
		(start 115.350036 -94.349824)
		(end 115.850162 -93.849698)
		(width 0.4572)
		(layer "F.Cu")
		(net "P0V9_E")
	)
	(segment
		(start 116.350034 -91.34983)
		(end 116.85016 -90.849704)
		(width 0.4572)
		(layer "F.Cu")
		(net "P0V9_E")
	)
	(segment
		(start 114.349784 -95.350076)
		(end 113.849658 -95.850202)
		(width 0.4572)
		(layer "F.Cu")
		(net "P0V9_E")
	)
	(segment
		(start 113.349786 -94.349824)
		(end 112.84966 -93.849698)
		(width 0.4572)
		(layer "F.Cu")
		(net "P0V9_E")
	)
	(segment
		(start 117.350032 -96.350074)
		(end 117.850158 -96.8502)
		(width 0.4572)
		(layer "F.Cu")
		(net "P0V9_E")
	)
	(segment
		(start 117.350032 -94.349824)
		(end 117.850158 -93.849698)
		(width 0.4572)
		(layer "F.Cu")
		(net "P0V9_E")
	)
	(segment
		(start 117.350032 -90.349832)
		(end 116.85016 -90.849704)
		(width 0.4572)
		(layer "F.Cu")
		(net "P0V9_E")
	)
	(segment
		(start 111.34979 -94.349824)
		(end 110.849664 -93.849698)
		(width 0.4572)
		(layer "F.Cu")
		(net "P0V9_E")
	)
	(segment
		(start 113.349786 -98.35007)
		(end 112.84966 -98.850196)
		(width 0.4572)
		(layer "F.Cu")
		(net "P0V9_E")
	)
	(segment
		(start 111.34979 -90.349832)
		(end 110.849664 -89.849706)
		(width 0.4572)
		(layer "F.Cu")
		(net "P0V9_E")
	)
	(segment
		(start 112.349788 -93.349826)
		(end 111.849662 -92.8497)
		(width 0.4572)
		(layer "F.Cu")
		(net "P0V9_E")
	)
	(segment
		(start 113.349786 -92.349828)
		(end 112.349788 -91.34983)
		(width 0.4572)
		(layer "F.Cu")
		(net "P0V9_E")
	)
	(segment
		(start 115.350036 -92.349828)
		(end 115.850162 -91.849702)
		(width 0.4572)
		(layer "F.Cu")
		(net "P0V9_E")
	)
	(segment
		(start 117.350032 -92.349828)
		(end 117.850158 -91.849702)
		(width 0.4572)
		(layer "F.Cu")
		(net "P0V9_E")
	)
	(segment
		(start 116.350034 -97.350072)
		(end 116.85016 -97.850198)
		(width 0.4572)
		(layer "F.Cu")
		(net "P0V9_E")
	)
	(segment
		(start 111.34979 -92.349828)
		(end 110.849664 -91.849702)
		(width 0.4572)
		(layer "F.Cu")
		(net "P0V9_E")
	)
	(segment
		(start 114.349784 -91.34983)
		(end 113.849658 -90.849704)
		(width 0.4572)
		(layer "F.Cu")
		(net "P0V9_E")
	)
	(segment
		(start 115.350036 -98.35007)
		(end 115.850162 -98.850196)
		(width 0.4572)
		(layer "F.Cu")
		(net "P0V9_E")
	)
	(segment
		(start 117.350032 -98.35007)
		(end 117.850158 -98.850196)
		(width 0.4572)
		(layer "F.Cu")
		(net "P0V9_E")
	)
	(segment
		(start 112.349788 -91.34983)
		(end 111.849662 -90.849704)
		(width 0.4572)
		(layer "F.Cu")
		(net "P0V9_E")
	)
	(segment
		(start 115.350036 -90.349832)
		(end 115.850162 -89.849706)
		(width 0.4572)
		(layer "F.Cu")
		(net "P0V9_E")
	)
	(segment
		(start 113.349786 -90.349832)
		(end 112.84966 -89.849706)
		(width 0.4572)
		(layer "F.Cu")
		(net "P0V9_E")
	)
	(segment
		(start 116.350034 -95.350076)
		(end 116.85016 -95.850202)
		(width 0.4572)
		(layer "F.Cu")
		(net "P0V9_E")
	)
	(segment
		(start 112.349788 -95.350076)
		(end 111.849662 -95.850202)
		(width 0.4572)
		(layer "F.Cu")
		(net "P0V9_E")
	)
	(segment
		(start 111.34979 -98.35007)
		(end 110.849664 -98.850196)
		(width 0.4572)
		(layer "F.Cu")
		(net "P0V9_E")
	)
	(via
		(at 168.91 -93.599)
		(size 0.7112)
		(drill 0.4064)
		(layers "F.Cu" "B.Cu")
		(net "P0V9_E")
	)
	(via
		(at 133.61797 -138.176)
		(size 0.7112)
		(drill 0.4064)
		(layers "F.Cu" "B.Cu")
		(net "P0V9_E")
	)
	(via
		(at 132.334 -133.096)
		(size 0.7112)
		(drill 0.4064)
		(layers "F.Cu" "B.Cu")
		(net "P0V9_E")
	)
	(via
		(at 169.291 -91.313)
		(size 0.7112)
		(drill 0.3556)
		(layers "F.Cu" "B.Cu")
		(net "P0V9_E")
	)
	(via
		(at 332.867 -158.75)
		(size 0.5588)
		(drill 0.3048)
		(layers "F.Cu" "B.Cu")
		(net "P0V9_E")
	)
	(via
		(at 73.133966 -90.551)
		(size 0.7112)
		(drill 0.3556)
		(layers "F.Cu" "B.Cu")
		(net "P0V9_E")
	)
	(via
		(at 132.34797 -138.176)
		(size 0.7112)
		(drill 0.4064)
		(layers "F.Cu" "B.Cu")
		(net "P0V9_E")
	)
	(via
		(at 115.850162 -98.850196)
		(size 0.508)
		(drill 0.254)
		(layers "F.Cu" "B.Cu")
		(net "P0V9_E")
	)
	(via
		(at 165.989 -93.599)
		(size 0.7112)
		(drill 0.4064)
		(layers "F.Cu" "B.Cu")
		(net "P0V9_E")
	)
	(via
		(at 163.068 -93.599)
		(size 0.7112)
		(drill 0.4064)
		(layers "F.Cu" "B.Cu")
		(net "P0V9_E")
	)
	(via
		(at 328.295 -185.541412)
		(size 0.508)
		(drill 0.254)
		(layers "F.Cu" "B.Cu")
		(net "P0V9_E")
	)
	(via
		(at 156.0068 -108.839)
		(size 0.7112)
		(drill 0.4064)
		(layers "F.Cu" "B.Cu")
		(net "P0V9_E")
	)
	(via
		(at 131.20497 -138.049)
		(size 0.7112)
		(drill 0.4064)
		(layers "F.Cu" "B.Cu")
		(net "P0V9_E")
	)
	(via
		(at 153.035 -119.4054)
		(size 0.7112)
		(drill 0.4064)
		(layers "F.Cu" "B.Cu")
		(net "P0V9_E")
	)
	(via
		(at 156.0068 -107.188)
		(size 0.7112)
		(drill 0.4064)
		(layers "F.Cu" "B.Cu")
		(net "P0V9_E")
	)
	(via
		(at 117.850158 -96.8502)
		(size 0.508)
		(drill 0.254)
		(layers "F.Cu" "B.Cu")
		(net "P0V9_E")
	)
	(via
		(at 155.829 -119.38)
		(size 0.7112)
		(drill 0.4064)
		(layers "F.Cu" "B.Cu")
		(net "P0V9_E")
	)
	(via
		(at 132.34797 -139.4206)
		(size 0.7112)
		(drill 0.4064)
		(layers "F.Cu" "B.Cu")
		(net "P0V9_E")
	)
	(via
		(at 111.849662 -92.8497)
		(size 0.508)
		(drill 0.254)
		(layers "F.Cu" "B.Cu")
		(net "P0V9_E")
	)
	(via
		(at 110.849664 -91.849702)
		(size 0.508)
		(drill 0.254)
		(layers "F.Cu" "B.Cu")
		(net "P0V9_E")
	)
	(via
		(at 77.832966 -78.74)
		(size 0.7112)
		(drill 0.3556)
		(layers "F.Cu" "B.Cu")
		(net "P0V9_E")
	)
	(via
		(at 154.94 -110.236)
		(size 0.7112)
		(drill 0.4064)
		(layers "F.Cu" "B.Cu")
		(net "P0V9_E")
	)
	(via
		(at 161.37255 -116.205)
		(size 0.5588)
		(drill 0.3048)
		(layers "F.Cu" "B.Cu")
		(net "P0V9_E")
	)
	(via
		(at 116.85016 -97.850198)
		(size 0.508)
		(drill 0.254)
		(layers "F.Cu" "B.Cu")
		(net "P0V9_E")
	)
	(via
		(at 157.48 -118.3132)
		(size 0.7112)
		(drill 0.4064)
		(layers "F.Cu" "B.Cu")
		(net "P0V9_E")
	)
	(via
		(at 110.849664 -96.8502)
		(size 0.508)
		(drill 0.254)
		(layers "F.Cu" "B.Cu")
		(net "P0V9_E")
	)
	(via
		(at 113.849658 -97.850198)
		(size 0.508)
		(drill 0.254)
		(layers "F.Cu" "B.Cu")
		(net "P0V9_E")
	)
	(via
		(at 154.432 -118.3132)
		(size 0.7112)
		(drill 0.4064)
		(layers "F.Cu" "B.Cu")
		(net "P0V9_E")
	)
	(via
		(at 113.849658 -95.850202)
		(size 0.508)
		(drill 0.254)
		(layers "F.Cu" "B.Cu")
		(net "P0V9_E")
	)
	(via
		(at 113.849658 -90.849704)
		(size 0.508)
		(drill 0.254)
		(layers "F.Cu" "B.Cu")
		(net "P0V9_E")
	)
	(via
		(at 133.61797 -139.4206)
		(size 0.7112)
		(drill 0.4064)
		(layers "F.Cu" "B.Cu")
		(net "P0V9_E")
	)
	(via
		(at 167.513 -93.599)
		(size 0.7112)
		(drill 0.4064)
		(layers "F.Cu" "B.Cu")
		(net "P0V9_E")
	)
	(via
		(at 117.850158 -93.849698)
		(size 0.508)
		(drill 0.254)
		(layers "F.Cu" "B.Cu")
		(net "P0V9_E")
	)
	(via
		(at 133.61797 -135.509)
		(size 0.7112)
		(drill 0.4064)
		(layers "F.Cu" "B.Cu")
		(net "P0V9_E")
	)
	(via
		(at 170.18 -100.33)
		(size 0.7112)
		(drill 0.4064)
		(layers "F.Cu" "B.Cu")
		(net "P0V9_E")
	)
	(via
		(at 115.850162 -91.849702)
		(size 0.508)
		(drill 0.254)
		(layers "F.Cu" "B.Cu")
		(net "P0V9_E")
	)
	(via
		(at 111.849662 -90.849704)
		(size 0.508)
		(drill 0.254)
		(layers "F.Cu" "B.Cu")
		(net "P0V9_E")
	)
	(via
		(at 116.85016 -92.8497)
		(size 0.508)
		(drill 0.254)
		(layers "F.Cu" "B.Cu")
		(net "P0V9_E")
	)
	(via
		(at 72.644 -85.344)
		(size 0.7112)
		(drill 0.4064)
		(layers "F.Cu" "B.Cu")
		(net "P0V9_E")
	)
	(via
		(at 117.850158 -91.849702)
		(size 0.508)
		(drill 0.254)
		(layers "F.Cu" "B.Cu")
		(net "P0V9_E")
	)
	(via
		(at 164.465 -93.599)
		(size 0.7112)
		(drill 0.4064)
		(layers "F.Cu" "B.Cu")
		(net "P0V9_E")
	)
	(via
		(at 112.84966 -98.850196)
		(size 0.508)
		(drill 0.254)
		(layers "F.Cu" "B.Cu")
		(net "P0V9_E")
	)
	(via
		(at 154.9654 -111.633)
		(size 0.7112)
		(drill 0.4064)
		(layers "F.Cu" "B.Cu")
		(net "P0V9_E")
	)
	(via
		(at 153.035 -118.3386)
		(size 0.7112)
		(drill 0.4064)
		(layers "F.Cu" "B.Cu")
		(net "P0V9_E")
	)
	(via
		(at 159.131 -118.3132)
		(size 0.7112)
		(drill 0.4064)
		(layers "F.Cu" "B.Cu")
		(net "P0V9_E")
	)
	(via
		(at 156.083 -110.236)
		(size 0.7112)
		(drill 0.4064)
		(layers "F.Cu" "B.Cu")
		(net "P0V9_E")
	)
	(via
		(at 111.849662 -95.850202)
		(size 0.508)
		(drill 0.254)
		(layers "F.Cu" "B.Cu")
		(net "P0V9_E")
	)
	(via
		(at 132.34797 -135.509)
		(size 0.7112)
		(drill 0.4064)
		(layers "F.Cu" "B.Cu")
		(net "P0V9_E")
	)
	(via
		(at 115.850162 -93.849698)
		(size 0.508)
		(drill 0.254)
		(layers "F.Cu" "B.Cu")
		(net "P0V9_E")
	)
	(via
		(at 112.84966 -89.849706)
		(size 0.508)
		(drill 0.254)
		(layers "F.Cu" "B.Cu")
		(net "P0V9_E")
	)
	(via
		(at 117.850158 -98.850196)
		(size 0.508)
		(drill 0.254)
		(layers "F.Cu" "B.Cu")
		(net "P0V9_E")
	)
	(via
		(at 154.94 -108.839)
		(size 0.7112)
		(drill 0.4064)
		(layers "F.Cu" "B.Cu")
		(net "P0V9_E")
	)
	(via
		(at 155.829 -118.3132)
		(size 0.7112)
		(drill 0.4064)
		(layers "F.Cu" "B.Cu")
		(net "P0V9_E")
	)
	(via
		(at 116.85016 -95.850202)
		(size 0.508)
		(drill 0.254)
		(layers "F.Cu" "B.Cu")
		(net "P0V9_E")
	)
	(via
		(at 133.604 -134.366)
		(size 0.7112)
		(drill 0.4064)
		(layers "F.Cu" "B.Cu")
		(net "P0V9_E")
	)
	(via
		(at 154.432 -119.4562)
		(size 0.7112)
		(drill 0.4064)
		(layers "F.Cu" "B.Cu")
		(net "P0V9_E")
	)
	(via
		(at 160.147 -93.599)
		(size 0.7112)
		(drill 0.4064)
		(layers "F.Cu" "B.Cu")
		(net "P0V9_E")
	)
	(via
		(at 133.604 -133.223)
		(size 0.7112)
		(drill 0.4064)
		(layers "F.Cu" "B.Cu")
		(net "P0V9_E")
	)
	(via
		(at 72.517 -83.82)
		(size 0.7112)
		(drill 0.4064)
		(layers "F.Cu" "B.Cu")
		(net "P0V9_E")
	)
	(via
		(at 156.0068 -105.537)
		(size 0.7112)
		(drill 0.4064)
		(layers "F.Cu" "B.Cu")
		(net "P0V9_E")
	)
	(via
		(at 132.34797 -134.239)
		(size 0.7112)
		(drill 0.4064)
		(layers "F.Cu" "B.Cu")
		(net "P0V9_E")
	)
	(via
		(at 154.94 -107.188)
		(size 0.7112)
		(drill 0.4064)
		(layers "F.Cu" "B.Cu")
		(net "P0V9_E")
	)
	(via
		(at 112.84966 -93.849698)
		(size 0.508)
		(drill 0.254)
		(layers "F.Cu" "B.Cu")
		(net "P0V9_E")
	)
	(via
		(at 110.849664 -89.849706)
		(size 0.508)
		(drill 0.254)
		(layers "F.Cu" "B.Cu")
		(net "P0V9_E")
	)
	(via
		(at 161.925 -93.4466)
		(size 0.7112)
		(drill 0.4064)
		(layers "F.Cu" "B.Cu")
		(net "P0V9_E")
	)
	(via
		(at 156.0322 -111.633)
		(size 0.7112)
		(drill 0.4064)
		(layers "F.Cu" "B.Cu")
		(net "P0V9_E")
	)
	(via
		(at 131.23037 -139.4206)
		(size 0.7112)
		(drill 0.4064)
		(layers "F.Cu" "B.Cu")
		(net "P0V9_E")
	)
	(via
		(at 131.20497 -136.906)
		(size 0.7112)
		(drill 0.4064)
		(layers "F.Cu" "B.Cu")
		(net "P0V9_E")
	)
	(via
		(at 110.849664 -98.850196)
		(size 0.508)
		(drill 0.254)
		(layers "F.Cu" "B.Cu")
		(net "P0V9_E")
	)
	(via
		(at 133.61797 -136.779)
		(size 0.7112)
		(drill 0.4064)
		(layers "F.Cu" "B.Cu")
		(net "P0V9_E")
	)
	(via
		(at 113.849658 -92.8497)
		(size 0.508)
		(drill 0.254)
		(layers "F.Cu" "B.Cu")
		(net "P0V9_E")
	)
	(via
		(at 112.84966 -96.8502)
		(size 0.508)
		(drill 0.254)
		(layers "F.Cu" "B.Cu")
		(net "P0V9_E")
	)
	(via
		(at 155.829 -114.681)
		(size 0.7112)
		(drill 0.3556)
		(layers "F.Cu" "B.Cu")
		(net "P0V9_E")
	)
	(via
		(at 115.850162 -96.8502)
		(size 0.508)
		(drill 0.254)
		(layers "F.Cu" "B.Cu")
		(net "P0V9_E")
	)
	(via
		(at 131.20497 -135.509)
		(size 0.7112)
		(drill 0.4064)
		(layers "F.Cu" "B.Cu")
		(net "P0V9_E")
	)
	(via
		(at 131.20497 -134.239)
		(size 0.7112)
		(drill 0.4064)
		(layers "F.Cu" "B.Cu")
		(net "P0V9_E")
	)
	(via
		(at 116.85016 -90.849704)
		(size 0.508)
		(drill 0.254)
		(layers "F.Cu" "B.Cu")
		(net "P0V9_E")
	)
	(via
		(at 159.131 -119.38)
		(size 0.7112)
		(drill 0.4064)
		(layers "F.Cu" "B.Cu")
		(net "P0V9_E")
	)
	(via
		(at 154.94 -105.537)
		(size 0.7112)
		(drill 0.4064)
		(layers "F.Cu" "B.Cu")
		(net "P0V9_E")
	)
	(via
		(at 110.849664 -93.849698)
		(size 0.508)
		(drill 0.254)
		(layers "F.Cu" "B.Cu")
		(net "P0V9_E")
	)
	(via
		(at 157.48 -119.38)
		(size 0.7112)
		(drill 0.4064)
		(layers "F.Cu" "B.Cu")
		(net "P0V9_E")
	)
	(via
		(at 301.879 -127)
		(size 0.7112)
		(drill 0.4064)
		(layers "F.Cu" "B.Cu")
		(net "P0V9_E")
	)
	(via
		(at 115.850162 -89.849706)
		(size 0.508)
		(drill 0.254)
		(layers "F.Cu" "B.Cu")
		(net "P0V9_E")
	)
	(via
		(at 132.34797 -136.779)
		(size 0.7112)
		(drill 0.4064)
		(layers "F.Cu" "B.Cu")
		(net "P0V9_E")
	)
	(segment
		(start 112.85347 -93.853508)
		(end 112.84966 -93.849698)
		(width 0.508)
		(layer "B.Cu")
		(net "P0V9_E")
	)
	(segment
		(start 117.93347 -94.615)
		(end 117.93347 -93.93301)
		(width 0.508)
		(layer "B.Cu")
		(net "P0V9_E")
	)
	(segment
		(start 113.97996 -97.9805)
		(end 113.849658 -97.850198)
		(width 0.508)
		(layer "B.Cu")
		(net "P0V9_E")
	)
	(segment
		(start 172.3136 -101.3079)
		(end 171.1579 -101.3079)
		(width 0.508)
		(layer "B.Cu")
		(net "P0V9_E")
	)
	(segment
		(start 114.41557 -92.6592)
		(end 114.040158 -92.6592)
		(width 0.3048)
		(layer "B.Cu")
		(net "P0V9_E")
	)
	(segment
		(start 114.56797 -97.9805)
		(end 113.97996 -97.9805)
		(width 0.508)
		(layer "B.Cu")
		(net "P0V9_E")
	)
	(segment
		(start 110.24997 -91.27998)
		(end 110.279942 -91.27998)
		(width 0.3048)
		(layer "B.Cu")
		(net "P0V9_E")
	)
	(segment
		(start 112.85347 -94.615)
		(end 112.85347 -93.853508)
		(width 0.508)
		(layer "B.Cu")
		(net "P0V9_E")
	)
	(segment
		(start 115.20297 -92.1004)
		(end 115.599464 -92.1004)
		(width 0.3048)
		(layer "B.Cu")
		(net "P0V9_E")
	)
	(segment
		(start 111.03737 -94.037404)
		(end 110.849664 -93.849698)
		(width 0.3556)
		(layer "B.Cu")
		(net "P0V9_E")
	)
	(segment
		(start 111.01197 -97.5106)
		(end 111.01197 -97.012506)
		(width 0.3556)
		(layer "B.Cu")
		(net "P0V9_E")
	)
	(segment
		(start 325.374 -184.8485)
		(end 326.144128 -184.8485)
		(width 0.508)
		(layer "B.Cu")
		(net "P0V9_E")
	)
	(segment
		(start 117.552724 -90.14714)
		(end 116.85016 -90.849704)
		(width 0.3048)
		(layer "B.Cu")
		(net "P0V9_E")
	)
	(segment
		(start 111.01197 -98.68789)
		(end 110.849664 -98.850196)
		(width 0.3556)
		(layer "B.Cu")
		(net "P0V9_E")
	)
	(segment
		(start 115.27917 -98.6536)
		(end 115.653566 -98.6536)
		(width 0.3048)
		(layer "B.Cu")
		(net "P0V9_E")
	)
	(segment
		(start 110.2614 -94.437962)
		(end 110.849664 -93.849698)
		(width 0.3048)
		(layer "B.Cu")
		(net "P0V9_E")
	)
	(segment
		(start 114.56797 -96.0755)
		(end 114.074956 -96.0755)
		(width 0.508)
		(layer "B.Cu")
		(net "P0V9_E")
	)
	(segment
		(start 111.01197 -98.1202)
		(end 111.01197 -98.68789)
		(width 0.3556)
		(layer "B.Cu")
		(net "P0V9_E")
	)
	(segment
		(start 115.599464 -92.1004)
		(end 115.850162 -91.849702)
		(width 0.3048)
		(layer "B.Cu")
		(net "P0V9_E")
	)
	(segment
		(start 112.02797 -91.028012)
		(end 111.849662 -90.849704)
		(width 0.3048)
		(layer "B.Cu")
		(net "P0V9_E")
	)
	(segment
		(start 112.02797 -92.671392)
		(end 111.849662 -92.8497)
		(width 0.3048)
		(layer "B.Cu")
		(net "P0V9_E")
	)
	(segment
		(start 326.83704 -185.541412)
		(end 328.295 -185.541412)
		(width 0.508)
		(layer "B.Cu")
		(net "P0V9_E")
	)
	(segment
		(start 115.653566 -98.6536)
		(end 115.850162 -98.850196)
		(width 0.3048)
		(layer "B.Cu")
		(net "P0V9_E")
	)
	(segment
		(start 116.02847 -94.615)
		(end 116.02847 -94.028006)
		(width 0.508)
		(layer "B.Cu")
		(net "P0V9_E")
	)
	(segment
		(start 115.27917 -96.7994)
		(end 115.799362 -96.7994)
		(width 0.3048)
		(layer "B.Cu")
		(net "P0V9_E")
	)
	(segment
		(start 111.03737 -94.488)
		(end 111.03737 -94.037404)
		(width 0.3556)
		(layer "B.Cu")
		(net "P0V9_E")
	)
	(segment
		(start 117.93347 -93.93301)
		(end 117.850158 -93.849698)
		(width 0.508)
		(layer "B.Cu")
		(net "P0V9_E")
	)
	(segment
		(start 110.279942 -91.27998)
		(end 110.849664 -91.849702)
		(width 0.3048)
		(layer "B.Cu")
		(net "P0V9_E")
	)
	(segment
		(start 115.799362 -96.7994)
		(end 115.850162 -96.8502)
		(width 0.3048)
		(layer "B.Cu")
		(net "P0V9_E")
	)
	(segment
		(start 111.69777 -95.1738)
		(end 111.69777 -95.69831)
		(width 0.3556)
		(layer "B.Cu")
		(net "P0V9_E")
	)
	(segment
		(start 117.73789 -90.14714)
		(end 117.552724 -90.14714)
		(width 0.3048)
		(layer "B.Cu")
		(net "P0V9_E")
	)
	(segment
		(start 112.02797 -91.5416)
		(end 112.02797 -91.028012)
		(width 0.3048)
		(layer "B.Cu")
		(net "P0V9_E")
	)
	(segment
		(start 114.040158 -92.6592)
		(end 113.849658 -92.8497)
		(width 0.3048)
		(layer "B.Cu")
		(net "P0V9_E")
	)
	(segment
		(start 112.02797 -92.1258)
		(end 112.02797 -92.671392)
		(width 0.3048)
		(layer "B.Cu")
		(net "P0V9_E")
	)
	(segment
		(start 326.144128 -184.8485)
		(end 326.83704 -185.541412)
		(width 0.508)
		(layer "B.Cu")
		(net "P0V9_E")
	)
	(segment
		(start 110.2614 -94.488)
		(end 110.2614 -94.437962)
		(width 0.3048)
		(layer "B.Cu")
		(net "P0V9_E")
	)
	(segment
		(start 114.074956 -96.0755)
		(end 113.849658 -95.850202)
		(width 0.508)
		(layer "B.Cu")
		(net "P0V9_E")
	)
	(segment
		(start 111.01197 -97.012506)
		(end 110.849664 -96.8502)
		(width 0.3556)
		(layer "B.Cu")
		(net "P0V9_E")
	)
	(segment
		(start 113.881154 -90.8812)
		(end 113.849658 -90.849704)
		(width 0.3048)
		(layer "B.Cu")
		(net "P0V9_E")
	)
	(segment
		(start 116.02847 -94.028006)
		(end 115.850162 -93.849698)
		(width 0.508)
		(layer "B.Cu")
		(net "P0V9_E")
	)
	(segment
		(start 171.1579 -101.3079)
		(end 170.18 -100.33)
		(width 0.508)
		(layer "B.Cu")
		(net "P0V9_E")
	)
	(segment
		(start 111.69777 -95.69831)
		(end 111.849662 -95.850202)
		(width 0.3556)
		(layer "B.Cu")
		(net "P0V9_E")
	)
	(segment
		(start 114.56797 -90.8812)
		(end 113.881154 -90.8812)
		(width 0.3048)
		(layer "B.Cu")
		(net "P0V9_E")
	)
	(segment
		(start 270.4592 -132.6388)
		(end 273.177 -129.921)
		(width 0.508)
		(layer "In2.Cu")
		(net "P0V9_E")
	)
	(segment
		(start 280.162 -129.921)
		(end 284.4292 -125.6538)
		(width 0.508)
		(layer "In2.Cu")
		(net "P0V9_E")
	)
	(segment
		(start 301.752 -126.873)
		(end 301.879 -127)
		(width 0.508)
		(layer "In2.Cu")
		(net "P0V9_E")
	)
	(segment
		(start 330.8477 -170.692826)
		(end 332.14945 -169.391076)
		(width 0.508)
		(layer "In2.Cu")
		(net "P0V9_E")
	)
	(segment
		(start 299.1358 -125.6538)
		(end 300.355 -126.873)
		(width 0.508)
		(layer "In2.Cu")
		(net "P0V9_E")
	)
	(segment
		(start 284.4292 -125.6538)
		(end 299.1358 -125.6538)
		(width 0.508)
		(layer "In2.Cu")
		(net "P0V9_E")
	)
	(segment
		(start 235.18749 -132.7658)
		(end 257.429 -132.7658)
		(width 0.508)
		(layer "In2.Cu")
		(net "P0V9_E")
	)
	(segment
		(start 186.878722 -139.954)
		(end 227.99929 -139.954)
		(width 0.508)
		(layer "In2.Cu")
		(net "P0V9_E")
	)
	(segment
		(start 330.8477 -182.3593)
		(end 330.8477 -170.692826)
		(width 0.508)
		(layer "In2.Cu")
		(net "P0V9_E")
	)
	(segment
		(start 134.3914 -139.4206)
		(end 134.9248 -139.954)
		(width 0.508)
		(layer "In2.Cu")
		(net "P0V9_E")
	)
	(segment
		(start 300.355 -126.873)
		(end 301.752 -126.873)
		(width 0.508)
		(layer "In2.Cu")
		(net "P0V9_E")
	)
	(segment
		(start 186.269122 -139.912852)
		(end 186.837574 -139.912852)
		(width 0.508)
		(layer "In2.Cu")
		(net "P0V9_E")
	)
	(segment
		(start 328.295 -185.541412)
		(end 328.295 -184.912)
		(width 0.508)
		(layer "In2.Cu")
		(net "P0V9_E")
	)
	(segment
		(start 133.61797 -139.4206)
		(end 134.3914 -139.4206)
		(width 0.508)
		(layer "In2.Cu")
		(net "P0V9_E")
	)
	(segment
		(start 134.9248 -139.954)
		(end 186.227974 -139.954)
		(width 0.508)
		(layer "In2.Cu")
		(net "P0V9_E")
	)
	(segment
		(start 332.14945 -169.391076)
		(end 332.14945 -159.46755)
		(width 0.508)
		(layer "In2.Cu")
		(net "P0V9_E")
	)
	(segment
		(start 273.177 -129.921)
		(end 280.162 -129.921)
		(width 0.508)
		(layer "In2.Cu")
		(net "P0V9_E")
	)
	(segment
		(start 257.429 -132.7658)
		(end 257.556 -132.6388)
		(width 0.508)
		(layer "In2.Cu")
		(net "P0V9_E")
	)
	(segment
		(start 227.99929 -139.954)
		(end 235.18749 -132.7658)
		(width 0.508)
		(layer "In2.Cu")
		(net "P0V9_E")
	)
	(segment
		(start 332.14945 -159.46755)
		(end 332.867 -158.75)
		(width 0.508)
		(layer "In2.Cu")
		(net "P0V9_E")
	)
	(segment
		(start 257.556 -132.6388)
		(end 270.4592 -132.6388)
		(width 0.508)
		(layer "In2.Cu")
		(net "P0V9_E")
	)
	(segment
		(start 328.295 -184.912)
		(end 330.8477 -182.3593)
		(width 0.508)
		(layer "In2.Cu")
		(net "P0V9_E")
	)
	(segment
		(start 186.837574 -139.912852)
		(end 186.878722 -139.954)
		(width 0.508)
		(layer "In2.Cu")
		(net "P0V9_E")
	)
	(segment
		(start 186.227974 -139.954)
		(end 186.269122 -139.912852)
		(width 0.508)
		(layer "In2.Cu")
		(net "P0V9_E")
	)
	(segment
		(start 327.12025 -152.287224)
		(end 323.029326 -148.1963)
		(width 0.508)
		(layer "In5.Cu")
		(net "P0V9_E")
	)
	(segment
		(start 306.414678 -138.982704)
		(end 301.8155 -134.383526)
		(width 0.508)
		(layer "In5.Cu")
		(net "P0V9_E")
	)
	(segment
		(start 332.867 -158.75)
		(end 332.430374 -158.75)
		(width 0.508)
		(layer "In5.Cu")
		(net "P0V9_E")
	)
	(segment
		(start 327.12025 -153.439876)
		(end 327.12025 -152.287224)
		(width 0.508)
		(layer "In5.Cu")
		(net "P0V9_E")
	)
	(segment
		(start 310.084978 -138.982704)
		(end 306.414678 -138.982704)
		(width 0.508)
		(layer "In5.Cu")
		(net "P0V9_E")
	)
	(segment
		(start 332.430374 -158.75)
		(end 327.12025 -153.439876)
		(width 0.508)
		(layer "In5.Cu")
		(net "P0V9_E")
	)
	(segment
		(start 159.512 -94.234)
		(end 160.147 -93.599)
		(width 0.508)
		(layer "In5.Cu")
		(net "P0V9_E")
	)
	(segment
		(start 319.298574 -148.1963)
		(end 310.084978 -138.982704)
		(width 0.508)
		(layer "In5.Cu")
		(net "P0V9_E")
	)
	(segment
		(start 301.8155 -134.383526)
		(end 301.8155 -127.0635)
		(width 0.508)
		(layer "In5.Cu")
		(net "P0V9_E")
	)
	(segment
		(start 323.029326 -148.1963)
		(end 319.298574 -148.1963)
		(width 0.508)
		(layer "In5.Cu")
		(net "P0V9_E")
	)
	(segment
		(start 301.8155 -127.0635)
		(end 301.879 -127)
		(width 0.508)
		(layer "In5.Cu")
		(net "P0V9_E")
	)
	(segment
		(start 159.512 -114.34445)
		(end 159.512 -94.234)
		(width 0.508)
		(layer "In5.Cu")
		(net "P0V9_E")
	)
	(segment
		(start 161.37255 -116.205)
		(end 159.512 -114.34445)
		(width 0.508)
		(layer "In5.Cu")
		(net "P0V9_E")
	)
	(segment
		(start 101.935788 -105.850182)
		(end 101.849682 -105.850182)
		(width 0.1143)
		(layer "F.Cu")
		(net "SIO_D_OUT")
	)
	(segment
		(start 102.349808 -105.436162)
		(end 101.935788 -105.850182)
		(width 0.1143)
		(layer "F.Cu")
		(net "SIO_D_OUT")
	)
	(segment
		(start 102.349808 -105.350056)
		(end 102.349808 -105.436162)
		(width 0.1143)
		(layer "F.Cu")
		(net "SIO_D_OUT")
	)
	(via
		(at 101.849682 -105.850182)
		(size 0.508)
		(drill 0.254)
		(layers "F.Cu" "B.Cu")
		(net "SIO_D_OUT")
	)
	(segment
		(start 100.21697 -107.482894)
		(end 100.21697 -108.204)
		(width 0.1143)
		(layer "B.Cu")
		(net "SIO_D_OUT")
	)
	(segment
		(start 101.849682 -105.850182)
		(end 100.21697 -107.482894)
		(width 0.1143)
		(layer "B.Cu")
		(net "SIO_D_OUT")
	)
	(segment
		(start 100.21697 -108.204)
		(end 100.21697 -109.5375)
		(width 0.1143)
		(layer "B.Cu")
		(net "SIO_D_OUT")
	)
	(segment
		(start 181.1655 -145.288)
		(end 181.56428 -145.288)
		(width 0.1143)
		(layer "F.Cu")
		(net "EXP_I2C_VREF_3")
	)
	(segment
		(start 183.7944 -145.58264)
		(end 182.92064 -145.58264)
		(width 0.1143)
		(layer "F.Cu")
		(net "EXP_I2C_VREF_3")
	)
	(segment
		(start 181.56428 -145.288)
		(end 182.50916 -146.23288)
		(width 0.1143)
		(layer "F.Cu")
		(net "EXP_I2C_VREF_3")
	)
	(segment
		(start 181.61 -144.272)
		(end 182.372 -145.034)
		(width 0.1143)
		(layer "F.Cu")
		(net "EXP_I2C_VREF_3")
	)
	(segment
		(start 182.50916 -146.23288)
		(end 183.7944 -146.23288)
		(width 0.1143)
		(layer "F.Cu")
		(net "EXP_I2C_VREF_3")
	)
	(segment
		(start 181.1655 -145.288)
		(end 181.1655 -144.272)
		(width 0.1143)
		(layer "F.Cu")
		(net "EXP_I2C_VREF_3")
	)
	(segment
		(start 182.92064 -145.58264)
		(end 182.372 -145.034)
		(width 0.1143)
		(layer "F.Cu")
		(net "EXP_I2C_VREF_3")
	)
	(segment
		(start 181.1655 -144.272)
		(end 181.61 -144.272)
		(width 0.1143)
		(layer "F.Cu")
		(net "EXP_I2C_VREF_3")
	)
	(via
		(at 182.372 -145.034)
		(size 0.7112)
		(drill 0.3556)
		(layers "F.Cu" "B.Cu")
		(net "EXP_I2C_VREF_3")
	)
	(segment
		(start 115.350036 -102.350062)
		(end 115.350036 -102.354888)
		(width 0.1016)
		(layer "F.Cu")
		(net "SAS_HDD_CONN_RX7_N")
	)
	(segment
		(start 115.350036 -102.354888)
		(end 114.864642 -102.840282)
		(width 0.1016)
		(layer "F.Cu")
		(net "SAS_HDD_CONN_RX7_N")
	)
	(via
		(at 114.864642 -102.840282)
		(size 0.508)
		(drill 0.254)
		(layers "F.Cu" "B.Cu")
		(net "SAS_HDD_CONN_RX7_N")
	)
	(segment
		(start 114.089942 -106.520488)
		(end 114.089942 -105.663492)
		(width 0.1016)
		(layer "B.Cu")
		(net "SAS_HDD_CONN_RX7_N")
	)
	(segment
		(start 116.542312 -204.649324)
		(end 116.542312 -198.165974)
		(width 0.1016)
		(layer "B.Cu")
		(net "SAS_HDD_CONN_RX7_N")
	)
	(segment
		(start 114.267742 -105.01884)
		(end 114.267742 -104.073452)
		(width 0.1016)
		(layer "B.Cu")
		(net "SAS_HDD_CONN_RX7_N")
	)
	(segment
		(start 117.316758 -114.159538)
		(end 115.87861 -112.72139)
		(width 0.1016)
		(layer "B.Cu")
		(net "SAS_HDD_CONN_RX7_N")
	)
	(segment
		(start 117.131592 -196.74332)
		(end 117.14988 -196.725032)
		(width 0.1016)
		(layer "B.Cu")
		(net "SAS_HDD_CONN_RX7_N")
	)
	(segment
		(start 117.518942 -195.834)
		(end 117.518942 -114.647726)
		(width 0.1016)
		(layer "B.Cu")
		(net "SAS_HDD_CONN_RX7_N")
	)
	(segment
		(start 116.263166 -205.269846)
		(end 116.301012 -205.232)
		(width 0.1016)
		(layer "B.Cu")
		(net "SAS_HDD_CONN_RX7_N")
	)
	(segment
		(start 114.717576 -102.987094)
		(end 114.864642 -102.840282)
		(width 0.1016)
		(layer "B.Cu")
		(net "SAS_HDD_CONN_RX7_N")
	)
	(segment
		(start 114.98707 -110.568994)
		(end 114.98707 -108.14558)
		(width 0.1016)
		(layer "B.Cu")
		(net "SAS_HDD_CONN_RX7_N")
	)
	(segment
		(start 114.759232 -107.595416)
		(end 114.375946 -107.21213)
		(width 0.1016)
		(layer "B.Cu")
		(net "SAS_HDD_CONN_RX7_N")
	)
	(arc
		(start 114.98707 -108.14558)
		(mid 114.927848 -107.847852)
		(end 114.759232 -107.595416)
		(width 0.1016)
		(layer "B.Cu")
		(net "SAS_HDD_CONN_RX7_N")
	)
	(arc
		(start 116.51361 -204.863446)
		(mid 116.535023 -204.757331)
		(end 116.542312 -204.649324)
		(width 0.1016)
		(layer "B.Cu")
		(net "SAS_HDD_CONN_RX7_N")
	)
	(arc
		(start 114.267742 -104.073452)
		(mid 114.384595 -103.485523)
		(end 114.717576 -102.987094)
		(width 0.1016)
		(layer "B.Cu")
		(net "SAS_HDD_CONN_RX7_N")
	)
	(arc
		(start 115.87861 -112.72139)
		(mid 115.218765 -111.733862)
		(end 114.98707 -110.568994)
		(width 0.1016)
		(layer "B.Cu")
		(net "SAS_HDD_CONN_RX7_N")
	)
	(arc
		(start 116.301012 -205.232)
		(mid 116.428544 -205.06693)
		(end 116.510562 -204.87513)
		(width 0.1016)
		(layer "B.Cu")
		(net "SAS_HDD_CONN_RX7_N")
	)
	(arc
		(start 114.154458 -105.357676)
		(mid 114.166667 -105.331653)
		(end 114.179858 -105.306114)
		(width 0.1016)
		(layer "B.Cu")
		(net "SAS_HDD_CONN_RX7_N")
	)
	(arc
		(start 116.510562 -204.87513)
		(mid 116.512108 -204.869294)
		(end 116.51361 -204.863446)
		(width 0.1016)
		(layer "B.Cu")
		(net "SAS_HDD_CONN_RX7_N")
	)
	(arc
		(start 114.179858 -105.306114)
		(mid 114.213479 -105.248235)
		(end 114.239294 -105.18648)
		(width 0.1016)
		(layer "B.Cu")
		(net "SAS_HDD_CONN_RX7_N")
	)
	(arc
		(start 114.239294 -105.18648)
		(mid 114.249554 -105.153482)
		(end 114.257836 -105.119932)
		(width 0.1016)
		(layer "B.Cu")
		(net "SAS_HDD_CONN_RX7_N")
	)
	(arc
		(start 117.518942 -114.647726)
		(mid 117.466391 -114.383532)
		(end 117.316758 -114.159538)
		(width 0.1016)
		(layer "B.Cu")
		(net "SAS_HDD_CONN_RX7_N")
	)
	(arc
		(start 114.089942 -105.663492)
		(mid 114.106175 -105.507205)
		(end 114.154458 -105.357676)
		(width 0.1016)
		(layer "B.Cu")
		(net "SAS_HDD_CONN_RX7_N")
	)
	(arc
		(start 117.14988 -196.725032)
		(mid 117.423037 -196.316223)
		(end 117.518942 -195.834)
		(width 0.1016)
		(layer "B.Cu")
		(net "SAS_HDD_CONN_RX7_N")
	)
	(arc
		(start 116.542312 -198.165974)
		(mid 116.695446 -197.396026)
		(end 117.131592 -196.74332)
		(width 0.1016)
		(layer "B.Cu")
		(net "SAS_HDD_CONN_RX7_N")
	)
	(arc
		(start 114.257836 -105.119932)
		(mid 114.265295 -105.069631)
		(end 114.267742 -105.01884)
		(width 0.1016)
		(layer "B.Cu")
		(net "SAS_HDD_CONN_RX7_N")
	)
	(arc
		(start 114.375946 -107.21213)
		(mid 114.164241 -106.894729)
		(end 114.089942 -106.520488)
		(width 0.1016)
		(layer "B.Cu")
		(net "SAS_HDD_CONN_RX7_N")
	)
	(arc
		(start 115.894612 -205.4225)
		(mid 116.09407 -205.382825)
		(end 116.263166 -205.269846)
		(width 0.1016)
		(layer "B.Cu")
		(net "SAS_HDD_CONN_RX7_N")
	)
	(segment
		(start 112.415574 -32.607758)
		(end 112.350042 -32.542226)
		(width 0.1143)
		(layer "F.Cu")
		(net "IOC_GPIO_19")
	)
	(segment
		(start 112.350042 -32.542226)
		(end 112.350042 -32.004)
		(width 0.1143)
		(layer "F.Cu")
		(net "IOC_GPIO_19")
	)
	(segment
		(start 112.350042 -33.020762)
		(end 112.415574 -32.95523)
		(width 0.1143)
		(layer "F.Cu")
		(net "IOC_GPIO_19")
	)
	(segment
		(start 112.350042 -33.399984)
		(end 112.350042 -33.020762)
		(width 0.1143)
		(layer "F.Cu")
		(net "IOC_GPIO_19")
	)
	(segment
		(start 112.415574 -32.95523)
		(end 112.415574 -32.607758)
		(width 0.1143)
		(layer "F.Cu")
		(net "IOC_GPIO_19")
	)
	(via
		(at 112.350042 -32.004)
		(size 0.508)
		(drill 0.254)
		(layers "F.Cu" "B.Cu")
		(net "IOC_GPIO_19")
	)
	(segment
		(start 112.91316 -31.115)
		(end 112.91316 -31.440882)
		(width 0.1143)
		(layer "B.Cu")
		(net "IOC_GPIO_19")
	)
	(segment
		(start 112.91316 -31.440882)
		(end 112.350042 -32.004)
		(width 0.1143)
		(layer "B.Cu")
		(net "IOC_GPIO_19")
	)
	(segment
		(start 100.10902 -116.153692)
		(end 100.10902 -115.748308)
		(width 0.1143)
		(layer "F.Cu")
		(net "SIO_D_IN")
	)
	(segment
		(start 100.10902 -115.748308)
		(end 100.11537 -115.741958)
		(width 0.1143)
		(layer "F.Cu")
		(net "SIO_D_IN")
	)
	(segment
		(start 100.11537 -115.741958)
		(end 100.11537 -114.808)
		(width 0.1143)
		(layer "F.Cu")
		(net "SIO_D_IN")
	)
	(segment
		(start 107.349798 -100.350066)
		(end 106.849672 -100.850192)
		(width 0.1143)
		(layer "F.Cu")
		(net "SIO_D_IN")
	)
	(segment
		(start 100.11537 -117.602)
		(end 100.11537 -116.84)
		(width 0.1143)
		(layer "F.Cu")
		(net "SIO_D_IN")
	)
	(segment
		(start 99.86137 -114.554)
		(end 99.83597 -114.554)
		(width 0.1143)
		(layer "F.Cu")
		(net "SIO_D_IN")
	)
	(segment
		(start 100.11537 -114.808)
		(end 99.86137 -114.554)
		(width 0.1143)
		(layer "F.Cu")
		(net "SIO_D_IN")
	)
	(segment
		(start 99.45497 -117.856)
		(end 99.86137 -117.856)
		(width 0.1143)
		(layer "F.Cu")
		(net "SIO_D_IN")
	)
	(segment
		(start 100.11537 -116.160042)
		(end 100.10902 -116.153692)
		(width 0.1143)
		(layer "F.Cu")
		(net "SIO_D_IN")
	)
	(segment
		(start 100.11537 -116.84)
		(end 100.11537 -116.160042)
		(width 0.1143)
		(layer "F.Cu")
		(net "SIO_D_IN")
	)
	(segment
		(start 99.86137 -117.856)
		(end 100.11537 -117.602)
		(width 0.1143)
		(layer "F.Cu")
		(net "SIO_D_IN")
	)
	(via
		(at 99.83597 -114.554)
		(size 0.5588)
		(drill 0.3048)
		(layers "F.Cu" "B.Cu")
		(net "SIO_D_IN")
	)
	(via
		(at 106.849672 -100.850192)
		(size 0.508)
		(drill 0.254)
		(layers "F.Cu" "B.Cu")
		(net "SIO_D_IN")
	)
	(segment
		(start 106.849672 -100.920042)
		(end 106.430572 -101.339142)
		(width 0.127)
		(layer "In2.Cu")
		(net "SIO_D_IN")
	)
	(segment
		(start 106.430572 -104.023922)
		(end 106.548174 -104.141524)
		(width 0.127)
		(layer "In2.Cu")
		(net "SIO_D_IN")
	)
	(segment
		(start 106.849672 -100.850192)
		(end 106.849672 -100.920042)
		(width 0.127)
		(layer "In2.Cu")
		(net "SIO_D_IN")
	)
	(segment
		(start 102.009702 -112.1664)
		(end 99.83597 -114.340132)
		(width 0.127)
		(layer "In2.Cu")
		(net "SIO_D_IN")
	)
	(segment
		(start 106.548174 -104.141524)
		(end 106.548174 -108.139738)
		(width 0.127)
		(layer "In2.Cu")
		(net "SIO_D_IN")
	)
	(segment
		(start 106.548174 -108.139738)
		(end 102.521512 -112.1664)
		(width 0.127)
		(layer "In2.Cu")
		(net "SIO_D_IN")
	)
	(segment
		(start 106.430572 -101.339142)
		(end 106.430572 -104.023922)
		(width 0.127)
		(layer "In2.Cu")
		(net "SIO_D_IN")
	)
	(segment
		(start 99.83597 -114.340132)
		(end 99.83597 -114.554)
		(width 0.127)
		(layer "In2.Cu")
		(net "SIO_D_IN")
	)
	(segment
		(start 102.521512 -112.1664)
		(end 102.009702 -112.1664)
		(width 0.127)
		(layer "In2.Cu")
		(net "SIO_D_IN")
	)
	(segment
		(start 130.289808 -91.478608)
		(end 130.2766 -91.4654)
		(width 0.1016)
		(layer "F.Cu")
		(net "3X24_SAS_TX19_N")
	)
	(segment
		(start 131.0386 -91.948)
		(end 131.0386 -91.9226)
		(width 0.1016)
		(layer "F.Cu")
		(net "3X24_SAS_TX19_N")
	)
	(segment
		(start 129.7686 -91.250008)
		(end 128.353312 -91.250008)
		(width 0.1016)
		(layer "F.Cu")
		(net "3X24_SAS_TX19_N")
	)
	(segment
		(start 130.2766 -91.4654)
		(end 130.267964 -91.457018)
		(width 0.1016)
		(layer "F.Cu")
		(net "3X24_SAS_TX19_N")
	)
	(segment
		(start 126.1999 -90.844624)
		(end 125.95606 -90.601038)
		(width 0.1016)
		(layer "F.Cu")
		(net "3X24_SAS_TX19_N")
	)
	(segment
		(start 127.6604 -90.962988)
		(end 126.48565 -90.962988)
		(width 0.1016)
		(layer "F.Cu")
		(net "3X24_SAS_TX19_N")
	)
	(arc
		(start 126.48565 -90.962988)
		(mid 126.331002 -90.932227)
		(end 126.1999 -90.844624)
		(width 0.1016)
		(layer "F.Cu")
		(net "3X24_SAS_TX19_N")
	)
	(arc
		(start 125.95606 -90.601038)
		(mid 125.67802 -90.415164)
		(end 125.350016 -90.349832)
		(width 0.1016)
		(layer "F.Cu")
		(net "3X24_SAS_TX19_N")
	)
	(arc
		(start 131.0386 -91.9226)
		(mid 130.971645 -91.760955)
		(end 130.81 -91.694)
		(width 0.1016)
		(layer "F.Cu")
		(net "3X24_SAS_TX19_N")
	)
	(arc
		(start 127.80137 -91.021408)
		(mid 127.736692 -90.978192)
		(end 127.6604 -90.962988)
		(width 0.1016)
		(layer "F.Cu")
		(net "3X24_SAS_TX19_N")
	)
	(arc
		(start 130.81 -91.694)
		(mid 130.52849 -91.638022)
		(end 130.289808 -91.478608)
		(width 0.1016)
		(layer "F.Cu")
		(net "3X24_SAS_TX19_N")
	)
	(arc
		(start 128.353312 -91.250008)
		(mid 128.054612 -91.190593)
		(end 127.80137 -91.021408)
		(width 0.1016)
		(layer "F.Cu")
		(net "3X24_SAS_TX19_N")
	)
	(arc
		(start 130.267964 -91.457018)
		(mid 130.038869 -91.303849)
		(end 129.7686 -91.250008)
		(width 0.1016)
		(layer "F.Cu")
		(net "3X24_SAS_TX19_N")
	)
	(segment
		(start 103.349806 -105.350056)
		(end 102.84968 -105.850182)
		(width 0.1143)
		(layer "F.Cu")
		(net "EXP_SIO_CLK_OUT")
	)
	(via
		(at 102.84968 -105.850182)
		(size 0.508)
		(drill 0.254)
		(layers "F.Cu" "B.Cu")
		(net "EXP_SIO_CLK_OUT")
	)
	(segment
		(start 101.48697 -107.212892)
		(end 101.48697 -108.204)
		(width 0.1143)
		(layer "B.Cu")
		(net "EXP_SIO_CLK_OUT")
	)
	(segment
		(start 101.48697 -108.204)
		(end 101.48697 -109.5375)
		(width 0.1143)
		(layer "B.Cu")
		(net "EXP_SIO_CLK_OUT")
	)
	(segment
		(start 102.84968 -105.850182)
		(end 101.48697 -107.212892)
		(width 0.1143)
		(layer "B.Cu")
		(net "EXP_SIO_CLK_OUT")
	)
	(segment
		(start 96.66097 -117.856)
		(end 97.24517 -117.2718)
		(width 0.1143)
		(layer "F.Cu")
		(net "EXP_SIO_CLK_IN")
	)
	(segment
		(start 98.05797 -115.443)
		(end 98.43897 -115.824)
		(width 0.1143)
		(layer "F.Cu")
		(net "EXP_SIO_CLK_IN")
	)
	(segment
		(start 97.24517 -117.2718)
		(end 97.93097 -117.2718)
		(width 0.1143)
		(layer "F.Cu")
		(net "EXP_SIO_CLK_IN")
	)
	(segment
		(start 97.93097 -117.2718)
		(end 98.43897 -116.7638)
		(width 0.1143)
		(layer "F.Cu")
		(net "EXP_SIO_CLK_IN")
	)
	(segment
		(start 98.43897 -115.824)
		(end 98.43897 -116.7638)
		(width 0.1143)
		(layer "F.Cu")
		(net "EXP_SIO_CLK_IN")
	)
	(segment
		(start 109.349794 -98.35007)
		(end 108.849668 -98.850196)
		(width 0.1143)
		(layer "F.Cu")
		(net "EXP_SIO_CLK_IN")
	)
	(via
		(at 108.849668 -98.850196)
		(size 0.508)
		(drill 0.254)
		(layers "F.Cu" "B.Cu")
		(net "EXP_SIO_CLK_IN")
	)
	(via
		(at 98.05797 -115.443)
		(size 0.5588)
		(drill 0.3048)
		(layers "F.Cu" "B.Cu")
		(net "EXP_SIO_CLK_IN")
	)
	(segment
		(start 106.64317 -98.3234)
		(end 106.38917 -98.5774)
		(width 0.127)
		(layer "In5.Cu")
		(net "EXP_SIO_CLK_IN")
	)
	(segment
		(start 108.849668 -98.850196)
		(end 108.322872 -98.3234)
		(width 0.127)
		(layer "In5.Cu")
		(net "EXP_SIO_CLK_IN")
	)
	(segment
		(start 105.34777 -101.5746)
		(end 105.34777 -108.2802)
		(width 0.127)
		(layer "In5.Cu")
		(net "EXP_SIO_CLK_IN")
	)
	(segment
		(start 106.03357 -101.3714)
		(end 105.55097 -101.3714)
		(width 0.127)
		(layer "In5.Cu")
		(net "EXP_SIO_CLK_IN")
	)
	(segment
		(start 100.52177 -114.3508)
		(end 100.52177 -114.6302)
		(width 0.127)
		(layer "In5.Cu")
		(net "EXP_SIO_CLK_IN")
	)
	(segment
		(start 105.34777 -108.2802)
		(end 105.09377 -108.5342)
		(width 0.127)
		(layer "In5.Cu")
		(net "EXP_SIO_CLK_IN")
	)
	(segment
		(start 106.38917 -98.5774)
		(end 106.38917 -101.0158)
		(width 0.127)
		(layer "In5.Cu")
		(net "EXP_SIO_CLK_IN")
	)
	(segment
		(start 100.52177 -114.6302)
		(end 99.70897 -115.443)
		(width 0.127)
		(layer "In5.Cu")
		(net "EXP_SIO_CLK_IN")
	)
	(segment
		(start 105.09377 -108.5342)
		(end 105.09377 -109.7788)
		(width 0.127)
		(layer "In5.Cu")
		(net "EXP_SIO_CLK_IN")
	)
	(segment
		(start 106.38917 -101.0158)
		(end 106.03357 -101.3714)
		(width 0.127)
		(layer "In5.Cu")
		(net "EXP_SIO_CLK_IN")
	)
	(segment
		(start 108.322872 -98.3234)
		(end 106.64317 -98.3234)
		(width 0.127)
		(layer "In5.Cu")
		(net "EXP_SIO_CLK_IN")
	)
	(segment
		(start 105.55097 -101.3714)
		(end 105.34777 -101.5746)
		(width 0.127)
		(layer "In5.Cu")
		(net "EXP_SIO_CLK_IN")
	)
	(segment
		(start 105.09377 -109.7788)
		(end 100.52177 -114.3508)
		(width 0.127)
		(layer "In5.Cu")
		(net "EXP_SIO_CLK_IN")
	)
	(segment
		(start 99.70897 -115.443)
		(end 98.05797 -115.443)
		(width 0.127)
		(layer "In5.Cu")
		(net "EXP_SIO_CLK_IN")
	)
	(segment
		(start 114.77498 -38.199822)
		(end 115.488466 -37.486336)
		(width 0.1143)
		(layer "F.Cu")
		(net "IOC_GPIO_17")
	)
	(segment
		(start 115.488466 -37.486336)
		(end 115.488466 -37.2745)
		(width 0.1143)
		(layer "F.Cu")
		(net "IOC_GPIO_17")
	)
	(segment
		(start 115.488466 -37.2745)
		(end 115.551966 -37.211)
		(width 0.1143)
		(layer "F.Cu")
		(net "IOC_GPIO_17")
	)
	(segment
		(start 113.949988 -38.199822)
		(end 114.77498 -38.199822)
		(width 0.1143)
		(layer "F.Cu")
		(net "IOC_GPIO_17")
	)
	(via
		(at 115.551966 -37.211)
		(size 0.508)
		(drill 0.254)
		(layers "F.Cu" "B.Cu")
		(net "IOC_GPIO_17")
	)
	(segment
		(start 116.059966 -36.703)
		(end 115.551966 -37.211)
		(width 0.1143)
		(layer "B.Cu")
		(net "IOC_GPIO_17")
	)
	(segment
		(start 116.059966 -36.322)
		(end 116.059966 -36.703)
		(width 0.1143)
		(layer "B.Cu")
		(net "IOC_GPIO_17")
	)
	(segment
		(start 128.820926 -89.67851)
		(end 128.768602 -89.730834)
		(width 0.1016)
		(layer "F.Cu")
		(net "3X24_SAS_TX18_P")
	)
	(segment
		(start 130.7338 -89.916)
		(end 130.175 -89.916)
		(width 0.1016)
		(layer "F.Cu")
		(net "3X24_SAS_TX18_P")
	)
	(segment
		(start 127.423164 -89.422986)
		(end 127.350012 -89.349834)
		(width 0.1016)
		(layer "F.Cu")
		(net "3X24_SAS_TX18_P")
	)
	(segment
		(start 128.768602 -89.730834)
		(end 128.166368 -89.730834)
		(width 0.1016)
		(layer "F.Cu")
		(net "3X24_SAS_TX18_P")
	)
	(segment
		(start 131.0386 -89.789)
		(end 131.03733 -89.79027)
		(width 0.1016)
		(layer "F.Cu")
		(net "3X24_SAS_TX18_P")
	)
	(segment
		(start 129.958338 -89.826084)
		(end 129.921 -89.789)
		(width 0.1016)
		(layer "F.Cu")
		(net "3X24_SAS_TX18_P")
	)
	(segment
		(start 129.6543 -89.67851)
		(end 128.820926 -89.67851)
		(width 0.1016)
		(layer "F.Cu")
		(net "3X24_SAS_TX18_P")
	)
	(arc
		(start 130.175 -89.916)
		(mid 130.057731 -89.89258)
		(end 129.958338 -89.826084)
		(width 0.1016)
		(layer "F.Cu")
		(net "3X24_SAS_TX18_P")
	)
	(arc
		(start 131.03733 -89.79027)
		(mid 130.898069 -89.883321)
		(end 130.7338 -89.916)
		(width 0.1016)
		(layer "F.Cu")
		(net "3X24_SAS_TX18_P")
	)
	(arc
		(start 128.166368 -89.730834)
		(mid 128.002032 -89.717827)
		(end 127.841756 -89.679272)
		(width 0.1016)
		(layer "F.Cu")
		(net "3X24_SAS_TX18_P")
	)
	(arc
		(start 129.921 -89.789)
		(mid 129.798637 -89.70724)
		(end 129.6543 -89.67851)
		(width 0.1016)
		(layer "F.Cu")
		(net "3X24_SAS_TX18_P")
	)
	(arc
		(start 127.841756 -89.679272)
		(mid 127.617292 -89.575904)
		(end 127.423164 -89.422986)
		(width 0.1016)
		(layer "F.Cu")
		(net "3X24_SAS_TX18_P")
	)
	(segment
		(start 114.535966 -25.781)
		(end 114.027966 -25.273)
		(width 0.1778)
		(layer "F.Cu")
		(net "SYS_ERROR_LED_D")
	)
	(segment
		(start 114.916966 -25.781)
		(end 114.535966 -25.781)
		(width 0.1778)
		(layer "F.Cu")
		(net "SYS_ERROR_LED_D")
	)
	(via
		(at 115.018566 -25.146)
		(size 0.7112)
		(drill 0.3556)
		(layers "F.Cu" "B.Cu")
		(net "SYS_ERROR_LED_D")
	)
	(via
		(at 114.027966 -25.273)
		(size 0.5588)
		(drill 0.3048)
		(layers "F.Cu" "B.Cu")
		(net "SYS_ERROR_LED_D")
	)
	(segment
		(start 113.748566 -25.5524)
		(end 114.027966 -25.273)
		(width 0.1778)
		(layer "B.Cu")
		(net "SYS_ERROR_LED_D")
	)
	(segment
		(start 114.154966 -25.146)
		(end 115.018566 -25.146)
		(width 0.1778)
		(layer "B.Cu")
		(net "SYS_ERROR_LED_D")
	)
	(segment
		(start 114.027966 -25.273)
		(end 114.154966 -25.146)
		(width 0.1778)
		(layer "B.Cu")
		(net "SYS_ERROR_LED_D")
	)
	(segment
		(start 113.748566 -26.416)
		(end 113.748566 -25.5524)
		(width 0.1778)
		(layer "B.Cu")
		(net "SYS_ERROR_LED_D")
	)
	(segment
		(start 117.729 -35.941)
		(end 117.729 -36.293552)
		(width 0.1143)
		(layer "F.Cu")
		(net "IOC_GPIO_8")
	)
	(segment
		(start 115.02263 -38.999922)
		(end 113.949988 -38.999922)
		(width 0.1143)
		(layer "F.Cu")
		(net "IOC_GPIO_8")
	)
	(segment
		(start 117.729 -36.293552)
		(end 115.02263 -38.999922)
		(width 0.1143)
		(layer "F.Cu")
		(net "IOC_GPIO_8")
	)
	(segment
		(start 116.440966 -25.781)
		(end 116.440966 -26.67)
		(width 0.1778)
		(layer "F.Cu")
		(net "SYS_ERROR_LED_R")
	)
	(segment
		(start 116.440966 -26.67)
		(end 116.694966 -26.924)
		(width 0.1778)
		(layer "F.Cu")
		(net "SYS_ERROR_LED_R")
	)
	(via
		(at 116.694966 -26.0858)
		(size 0.7112)
		(drill 0.3556)
		(layers "F.Cu" "B.Cu")
		(net "SYS_ERROR_LED_R")
	)
	(via
		(at 116.694966 -26.924)
		(size 0.5588)
		(drill 0.3048)
		(layers "F.Cu" "B.Cu")
		(net "SYS_ERROR_LED_R")
	)
	(segment
		(start 116.694966 -26.924)
		(end 116.694966 -26.0858)
		(width 0.1778)
		(layer "B.Cu")
		(net "SYS_ERROR_LED_R")
	)
	(segment
		(start 118.028466 -26.416)
		(end 117.520466 -26.924)
		(width 0.1778)
		(layer "B.Cu")
		(net "SYS_ERROR_LED_R")
	)
	(segment
		(start 117.520466 -26.924)
		(end 116.694966 -26.924)
		(width 0.1778)
		(layer "B.Cu")
		(net "SYS_ERROR_LED_R")
	)
	(segment
		(start 129.267966 -38.608)
		(end 128.632966 -37.973)
		(width 0.1778)
		(layer "F.Cu")
		(net "SYS_HB_LED_R")
	)
	(segment
		(start 132.08 -38.608)
		(end 129.267966 -38.608)
		(width 0.1778)
		(layer "F.Cu")
		(net "SYS_HB_LED_R")
	)
	(via
		(at 128.632966 -37.973)
		(size 0.5588)
		(drill 0.3048)
		(layers "F.Cu" "B.Cu")
		(net "SYS_HB_LED_R")
	)
	(via
		(at 129.3368 -37.2618)
		(size 0.7112)
		(drill 0.3556)
		(layers "F.Cu" "B.Cu")
		(net "SYS_HB_LED_R")
	)
	(segment
		(start 129.3368 -37.269166)
		(end 129.3368 -37.2618)
		(width 0.1778)
		(layer "B.Cu")
		(net "SYS_HB_LED_R")
	)
	(segment
		(start 129.636266 -37.2618)
		(end 129.3368 -37.2618)
		(width 0.1778)
		(layer "B.Cu")
		(net "SYS_HB_LED_R")
	)
	(segment
		(start 129.839466 -38.354)
		(end 129.839466 -37.465)
		(width 0.1778)
		(layer "B.Cu")
		(net "SYS_HB_LED_R")
	)
	(segment
		(start 129.839466 -37.465)
		(end 129.636266 -37.2618)
		(width 0.1778)
		(layer "B.Cu")
		(net "SYS_HB_LED_R")
	)
	(segment
		(start 128.632966 -37.973)
		(end 129.3368 -37.269166)
		(width 0.1778)
		(layer "B.Cu")
		(net "SYS_HB_LED_R")
	)
	(segment
		(start 115.068604 -34.749994)
		(end 115.528598 -34.29)
		(width 0.1143)
		(layer "F.Cu")
		(net "IOC_GPIO_21")
	)
	(segment
		(start 115.528598 -34.29)
		(end 115.932966 -34.29)
		(width 0.1143)
		(layer "F.Cu")
		(net "IOC_GPIO_21")
	)
	(segment
		(start 114.030252 -35.80003)
		(end 115.068604 -34.761678)
		(width 0.1143)
		(layer "F.Cu")
		(net "IOC_GPIO_21")
	)
	(segment
		(start 113.949988 -35.80003)
		(end 114.030252 -35.80003)
		(width 0.1143)
		(layer "F.Cu")
		(net "IOC_GPIO_21")
	)
	(segment
		(start 115.068604 -34.761678)
		(end 115.068604 -34.749994)
		(width 0.1143)
		(layer "F.Cu")
		(net "IOC_GPIO_21")
	)
	(via
		(at 115.932966 -34.29)
		(size 0.508)
		(drill 0.254)
		(layers "F.Cu" "B.Cu")
		(net "IOC_GPIO_21")
	)
	(segment
		(start 115.551966 -33.02)
		(end 115.551966 -33.909)
		(width 0.1143)
		(layer "B.Cu")
		(net "IOC_GPIO_21")
	)
	(segment
		(start 115.551966 -33.909)
		(end 115.932966 -34.29)
		(width 0.1143)
		(layer "B.Cu")
		(net "IOC_GPIO_21")
	)
	(segment
		(start 128.143 -37.211)
		(end 127.997966 -37.211)
		(width 0.1778)
		(layer "F.Cu")
		(net "SYS_HB_LED_D")
	)
	(segment
		(start 128.651 -36.703)
		(end 128.143 -37.211)
		(width 0.1778)
		(layer "F.Cu")
		(net "SYS_HB_LED_D")
	)
	(segment
		(start 130.81 -36.703)
		(end 128.651 -36.703)
		(width 0.1778)
		(layer "F.Cu")
		(net "SYS_HB_LED_D")
	)
	(segment
		(start 132.08 -37.084)
		(end 131.191 -37.084)
		(width 0.1778)
		(layer "F.Cu")
		(net "SYS_HB_LED_D")
	)
	(segment
		(start 131.191 -37.084)
		(end 130.81 -36.703)
		(width 0.1778)
		(layer "F.Cu")
		(net "SYS_HB_LED_D")
	)
	(via
		(at 127.997966 -37.211)
		(size 0.5588)
		(drill 0.3048)
		(layers "F.Cu" "B.Cu")
		(net "SYS_HB_LED_D")
	)
	(via
		(at 126.981966 -37.084)
		(size 0.7112)
		(drill 0.3556)
		(layers "F.Cu" "B.Cu")
		(net "SYS_HB_LED_D")
	)
	(segment
		(start 127.108966 -37.211)
		(end 127.997966 -37.211)
		(width 0.1778)
		(layer "B.Cu")
		(net "SYS_HB_LED_D")
	)
	(segment
		(start 125.559566 -37.973)
		(end 125.559566 -37.889434)
		(width 0.1778)
		(layer "B.Cu")
		(net "SYS_HB_LED_D")
	)
	(segment
		(start 126.981966 -37.084)
		(end 127.108966 -37.211)
		(width 0.1778)
		(layer "B.Cu")
		(net "SYS_HB_LED_D")
	)
	(segment
		(start 125.559566 -37.889434)
		(end 126.365 -37.084)
		(width 0.1778)
		(layer "B.Cu")
		(net "SYS_HB_LED_D")
	)
	(segment
		(start 126.365 -37.084)
		(end 126.981966 -37.084)
		(width 0.1778)
		(layer "B.Cu")
		(net "SYS_HB_LED_D")
	)
	(segment
		(start 114.33302 -196.089016)
		(end 114.33302 -114.955828)
		(width 0.1016)
		(layer "F.Cu")
		(net "SAS_HDD_REDV_TX8_N")
	)
	(segment
		(start 111.322612 -205.4225)
		(end 111.533686 -205.4225)
		(width 0.1016)
		(layer "F.Cu")
		(net "SAS_HDD_REDV_TX8_N")
	)
	(segment
		(start 114.18697 -114.6429)
		(end 114.18697 -114.5794)
		(width 0.1016)
		(layer "F.Cu")
		(net "SAS_HDD_REDV_TX8_N")
	)
	(segment
		(start 112.008412 -204.932788)
		(end 112.008412 -201.7014)
		(width 0.1016)
		(layer "F.Cu")
		(net "SAS_HDD_REDV_TX8_N")
	)
	(segment
		(start 114.260122 -114.779552)
		(end 114.231928 -114.751358)
		(width 0.1016)
		(layer "F.Cu")
		(net "SAS_HDD_REDV_TX8_N")
	)
	(arc
		(start 111.844328 -205.329028)
		(mid 111.965801 -205.147232)
		(end 112.008412 -204.932788)
		(width 0.1016)
		(layer "F.Cu")
		(net "SAS_HDD_REDV_TX8_N")
	)
	(arc
		(start 114.231928 -114.751358)
		(mid 114.198679 -114.701597)
		(end 114.18697 -114.6429)
		(width 0.1016)
		(layer "F.Cu")
		(net "SAS_HDD_REDV_TX8_N")
	)
	(arc
		(start 112.008412 -201.7014)
		(mid 112.399666 -199.733875)
		(end 113.514124 -198.065898)
		(width 0.1016)
		(layer "F.Cu")
		(net "SAS_HDD_REDV_TX8_N")
	)
	(arc
		(start 111.533686 -205.4225)
		(mid 111.695872 -205.398585)
		(end 111.844328 -205.329028)
		(width 0.1016)
		(layer "F.Cu")
		(net "SAS_HDD_REDV_TX8_N")
	)
	(arc
		(start 113.514124 -198.065898)
		(mid 114.120163 -197.158897)
		(end 114.33302 -196.089016)
		(width 0.1016)
		(layer "F.Cu")
		(net "SAS_HDD_REDV_TX8_N")
	)
	(arc
		(start 114.33302 -114.955828)
		(mid 114.314083 -114.860445)
		(end 114.260122 -114.779552)
		(width 0.1016)
		(layer "F.Cu")
		(net "SAS_HDD_REDV_TX8_N")
	)
	(segment
		(start 99.930966 -56.381396)
		(end 99.930966 -58.293)
		(width 0.1143)
		(layer "F.Cu")
		(net "AVSO_IDDTN18")
	)
	(segment
		(start 99.549966 -55.79999)
		(end 99.549966 -56.000396)
		(width 0.1143)
		(layer "F.Cu")
		(net "AVSO_IDDTN18")
	)
	(segment
		(start 99.549966 -56.000396)
		(end 99.930966 -56.381396)
		(width 0.1143)
		(layer "F.Cu")
		(net "AVSO_IDDTN18")
	)
	(via
		(at 100.667566 -57.8612)
		(size 0.7112)
		(drill 0.3556)
		(layers "F.Cu" "B.Cu")
		(net "AVSO_IDDTN18")
	)
	(via
		(at 99.930966 -58.293)
		(size 0.5588)
		(drill 0.3048)
		(layers "F.Cu" "B.Cu")
		(net "AVSO_IDDTN18")
	)
	(segment
		(start 100.667566 -57.8612)
		(end 100.667566 -57.9628)
		(width 0.1143)
		(layer "B.Cu")
		(net "AVSO_IDDTN18")
	)
	(segment
		(start 100.667566 -57.9628)
		(end 100.337366 -58.293)
		(width 0.1143)
		(layer "B.Cu")
		(net "AVSO_IDDTN18")
	)
	(segment
		(start 100.337366 -58.293)
		(end 99.930966 -58.293)
		(width 0.1143)
		(layer "B.Cu")
		(net "AVSO_IDDTN18")
	)
	(segment
		(start 100.057966 -57.0865)
		(end 100.667566 -57.6961)
		(width 0.1143)
		(layer "B.Cu")
		(net "AVSO_IDDTN18")
	)
	(segment
		(start 100.667566 -57.6961)
		(end 100.667566 -57.8612)
		(width 0.1143)
		(layer "B.Cu")
		(net "AVSO_IDDTN18")
	)
	(segment
		(start 143.256 -39.3065)
		(end 142.806674 -39.755826)
		(width 0.1143)
		(layer "F.Cu")
		(net "IOC_WP_N")
	)
	(segment
		(start 143.099536 -42.7101)
		(end 143.099536 -40.843962)
		(width 0.1143)
		(layer "F.Cu")
		(net "IOC_WP_N")
	)
	(segment
		(start 142.806674 -39.755826)
		(end 142.806674 -40.5511)
		(width 0.1143)
		(layer "F.Cu")
		(net "IOC_WP_N")
	)
	(segment
		(start 143.099536 -40.843962)
		(end 142.806674 -40.5511)
		(width 0.1143)
		(layer "F.Cu")
		(net "IOC_WP_N")
	)
	(via
		(at 142.806674 -40.5511)
		(size 0.7112)
		(drill 0.3556)
		(layers "F.Cu" "B.Cu")
		(net "IOC_WP_N")
	)
	(segment
		(start 91.549982 -48.599852)
		(end 91.549982 -48.60925)
		(width 0.1143)
		(layer "F.Cu")
		(net "SIO_DIN_1")
	)
	(segment
		(start 91.549982 -48.60925)
		(end 91.155266 -49.003966)
		(width 0.1143)
		(layer "F.Cu")
		(net "SIO_DIN_1")
	)
	(via
		(at 91.155266 -49.003966)
		(size 0.508)
		(drill 0.254)
		(layers "F.Cu" "B.Cu")
		(net "SIO_DIN_1")
	)
	(segment
		(start 91.155266 -49.003966)
		(end 90.17 -49.003966)
		(width 0.1143)
		(layer "B.Cu")
		(net "SIO_DIN_1")
	)
	(segment
		(start 89.78011 -49.54905)
		(end 88.91016 -50.419)
		(width 0.1143)
		(layer "B.Cu")
		(net "SIO_DIN_1")
	)
	(segment
		(start 88.52916 -52.6415)
		(end 88.52916 -50.8)
		(width 0.1143)
		(layer "B.Cu")
		(net "SIO_DIN_1")
	)
	(segment
		(start 90.17 -49.003966)
		(end 89.78011 -49.393856)
		(width 0.1143)
		(layer "B.Cu")
		(net "SIO_DIN_1")
	)
	(segment
		(start 88.52916 -50.8)
		(end 88.91016 -50.419)
		(width 0.1143)
		(layer "B.Cu")
		(net "SIO_DIN_1")
	)
	(segment
		(start 89.78011 -49.393856)
		(end 89.78011 -49.54905)
		(width 0.1143)
		(layer "B.Cu")
		(net "SIO_DIN_1")
	)
	(segment
		(start 116.038122 -114.779298)
		(end 116.010182 -114.751358)
		(width 0.1016)
		(layer "F.Cu")
		(net "SAS_HDD_REDV_TX7_N")
	)
	(segment
		(start 115.96497 -114.642646)
		(end 115.96497 -114.5794)
		(width 0.1016)
		(layer "F.Cu")
		(net "SAS_HDD_REDV_TX7_N")
	)
	(segment
		(start 116.9797 -195.2117)
		(end 116.672868 -194.905122)
		(width 0.1016)
		(layer "F.Cu")
		(net "SAS_HDD_REDV_TX7_N")
	)
	(segment
		(start 119.5578 -197.7898)
		(end 116.9797 -195.2117)
		(width 0.1016)
		(layer "F.Cu")
		(net "SAS_HDD_REDV_TX7_N")
	)
	(segment
		(start 119.196612 -205.4225)
		(end 119.335042 -205.4225)
		(width 0.1016)
		(layer "F.Cu")
		(net "SAS_HDD_REDV_TX7_N")
	)
	(segment
		(start 116.110766 -193.548)
		(end 116.11102 -193.548)
		(width 0.1016)
		(layer "F.Cu")
		(net "SAS_HDD_REDV_TX7_N")
	)
	(segment
		(start 116.11102 -193.548)
		(end 116.11102 -114.955828)
		(width 0.1016)
		(layer "F.Cu")
		(net "SAS_HDD_REDV_TX7_N")
	)
	(segment
		(start 119.844312 -204.935074)
		(end 119.844312 -198.481442)
		(width 0.1016)
		(layer "F.Cu")
		(net "SAS_HDD_REDV_TX7_N")
	)
	(arc
		(start 116.010182 -114.751358)
		(mid 115.976747 -114.701509)
		(end 115.96497 -114.642646)
		(width 0.1016)
		(layer "F.Cu")
		(net "SAS_HDD_REDV_TX7_N")
	)
	(arc
		(start 119.844312 -198.481442)
		(mid 119.769854 -198.107119)
		(end 119.5578 -197.7898)
		(width 0.1016)
		(layer "F.Cu")
		(net "SAS_HDD_REDV_TX7_N")
	)
	(arc
		(start 119.692928 -205.30058)
		(mid 119.804979 -205.132884)
		(end 119.844312 -204.935074)
		(width 0.1016)
		(layer "F.Cu")
		(net "SAS_HDD_REDV_TX7_N")
	)
	(arc
		(start 116.672868 -194.905122)
		(mid 116.256825 -194.282469)
		(end 116.110766 -193.548)
		(width 0.1016)
		(layer "F.Cu")
		(net "SAS_HDD_REDV_TX7_N")
	)
	(arc
		(start 119.335042 -205.4225)
		(mid 119.524097 -205.391223)
		(end 119.692928 -205.30058)
		(width 0.1016)
		(layer "F.Cu")
		(net "SAS_HDD_REDV_TX7_N")
	)
	(arc
		(start 116.11102 -114.955828)
		(mid 116.092116 -114.860322)
		(end 116.038122 -114.779298)
		(width 0.1016)
		(layer "F.Cu")
		(net "SAS_HDD_REDV_TX7_N")
	)
	(segment
		(start 127.423164 -87.42299)
		(end 127.350012 -87.349838)
		(width 0.1016)
		(layer "F.Cu")
		(net "3X24_SAS_TX16_P")
	)
	(segment
		(start 129.224024 -87.678514)
		(end 128.820926 -87.678514)
		(width 0.1016)
		(layer "F.Cu")
		(net "3X24_SAS_TX16_P")
	)
	(segment
		(start 128.768602 -87.730838)
		(end 128.166368 -87.730838)
		(width 0.1016)
		(layer "F.Cu")
		(net "3X24_SAS_TX16_P")
	)
	(segment
		(start 130.732022 -87.376)
		(end 129.954782 -87.376)
		(width 0.1016)
		(layer "F.Cu")
		(net "3X24_SAS_TX16_P")
	)
	(segment
		(start 128.820926 -87.678514)
		(end 128.768602 -87.730838)
		(width 0.1016)
		(layer "F.Cu")
		(net "3X24_SAS_TX16_P")
	)
	(arc
		(start 128.02108 -87.720678)
		(mid 127.930508 -87.703916)
		(end 127.841756 -87.679276)
		(width 0.1016)
		(layer "F.Cu")
		(net "3X24_SAS_TX16_P")
	)
	(arc
		(start 129.4638 -87.5792)
		(mid 129.35379 -87.652706)
		(end 129.224024 -87.678514)
		(width 0.1016)
		(layer "F.Cu")
		(net "3X24_SAS_TX16_P")
	)
	(arc
		(start 131.0386 -87.249)
		(mid 130.897941 -87.342985)
		(end 130.732022 -87.376)
		(width 0.1016)
		(layer "F.Cu")
		(net "3X24_SAS_TX16_P")
	)
	(arc
		(start 128.166368 -87.730838)
		(mid 128.093548 -87.728277)
		(end 128.02108 -87.720678)
		(width 0.1016)
		(layer "F.Cu")
		(net "3X24_SAS_TX16_P")
	)
	(arc
		(start 129.954782 -87.376)
		(mid 129.689076 -87.428758)
		(end 129.4638 -87.5792)
		(width 0.1016)
		(layer "F.Cu")
		(net "3X24_SAS_TX16_P")
	)
	(arc
		(start 127.841756 -87.679276)
		(mid 127.617292 -87.575908)
		(end 127.423164 -87.42299)
		(width 0.1016)
		(layer "F.Cu")
		(net "3X24_SAS_TX16_P")
	)
	(segment
		(start 115.185698 -35.225736)
		(end 115.487704 -34.92373)
		(width 0.1143)
		(layer "F.Cu")
		(net "IOC_GPIO_0")
	)
	(segment
		(start 114.154966 -36.195)
		(end 115.12423 -35.225736)
		(width 0.1143)
		(layer "F.Cu")
		(net "IOC_GPIO_0")
	)
	(segment
		(start 113.67516 -36.195)
		(end 114.154966 -36.195)
		(width 0.1143)
		(layer "F.Cu")
		(net "IOC_GPIO_0")
	)
	(segment
		(start 113.150142 -36.599876)
		(end 113.270284 -36.599876)
		(width 0.1143)
		(layer "F.Cu")
		(net "IOC_GPIO_0")
	)
	(segment
		(start 115.12423 -35.225736)
		(end 115.185698 -35.225736)
		(width 0.1143)
		(layer "F.Cu")
		(net "IOC_GPIO_0")
	)
	(segment
		(start 113.270284 -36.599876)
		(end 113.67516 -36.195)
		(width 0.1143)
		(layer "F.Cu")
		(net "IOC_GPIO_0")
	)
	(via
		(at 115.487704 -34.92373)
		(size 0.508)
		(drill 0.254)
		(layers "F.Cu" "B.Cu")
		(net "IOC_GPIO_0")
	)
	(segment
		(start 115.043966 -34.479992)
		(end 115.487704 -34.92373)
		(width 0.1143)
		(layer "B.Cu")
		(net "IOC_GPIO_0")
	)
	(segment
		(start 115.043966 -34.163)
		(end 115.043966 -34.479992)
		(width 0.1143)
		(layer "B.Cu")
		(net "IOC_GPIO_0")
	)
	(segment
		(start 116.827554 -36.528248)
		(end 114.830606 -38.525196)
		(width 0.1143)
		(layer "F.Cu")
		(net "IOC_GPIO_30")
	)
	(segment
		(start 114.61877 -38.525196)
		(end 114.497866 -38.6461)
		(width 0.1143)
		(layer "F.Cu")
		(net "IOC_GPIO_30")
	)
	(segment
		(start 116.9162 -35.8394)
		(end 116.9162 -35.973766)
		(width 0.1143)
		(layer "F.Cu")
		(net "IOC_GPIO_30")
	)
	(segment
		(start 114.497866 -38.6461)
		(end 113.81867 -38.6461)
		(width 0.1143)
		(layer "F.Cu")
		(net "IOC_GPIO_30")
	)
	(segment
		(start 116.9162 -35.973766)
		(end 116.827554 -36.062412)
		(width 0.1143)
		(layer "F.Cu")
		(net "IOC_GPIO_30")
	)
	(segment
		(start 113.81867 -38.6461)
		(end 113.464848 -38.999922)
		(width 0.1143)
		(layer "F.Cu")
		(net "IOC_GPIO_30")
	)
	(segment
		(start 116.827554 -36.062412)
		(end 116.827554 -36.528248)
		(width 0.1143)
		(layer "F.Cu")
		(net "IOC_GPIO_30")
	)
	(segment
		(start 114.830606 -38.525196)
		(end 114.61877 -38.525196)
		(width 0.1143)
		(layer "F.Cu")
		(net "IOC_GPIO_30")
	)
	(segment
		(start 113.464848 -38.999922)
		(end 113.150142 -38.999922)
		(width 0.1143)
		(layer "F.Cu")
		(net "IOC_GPIO_30")
	)
	(via
		(at 116.9162 -35.8394)
		(size 0.508)
		(drill 0.254)
		(layers "F.Cu" "B.Cu")
		(net "IOC_GPIO_30")
	)
	(segment
		(start 117.050566 -35.8394)
		(end 116.9162 -35.8394)
		(width 0.1143)
		(layer "B.Cu")
		(net "IOC_GPIO_30")
	)
	(segment
		(start 117.710966 -35.306)
		(end 117.583966 -35.306)
		(width 0.1143)
		(layer "B.Cu")
		(net "IOC_GPIO_30")
	)
	(segment
		(start 117.583966 -35.306)
		(end 117.050566 -35.8394)
		(width 0.1143)
		(layer "B.Cu")
		(net "IOC_GPIO_30")
	)
	(segment
		(start 113.150142 -33.399984)
		(end 113.636806 -32.91332)
		(width 0.1143)
		(layer "F.Cu")
		(net "IOC_GPIO_9")
	)
	(via
		(at 113.636806 -32.91332)
		(size 0.508)
		(drill 0.254)
		(layers "F.Cu" "B.Cu")
		(net "IOC_GPIO_9")
	)
	(segment
		(start 113.192306 -32.46882)
		(end 113.636806 -32.91332)
		(width 0.1143)
		(layer "B.Cu")
		(net "IOC_GPIO_9")
	)
	(segment
		(start 113.044986 -32.46882)
		(end 113.192306 -32.46882)
		(width 0.1143)
		(layer "B.Cu")
		(net "IOC_GPIO_9")
	)
	(segment
		(start 127.637032 -94.96298)
		(end 126.48565 -94.96298)
		(width 0.1016)
		(layer "F.Cu")
		(net "3X24_SAS_TX23_N")
	)
	(segment
		(start 131.076954 -98.034094)
		(end 128.42113 -95.37827)
		(width 0.1016)
		(layer "F.Cu")
		(net "3X24_SAS_TX23_N")
	)
	(segment
		(start 127.686054 -95.012002)
		(end 127.637032 -94.96298)
		(width 0.1016)
		(layer "F.Cu")
		(net "3X24_SAS_TX23_N")
	)
	(segment
		(start 126.1999 -94.844616)
		(end 125.95606 -94.60103)
		(width 0.1016)
		(layer "F.Cu")
		(net "3X24_SAS_TX23_N")
	)
	(segment
		(start 128.42113 -95.37827)
		(end 128.315974 -95.27286)
		(width 0.1016)
		(layer "F.Cu")
		(net "3X24_SAS_TX23_N")
	)
	(arc
		(start 131.17957 -98.281744)
		(mid 131.152908 -98.147703)
		(end 131.076954 -98.034094)
		(width 0.1016)
		(layer "F.Cu")
		(net "3X24_SAS_TX23_N")
	)
	(arc
		(start 125.95606 -94.60103)
		(mid 125.67802 -94.415156)
		(end 125.350016 -94.349824)
		(width 0.1016)
		(layer "F.Cu")
		(net "3X24_SAS_TX23_N")
	)
	(arc
		(start 126.48565 -94.96298)
		(mid 126.331002 -94.932219)
		(end 126.1999 -94.844616)
		(width 0.1016)
		(layer "F.Cu")
		(net "3X24_SAS_TX23_N")
	)
	(arc
		(start 128.1684 -95.211646)
		(mid 127.90736 -95.159816)
		(end 127.686054 -95.012002)
		(width 0.1016)
		(layer "F.Cu")
		(net "3X24_SAS_TX23_N")
	)
	(arc
		(start 131.02971 -98.64344)
		(mid 131.140593 -98.477492)
		(end 131.17957 -98.281744)
		(width 0.1016)
		(layer "F.Cu")
		(net "3X24_SAS_TX23_N")
	)
	(arc
		(start 128.315974 -95.27286)
		(mid 128.248266 -95.227619)
		(end 128.1684 -95.211646)
		(width 0.1016)
		(layer "F.Cu")
		(net "3X24_SAS_TX23_N")
	)
	(segment
		(start 131.52247 -98.300032)
		(end 131.52247 -98.281744)
		(width 0.1016)
		(layer "F.Cu")
		(net "3X24_SAS_TX23_P")
	)
	(segment
		(start 131.319524 -97.791524)
		(end 128.663954 -95.135954)
		(width 0.1016)
		(layer "F.Cu")
		(net "3X24_SAS_TX23_P")
	)
	(segment
		(start 127.928624 -94.769432)
		(end 127.901192 -94.742)
		(width 0.1016)
		(layer "F.Cu")
		(net "3X24_SAS_TX23_P")
	)
	(segment
		(start 126.517654 -94.517718)
		(end 126.350014 -94.349824)
		(width 0.1016)
		(layer "F.Cu")
		(net "3X24_SAS_TX23_P")
	)
	(segment
		(start 126.764796 -94.742)
		(end 126.642876 -94.62008)
		(width 0.1016)
		(layer "F.Cu")
		(net "3X24_SAS_TX23_P")
	)
	(segment
		(start 128.663954 -95.135954)
		(end 128.558798 -95.03029)
		(width 0.1016)
		(layer "F.Cu")
		(net "3X24_SAS_TX23_P")
	)
	(segment
		(start 127.901192 -94.742)
		(end 126.764796 -94.742)
		(width 0.1016)
		(layer "F.Cu")
		(net "3X24_SAS_TX23_P")
	)
	(arc
		(start 126.642876 -94.62008)
		(mid 126.577706 -94.57203)
		(end 126.517654 -94.517718)
		(width 0.1016)
		(layer "F.Cu")
		(net "3X24_SAS_TX23_P")
	)
	(arc
		(start 131.52247 -98.281744)
		(mid 131.469789 -98.016427)
		(end 131.319524 -97.791524)
		(width 0.1016)
		(layer "F.Cu")
		(net "3X24_SAS_TX23_P")
	)
	(arc
		(start 128.1684 -94.868746)
		(mid 128.038636 -94.842934)
		(end 127.928624 -94.769432)
		(width 0.1016)
		(layer "F.Cu")
		(net "3X24_SAS_TX23_P")
	)
	(arc
		(start 128.558798 -95.03029)
		(mid 128.379681 -94.910638)
		(end 128.1684 -94.868746)
		(width 0.1016)
		(layer "F.Cu")
		(net "3X24_SAS_TX23_P")
	)
	(arc
		(start 131.66471 -98.64344)
		(mid 131.559434 -98.485883)
		(end 131.52247 -98.300032)
		(width 0.1016)
		(layer "F.Cu")
		(net "3X24_SAS_TX23_P")
	)
	(segment
		(start 113.264696 -34.60623)
		(end 113.543842 -34.327084)
		(width 0.1143)
		(layer "F.Cu")
		(net "IOC_GPIO_10")
	)
	(segment
		(start 112.98682 -34.60623)
		(end 113.264696 -34.60623)
		(width 0.1143)
		(layer "F.Cu")
		(net "IOC_GPIO_10")
	)
	(segment
		(start 114.353086 -33.275778)
		(end 114.353086 -32.82442)
		(width 0.1143)
		(layer "F.Cu")
		(net "IOC_GPIO_10")
	)
	(segment
		(start 113.543842 -34.327084)
		(end 113.543842 -34.085022)
		(width 0.1143)
		(layer "F.Cu")
		(net "IOC_GPIO_10")
	)
	(segment
		(start 113.543842 -34.085022)
		(end 114.353086 -33.275778)
		(width 0.1143)
		(layer "F.Cu")
		(net "IOC_GPIO_10")
	)
	(segment
		(start 112.350042 -34.99993)
		(end 112.59312 -34.99993)
		(width 0.1143)
		(layer "F.Cu")
		(net "IOC_GPIO_10")
	)
	(segment
		(start 112.59312 -34.99993)
		(end 112.98682 -34.60623)
		(width 0.1143)
		(layer "F.Cu")
		(net "IOC_GPIO_10")
	)
	(via
		(at 114.353086 -32.82442)
		(size 0.508)
		(drill 0.254)
		(layers "F.Cu" "B.Cu")
		(net "IOC_GPIO_10")
	)
	(segment
		(start 114.353086 -33.32988)
		(end 114.353086 -32.82442)
		(width 0.1143)
		(layer "B.Cu")
		(net "IOC_GPIO_10")
	)
	(segment
		(start 113.850166 -33.782)
		(end 114.353086 -33.32988)
		(width 0.1143)
		(layer "B.Cu")
		(net "IOC_GPIO_10")
	)
	(segment
		(start 132.85597 -98.220022)
		(end 132.85597 -98.116644)
		(width 0.1016)
		(layer "F.Cu")
		(net "3X24_SAS_TX22_N")
	)
	(segment
		(start 126.91237 -93.584268)
		(end 126.90983 -93.581728)
		(width 0.1016)
		(layer "F.Cu")
		(net "3X24_SAS_TX22_N")
	)
	(segment
		(start 132.7785 -97.9297)
		(end 128.881378 -94.032578)
		(width 0.1016)
		(layer "F.Cu")
		(net "3X24_SAS_TX22_N")
	)
	(segment
		(start 128.4478 -93.853)
		(end 127.561086 -93.853)
		(width 0.1016)
		(layer "F.Cu")
		(net "3X24_SAS_TX22_N")
	)
	(arc
		(start 126.90983 -93.581728)
		(mid 126.652984 -93.410109)
		(end 126.350014 -93.349826)
		(width 0.1016)
		(layer "F.Cu")
		(net "3X24_SAS_TX22_N")
	)
	(arc
		(start 132.85597 -98.116644)
		(mid 132.835843 -98.015457)
		(end 132.7785 -97.9297)
		(width 0.1016)
		(layer "F.Cu")
		(net "3X24_SAS_TX22_N")
	)
	(arc
		(start 128.881378 -94.032578)
		(mid 128.682451 -93.899659)
		(end 128.4478 -93.853)
		(width 0.1016)
		(layer "F.Cu")
		(net "3X24_SAS_TX22_N")
	)
	(arc
		(start 127.561086 -93.853)
		(mid 127.209994 -93.783163)
		(end 126.91237 -93.584268)
		(width 0.1016)
		(layer "F.Cu")
		(net "3X24_SAS_TX22_N")
	)
	(arc
		(start 132.72897 -98.5266)
		(mid 132.822955 -98.385941)
		(end 132.85597 -98.220022)
		(width 0.1016)
		(layer "F.Cu")
		(net "3X24_SAS_TX22_N")
	)
	(segment
		(start 133.02107 -97.68713)
		(end 129.123948 -93.790008)
		(width 0.1016)
		(layer "F.Cu")
		(net "3X24_SAS_TX22_P")
	)
	(segment
		(start 133.19887 -98.20275)
		(end 133.19887 -98.11639)
		(width 0.1016)
		(layer "F.Cu")
		(net "3X24_SAS_TX22_P")
	)
	(segment
		(start 133.36397 -98.5266)
		(end 133.311138 -98.473768)
		(width 0.1016)
		(layer "F.Cu")
		(net "3X24_SAS_TX22_P")
	)
	(segment
		(start 128.4478 -93.5101)
		(end 127.736854 -93.5101)
		(width 0.1016)
		(layer "F.Cu")
		(net "3X24_SAS_TX22_P")
	)
	(arc
		(start 127.644652 -93.502226)
		(mid 127.591351 -93.490373)
		(end 127.539496 -93.47327)
		(width 0.1016)
		(layer "F.Cu")
		(net "3X24_SAS_TX22_P")
	)
	(arc
		(start 133.19887 -98.11639)
		(mid 133.152675 -97.884064)
		(end 133.02107 -97.68713)
		(width 0.1016)
		(layer "F.Cu")
		(net "3X24_SAS_TX22_P")
	)
	(arc
		(start 129.123948 -93.790008)
		(mid 128.813699 -93.582863)
		(end 128.4478 -93.5101)
		(width 0.1016)
		(layer "F.Cu")
		(net "3X24_SAS_TX22_P")
	)
	(arc
		(start 127.539496 -93.47327)
		(mid 127.438292 -93.421463)
		(end 127.350012 -93.349826)
		(width 0.1016)
		(layer "F.Cu")
		(net "3X24_SAS_TX22_P")
	)
	(arc
		(start 133.311138 -98.473768)
		(mid 133.228054 -98.349424)
		(end 133.19887 -98.20275)
		(width 0.1016)
		(layer "F.Cu")
		(net "3X24_SAS_TX22_P")
	)
	(arc
		(start 127.736854 -93.5101)
		(mid 127.690586 -93.508119)
		(end 127.644652 -93.502226)
		(width 0.1016)
		(layer "F.Cu")
		(net "3X24_SAS_TX22_P")
	)
	(segment
		(start 117.34038 -34.798)
		(end 114.90198 -37.2364)
		(width 0.1143)
		(layer "F.Cu")
		(net "IOC_GPIO_31")
	)
	(segment
		(start 114.113564 -37.2364)
		(end 113.949988 -37.399976)
		(width 0.1143)
		(layer "F.Cu")
		(net "IOC_GPIO_31")
	)
	(segment
		(start 118.364 -34.798)
		(end 117.34038 -34.798)
		(width 0.1143)
		(layer "F.Cu")
		(net "IOC_GPIO_31")
	)
	(segment
		(start 114.90198 -37.2364)
		(end 114.113564 -37.2364)
		(width 0.1143)
		(layer "F.Cu")
		(net "IOC_GPIO_31")
	)
	(segment
		(start 134.5819 -97.8027)
		(end 131.965446 -95.186246)
		(width 0.1016)
		(layer "F.Cu")
		(net "3X24_SAS_TX21_N")
	)
	(segment
		(start 129.145284 -93.099128)
		(end 127.74422 -93.099128)
		(width 0.1016)
		(layer "F.Cu")
		(net "3X24_SAS_TX21_N")
	)
	(segment
		(start 125.600714 -92.60078)
		(end 125.350016 -92.349828)
		(width 0.1016)
		(layer "F.Cu")
		(net "3X24_SAS_TX21_N")
	)
	(segment
		(start 126.293118 -92.7862)
		(end 126.04877 -92.7862)
		(width 0.1016)
		(layer "F.Cu")
		(net "3X24_SAS_TX21_N")
	)
	(segment
		(start 134.65937 -98.158554)
		(end 134.65937 -97.989644)
		(width 0.1016)
		(layer "F.Cu")
		(net "3X24_SAS_TX21_N")
	)
	(segment
		(start 131.965446 -95.186246)
		(end 131.774946 -94.995492)
		(width 0.1016)
		(layer "F.Cu")
		(net "3X24_SAS_TX21_N")
	)
	(segment
		(start 130.994404 -94.672658)
		(end 130.9878 -94.6658)
		(width 0.1016)
		(layer "F.Cu")
		(net "3X24_SAS_TX21_N")
	)
	(segment
		(start 130.9878 -94.6658)
		(end 129.6162 -93.2942)
		(width 0.1016)
		(layer "F.Cu")
		(net "3X24_SAS_TX21_N")
	)
	(segment
		(start 127.429768 -92.968826)
		(end 126.734062 -92.968826)
		(width 0.1016)
		(layer "F.Cu")
		(net "3X24_SAS_TX21_N")
	)
	(arc
		(start 131.6228 -94.932754)
		(mid 131.416781 -94.908553)
		(end 131.221988 -94.83725)
		(width 0.1016)
		(layer "F.Cu")
		(net "3X24_SAS_TX21_N")
	)
	(arc
		(start 126.349506 -92.809568)
		(mid 126.323635 -92.792282)
		(end 126.293118 -92.7862)
		(width 0.1016)
		(layer "F.Cu")
		(net "3X24_SAS_TX21_N")
	)
	(arc
		(start 131.221988 -94.83725)
		(mid 131.101654 -94.764)
		(end 130.994404 -94.672658)
		(width 0.1016)
		(layer "F.Cu")
		(net "3X24_SAS_TX21_N")
	)
	(arc
		(start 127.74422 -93.099128)
		(mid 127.646338 -93.079658)
		(end 127.563372 -93.024198)
		(width 0.1016)
		(layer "F.Cu")
		(net "3X24_SAS_TX21_N")
	)
	(arc
		(start 134.65937 -97.989644)
		(mid 134.639243 -97.888457)
		(end 134.5819 -97.8027)
		(width 0.1016)
		(layer "F.Cu")
		(net "3X24_SAS_TX21_N")
	)
	(arc
		(start 127.563372 -93.024198)
		(mid 127.502074 -92.98324)
		(end 127.429768 -92.968826)
		(width 0.1016)
		(layer "F.Cu")
		(net "3X24_SAS_TX21_N")
	)
	(arc
		(start 126.734062 -92.968826)
		(mid 126.525953 -92.927431)
		(end 126.349506 -92.809568)
		(width 0.1016)
		(layer "F.Cu")
		(net "3X24_SAS_TX21_N")
	)
	(arc
		(start 129.6162 -93.2942)
		(mid 129.400142 -93.149835)
		(end 129.145284 -93.099128)
		(width 0.1016)
		(layer "F.Cu")
		(net "3X24_SAS_TX21_N")
	)
	(arc
		(start 131.774946 -94.995492)
		(mid 131.705112 -94.948986)
		(end 131.6228 -94.932754)
		(width 0.1016)
		(layer "F.Cu")
		(net "3X24_SAS_TX21_N")
	)
	(arc
		(start 134.50697 -98.5266)
		(mid 134.619799 -98.357739)
		(end 134.65937 -98.158554)
		(width 0.1016)
		(layer "F.Cu")
		(net "3X24_SAS_TX21_N")
	)
	(arc
		(start 126.04877 -92.7862)
		(mid 125.806296 -92.738062)
		(end 125.600714 -92.60078)
		(width 0.1016)
		(layer "F.Cu")
		(net "3X24_SAS_TX21_N")
	)
	(segment
		(start 126.423166 -92.42298)
		(end 126.350014 -92.349828)
		(width 0.1016)
		(layer "F.Cu")
		(net "3X24_SAS_TX21_P")
	)
	(segment
		(start 131.236974 -94.429834)
		(end 129.85877 -93.05163)
		(width 0.1016)
		(layer "F.Cu")
		(net "3X24_SAS_TX21_P")
	)
	(segment
		(start 134.82447 -97.56013)
		(end 132.20827 -94.94393)
		(width 0.1016)
		(layer "F.Cu")
		(net "3X24_SAS_TX21_P")
	)
	(segment
		(start 127.719328 -92.730828)
		(end 127.16637 -92.730828)
		(width 0.1016)
		(layer "F.Cu")
		(net "3X24_SAS_TX21_P")
	)
	(segment
		(start 129.145538 -92.756228)
		(end 127.780542 -92.756228)
		(width 0.1016)
		(layer "F.Cu")
		(net "3X24_SAS_TX21_P")
	)
	(segment
		(start 132.20827 -94.94393)
		(end 132.017516 -94.752922)
		(width 0.1016)
		(layer "F.Cu")
		(net "3X24_SAS_TX21_P")
	)
	(segment
		(start 135.00227 -98.189288)
		(end 135.00227 -97.989644)
		(width 0.1016)
		(layer "F.Cu")
		(net "3X24_SAS_TX21_P")
	)
	(arc
		(start 132.017516 -94.752922)
		(mid 131.836404 -94.632)
		(end 131.6228 -94.5896)
		(width 0.1016)
		(layer "F.Cu")
		(net "3X24_SAS_TX21_P")
	)
	(arc
		(start 127.780542 -92.756228)
		(mid 127.747396 -92.749635)
		(end 127.719328 -92.730828)
		(width 0.1016)
		(layer "F.Cu")
		(net "3X24_SAS_TX21_P")
	)
	(arc
		(start 135.00227 -97.989644)
		(mid 134.956124 -97.757181)
		(end 134.82447 -97.56013)
		(width 0.1016)
		(layer "F.Cu")
		(net "3X24_SAS_TX21_P")
	)
	(arc
		(start 126.841758 -92.679266)
		(mid 126.617294 -92.575898)
		(end 126.423166 -92.42298)
		(width 0.1016)
		(layer "F.Cu")
		(net "3X24_SAS_TX21_P")
	)
	(arc
		(start 127.16637 -92.730828)
		(mid 127.002034 -92.717821)
		(end 126.841758 -92.679266)
		(width 0.1016)
		(layer "F.Cu")
		(net "3X24_SAS_TX21_P")
	)
	(arc
		(start 131.6228 -94.5896)
		(mid 131.413997 -94.548084)
		(end 131.236974 -94.429834)
		(width 0.1016)
		(layer "F.Cu")
		(net "3X24_SAS_TX21_P")
	)
	(arc
		(start 135.14197 -98.5266)
		(mid 135.038563 -98.37184)
		(end 135.00227 -98.189288)
		(width 0.1016)
		(layer "F.Cu")
		(net "3X24_SAS_TX21_P")
	)
	(arc
		(start 129.85877 -93.05163)
		(mid 129.531522 -92.833033)
		(end 129.145538 -92.756228)
		(width 0.1016)
		(layer "F.Cu")
		(net "3X24_SAS_TX21_P")
	)
	(segment
		(start 103.01097 -108.8136)
		(end 103.03637 -108.7882)
		(width 0.1143)
		(layer "F.Cu")
		(net "EXP_I2C_SDA_4")
	)
	(segment
		(start 187.0456 -147.53336)
		(end 186.34456 -147.53336)
		(width 0.1143)
		(layer "F.Cu")
		(net "EXP_I2C_SDA_4")
	)
	(segment
		(start 186.34456 -147.53336)
		(end 184.7596 -145.9484)
		(width 0.1143)
		(layer "F.Cu")
		(net "EXP_I2C_SDA_4")
	)
	(segment
		(start 183.706262 -144.78)
		(end 182.127144 -143.200882)
		(width 0.1143)
		(layer "F.Cu")
		(net "EXP_I2C_SDA_4")
	)
	(segment
		(start 96.68637 -108.331)
		(end 97.16897 -108.8136)
		(width 0.1143)
		(layer "F.Cu")
		(net "EXP_I2C_SDA_4")
	)
	(segment
		(start 97.16897 -108.8136)
		(end 103.01097 -108.8136)
		(width 0.1143)
		(layer "F.Cu")
		(net "EXP_I2C_SDA_4")
	)
	(segment
		(start 184.7596 -145.9484)
		(end 184.7596 -145.347436)
		(width 0.1143)
		(layer "F.Cu")
		(net "EXP_I2C_SDA_4")
	)
	(segment
		(start 184.192164 -144.78)
		(end 183.706262 -144.78)
		(width 0.1143)
		(layer "F.Cu")
		(net "EXP_I2C_SDA_4")
	)
	(segment
		(start 103.03637 -108.7882)
		(end 103.26497 -108.7882)
		(width 0.1143)
		(layer "F.Cu")
		(net "EXP_I2C_SDA_4")
	)
	(segment
		(start 96.15297 -108.331)
		(end 96.68637 -108.331)
		(width 0.1143)
		(layer "F.Cu")
		(net "EXP_I2C_SDA_4")
	)
	(segment
		(start 184.7596 -145.347436)
		(end 184.192164 -144.78)
		(width 0.1143)
		(layer "F.Cu")
		(net "EXP_I2C_SDA_4")
	)
	(segment
		(start 108.349796 -100.350066)
		(end 107.84967 -100.850192)
		(width 0.1143)
		(layer "F.Cu")
		(net "EXP_I2C_SDA_4")
	)
	(via
		(at 107.84967 -100.850192)
		(size 0.508)
		(drill 0.254)
		(layers "F.Cu" "B.Cu")
		(net "EXP_I2C_SDA_4")
	)
	(via
		(at 103.26497 -108.7882)
		(size 0.508)
		(drill 0.254)
		(layers "F.Cu" "B.Cu")
		(net "EXP_I2C_SDA_4")
	)
	(via
		(at 105.60177 -103.6828)
		(size 0.7112)
		(drill 0.3556)
		(layers "F.Cu" "B.Cu")
		(net "EXP_I2C_SDA_4")
	)
	(via
		(at 182.127144 -143.200882)
		(size 0.5588)
		(drill 0.3048)
		(layers "F.Cu" "B.Cu")
		(net "EXP_I2C_SDA_4")
	)
	(segment
		(start 103.26497 -108.7882)
		(end 103.46817 -108.7882)
		(width 0.1143)
		(layer "B.Cu")
		(net "EXP_I2C_SDA_4")
	)
	(segment
		(start 105.411524 -108.766864)
		(end 105.411524 -103.873046)
		(width 0.1143)
		(layer "B.Cu")
		(net "EXP_I2C_SDA_4")
	)
	(segment
		(start 106.287824 -102.82809)
		(end 106.703876 -102.412038)
		(width 0.1143)
		(layer "B.Cu")
		(net "EXP_I2C_SDA_4")
	)
	(segment
		(start 107.84967 -101.23043)
		(end 107.84967 -100.850192)
		(width 0.1143)
		(layer "B.Cu")
		(net "EXP_I2C_SDA_4")
	)
	(segment
		(start 106.87177 -102.412038)
		(end 107.41152 -101.872288)
		(width 0.1143)
		(layer "B.Cu")
		(net "EXP_I2C_SDA_4")
	)
	(segment
		(start 105.60177 -103.6828)
		(end 106.287824 -102.996746)
		(width 0.1143)
		(layer "B.Cu")
		(net "EXP_I2C_SDA_4")
	)
	(segment
		(start 106.703876 -102.412038)
		(end 106.87177 -102.412038)
		(width 0.1143)
		(layer "B.Cu")
		(net "EXP_I2C_SDA_4")
	)
	(segment
		(start 103.85552 -109.17555)
		(end 105.002838 -109.17555)
		(width 0.1143)
		(layer "B.Cu")
		(net "EXP_I2C_SDA_4")
	)
	(segment
		(start 105.002838 -109.17555)
		(end 105.411524 -108.766864)
		(width 0.1143)
		(layer "B.Cu")
		(net "EXP_I2C_SDA_4")
	)
	(segment
		(start 107.41152 -101.66858)
		(end 107.84967 -101.23043)
		(width 0.1143)
		(layer "B.Cu")
		(net "EXP_I2C_SDA_4")
	)
	(segment
		(start 106.287824 -102.996746)
		(end 106.287824 -102.82809)
		(width 0.1143)
		(layer "B.Cu")
		(net "EXP_I2C_SDA_4")
	)
	(segment
		(start 107.41152 -101.872288)
		(end 107.41152 -101.66858)
		(width 0.1143)
		(layer "B.Cu")
		(net "EXP_I2C_SDA_4")
	)
	(segment
		(start 105.411524 -103.873046)
		(end 105.60177 -103.6828)
		(width 0.1143)
		(layer "B.Cu")
		(net "EXP_I2C_SDA_4")
	)
	(segment
		(start 103.46817 -108.7882)
		(end 103.85552 -109.17555)
		(width 0.1143)
		(layer "B.Cu")
		(net "EXP_I2C_SDA_4")
	)
	(segment
		(start 92.254578 -118.491)
		(end 92.64777 -118.491)
		(width 0.127)
		(layer "In2.Cu")
		(net "EXP_I2C_SDA_4")
	)
	(segment
		(start 102.60457 -108.7882)
		(end 103.26497 -108.7882)
		(width 0.127)
		(layer "In2.Cu")
		(net "EXP_I2C_SDA_4")
	)
	(segment
		(start 182.127144 -143.200882)
		(end 181.445662 -142.5194)
		(width 0.127)
		(layer "In2.Cu")
		(net "EXP_I2C_SDA_4")
	)
	(segment
		(start 181.445662 -142.5194)
		(end 158.73603 -142.5194)
		(width 0.127)
		(layer "In2.Cu")
		(net "EXP_I2C_SDA_4")
	)
	(segment
		(start 111.882174 -141.986)
		(end 91.96451 -122.068336)
		(width 0.127)
		(layer "In2.Cu")
		(net "EXP_I2C_SDA_4")
	)
	(segment
		(start 158.73603 -142.5194)
		(end 158.20263 -141.986)
		(width 0.127)
		(layer "In2.Cu")
		(net "EXP_I2C_SDA_4")
	)
	(segment
		(start 91.96451 -118.781068)
		(end 92.254578 -118.491)
		(width 0.127)
		(layer "In2.Cu")
		(net "EXP_I2C_SDA_4")
	)
	(segment
		(start 98.28657 -113.1062)
		(end 102.60457 -108.7882)
		(width 0.127)
		(layer "In2.Cu")
		(net "EXP_I2C_SDA_4")
	)
	(segment
		(start 91.96451 -122.068336)
		(end 91.96451 -118.781068)
		(width 0.127)
		(layer "In2.Cu")
		(net "EXP_I2C_SDA_4")
	)
	(segment
		(start 158.20263 -141.986)
		(end 111.882174 -141.986)
		(width 0.127)
		(layer "In2.Cu")
		(net "EXP_I2C_SDA_4")
	)
	(segment
		(start 92.64777 -118.491)
		(end 98.03257 -113.1062)
		(width 0.127)
		(layer "In2.Cu")
		(net "EXP_I2C_SDA_4")
	)
	(segment
		(start 98.03257 -113.1062)
		(end 98.28657 -113.1062)
		(width 0.127)
		(layer "In2.Cu")
		(net "EXP_I2C_SDA_4")
	)
	(segment
		(start 116.079778 -33.02)
		(end 114.099848 -34.99993)
		(width 0.1143)
		(layer "F.Cu")
		(net "IOC_GPIO_11")
	)
	(segment
		(start 114.099848 -34.99993)
		(end 113.949988 -34.99993)
		(width 0.1143)
		(layer "F.Cu")
		(net "IOC_GPIO_11")
	)
	(segment
		(start 118.364 -33.02)
		(end 116.079778 -33.02)
		(width 0.1143)
		(layer "F.Cu")
		(net "IOC_GPIO_11")
	)
	(segment
		(start 136.305798 -97.373948)
		(end 132.800598 -93.868748)
		(width 0.1016)
		(layer "F.Cu")
		(net "3X24_SAS_TX20_N")
	)
	(segment
		(start 129.295906 -91.8464)
		(end 127.62357 -91.8464)
		(width 0.1016)
		(layer "F.Cu")
		(net "3X24_SAS_TX20_N")
	)
	(segment
		(start 132.363972 -93.6879)
		(end 131.78409 -93.6879)
		(width 0.1016)
		(layer "F.Cu")
		(net "3X24_SAS_TX20_N")
	)
	(segment
		(start 127.62357 -91.8464)
		(end 127.61087 -91.8591)
		(width 0.1016)
		(layer "F.Cu")
		(net "3X24_SAS_TX20_N")
	)
	(segment
		(start 131.1402 -93.4212)
		(end 129.7559 -92.0369)
		(width 0.1016)
		(layer "F.Cu")
		(net "3X24_SAS_TX20_N")
	)
	(segment
		(start 126.584964 -91.736164)
		(end 126.456948 -91.608148)
		(width 0.1016)
		(layer "F.Cu")
		(net "3X24_SAS_TX20_N")
	)
	(segment
		(start 136.300718 -98.171)
		(end 136.387332 -98.084386)
		(width 0.1016)
		(layer "F.Cu")
		(net "3X24_SAS_TX20_N")
	)
	(segment
		(start 127.39624 -91.948)
		(end 127.09652 -91.948)
		(width 0.1016)
		(layer "F.Cu")
		(net "3X24_SAS_TX20_N")
	)
	(segment
		(start 136.41705 -98.012504)
		(end 136.41705 -97.642426)
		(width 0.1016)
		(layer "F.Cu")
		(net "3X24_SAS_TX20_N")
	)
	(segment
		(start 136.271 -98.5266)
		(end 136.271 -98.242882)
		(width 0.1016)
		(layer "F.Cu")
		(net "3X24_SAS_TX20_N")
	)
	(arc
		(start 131.78409 -93.6879)
		(mid 131.435622 -93.618585)
		(end 131.1402 -93.4212)
		(width 0.1016)
		(layer "F.Cu")
		(net "3X24_SAS_TX20_N")
	)
	(arc
		(start 129.7559 -92.0369)
		(mid 129.544853 -91.895883)
		(end 129.295906 -91.8464)
		(width 0.1016)
		(layer "F.Cu")
		(net "3X24_SAS_TX20_N")
	)
	(arc
		(start 136.387332 -98.084386)
		(mid 136.409315 -98.051392)
		(end 136.41705 -98.012504)
		(width 0.1016)
		(layer "F.Cu")
		(net "3X24_SAS_TX20_N")
	)
	(arc
		(start 132.800598 -93.868748)
		(mid 132.600272 -93.734895)
		(end 132.363972 -93.6879)
		(width 0.1016)
		(layer "F.Cu")
		(net "3X24_SAS_TX20_N")
	)
	(arc
		(start 127.09652 -91.948)
		(mid 126.819676 -91.89295)
		(end 126.584964 -91.736164)
		(width 0.1016)
		(layer "F.Cu")
		(net "3X24_SAS_TX20_N")
	)
	(arc
		(start 136.271 -98.242882)
		(mid 136.278719 -98.203987)
		(end 136.300718 -98.171)
		(width 0.1016)
		(layer "F.Cu")
		(net "3X24_SAS_TX20_N")
	)
	(arc
		(start 126.456948 -91.608148)
		(mid 126.377811 -91.489616)
		(end 126.350014 -91.34983)
		(width 0.1016)
		(layer "F.Cu")
		(net "3X24_SAS_TX20_N")
	)
	(arc
		(start 136.41705 -97.642426)
		(mid 136.388145 -97.49711)
		(end 136.305798 -97.373948)
		(width 0.1016)
		(layer "F.Cu")
		(net "3X24_SAS_TX20_N")
	)
	(arc
		(start 127.61087 -91.8591)
		(mid 127.512397 -91.924898)
		(end 127.39624 -91.948)
		(width 0.1016)
		(layer "F.Cu")
		(net "3X24_SAS_TX20_N")
	)
	(segment
		(start 136.906 -98.5266)
		(end 136.906 -98.242882)
		(width 0.1016)
		(layer "F.Cu")
		(net "3X24_SAS_TX20_P")
	)
	(segment
		(start 127.503682 -91.5035)
		(end 127.350012 -91.34983)
		(width 0.1016)
		(layer "F.Cu")
		(net "3X24_SAS_TX20_P")
	)
	(segment
		(start 129.295906 -91.5035)
		(end 127.503682 -91.5035)
		(width 0.1016)
		(layer "F.Cu")
		(net "3X24_SAS_TX20_P")
	)
	(segment
		(start 136.548368 -97.131378)
		(end 133.043168 -93.626178)
		(width 0.1016)
		(layer "F.Cu")
		(net "3X24_SAS_TX20_P")
	)
	(segment
		(start 136.75995 -98.012504)
		(end 136.75995 -97.642172)
		(width 0.1016)
		(layer "F.Cu")
		(net "3X24_SAS_TX20_P")
	)
	(segment
		(start 131.38277 -93.17863)
		(end 129.99847 -91.79433)
		(width 0.1016)
		(layer "F.Cu")
		(net "3X24_SAS_TX20_P")
	)
	(segment
		(start 132.363972 -93.345)
		(end 131.78409 -93.345)
		(width 0.1016)
		(layer "F.Cu")
		(net "3X24_SAS_TX20_P")
	)
	(segment
		(start 136.876282 -98.171)
		(end 136.789668 -98.084386)
		(width 0.1016)
		(layer "F.Cu")
		(net "3X24_SAS_TX20_P")
	)
	(arc
		(start 129.99847 -91.79433)
		(mid 129.676116 -91.579033)
		(end 129.295906 -91.5035)
		(width 0.1016)
		(layer "F.Cu")
		(net "3X24_SAS_TX20_P")
	)
	(arc
		(start 136.75995 -97.642172)
		(mid 136.704894 -97.36577)
		(end 136.548368 -97.131378)
		(width 0.1016)
		(layer "F.Cu")
		(net "3X24_SAS_TX20_P")
	)
	(arc
		(start 136.789668 -98.084386)
		(mid 136.767685 -98.051392)
		(end 136.75995 -98.012504)
		(width 0.1016)
		(layer "F.Cu")
		(net "3X24_SAS_TX20_P")
	)
	(arc
		(start 131.78409 -93.345)
		(mid 131.566898 -93.301704)
		(end 131.38277 -93.17863)
		(width 0.1016)
		(layer "F.Cu")
		(net "3X24_SAS_TX20_P")
	)
	(arc
		(start 133.043168 -93.626178)
		(mid 132.731535 -93.418045)
		(end 132.363972 -93.345)
		(width 0.1016)
		(layer "F.Cu")
		(net "3X24_SAS_TX20_P")
	)
	(arc
		(start 136.906 -98.242882)
		(mid 136.898281 -98.203987)
		(end 136.876282 -98.171)
		(width 0.1016)
		(layer "F.Cu")
		(net "3X24_SAS_TX20_P")
	)
	(segment
		(start 112.350042 -46.999906)
		(end 112.350042 -46.998636)
		(width 0.1143)
		(layer "F.Cu")
		(net "IOC_GPIO_32")
	)
	(segment
		(start 112.350042 -46.998636)
		(end 111.955326 -46.60392)
		(width 0.1143)
		(layer "F.Cu")
		(net "IOC_GPIO_32")
	)
	(via
		(at 111.955326 -46.60392)
		(size 0.508)
		(drill 0.254)
		(layers "F.Cu" "B.Cu")
		(net "IOC_GPIO_32")
	)
	(segment
		(start 112.293146 -47.6504)
		(end 112.293146 -46.94174)
		(width 0.1143)
		(layer "B.Cu")
		(net "IOC_GPIO_32")
	)
	(segment
		(start 112.293146 -46.94174)
		(end 111.955326 -46.60392)
		(width 0.1143)
		(layer "B.Cu")
		(net "IOC_GPIO_32")
	)
	(segment
		(start 113.150142 -34.19983)
		(end 113.150142 -34.171382)
		(width 0.1143)
		(layer "F.Cu")
		(net "IOC_GPIO_12")
	)
	(segment
		(start 112.781842 -33.803082)
		(end 112.781842 -33.175448)
		(width 0.1143)
		(layer "F.Cu")
		(net "IOC_GPIO_12")
	)
	(segment
		(start 113.46307 -32.49422)
		(end 113.601246 -32.49422)
		(width 0.1143)
		(layer "F.Cu")
		(net "IOC_GPIO_12")
	)
	(segment
		(start 113.150142 -34.171382)
		(end 112.781842 -33.803082)
		(width 0.1143)
		(layer "F.Cu")
		(net "IOC_GPIO_12")
	)
	(segment
		(start 112.781842 -33.175448)
		(end 113.46307 -32.49422)
		(width 0.1143)
		(layer "F.Cu")
		(net "IOC_GPIO_12")
	)
	(segment
		(start 113.601246 -32.49422)
		(end 113.961926 -32.13354)
		(width 0.1143)
		(layer "F.Cu")
		(net "IOC_GPIO_12")
	)
	(via
		(at 113.961926 -32.13354)
		(size 0.508)
		(drill 0.254)
		(layers "F.Cu" "B.Cu")
		(net "IOC_GPIO_12")
	)
	(segment
		(start 114.251486 -31.84398)
		(end 113.961926 -32.13354)
		(width 0.1143)
		(layer "B.Cu")
		(net "IOC_GPIO_12")
	)
	(segment
		(start 114.848386 -31.84398)
		(end 114.251486 -31.84398)
		(width 0.1143)
		(layer "B.Cu")
		(net "IOC_GPIO_12")
	)
	(segment
		(start 115.626896 -39.856156)
		(end 115.626896 -39.650924)
		(width 0.1143)
		(layer "F.Cu")
		(net "IOC_GPIO_33")
	)
	(segment
		(start 115.341146 -40.256968)
		(end 115.626642 -39.971472)
		(width 0.1143)
		(layer "F.Cu")
		(net "IOC_GPIO_33")
	)
	(segment
		(start 113.807748 -40.256968)
		(end 115.341146 -40.256968)
		(width 0.1143)
		(layer "F.Cu")
		(net "IOC_GPIO_33")
	)
	(segment
		(start 113.464848 -40.599868)
		(end 113.807748 -40.256968)
		(width 0.1143)
		(layer "F.Cu")
		(net "IOC_GPIO_33")
	)
	(segment
		(start 115.626896 -39.650924)
		(end 115.755674 -39.522146)
		(width 0.1143)
		(layer "F.Cu")
		(net "IOC_GPIO_33")
	)
	(segment
		(start 115.755674 -39.522146)
		(end 115.755674 -39.192708)
		(width 0.1143)
		(layer "F.Cu")
		(net "IOC_GPIO_33")
	)
	(segment
		(start 115.626642 -39.971472)
		(end 115.626642 -39.85641)
		(width 0.1143)
		(layer "F.Cu")
		(net "IOC_GPIO_33")
	)
	(segment
		(start 113.150142 -40.599868)
		(end 113.464848 -40.599868)
		(width 0.1143)
		(layer "F.Cu")
		(net "IOC_GPIO_33")
	)
	(segment
		(start 115.626642 -39.85641)
		(end 115.626896 -39.856156)
		(width 0.1143)
		(layer "F.Cu")
		(net "IOC_GPIO_33")
	)
	(via
		(at 115.755674 -39.192708)
		(size 0.508)
		(drill 0.254)
		(layers "F.Cu" "B.Cu")
		(net "IOC_GPIO_33")
	)
	(segment
		(start 115.755674 -39.434008)
		(end 115.755674 -39.192708)
		(width 0.1143)
		(layer "B.Cu")
		(net "IOC_GPIO_33")
	)
	(segment
		(start 115.902486 -39.58082)
		(end 115.755674 -39.434008)
		(width 0.1143)
		(layer "B.Cu")
		(net "IOC_GPIO_33")
	)
	(segment
		(start 115.902486 -40.06596)
		(end 115.902486 -39.58082)
		(width 0.1143)
		(layer "B.Cu")
		(net "IOC_GPIO_33")
	)
	(segment
		(start 110.750096 -34.19983)
		(end 110.750096 -34.031936)
		(width 0.1143)
		(layer "F.Cu")
		(net "IOC_GPIO_1")
	)
	(segment
		(start 110.407196 -31.842964)
		(end 110.50016 -31.75)
		(width 0.1143)
		(layer "F.Cu")
		(net "IOC_GPIO_1")
	)
	(segment
		(start 110.50016 -31.3944)
		(end 110.65256 -31.242)
		(width 0.1143)
		(layer "F.Cu")
		(net "IOC_GPIO_1")
	)
	(segment
		(start 110.50016 -31.75)
		(end 110.50016 -31.3944)
		(width 0.1143)
		(layer "F.Cu")
		(net "IOC_GPIO_1")
	)
	(segment
		(start 110.407196 -33.689036)
		(end 110.407196 -31.842964)
		(width 0.1143)
		(layer "F.Cu")
		(net "IOC_GPIO_1")
	)
	(segment
		(start 110.750096 -34.031936)
		(end 110.407196 -33.689036)
		(width 0.1143)
		(layer "F.Cu")
		(net "IOC_GPIO_1")
	)
	(via
		(at 110.65256 -31.242)
		(size 0.508)
		(drill 0.254)
		(layers "F.Cu" "B.Cu")
		(net "IOC_GPIO_1")
	)
	(segment
		(start 111.38916 -30.226)
		(end 111.38916 -30.5054)
		(width 0.1143)
		(layer "B.Cu")
		(net "IOC_GPIO_1")
	)
	(segment
		(start 111.38916 -30.5054)
		(end 110.65256 -31.242)
		(width 0.1143)
		(layer "B.Cu")
		(net "IOC_GPIO_1")
	)
	(segment
		(start 121.78792 -113.853214)
		(end 121.78792 -111.910114)
		(width 0.1016)
		(layer "F.Cu")
		(net "SAS_HDD_TX0_P")
	)
	(segment
		(start 121.93397 -114.0206)
		(end 121.909586 -114.0206)
		(width 0.1016)
		(layer "F.Cu")
		(net "SAS_HDD_TX0_P")
	)
	(segment
		(start 117.966236 -108.198412)
		(end 117.966236 -106.80065)
		(width 0.1016)
		(layer "F.Cu")
		(net "SAS_HDD_TX0_P")
	)
	(segment
		(start 118.255542 -106.350054)
		(end 118.35003 -106.350054)
		(width 0.1016)
		(layer "F.Cu")
		(net "SAS_HDD_TX0_P")
	)
	(segment
		(start 121.10974 -110.27283)
		(end 120.388888 -109.551978)
		(width 0.1016)
		(layer "F.Cu")
		(net "SAS_HDD_TX0_P")
	)
	(segment
		(start 118.759224 -108.8771)
		(end 118.636034 -108.8771)
		(width 0.1016)
		(layer "F.Cu")
		(net "SAS_HDD_TX0_P")
	)
	(segment
		(start 121.844054 -113.986564)
		(end 121.8184 -113.949734)
		(width 0.1016)
		(layer "F.Cu")
		(net "SAS_HDD_TX0_P")
	)
	(segment
		(start 118.26494 -108.72343)
		(end 118.18874 -108.64723)
		(width 0.1016)
		(layer "F.Cu")
		(net "SAS_HDD_TX0_P")
	)
	(arc
		(start 118.340632 -108.786168)
		(mid 118.30132 -108.756569)
		(end 118.26494 -108.72343)
		(width 0.1016)
		(layer "F.Cu")
		(net "SAS_HDD_TX0_P")
	)
	(arc
		(start 118.13159 -106.401362)
		(mid 118.18846 -106.363363)
		(end 118.255542 -106.350054)
		(width 0.1016)
		(layer "F.Cu")
		(net "SAS_HDD_TX0_P")
	)
	(arc
		(start 118.18874 -108.64723)
		(mid 118.040694 -108.441067)
		(end 117.966236 -108.198412)
		(width 0.1016)
		(layer "F.Cu")
		(net "SAS_HDD_TX0_P")
	)
	(arc
		(start 121.909586 -114.0206)
		(mid 121.872622 -114.01165)
		(end 121.844054 -113.986564)
		(width 0.1016)
		(layer "F.Cu")
		(net "SAS_HDD_TX0_P")
	)
	(arc
		(start 121.78792 -111.910114)
		(mid 121.611681 -111.02401)
		(end 121.10974 -110.27283)
		(width 0.1016)
		(layer "F.Cu")
		(net "SAS_HDD_TX0_P")
	)
	(arc
		(start 121.8184 -113.949734)
		(mid 121.795732 -113.903821)
		(end 121.78792 -113.853214)
		(width 0.1016)
		(layer "F.Cu")
		(net "SAS_HDD_TX0_P")
	)
	(arc
		(start 117.966236 -106.80065)
		(mid 118.009217 -106.584571)
		(end 118.13159 -106.401362)
		(width 0.1016)
		(layer "F.Cu")
		(net "SAS_HDD_TX0_P")
	)
	(arc
		(start 120.388888 -109.551978)
		(mid 119.641163 -109.052491)
		(end 118.759224 -108.8771)
		(width 0.1016)
		(layer "F.Cu")
		(net "SAS_HDD_TX0_P")
	)
	(arc
		(start 118.636034 -108.8771)
		(mid 118.481475 -108.853901)
		(end 118.340632 -108.786168)
		(width 0.1016)
		(layer "F.Cu")
		(net "SAS_HDD_TX0_P")
	)
	(segment
		(start 118.237 -31.115)
		(end 117.76075 -31.59125)
		(width 0.1143)
		(layer "F.Cu")
		(net "IOC_GPIO_4")
	)
	(segment
		(start 116.558568 -31.59125)
		(end 113.949988 -34.19983)
		(width 0.1143)
		(layer "F.Cu")
		(net "IOC_GPIO_4")
	)
	(segment
		(start 117.76075 -31.59125)
		(end 116.558568 -31.59125)
		(width 0.1143)
		(layer "F.Cu")
		(net "IOC_GPIO_4")
	)
	(segment
		(start 109.56036 -33.655)
		(end 109.56036 -31.983426)
		(width 0.1143)
		(layer "F.Cu")
		(net "IOC_GPIO_13")
	)
	(segment
		(start 109.949996 -34.19983)
		(end 109.949996 -34.044636)
		(width 0.1143)
		(layer "F.Cu")
		(net "IOC_GPIO_13")
	)
	(segment
		(start 109.949996 -34.044636)
		(end 109.56036 -33.655)
		(width 0.1143)
		(layer "F.Cu")
		(net "IOC_GPIO_13")
	)
	(segment
		(start 109.56036 -31.983426)
		(end 109.562392 -31.981394)
		(width 0.1143)
		(layer "F.Cu")
		(net "IOC_GPIO_13")
	)
	(via
		(at 109.562392 -31.981394)
		(size 0.508)
		(drill 0.254)
		(layers "F.Cu" "B.Cu")
		(net "IOC_GPIO_13")
	)
	(segment
		(start 109.537754 -31.981394)
		(end 109.562392 -31.981394)
		(width 0.1143)
		(layer "B.Cu")
		(net "IOC_GPIO_13")
	)
	(segment
		(start 108.92536 -31.369)
		(end 109.537754 -31.981394)
		(width 0.1143)
		(layer "B.Cu")
		(net "IOC_GPIO_13")
	)
	(segment
		(start 108.72216 -31.369)
		(end 108.92536 -31.369)
		(width 0.1143)
		(layer "B.Cu")
		(net "IOC_GPIO_13")
	)
	(segment
		(start 185.5724 -145.459704)
		(end 184.121298 -144.008602)
		(width 0.1143)
		(layer "F.Cu")
		(net "EXP_I2C_SCL_4")
	)
	(segment
		(start 187.0456 -146.88312)
		(end 186.40552 -146.88312)
		(width 0.1143)
		(layer "F.Cu")
		(net "EXP_I2C_SCL_4")
	)
	(segment
		(start 185.5724 -146.05)
		(end 185.5724 -145.459704)
		(width 0.1143)
		(layer "F.Cu")
		(net "EXP_I2C_SCL_4")
	)
	(segment
		(start 96.15297 -107.188)
		(end 96.66097 -107.188)
		(width 0.1143)
		(layer "F.Cu")
		(net "EXP_I2C_SCL_4")
	)
	(segment
		(start 183.0578 -143.3068)
		(end 183.419496 -143.3068)
		(width 0.1143)
		(layer "F.Cu")
		(net "EXP_I2C_SCL_4")
	)
	(segment
		(start 102.349808 -106.350054)
		(end 102.349808 -108.114338)
		(width 0.1143)
		(layer "F.Cu")
		(net "EXP_I2C_SCL_4")
	)
	(segment
		(start 102.349808 -108.114338)
		(end 102.42677 -108.1913)
		(width 0.1143)
		(layer "F.Cu")
		(net "EXP_I2C_SCL_4")
	)
	(segment
		(start 183.419496 -143.3068)
		(end 184.121298 -144.008602)
		(width 0.1143)
		(layer "F.Cu")
		(net "EXP_I2C_SCL_4")
	)
	(segment
		(start 97.66427 -108.1913)
		(end 102.42677 -108.1913)
		(width 0.1143)
		(layer "F.Cu")
		(net "EXP_I2C_SCL_4")
	)
	(segment
		(start 96.66097 -107.188)
		(end 97.66427 -108.1913)
		(width 0.1143)
		(layer "F.Cu")
		(net "EXP_I2C_SCL_4")
	)
	(segment
		(start 186.40552 -146.88312)
		(end 185.5724 -146.05)
		(width 0.1143)
		(layer "F.Cu")
		(net "EXP_I2C_SCL_4")
	)
	(via
		(at 102.42677 -108.1913)
		(size 0.5588)
		(drill 0.3048)
		(layers "F.Cu" "B.Cu")
		(net "EXP_I2C_SCL_4")
	)
	(via
		(at 184.121298 -144.008602)
		(size 0.7112)
		(drill 0.3556)
		(layers "F.Cu" "B.Cu")
		(net "EXP_I2C_SCL_4")
	)
	(via
		(at 183.0578 -143.3068)
		(size 0.5588)
		(drill 0.3048)
		(layers "F.Cu" "B.Cu")
		(net "EXP_I2C_SCL_4")
	)
	(segment
		(start 99.91217 -110.49)
		(end 92.41917 -117.983)
		(width 0.127)
		(layer "In2.Cu")
		(net "EXP_I2C_SCL_4")
	)
	(segment
		(start 102.42677 -108.1913)
		(end 100.12807 -110.49)
		(width 0.127)
		(layer "In2.Cu")
		(net "EXP_I2C_SCL_4")
	)
	(segment
		(start 180.555646 -143.696182)
		(end 182.668418 -143.696182)
		(width 0.127)
		(layer "In2.Cu")
		(net "EXP_I2C_SCL_4")
	)
	(segment
		(start 92.41917 -117.983)
		(end 92.044012 -117.983)
		(width 0.127)
		(layer "In2.Cu")
		(net "EXP_I2C_SCL_4")
	)
	(segment
		(start 92.044012 -117.983)
		(end 91.45651 -118.570502)
		(width 0.127)
		(layer "In2.Cu")
		(net "EXP_I2C_SCL_4")
	)
	(segment
		(start 111.671608 -142.494)
		(end 157.992064 -142.494)
		(width 0.127)
		(layer "In2.Cu")
		(net "EXP_I2C_SCL_4")
	)
	(segment
		(start 91.45651 -122.278902)
		(end 111.671608 -142.494)
		(width 0.127)
		(layer "In2.Cu")
		(net "EXP_I2C_SCL_4")
	)
	(segment
		(start 179.886864 -143.0274)
		(end 180.555646 -143.696182)
		(width 0.127)
		(layer "In2.Cu")
		(net "EXP_I2C_SCL_4")
	)
	(segment
		(start 182.668418 -143.696182)
		(end 183.0578 -143.3068)
		(width 0.127)
		(layer "In2.Cu")
		(net "EXP_I2C_SCL_4")
	)
	(segment
		(start 100.12807 -110.49)
		(end 99.91217 -110.49)
		(width 0.127)
		(layer "In2.Cu")
		(net "EXP_I2C_SCL_4")
	)
	(segment
		(start 158.525464 -143.0274)
		(end 179.886864 -143.0274)
		(width 0.127)
		(layer "In2.Cu")
		(net "EXP_I2C_SCL_4")
	)
	(segment
		(start 157.992064 -142.494)
		(end 158.525464 -143.0274)
		(width 0.127)
		(layer "In2.Cu")
		(net "EXP_I2C_SCL_4")
	)
	(segment
		(start 91.45651 -118.570502)
		(end 91.45651 -122.278902)
		(width 0.127)
		(layer "In2.Cu")
		(net "EXP_I2C_SCL_4")
	)
	(segment
		(start 111.918242 -32.998918)
		(end 111.996474 -32.920686)
		(width 0.1143)
		(layer "F.Cu")
		(net "IOC_GPIO_20")
	)
	(segment
		(start 111.996474 -32.920686)
		(end 111.996474 -32.781494)
		(width 0.1143)
		(layer "F.Cu")
		(net "IOC_GPIO_20")
	)
	(segment
		(start 112.350042 -34.158682)
		(end 111.918242 -33.726882)
		(width 0.1143)
		(layer "F.Cu")
		(net "IOC_GPIO_20")
	)
	(segment
		(start 112.350042 -34.19983)
		(end 112.350042 -34.158682)
		(width 0.1143)
		(layer "F.Cu")
		(net "IOC_GPIO_20")
	)
	(segment
		(start 111.918242 -33.726882)
		(end 111.918242 -32.998918)
		(width 0.1143)
		(layer "F.Cu")
		(net "IOC_GPIO_20")
	)
	(via
		(at 111.996474 -32.781494)
		(size 0.508)
		(drill 0.254)
		(layers "F.Cu" "B.Cu")
		(net "IOC_GPIO_20")
	)
	(segment
		(start 112.630966 -33.6296)
		(end 112.65916 -33.44418)
		(width 0.1143)
		(layer "B.Cu")
		(net "IOC_GPIO_20")
	)
	(segment
		(start 112.65916 -33.44418)
		(end 111.996474 -32.781494)
		(width 0.1143)
		(layer "B.Cu")
		(net "IOC_GPIO_20")
	)
	(segment
		(start 107.54995 -34.99993)
		(end 107.150154 -34.600134)
		(width 0.1143)
		(layer "F.Cu")
		(net "IOC_GPIO_2")
	)
	(via
		(at 107.150154 -34.600134)
		(size 0.508)
		(drill 0.254)
		(layers "F.Cu" "B.Cu")
		(net "IOC_GPIO_2")
	)
	(segment
		(start 107.42676 -33.782)
		(end 107.42676 -34.323528)
		(width 0.1143)
		(layer "B.Cu")
		(net "IOC_GPIO_2")
	)
	(segment
		(start 107.42676 -34.323528)
		(end 107.150154 -34.600134)
		(width 0.1143)
		(layer "B.Cu")
		(net "IOC_GPIO_2")
	)
	(segment
		(start 113.29543 -34.99993)
		(end 113.150142 -34.99993)
		(width 0.1143)
		(layer "F.Cu")
		(net "IOC_GPIO_22")
	)
	(segment
		(start 117.475 -32.131)
		(end 116.609368 -32.131)
		(width 0.1143)
		(layer "F.Cu")
		(net "IOC_GPIO_22")
	)
	(segment
		(start 114.108738 -34.63163)
		(end 113.66373 -34.63163)
		(width 0.1143)
		(layer "F.Cu")
		(net "IOC_GPIO_22")
	)
	(segment
		(start 113.66373 -34.63163)
		(end 113.29543 -34.99993)
		(width 0.1143)
		(layer "F.Cu")
		(net "IOC_GPIO_22")
	)
	(segment
		(start 116.609368 -32.131)
		(end 114.108738 -34.63163)
		(width 0.1143)
		(layer "F.Cu")
		(net "IOC_GPIO_22")
	)
	(segment
		(start 45.466 -110.363)
		(end 43.053 -112.776)
		(width 0.1143)
		(layer "F.Cu")
		(net "SAS_SDBTX_R")
	)
	(segment
		(start 52.832 -104.14)
		(end 52.832 -109.474)
		(width 0.1143)
		(layer "F.Cu")
		(net "SAS_SDBTX_R")
	)
	(segment
		(start 52.354734 -103.662734)
		(end 52.832 -104.14)
		(width 0.1143)
		(layer "F.Cu")
		(net "SAS_SDBTX_R")
	)
	(segment
		(start 50.8 -104.043734)
		(end 51.181 -103.662734)
		(width 0.1143)
		(layer "F.Cu")
		(net "SAS_SDBTX_R")
	)
	(segment
		(start 43.053 -112.776)
		(end 43.053 -114.0079)
		(width 0.1143)
		(layer "F.Cu")
		(net "SAS_SDBTX_R")
	)
	(segment
		(start 50.8 -104.521)
		(end 50.8 -104.043734)
		(width 0.1143)
		(layer "F.Cu")
		(net "SAS_SDBTX_R")
	)
	(segment
		(start 52.832 -109.474)
		(end 51.943 -110.363)
		(width 0.1143)
		(layer "F.Cu")
		(net "SAS_SDBTX_R")
	)
	(segment
		(start 51.943 -110.363)
		(end 45.466 -110.363)
		(width 0.1143)
		(layer "F.Cu")
		(net "SAS_SDBTX_R")
	)
	(segment
		(start 51.181 -103.662734)
		(end 52.354734 -103.662734)
		(width 0.1143)
		(layer "F.Cu")
		(net "SAS_SDBTX_R")
	)
	(segment
		(start 43.053 -114.0079)
		(end 42.7482 -114.3127)
		(width 0.1143)
		(layer "F.Cu")
		(net "SAS_SDBTX_R")
	)
	(segment
		(start 112.747044 -39.40302)
		(end 112.756696 -39.40302)
		(width 0.1143)
		(layer "F.Cu")
		(net "IOC_GPIO_34")
	)
	(segment
		(start 112.350042 -39.800022)
		(end 112.747044 -39.40302)
		(width 0.1143)
		(layer "F.Cu")
		(net "IOC_GPIO_34")
	)
	(segment
		(start 112.756696 -39.40302)
		(end 112.759744 -39.399972)
		(width 0.1143)
		(layer "F.Cu")
		(net "IOC_GPIO_34")
	)
	(via
		(at 112.759744 -39.399972)
		(size 0.508)
		(drill 0.254)
		(layers "F.Cu" "B.Cu")
		(net "IOC_GPIO_34")
	)
	(segment
		(start 114.551206 -39.1033)
		(end 113.056416 -39.1033)
		(width 0.1143)
		(layer "B.Cu")
		(net "IOC_GPIO_34")
	)
	(segment
		(start 113.056416 -39.1033)
		(end 112.759744 -39.399972)
		(width 0.1143)
		(layer "B.Cu")
		(net "IOC_GPIO_34")
	)
	(segment
		(start 44.8056 -116.1923)
		(end 44.8056 -115.3668)
		(width 0.1143)
		(layer "F.Cu")
		(net "SAS_SDBRX")
	)
	(segment
		(start 44.7167 -116.2812)
		(end 44.8056 -116.1923)
		(width 0.1143)
		(layer "F.Cu")
		(net "SAS_SDBRX")
	)
	(segment
		(start 43.8912 -115.2017)
		(end 44.6405 -115.2017)
		(width 0.1143)
		(layer "F.Cu")
		(net "SAS_SDBRX")
	)
	(segment
		(start 44.6405 -115.2017)
		(end 44.8056 -115.3668)
		(width 0.1143)
		(layer "F.Cu")
		(net "SAS_SDBRX")
	)
	(via
		(at 44.8056 -115.3668)
		(size 0.7112)
		(drill 0.3556)
		(layers "F.Cu" "B.Cu")
		(net "SAS_SDBRX")
	)
	(segment
		(start 108.750354 -34.608262)
		(end 108.750354 -34.648394)
		(width 0.1143)
		(layer "F.Cu")
		(net "IOC_GPIO_5")
	)
	(segment
		(start 108.741464 -34.599372)
		(end 108.750354 -34.608262)
		(width 0.1143)
		(layer "F.Cu")
		(net "IOC_GPIO_5")
	)
	(segment
		(start 108.750354 -34.648394)
		(end 109.10189 -34.99993)
		(width 0.1143)
		(layer "F.Cu")
		(net "IOC_GPIO_5")
	)
	(segment
		(start 109.10189 -34.99993)
		(end 109.15015 -34.99993)
		(width 0.1143)
		(layer "F.Cu")
		(net "IOC_GPIO_5")
	)
	(via
		(at 108.741464 -34.599372)
		(size 0.508)
		(drill 0.254)
		(layers "F.Cu" "B.Cu")
		(net "IOC_GPIO_5")
	)
	(segment
		(start 108.72216 -33.782)
		(end 108.72216 -34.57194)
		(width 0.1143)
		(layer "B.Cu")
		(net "IOC_GPIO_5")
	)
	(segment
		(start 108.72216 -34.57194)
		(end 108.741464 -34.591244)
		(width 0.1143)
		(layer "B.Cu")
		(net "IOC_GPIO_5")
	)
	(segment
		(start 108.741464 -34.591244)
		(end 108.741464 -34.599372)
		(width 0.1143)
		(layer "B.Cu")
		(net "IOC_GPIO_5")
	)
	(segment
		(start 43.4213 -113.8428)
		(end 43.8912 -114.3127)
		(width 0.1143)
		(layer "F.Cu")
		(net "SAS_SDBRX_R")
	)
	(segment
		(start 53.370734 -109.697266)
		(end 52.324 -110.744)
		(width 0.1143)
		(layer "F.Cu")
		(net "SAS_SDBRX_R")
	)
	(segment
		(start 43.4213 -113.0427)
		(end 43.4213 -113.8428)
		(width 0.1143)
		(layer "F.Cu")
		(net "SAS_SDBRX_R")
	)
	(segment
		(start 50.8 -102.7176)
		(end 51.2064 -103.124)
		(width 0.1143)
		(layer "F.Cu")
		(net "SAS_SDBRX_R")
	)
	(segment
		(start 50.8 -101.981)
		(end 50.8 -102.7176)
		(width 0.1143)
		(layer "F.Cu")
		(net "SAS_SDBRX_R")
	)
	(segment
		(start 52.578 -103.124)
		(end 53.370734 -103.916734)
		(width 0.1143)
		(layer "F.Cu")
		(net "SAS_SDBRX_R")
	)
	(segment
		(start 52.324 -110.744)
		(end 45.72 -110.744)
		(width 0.1143)
		(layer "F.Cu")
		(net "SAS_SDBRX_R")
	)
	(segment
		(start 45.72 -110.744)
		(end 43.4213 -113.0427)
		(width 0.1143)
		(layer "F.Cu")
		(net "SAS_SDBRX_R")
	)
	(segment
		(start 53.370734 -103.916734)
		(end 53.370734 -109.697266)
		(width 0.1143)
		(layer "F.Cu")
		(net "SAS_SDBRX_R")
	)
	(segment
		(start 51.2064 -103.124)
		(end 52.578 -103.124)
		(width 0.1143)
		(layer "F.Cu")
		(net "SAS_SDBRX_R")
	)
	(segment
		(start 126.1999 -88.844628)
		(end 125.95606 -88.601042)
		(width 0.1016)
		(layer "F.Cu")
		(net "3X24_SAS_TX17_N")
	)
	(segment
		(start 130.505708 -89.051638)
		(end 130.4544 -89.1032)
		(width 0.1016)
		(layer "F.Cu")
		(net "3X24_SAS_TX17_N")
	)
	(segment
		(start 130.10007 -89.250012)
		(end 128.353312 -89.250012)
		(width 0.1016)
		(layer "F.Cu")
		(net "3X24_SAS_TX17_N")
	)
	(segment
		(start 131.0386 -89.154)
		(end 130.936492 -89.051638)
		(width 0.1016)
		(layer "F.Cu")
		(net "3X24_SAS_TX17_N")
	)
	(segment
		(start 127.6604 -88.962992)
		(end 126.48565 -88.962992)
		(width 0.1016)
		(layer "F.Cu")
		(net "3X24_SAS_TX17_N")
	)
	(segment
		(start 130.7846 -88.9889)
		(end 130.6576 -88.9889)
		(width 0.1016)
		(layer "F.Cu")
		(net "3X24_SAS_TX17_N")
	)
	(arc
		(start 127.80137 -89.021412)
		(mid 127.736692 -88.978196)
		(end 127.6604 -88.962992)
		(width 0.1016)
		(layer "F.Cu")
		(net "3X24_SAS_TX17_N")
	)
	(arc
		(start 130.936492 -89.051638)
		(mid 130.866788 -89.005157)
		(end 130.7846 -88.9889)
		(width 0.1016)
		(layer "F.Cu")
		(net "3X24_SAS_TX17_N")
	)
	(arc
		(start 130.6576 -88.9889)
		(mid 130.575411 -89.005155)
		(end 130.505708 -89.051638)
		(width 0.1016)
		(layer "F.Cu")
		(net "3X24_SAS_TX17_N")
	)
	(arc
		(start 126.48565 -88.962992)
		(mid 126.331002 -88.932231)
		(end 126.1999 -88.844628)
		(width 0.1016)
		(layer "F.Cu")
		(net "3X24_SAS_TX17_N")
	)
	(arc
		(start 128.353312 -89.250012)
		(mid 128.054612 -89.190597)
		(end 127.80137 -89.021412)
		(width 0.1016)
		(layer "F.Cu")
		(net "3X24_SAS_TX17_N")
	)
	(arc
		(start 125.95606 -88.601042)
		(mid 125.67802 -88.415168)
		(end 125.350016 -88.349836)
		(width 0.1016)
		(layer "F.Cu")
		(net "3X24_SAS_TX17_N")
	)
	(arc
		(start 130.4544 -89.1032)
		(mid 130.291832 -89.211824)
		(end 130.10007 -89.250012)
		(width 0.1016)
		(layer "F.Cu")
		(net "3X24_SAS_TX17_N")
	)
	(segment
		(start 108.35005 -34.99993)
		(end 107.95 -34.59988)
		(width 0.1143)
		(layer "F.Cu")
		(net "IOC_GPIO_3")
	)
	(via
		(at 107.95 -34.59988)
		(size 0.508)
		(drill 0.254)
		(layers "F.Cu" "B.Cu")
		(net "IOC_GPIO_3")
	)
	(segment
		(start 108.008166 -34.541714)
		(end 107.95 -34.59988)
		(width 0.1143)
		(layer "B.Cu")
		(net "IOC_GPIO_3")
	)
	(segment
		(start 108.008166 -32.6898)
		(end 108.008166 -34.541714)
		(width 0.1143)
		(layer "B.Cu")
		(net "IOC_GPIO_3")
	)
	(segment
		(start 94.113096 -104.11587)
		(end 94.114112 -104.11587)
		(width 0.1143)
		(layer "F.Cu")
		(net "SDB_TX")
	)
	(segment
		(start 38.862 -121.793)
		(end 38.605968 -121.536968)
		(width 0.1143)
		(layer "F.Cu")
		(net "SDB_TX")
	)
	(segment
		(start 38.8747 -123.571)
		(end 38.862 -123.5583)
		(width 0.1143)
		(layer "F.Cu")
		(net "SDB_TX")
	)
	(segment
		(start 95.26397 -103.759)
		(end 95.11284 -103.759)
		(width 0.1143)
		(layer "F.Cu")
		(net "SDB_TX")
	)
	(segment
		(start 94.75597 -104.11587)
		(end 94.114112 -104.11587)
		(width 0.1143)
		(layer "F.Cu")
		(net "SDB_TX")
	)
	(segment
		(start 95.11284 -103.759)
		(end 94.75597 -104.11587)
		(width 0.1143)
		(layer "F.Cu")
		(net "SDB_TX")
	)
	(segment
		(start 38.862 -123.5583)
		(end 38.862 -121.793)
		(width 0.1143)
		(layer "F.Cu")
		(net "SDB_TX")
	)
	(segment
		(start 38.605968 -120.486932)
		(end 38.6207 -120.4722)
		(width 0.1143)
		(layer "F.Cu")
		(net "SDB_TX")
	)
	(segment
		(start 38.605968 -121.536968)
		(end 38.605968 -120.486932)
		(width 0.1143)
		(layer "F.Cu")
		(net "SDB_TX")
	)
	(segment
		(start 92.72397 -104.14)
		(end 94.088966 -104.14)
		(width 0.1143)
		(layer "F.Cu")
		(net "SDB_TX")
	)
	(segment
		(start 94.088966 -104.14)
		(end 94.113096 -104.11587)
		(width 0.1143)
		(layer "F.Cu")
		(net "SDB_TX")
	)
	(segment
		(start 94.12605 -104.127808)
		(end 94.114112 -104.11587)
		(width 0.1143)
		(layer "F.Cu")
		(net "SDB_TX")
	)
	(via
		(at 51.562 -143.383)
		(size 0.5588)
		(drill 0.3048)
		(layers "F.Cu" "B.Cu")
		(net "SDB_TX")
	)
	(via
		(at 38.8747 -123.571)
		(size 0.5588)
		(drill 0.3048)
		(layers "F.Cu" "B.Cu")
		(net "SDB_TX")
	)
	(via
		(at 93.218 -104.648)
		(size 0.7112)
		(drill 0.3556)
		(layers "F.Cu" "B.Cu")
		(net "SDB_TX")
	)
	(via
		(at 94.12605 -104.127808)
		(size 0.5588)
		(drill 0.3048)
		(layers "F.Cu" "B.Cu")
		(net "SDB_TX")
	)
	(segment
		(start 93.218 -104.648)
		(end 93.605858 -104.648)
		(width 0.1143)
		(layer "B.Cu")
		(net "SDB_TX")
	)
	(segment
		(start 93.605858 -104.648)
		(end 94.12605 -104.127808)
		(width 0.1143)
		(layer "B.Cu")
		(net "SDB_TX")
	)
	(segment
		(start 44.099734 -136.428734)
		(end 44.099734 -137.383266)
		(width 0.127)
		(layer "In2.Cu")
		(net "SDB_TX")
	)
	(segment
		(start 44.099734 -137.383266)
		(end 50.213768 -143.4973)
		(width 0.127)
		(layer "In2.Cu")
		(net "SDB_TX")
	)
	(segment
		(start 38.8747 -123.571)
		(end 39.116 -123.8123)
		(width 0.127)
		(layer "In2.Cu")
		(net "SDB_TX")
	)
	(segment
		(start 39.116 -131.445)
		(end 44.099734 -136.428734)
		(width 0.127)
		(layer "In2.Cu")
		(net "SDB_TX")
	)
	(segment
		(start 50.213768 -143.4973)
		(end 51.4477 -143.4973)
		(width 0.127)
		(layer "In2.Cu")
		(net "SDB_TX")
	)
	(segment
		(start 39.116 -123.8123)
		(end 39.116 -131.445)
		(width 0.127)
		(layer "In2.Cu")
		(net "SDB_TX")
	)
	(segment
		(start 51.4477 -143.4973)
		(end 51.562 -143.383)
		(width 0.127)
		(layer "In2.Cu")
		(net "SDB_TX")
	)
	(segment
		(start 86.926928 -108.652818)
		(end 91.451938 -104.127808)
		(width 0.127)
		(layer "In5.Cu")
		(net "SDB_TX")
	)
	(segment
		(start 85.979 -108.652818)
		(end 86.926928 -108.652818)
		(width 0.127)
		(layer "In5.Cu")
		(net "SDB_TX")
	)
	(segment
		(start 91.451938 -104.127808)
		(end 94.12605 -104.127808)
		(width 0.127)
		(layer "In5.Cu")
		(net "SDB_TX")
	)
	(segment
		(start 51.562 -143.069818)
		(end 85.979 -108.652818)
		(width 0.127)
		(layer "In5.Cu")
		(net "SDB_TX")
	)
	(segment
		(start 51.562 -143.383)
		(end 51.562 -143.069818)
		(width 0.127)
		(layer "In5.Cu")
		(net "SDB_TX")
	)
	(segment
		(start 118.491 -36.703)
		(end 117.914928 -36.703)
		(width 0.1143)
		(layer "F.Cu")
		(net "IOC_GPIO_23")
	)
	(segment
		(start 117.914928 -36.703)
		(end 116.434108 -38.18382)
		(width 0.1143)
		(layer "F.Cu")
		(net "IOC_GPIO_23")
	)
	(segment
		(start 113.883948 -39.380922)
		(end 113.464848 -39.800022)
		(width 0.1143)
		(layer "F.Cu")
		(net "IOC_GPIO_23")
	)
	(segment
		(start 113.464848 -39.800022)
		(end 113.150142 -39.800022)
		(width 0.1143)
		(layer "F.Cu")
		(net "IOC_GPIO_23")
	)
	(segment
		(start 116.434108 -38.18382)
		(end 116.42979 -38.18382)
		(width 0.1143)
		(layer "F.Cu")
		(net "IOC_GPIO_23")
	)
	(segment
		(start 115.934744 -38.429184)
		(end 115.122706 -39.241222)
		(width 0.1143)
		(layer "F.Cu")
		(net "IOC_GPIO_23")
	)
	(segment
		(start 116.42979 -38.18382)
		(end 116.184426 -38.429184)
		(width 0.1143)
		(layer "F.Cu")
		(net "IOC_GPIO_23")
	)
	(segment
		(start 116.184426 -38.429184)
		(end 115.934744 -38.429184)
		(width 0.1143)
		(layer "F.Cu")
		(net "IOC_GPIO_23")
	)
	(segment
		(start 115.045744 -39.241222)
		(end 114.906044 -39.380922)
		(width 0.1143)
		(layer "F.Cu")
		(net "IOC_GPIO_23")
	)
	(segment
		(start 115.122706 -39.241222)
		(end 115.045744 -39.241222)
		(width 0.1143)
		(layer "F.Cu")
		(net "IOC_GPIO_23")
	)
	(segment
		(start 114.906044 -39.380922)
		(end 113.883948 -39.380922)
		(width 0.1143)
		(layer "F.Cu")
		(net "IOC_GPIO_23")
	)
	(via
		(at 118.491 -36.703)
		(size 0.508)
		(drill 0.254)
		(layers "F.Cu" "B.Cu")
		(net "IOC_GPIO_23")
	)
	(segment
		(start 118.491 -36.126928)
		(end 118.491 -36.703)
		(width 0.1143)
		(layer "B.Cu")
		(net "IOC_GPIO_23")
	)
	(segment
		(start 118.980966 -35.636962)
		(end 118.491 -36.126928)
		(width 0.1143)
		(layer "B.Cu")
		(net "IOC_GPIO_23")
	)
	(segment
		(start 119.0244 -34.7218)
		(end 118.980966 -35.636962)
		(width 0.1143)
		(layer "B.Cu")
		(net "IOC_GPIO_23")
	)
	(segment
		(start 115.214146 -39.800022)
		(end 113.949988 -39.800022)
		(width 0.1143)
		(layer "F.Cu")
		(net "IOC_GPIO_35")
	)
	(via
		(at 115.214146 -39.800022)
		(size 0.508)
		(drill 0.254)
		(layers "F.Cu" "B.Cu")
		(net "IOC_GPIO_35")
	)
	(segment
		(start 114.723926 -40.290242)
		(end 115.214146 -39.800022)
		(width 0.1143)
		(layer "B.Cu")
		(net "IOC_GPIO_35")
	)
	(segment
		(start 114.723926 -40.41648)
		(end 114.723926 -40.290242)
		(width 0.1143)
		(layer "B.Cu")
		(net "IOC_GPIO_35")
	)
	(segment
		(start 109.585252 -34.624264)
		(end 109.577378 -34.61639)
		(width 0.1143)
		(layer "F.Cu")
		(net "IOC_GPIO_6")
	)
	(segment
		(start 109.949996 -34.99993)
		(end 109.585252 -34.635186)
		(width 0.1143)
		(layer "F.Cu")
		(net "IOC_GPIO_6")
	)
	(segment
		(start 109.585252 -34.635186)
		(end 109.585252 -34.624264)
		(width 0.1143)
		(layer "F.Cu")
		(net "IOC_GPIO_6")
	)
	(via
		(at 109.577378 -34.61639)
		(size 0.508)
		(drill 0.254)
		(layers "F.Cu" "B.Cu")
		(net "IOC_GPIO_6")
	)
	(segment
		(start 109.303566 -33.626806)
		(end 109.303566 -34.3535)
		(width 0.1143)
		(layer "B.Cu")
		(net "IOC_GPIO_6")
	)
	(segment
		(start 109.23016 -33.5534)
		(end 109.303566 -33.626806)
		(width 0.1143)
		(layer "B.Cu")
		(net "IOC_GPIO_6")
	)
	(segment
		(start 109.23016 -32.639)
		(end 109.23016 -33.5534)
		(width 0.1143)
		(layer "B.Cu")
		(net "IOC_GPIO_6")
	)
	(segment
		(start 109.568488 -34.6075)
		(end 109.577378 -34.61639)
		(width 0.1143)
		(layer "B.Cu")
		(net "IOC_GPIO_6")
	)
	(segment
		(start 109.557566 -34.6075)
		(end 109.568488 -34.6075)
		(width 0.1143)
		(layer "B.Cu")
		(net "IOC_GPIO_6")
	)
	(segment
		(start 109.303566 -34.3535)
		(end 109.557566 -34.6075)
		(width 0.1143)
		(layer "B.Cu")
		(net "IOC_GPIO_6")
	)
	(segment
		(start 91.435682 -42.731944)
		(end 91.5162 -42.812716)
		(width 0.1016)
		(layer "F.Cu")
		(net "SAS3008_RAID_TX_C_N4")
	)
	(segment
		(start 89.990168 -42.6212)
		(end 91.167966 -42.6212)
		(width 0.1016)
		(layer "F.Cu")
		(net "SAS3008_RAID_TX_C_N4")
	)
	(segment
		(start 87.144606 -44.7294)
		(end 87.807292 -44.7294)
		(width 0.1016)
		(layer "F.Cu")
		(net "SAS3008_RAID_TX_C_N4")
	)
	(segment
		(start 88.297766 -44.5262)
		(end 89.010998 -43.812968)
		(width 0.1016)
		(layer "F.Cu")
		(net "SAS3008_RAID_TX_C_N4")
	)
	(segment
		(start 91.549982 -42.981118)
		(end 91.549982 -42.999914)
		(width 0.1016)
		(layer "F.Cu")
		(net "SAS3008_RAID_TX_C_N4")
	)
	(arc
		(start 91.167966 -42.6212)
		(mid 91.31285 -42.649926)
		(end 91.435682 -42.731944)
		(width 0.1016)
		(layer "F.Cu")
		(net "SAS3008_RAID_TX_C_N4")
	)
	(arc
		(start 87.807292 -44.7294)
		(mid 88.07275 -44.676597)
		(end 88.297766 -44.5262)
		(width 0.1016)
		(layer "F.Cu")
		(net "SAS3008_RAID_TX_C_N4")
	)
	(arc
		(start 86.77656 -44.577)
		(mid 86.945421 -44.689829)
		(end 87.144606 -44.7294)
		(width 0.1016)
		(layer "F.Cu")
		(net "SAS3008_RAID_TX_C_N4")
	)
	(arc
		(start 91.5162 -42.812716)
		(mid 91.541424 -42.895243)
		(end 91.549982 -42.981118)
		(width 0.1016)
		(layer "F.Cu")
		(net "SAS3008_RAID_TX_C_N4")
	)
	(arc
		(start 89.010998 -43.812968)
		(mid 89.12227 -43.646438)
		(end 89.161366 -43.450002)
		(width 0.1016)
		(layer "F.Cu")
		(net "SAS3008_RAID_TX_C_N4")
	)
	(arc
		(start 89.161366 -43.450002)
		(mid 89.404116 -42.86395)
		(end 89.990168 -42.6212)
		(width 0.1016)
		(layer "F.Cu")
		(net "SAS3008_RAID_TX_C_N4")
	)
	(segment
		(start 41.9227 -116.2812)
		(end 41.7322 -116.0907)
		(width 0.1143)
		(layer "F.Cu")
		(net "SAS_SDBTX")
	)
	(segment
		(start 42.7482 -115.2017)
		(end 41.7957 -115.2017)
		(width 0.1143)
		(layer "F.Cu")
		(net "SAS_SDBTX")
	)
	(segment
		(start 41.7322 -116.0907)
		(end 41.7322 -115.2652)
		(width 0.1143)
		(layer "F.Cu")
		(net "SAS_SDBTX")
	)
	(segment
		(start 41.7957 -115.2017)
		(end 41.7322 -115.2652)
		(width 0.1143)
		(layer "F.Cu")
		(net "SAS_SDBTX")
	)
	(via
		(at 41.7322 -115.2652)
		(size 0.7112)
		(drill 0.3556)
		(layers "F.Cu" "B.Cu")
		(net "SAS_SDBTX")
	)
	(segment
		(start 113.464848 -45.39996)
		(end 113.150142 -45.39996)
		(width 0.1143)
		(layer "F.Cu")
		(net "IOC_SDA_0")
	)
	(segment
		(start 113.807748 -45.05706)
		(end 113.464848 -45.39996)
		(width 0.1143)
		(layer "F.Cu")
		(net "IOC_SDA_0")
	)
	(segment
		(start 117.520466 -44.9326)
		(end 117.396006 -45.05706)
		(width 0.1143)
		(layer "F.Cu")
		(net "IOC_SDA_0")
	)
	(segment
		(start 117.622066 -44.831)
		(end 117.520466 -44.9326)
		(width 0.1143)
		(layer "F.Cu")
		(net "IOC_SDA_0")
	)
	(segment
		(start 118.364 -44.831)
		(end 117.622066 -44.831)
		(width 0.1143)
		(layer "F.Cu")
		(net "IOC_SDA_0")
	)
	(segment
		(start 117.396006 -45.05706)
		(end 113.807748 -45.05706)
		(width 0.1143)
		(layer "F.Cu")
		(net "IOC_SDA_0")
	)
	(via
		(at 117.520466 -44.9326)
		(size 0.5588)
		(drill 0.3048)
		(layers "F.Cu" "B.Cu")
		(net "IOC_SDA_0")
	)
	(via
		(at 118.364 -44.831)
		(size 0.7112)
		(drill 0.3556)
		(layers "F.Cu" "B.Cu")
		(net "IOC_SDA_0")
	)
	(segment
		(start 117.749066 -44.704)
		(end 117.520466 -44.9326)
		(width 0.1143)
		(layer "B.Cu")
		(net "IOC_SDA_0")
	)
	(segment
		(start 118.4275 -44.704)
		(end 117.749066 -44.704)
		(width 0.1143)
		(layer "B.Cu")
		(net "IOC_SDA_0")
	)
	(segment
		(start 89.990168 -42.9641)
		(end 90.663776 -42.9641)
		(width 0.1016)
		(layer "F.Cu")
		(net "SAS3008_RAID_TX_C_P4")
	)
	(segment
		(start 86.77656 -45.212)
		(end 86.796118 -45.192442)
		(width 0.1016)
		(layer "F.Cu")
		(net "SAS3008_RAID_TX_C_P4")
	)
	(segment
		(start 87.086186 -45.0723)
		(end 87.807546 -45.0723)
		(width 0.1016)
		(layer "F.Cu")
		(net "SAS3008_RAID_TX_C_P4")
	)
	(segment
		(start 88.540336 -44.76877)
		(end 89.253568 -44.055538)
		(width 0.1016)
		(layer "F.Cu")
		(net "SAS3008_RAID_TX_C_P4")
	)
	(arc
		(start 90.695018 -42.968164)
		(mid 90.708532 -42.972595)
		(end 90.721434 -42.978578)
		(width 0.1016)
		(layer "F.Cu")
		(net "SAS3008_RAID_TX_C_P4")
	)
	(arc
		(start 90.721434 -42.978578)
		(mid 90.736579 -42.988179)
		(end 90.750136 -42.999914)
		(width 0.1016)
		(layer "F.Cu")
		(net "SAS3008_RAID_TX_C_P4")
	)
	(arc
		(start 89.504266 -43.450002)
		(mid 89.646583 -43.106417)
		(end 89.990168 -42.9641)
		(width 0.1016)
		(layer "F.Cu")
		(net "SAS3008_RAID_TX_C_P4")
	)
	(arc
		(start 87.807546 -45.0723)
		(mid 88.204143 -44.99343)
		(end 88.540336 -44.76877)
		(width 0.1016)
		(layer "F.Cu")
		(net "SAS3008_RAID_TX_C_P4")
	)
	(arc
		(start 89.253568 -44.055538)
		(mid 89.43912 -43.777701)
		(end 89.504266 -43.450002)
		(width 0.1016)
		(layer "F.Cu")
		(net "SAS3008_RAID_TX_C_P4")
	)
	(arc
		(start 86.796118 -45.192442)
		(mid 86.929202 -45.103518)
		(end 87.086186 -45.0723)
		(width 0.1016)
		(layer "F.Cu")
		(net "SAS3008_RAID_TX_C_P4")
	)
	(arc
		(start 90.663776 -42.9641)
		(mid 90.679529 -42.96512)
		(end 90.695018 -42.968164)
		(width 0.1016)
		(layer "F.Cu")
		(net "SAS3008_RAID_TX_C_P4")
	)
	(segment
		(start 126.517654 -88.51773)
		(end 126.350014 -88.349836)
		(width 0.1016)
		(layer "F.Cu")
		(net "3X24_SAS_TX17_P")
	)
	(segment
		(start 130.262884 -88.809322)
		(end 130.211576 -88.86063)
		(width 0.1016)
		(layer "F.Cu")
		(net "3X24_SAS_TX17_P")
	)
	(segment
		(start 131.0386 -88.519)
		(end 131.001262 -88.556084)
		(width 0.1016)
		(layer "F.Cu")
		(net "3X24_SAS_TX17_P")
	)
	(segment
		(start 130.099816 -88.907112)
		(end 128.281684 -88.907112)
		(width 0.1016)
		(layer "F.Cu")
		(net "3X24_SAS_TX17_P")
	)
	(segment
		(start 130.7846 -88.646)
		(end 130.6576 -88.646)
		(width 0.1016)
		(layer "F.Cu")
		(net "3X24_SAS_TX17_P")
	)
	(segment
		(start 130.6576 -88.646)
		(end 130.6576 -88.645746)
		(width 0.1016)
		(layer "F.Cu")
		(net "3X24_SAS_TX17_P")
	)
	(segment
		(start 127.913892 -88.754712)
		(end 127.09017 -88.754712)
		(width 0.1016)
		(layer "F.Cu")
		(net "3X24_SAS_TX17_P")
	)
	(arc
		(start 130.6576 -88.645746)
		(mid 130.443979 -88.688274)
		(end 130.262884 -88.809322)
		(width 0.1016)
		(layer "F.Cu")
		(net "3X24_SAS_TX17_P")
	)
	(arc
		(start 128.281684 -88.907112)
		(mid 128.180497 -88.886985)
		(end 128.09474 -88.829642)
		(width 0.1016)
		(layer "F.Cu")
		(net "3X24_SAS_TX17_P")
	)
	(arc
		(start 128.09474 -88.829642)
		(mid 128.011766 -88.774201)
		(end 127.913892 -88.754712)
		(width 0.1016)
		(layer "F.Cu")
		(net "3X24_SAS_TX17_P")
	)
	(arc
		(start 131.001262 -88.556084)
		(mid 130.901872 -88.622587)
		(end 130.7846 -88.646)
		(width 0.1016)
		(layer "F.Cu")
		(net "3X24_SAS_TX17_P")
	)
	(arc
		(start 130.211576 -88.86063)
		(mid 130.160329 -88.895028)
		(end 130.099816 -88.907112)
		(width 0.1016)
		(layer "F.Cu")
		(net "3X24_SAS_TX17_P")
	)
	(arc
		(start 127.09017 -88.754712)
		(mid 126.780335 -88.693176)
		(end 126.517654 -88.51773)
		(width 0.1016)
		(layer "F.Cu")
		(net "3X24_SAS_TX17_P")
	)
	(segment
		(start 114.492532 -42.199814)
		(end 114.637566 -42.05478)
		(width 0.1143)
		(layer "F.Cu")
		(net "IOC_GPIO_24")
	)
	(segment
		(start 113.949988 -42.199814)
		(end 114.492532 -42.199814)
		(width 0.1143)
		(layer "F.Cu")
		(net "IOC_GPIO_24")
	)
	(via
		(at 114.637566 -42.05478)
		(size 0.508)
		(drill 0.254)
		(layers "F.Cu" "B.Cu")
		(net "IOC_GPIO_24")
	)
	(segment
		(start 115.628166 -41.26484)
		(end 114.838226 -42.05478)
		(width 0.1143)
		(layer "B.Cu")
		(net "IOC_GPIO_24")
	)
	(segment
		(start 114.838226 -42.05478)
		(end 114.637566 -42.05478)
		(width 0.1143)
		(layer "B.Cu")
		(net "IOC_GPIO_24")
	)
	(segment
		(start 243.095272 -120.321578)
		(end 242.89385 -120.523)
		(width 0.1143)
		(layer "F.Cu")
		(net "SAS_SMART_RX")
	)
	(segment
		(start 92.72397 -106.426)
		(end 92.83192 -106.31805)
		(width 0.1143)
		(layer "F.Cu")
		(net "SAS_SMART_RX")
	)
	(segment
		(start 92.83192 -106.31805)
		(end 93.59392 -106.31805)
		(width 0.1143)
		(layer "F.Cu")
		(net "SAS_SMART_RX")
	)
	(segment
		(start 242.89385 -120.523)
		(end 242.89385 -147.38985)
		(width 0.1143)
		(layer "F.Cu")
		(net "SAS_SMART_RX")
	)
	(segment
		(start 243.095272 -118.618)
		(end 243.095272 -120.321578)
		(width 0.1143)
		(layer "F.Cu")
		(net "SAS_SMART_RX")
	)
	(segment
		(start 242.89385 -147.38985)
		(end 244.221 -148.717)
		(width 0.1143)
		(layer "F.Cu")
		(net "SAS_SMART_RX")
	)
	(segment
		(start 93.59392 -106.31805)
		(end 93.86697 -106.045)
		(width 0.1143)
		(layer "F.Cu")
		(net "SAS_SMART_RX")
	)
	(segment
		(start 93.86697 -106.045)
		(end 95.26397 -106.045)
		(width 0.1143)
		(layer "F.Cu")
		(net "SAS_SMART_RX")
	)
	(via
		(at 93.86697 -106.045)
		(size 0.5588)
		(drill 0.3048)
		(layers "F.Cu" "B.Cu")
		(net "SAS_SMART_RX")
	)
	(via
		(at 93.4212 -106.7562)
		(size 0.7112)
		(drill 0.3556)
		(layers "F.Cu" "B.Cu")
		(net "SAS_SMART_RX")
	)
	(via
		(at 244.221 -148.717)
		(size 0.5588)
		(drill 0.3048)
		(layers "F.Cu" "B.Cu")
		(net "SAS_SMART_RX")
	)
	(segment
		(start 93.86697 -106.31043)
		(end 93.86697 -106.045)
		(width 0.1143)
		(layer "B.Cu")
		(net "SAS_SMART_RX")
	)
	(segment
		(start 93.4212 -106.7562)
		(end 93.86697 -106.31043)
		(width 0.1143)
		(layer "B.Cu")
		(net "SAS_SMART_RX")
	)
	(segment
		(start 211.0613 -148.2217)
		(end 243.7257 -148.2217)
		(width 0.127)
		(layer "In2.Cu")
		(net "SAS_SMART_RX")
	)
	(segment
		(start 85.023452 -117.093746)
		(end 83.064858 -117.093746)
		(width 0.127)
		(layer "In2.Cu")
		(net "SAS_SMART_RX")
	)
	(segment
		(start 93.86697 -108.250228)
		(end 85.023452 -117.093746)
		(width 0.127)
		(layer "In2.Cu")
		(net "SAS_SMART_RX")
	)
	(segment
		(start 110.052104 -150.495)
		(end 159.07766 -150.495)
		(width 0.127)
		(layer "In2.Cu")
		(net "SAS_SMART_RX")
	)
	(segment
		(start 243.7257 -148.2217)
		(end 244.221 -148.717)
		(width 0.127)
		(layer "In2.Cu")
		(net "SAS_SMART_RX")
	)
	(segment
		(start 82.418936 -126.24816)
		(end 84.824062 -126.24816)
		(width 0.127)
		(layer "In2.Cu")
		(net "SAS_SMART_RX")
	)
	(segment
		(start 159.439864 -150.857204)
		(end 159.850328 -150.857204)
		(width 0.127)
		(layer "In2.Cu")
		(net "SAS_SMART_RX")
	)
	(segment
		(start 79.55407 -123.383294)
		(end 82.418936 -126.24816)
		(width 0.127)
		(layer "In2.Cu")
		(net "SAS_SMART_RX")
	)
	(segment
		(start 209.0801 -150.2029)
		(end 211.0613 -148.2217)
		(width 0.127)
		(layer "In2.Cu")
		(net "SAS_SMART_RX")
	)
	(segment
		(start 88.95207 -130.376168)
		(end 88.95207 -130.970782)
		(width 0.127)
		(layer "In2.Cu")
		(net "SAS_SMART_RX")
	)
	(segment
		(start 169.475912 -150.2029)
		(end 209.0801 -150.2029)
		(width 0.127)
		(layer "In2.Cu")
		(net "SAS_SMART_RX")
	)
	(segment
		(start 84.824062 -126.24816)
		(end 88.95207 -130.376168)
		(width 0.127)
		(layer "In2.Cu")
		(net "SAS_SMART_RX")
	)
	(segment
		(start 91.216988 -132.588)
		(end 91.468448 -132.83946)
		(width 0.127)
		(layer "In2.Cu")
		(net "SAS_SMART_RX")
	)
	(segment
		(start 95.98025 -136.423146)
		(end 110.052104 -150.495)
		(width 0.127)
		(layer "In2.Cu")
		(net "SAS_SMART_RX")
	)
	(segment
		(start 88.95207 -130.970782)
		(end 90.569288 -132.588)
		(width 0.127)
		(layer "In2.Cu")
		(net "SAS_SMART_RX")
	)
	(segment
		(start 91.468448 -132.83946)
		(end 91.61145 -132.83946)
		(width 0.127)
		(layer "In2.Cu")
		(net "SAS_SMART_RX")
	)
	(segment
		(start 95.195136 -136.423146)
		(end 95.98025 -136.423146)
		(width 0.127)
		(layer "In2.Cu")
		(net "SAS_SMART_RX")
	)
	(segment
		(start 83.064858 -117.093746)
		(end 79.55407 -120.604534)
		(width 0.127)
		(layer "In2.Cu")
		(net "SAS_SMART_RX")
	)
	(segment
		(start 160.212532 -150.495)
		(end 169.183812 -150.495)
		(width 0.127)
		(layer "In2.Cu")
		(net "SAS_SMART_RX")
	)
	(segment
		(start 169.183812 -150.495)
		(end 169.475912 -150.2029)
		(width 0.127)
		(layer "In2.Cu")
		(net "SAS_SMART_RX")
	)
	(segment
		(start 93.86697 -106.045)
		(end 93.86697 -108.250228)
		(width 0.127)
		(layer "In2.Cu")
		(net "SAS_SMART_RX")
	)
	(segment
		(start 159.850328 -150.857204)
		(end 160.212532 -150.495)
		(width 0.127)
		(layer "In2.Cu")
		(net "SAS_SMART_RX")
	)
	(segment
		(start 91.61145 -132.83946)
		(end 95.195136 -136.423146)
		(width 0.127)
		(layer "In2.Cu")
		(net "SAS_SMART_RX")
	)
	(segment
		(start 90.569288 -132.588)
		(end 91.216988 -132.588)
		(width 0.127)
		(layer "In2.Cu")
		(net "SAS_SMART_RX")
	)
	(segment
		(start 79.55407 -120.604534)
		(end 79.55407 -123.383294)
		(width 0.127)
		(layer "In2.Cu")
		(net "SAS_SMART_RX")
	)
	(segment
		(start 159.07766 -150.495)
		(end 159.439864 -150.857204)
		(width 0.127)
		(layer "In2.Cu")
		(net "SAS_SMART_RX")
	)
	(segment
		(start 116.198396 -41.789604)
		(end 114.988086 -42.999914)
		(width 0.1143)
		(layer "F.Cu")
		(net "IOC_SDA_1")
	)
	(segment
		(start 117.562376 -41.0464)
		(end 118.375176 -40.2336)
		(width 0.1143)
		(layer "F.Cu")
		(net "IOC_SDA_1")
	)
	(segment
		(start 116.315236 -41.789604)
		(end 116.198396 -41.789604)
		(width 0.1143)
		(layer "F.Cu")
		(net "IOC_SDA_1")
	)
	(segment
		(start 117.05844 -41.0464)
		(end 117.562376 -41.0464)
		(width 0.1143)
		(layer "F.Cu")
		(net "IOC_SDA_1")
	)
	(segment
		(start 118.375176 -40.2336)
		(end 118.7704 -40.2336)
		(width 0.1143)
		(layer "F.Cu")
		(net "IOC_SDA_1")
	)
	(segment
		(start 114.988086 -42.999914)
		(end 113.949988 -42.999914)
		(width 0.1143)
		(layer "F.Cu")
		(net "IOC_SDA_1")
	)
	(segment
		(start 116.315236 -41.789604)
		(end 117.05844 -41.0464)
		(width 0.1143)
		(layer "F.Cu")
		(net "IOC_SDA_1")
	)
	(via
		(at 116.315236 -41.789604)
		(size 0.7112)
		(drill 0.3556)
		(layers "F.Cu" "B.Cu")
		(net "IOC_SDA_1")
	)
	(via
		(at 118.7704 -40.2336)
		(size 0.5588)
		(drill 0.3048)
		(layers "F.Cu" "B.Cu")
		(net "IOC_SDA_1")
	)
	(segment
		(start 118.8212 -40.2336)
		(end 118.7704 -40.2336)
		(width 0.1143)
		(layer "B.Cu")
		(net "IOC_SDA_1")
	)
	(segment
		(start 119.6975 -40.005)
		(end 119.0498 -40.005)
		(width 0.1143)
		(layer "B.Cu")
		(net "IOC_SDA_1")
	)
	(segment
		(start 119.0498 -40.005)
		(end 118.8212 -40.2336)
		(width 0.1143)
		(layer "B.Cu")
		(net "IOC_SDA_1")
	)
	(segment
		(start 106.750104 -37.399976)
		(end 107.1499 -37.799772)
		(width 0.1143)
		(layer "F.Cu")
		(net "IOC_GPIO_7")
	)
	(via
		(at 107.1499 -37.799772)
		(size 0.508)
		(drill 0.254)
		(layers "F.Cu" "B.Cu")
		(net "IOC_GPIO_7")
	)
	(segment
		(start 106.735626 -38.55974)
		(end 107.00512 -38.290246)
		(width 0.1143)
		(layer "B.Cu")
		(net "IOC_GPIO_7")
	)
	(segment
		(start 107.00512 -38.290246)
		(end 107.1499 -37.799772)
		(width 0.1143)
		(layer "B.Cu")
		(net "IOC_GPIO_7")
	)
	(segment
		(start 92.97289 -103.25989)
		(end 94.41434 -103.25989)
		(width 0.1143)
		(layer "F.Cu")
		(net "SDB_RX")
	)
	(segment
		(start 43.561 -121.589546)
		(end 47.409354 -121.589546)
		(width 0.1143)
		(layer "F.Cu")
		(net "SDB_RX")
	)
	(segment
		(start 92.72397 -102.93858)
		(end 92.72397 -103.01097)
		(width 0.1143)
		(layer "F.Cu")
		(net "SDB_RX")
	)
	(segment
		(start 92.72397 -103.01097)
		(end 92.97289 -103.25989)
		(width 0.1143)
		(layer "F.Cu")
		(net "SDB_RX")
	)
	(segment
		(start 94.37497 -103.22052)
		(end 94.41434 -103.25989)
		(width 0.1143)
		(layer "F.Cu")
		(net "SDB_RX")
	)
	(segment
		(start 47.409354 -121.589546)
		(end 48.3997 -120.5992)
		(width 0.1143)
		(layer "F.Cu")
		(net "SDB_RX")
	)
	(segment
		(start 95.25635 -102.56012)
		(end 94.66707 -102.56012)
		(width 0.1143)
		(layer "F.Cu")
		(net "SDB_RX")
	)
	(segment
		(start 94.66707 -102.56012)
		(end 94.37497 -102.85222)
		(width 0.1143)
		(layer "F.Cu")
		(net "SDB_RX")
	)
	(segment
		(start 94.37497 -102.85222)
		(end 94.37497 -103.22052)
		(width 0.1143)
		(layer "F.Cu")
		(net "SDB_RX")
	)
	(via
		(at 50.419 -143.002)
		(size 0.5588)
		(drill 0.3048)
		(layers "F.Cu" "B.Cu")
		(net "SDB_RX")
	)
	(via
		(at 95.2246 -102.6922)
		(size 0.7112)
		(drill 0.3556)
		(layers "F.Cu" "B.Cu")
		(net "SDB_RX")
	)
	(via
		(at 43.561 -121.589546)
		(size 0.5588)
		(drill 0.3048)
		(layers "F.Cu" "B.Cu")
		(net "SDB_RX")
	)
	(via
		(at 94.41434 -103.25989)
		(size 0.5588)
		(drill 0.3048)
		(layers "F.Cu" "B.Cu")
		(net "SDB_RX")
	)
	(segment
		(start 94.6658 -103.251)
		(end 94.42323 -103.251)
		(width 0.1143)
		(layer "B.Cu")
		(net "SDB_RX")
	)
	(segment
		(start 94.42323 -103.251)
		(end 94.41434 -103.25989)
		(width 0.1143)
		(layer "B.Cu")
		(net "SDB_RX")
	)
	(segment
		(start 95.2246 -102.6922)
		(end 94.6658 -103.251)
		(width 0.1143)
		(layer "B.Cu")
		(net "SDB_RX")
	)
	(segment
		(start 42.926 -134.716012)
		(end 42.926 -131.953)
		(width 0.127)
		(layer "In2.Cu")
		(net "SDB_RX")
	)
	(segment
		(start 44.480734 -136.270746)
		(end 42.926 -134.716012)
		(width 0.127)
		(layer "In2.Cu")
		(net "SDB_RX")
	)
	(segment
		(start 41.7449 -130.7719)
		(end 41.7449 -124.1171)
		(width 0.127)
		(layer "In2.Cu")
		(net "SDB_RX")
	)
	(segment
		(start 42.926 -131.953)
		(end 41.7449 -130.7719)
		(width 0.127)
		(layer "In2.Cu")
		(net "SDB_RX")
	)
	(segment
		(start 41.7449 -124.1171)
		(end 43.561 -122.301)
		(width 0.127)
		(layer "In2.Cu")
		(net "SDB_RX")
	)
	(segment
		(start 43.561 -122.301)
		(end 43.561 -121.589546)
		(width 0.127)
		(layer "In2.Cu")
		(net "SDB_RX")
	)
	(segment
		(start 44.480734 -137.063734)
		(end 44.480734 -136.270746)
		(width 0.127)
		(layer "In2.Cu")
		(net "SDB_RX")
	)
	(segment
		(start 50.419 -143.002)
		(end 44.480734 -137.063734)
		(width 0.127)
		(layer "In2.Cu")
		(net "SDB_RX")
	)
	(segment
		(start 91.68511 -103.25989)
		(end 94.41434 -103.25989)
		(width 0.127)
		(layer "In5.Cu")
		(net "SDB_RX")
	)
	(segment
		(start 80.187038 -108.204)
		(end 86.741 -108.204)
		(width 0.127)
		(layer "In5.Cu")
		(net "SDB_RX")
	)
	(segment
		(start 86.741 -108.204)
		(end 91.68511 -103.25989)
		(width 0.127)
		(layer "In5.Cu")
		(net "SDB_RX")
	)
	(segment
		(start 54.483 -138.938)
		(end 54.483 -133.908038)
		(width 0.127)
		(layer "In5.Cu")
		(net "SDB_RX")
	)
	(segment
		(start 54.483 -133.908038)
		(end 80.187038 -108.204)
		(width 0.127)
		(layer "In5.Cu")
		(net "SDB_RX")
	)
	(segment
		(start 50.419 -143.002)
		(end 54.483 -138.938)
		(width 0.127)
		(layer "In5.Cu")
		(net "SDB_RX")
	)
	(segment
		(start 118.75897 -109.22)
		(end 118.636288 -109.22)
		(width 0.1016)
		(layer "F.Cu")
		(net "SAS_HDD_TX0_N")
	)
	(segment
		(start 117.73281 -108.266992)
		(end 117.73281 -106.840274)
		(width 0.1016)
		(layer "F.Cu")
		(net "SAS_HDD_TX0_N")
	)
	(segment
		(start 121.44502 -113.668048)
		(end 121.44502 -111.910368)
		(width 0.1016)
		(layer "F.Cu")
		(net "SAS_HDD_TX0_N")
	)
	(segment
		(start 120.86717 -110.5154)
		(end 120.33377 -109.982)
		(width 0.1016)
		(layer "F.Cu")
		(net "SAS_HDD_TX0_N")
	)
	(segment
		(start 120.33377 -109.982)
		(end 120.146318 -109.794802)
		(width 0.1016)
		(layer "F.Cu")
		(net "SAS_HDD_TX0_N")
	)
	(arc
		(start 118.147846 -109.069886)
		(mid 118.082667 -109.020891)
		(end 118.02237 -108.966)
		(width 0.1016)
		(layer "F.Cu")
		(net "SAS_HDD_TX0_N")
	)
	(arc
		(start 120.146318 -109.794802)
		(mid 119.509812 -109.36941)
		(end 118.75897 -109.22)
		(width 0.1016)
		(layer "F.Cu")
		(net "SAS_HDD_TX0_N")
	)
	(arc
		(start 117.73281 -106.840274)
		(mid 117.893229 -106.033792)
		(end 118.35003 -105.350056)
		(width 0.1016)
		(layer "F.Cu")
		(net "SAS_HDD_TX0_N")
	)
	(arc
		(start 121.44502 -111.910368)
		(mid 121.294848 -111.155403)
		(end 120.86717 -110.5154)
		(width 0.1016)
		(layer "F.Cu")
		(net "SAS_HDD_TX0_N")
	)
	(arc
		(start 121.29897 -114.0206)
		(mid 121.407049 -113.858848)
		(end 121.44502 -113.668048)
		(width 0.1016)
		(layer "F.Cu")
		(net "SAS_HDD_TX0_N")
	)
	(arc
		(start 118.02237 -108.966)
		(mid 117.80808 -108.645292)
		(end 117.73281 -108.266992)
		(width 0.1016)
		(layer "F.Cu")
		(net "SAS_HDD_TX0_N")
	)
	(arc
		(start 118.636288 -109.22)
		(mid 118.380781 -109.181683)
		(end 118.147846 -109.069886)
		(width 0.1016)
		(layer "F.Cu")
		(net "SAS_HDD_TX0_N")
	)
	(segment
		(start 118.35003 -88.349836)
		(end 118.850156 -87.84971)
		(width 0.4572)
		(layer "F.Cu")
		(net "XTAL_VDDA09")
	)
	(via
		(at 88.373966 -81.661)
		(size 0.7112)
		(drill 0.3556)
		(layers "F.Cu" "B.Cu")
		(net "XTAL_VDDA09")
	)
	(via
		(at 118.850156 -87.84971)
		(size 0.508)
		(drill 0.254)
		(layers "F.Cu" "B.Cu")
		(net "XTAL_VDDA09")
	)
	(via
		(at 87.357966 -81.4578)
		(size 0.5588)
		(drill 0.3048)
		(layers "F.Cu" "B.Cu")
		(net "XTAL_VDDA09")
	)
	(segment
		(start 114.265456 -78.402434)
		(end 114.38763 -78.524862)
		(width 0.508)
		(layer "In2.Cu")
		(net "XTAL_VDDA09")
	)
	(segment
		(start 93.472 -77.47)
		(end 112.014 -77.47)
		(width 0.508)
		(layer "In2.Cu")
		(net "XTAL_VDDA09")
	)
	(segment
		(start 120.459754 -84.596986)
		(end 120.459754 -86.240112)
		(width 0.508)
		(layer "In2.Cu")
		(net "XTAL_VDDA09")
	)
	(segment
		(start 120.459754 -86.240112)
		(end 118.850156 -87.84971)
		(width 0.508)
		(layer "In2.Cu")
		(net "XTAL_VDDA09")
	)
	(segment
		(start 87.357966 -81.4578)
		(end 89.4842 -81.4578)
		(width 0.508)
		(layer "In2.Cu")
		(net "XTAL_VDDA09")
	)
	(segment
		(start 114.38763 -78.524862)
		(end 120.459754 -84.596986)
		(width 0.508)
		(layer "In2.Cu")
		(net "XTAL_VDDA09")
	)
	(segment
		(start 89.4842 -81.4578)
		(end 93.472 -77.47)
		(width 0.508)
		(layer "In2.Cu")
		(net "XTAL_VDDA09")
	)
	(arc
		(start 112.014 -77.47)
		(mid 113.232476 -77.712276)
		(end 114.265456 -78.402434)
		(width 0.508)
		(layer "In2.Cu")
		(net "XTAL_VDDA09")
	)
	(segment
		(start 119.38 -47.879)
		(end 119.126 -47.625)
		(width 0.1143)
		(layer "F.Cu")
		(net "IOC_SCL_1")
	)
	(segment
		(start 119.126 -47.625)
		(end 116.30152 -47.625)
		(width 0.1143)
		(layer "F.Cu")
		(net "IOC_SCL_1")
	)
	(segment
		(start 114.876326 -46.199806)
		(end 113.949988 -46.199806)
		(width 0.1143)
		(layer "F.Cu")
		(net "IOC_SCL_1")
	)
	(segment
		(start 116.30152 -47.625)
		(end 114.876326 -46.199806)
		(width 0.1143)
		(layer "F.Cu")
		(net "IOC_SCL_1")
	)
	(via
		(at 119.38 -47.879)
		(size 0.5588)
		(drill 0.3048)
		(layers "F.Cu" "B.Cu")
		(net "IOC_SCL_1")
	)
	(via
		(at 118.62054 -47.244)
		(size 0.7112)
		(drill 0.3556)
		(layers "F.Cu" "B.Cu")
		(net "IOC_SCL_1")
	)
	(segment
		(start 120.975374 -48.333914)
		(end 120.898412 -48.256952)
		(width 0.1143)
		(layer "B.Cu")
		(net "IOC_SCL_1")
	)
	(segment
		(start 118.62054 -47.244)
		(end 118.74754 -47.244)
		(width 0.1143)
		(layer "B.Cu")
		(net "IOC_SCL_1")
	)
	(segment
		(start 118.74754 -47.244)
		(end 119.38 -47.87646)
		(width 0.1143)
		(layer "B.Cu")
		(net "IOC_SCL_1")
	)
	(segment
		(start 119.38 -47.87646)
		(end 119.38 -47.879)
		(width 0.1143)
		(layer "B.Cu")
		(net "IOC_SCL_1")
	)
	(segment
		(start 120.898412 -48.256952)
		(end 119.757952 -48.256952)
		(width 0.1143)
		(layer "B.Cu")
		(net "IOC_SCL_1")
	)
	(segment
		(start 119.757952 -48.256952)
		(end 119.38 -47.879)
		(width 0.1143)
		(layer "B.Cu")
		(net "IOC_SCL_1")
	)
	(segment
		(start 112.349788 -88.349836)
		(end 111.849662 -87.84971)
		(width 0.4572)
		(layer "F.Cu")
		(net "SYSPLL_VDDA09")
	)
	(via
		(at 111.849662 -87.84971)
		(size 0.508)
		(drill 0.254)
		(layers "F.Cu" "B.Cu")
		(net "SYSPLL_VDDA09")
	)
	(via
		(at 89.389966 -84.455)
		(size 0.5588)
		(drill 0.3048)
		(layers "F.Cu" "B.Cu")
		(net "SYSPLL_VDDA09")
	)
	(via
		(at 89.770966 -87.376)
		(size 0.7112)
		(drill 0.3556)
		(layers "F.Cu" "B.Cu")
		(net "SYSPLL_VDDA09")
	)
	(via
		(at 113.13033 -80.67294)
		(size 0.7112)
		(drill 0.4064)
		(layers "F.Cu" "B.Cu")
		(net "SYSPLL_VDDA09")
	)
	(segment
		(start 102.28453 -80.0735)
		(end 102.34803 -80.137)
		(width 0.635)
		(layer "In2.Cu")
		(net "SYSPLL_VDDA09")
	)
	(segment
		(start 101.70541 -80.0735)
		(end 102.28453 -80.0735)
		(width 0.635)
		(layer "In2.Cu")
		(net "SYSPLL_VDDA09")
	)
	(segment
		(start 105.359708 -80.137)
		(end 105.804208 -79.6925)
		(width 0.635)
		(layer "In2.Cu")
		(net "SYSPLL_VDDA09")
	)
	(segment
		(start 100.04552 -79.883)
		(end 100.29952 -80.137)
		(width 0.635)
		(layer "In2.Cu")
		(net "SYSPLL_VDDA09")
	)
	(segment
		(start 111.72063 -79.756)
		(end 112.63757 -80.67294)
		(width 0.635)
		(layer "In2.Cu")
		(net "SYSPLL_VDDA09")
	)
	(segment
		(start 98.898964 -80.137)
		(end 99.152964 -79.883)
		(width 0.635)
		(layer "In2.Cu")
		(net "SYSPLL_VDDA09")
	)
	(segment
		(start 102.34803 -80.137)
		(end 105.359708 -80.137)
		(width 0.635)
		(layer "In2.Cu")
		(net "SYSPLL_VDDA09")
	)
	(segment
		(start 100.29952 -80.137)
		(end 101.64191 -80.137)
		(width 0.635)
		(layer "In2.Cu")
		(net "SYSPLL_VDDA09")
	)
	(segment
		(start 106.425492 -79.756)
		(end 111.72063 -79.756)
		(width 0.635)
		(layer "In2.Cu")
		(net "SYSPLL_VDDA09")
	)
	(segment
		(start 99.152964 -79.883)
		(end 100.04552 -79.883)
		(width 0.635)
		(layer "In2.Cu")
		(net "SYSPLL_VDDA09")
	)
	(segment
		(start 112.63757 -80.67294)
		(end 113.13033 -80.67294)
		(width 0.635)
		(layer "In2.Cu")
		(net "SYSPLL_VDDA09")
	)
	(segment
		(start 106.361992 -79.6925)
		(end 106.425492 -79.756)
		(width 0.635)
		(layer "In2.Cu")
		(net "SYSPLL_VDDA09")
	)
	(segment
		(start 96.78797 -80.137)
		(end 98.898964 -80.137)
		(width 0.635)
		(layer "In2.Cu")
		(net "SYSPLL_VDDA09")
	)
	(segment
		(start 105.804208 -79.6925)
		(end 106.361992 -79.6925)
		(width 0.635)
		(layer "In2.Cu")
		(net "SYSPLL_VDDA09")
	)
	(segment
		(start 101.64191 -80.137)
		(end 101.70541 -80.0735)
		(width 0.635)
		(layer "In2.Cu")
		(net "SYSPLL_VDDA09")
	)
	(segment
		(start 92.46997 -84.455)
		(end 96.78797 -80.137)
		(width 0.635)
		(layer "In2.Cu")
		(net "SYSPLL_VDDA09")
	)
	(segment
		(start 89.389966 -84.455)
		(end 92.46997 -84.455)
		(width 0.635)
		(layer "In2.Cu")
		(net "SYSPLL_VDDA09")
	)
	(segment
		(start 113.464848 -42.999914)
		(end 113.150142 -42.999914)
		(width 0.1143)
		(layer "F.Cu")
		(net "IOC_SCL_0")
	)
	(segment
		(start 116.753894 -40.5511)
		(end 114.64798 -42.657014)
		(width 0.1143)
		(layer "F.Cu")
		(net "IOC_SCL_0")
	)
	(segment
		(start 114.64798 -42.657014)
		(end 113.807748 -42.657014)
		(width 0.1143)
		(layer "F.Cu")
		(net "IOC_SCL_0")
	)
	(segment
		(start 118.790466 -39.197534)
		(end 119.41683 -38.466776)
		(width 0.1143)
		(layer "F.Cu")
		(net "IOC_SCL_0")
	)
	(segment
		(start 118.491 -39.497)
		(end 118.790466 -39.197534)
		(width 0.1143)
		(layer "F.Cu")
		(net "IOC_SCL_0")
	)
	(segment
		(start 119.41683 -38.466776)
		(end 119.41683 -36.03117)
		(width 0.1143)
		(layer "F.Cu")
		(net "IOC_SCL_0")
	)
	(segment
		(start 118.491 -39.497)
		(end 118.411244 -39.497)
		(width 0.1143)
		(layer "F.Cu")
		(net "IOC_SCL_0")
	)
	(segment
		(start 113.807748 -42.657014)
		(end 113.464848 -42.999914)
		(width 0.1143)
		(layer "F.Cu")
		(net "IOC_SCL_0")
	)
	(segment
		(start 118.411244 -39.497)
		(end 117.357144 -40.5511)
		(width 0.1143)
		(layer "F.Cu")
		(net "IOC_SCL_0")
	)
	(segment
		(start 119.41683 -36.03117)
		(end 119.634 -35.814)
		(width 0.1143)
		(layer "F.Cu")
		(net "IOC_SCL_0")
	)
	(segment
		(start 117.357144 -40.5511)
		(end 116.753894 -40.5511)
		(width 0.1143)
		(layer "F.Cu")
		(net "IOC_SCL_0")
	)
	(via
		(at 119.634 -35.814)
		(size 0.5588)
		(drill 0.3048)
		(layers "F.Cu" "B.Cu")
		(net "IOC_SCL_0")
	)
	(via
		(at 118.491 -39.497)
		(size 0.7112)
		(drill 0.3556)
		(layers "F.Cu" "B.Cu")
		(net "IOC_SCL_0")
	)
	(segment
		(start 120.4595 -35.56)
		(end 119.888 -35.56)
		(width 0.1143)
		(layer "B.Cu")
		(net "IOC_SCL_0")
	)
	(segment
		(start 119.888 -35.56)
		(end 119.634 -35.814)
		(width 0.1143)
		(layer "B.Cu")
		(net "IOC_SCL_0")
	)
	(segment
		(start 125.350016 -87.349838)
		(end 124.350018 -88.349836)
		(width 0.4572)
		(layer "F.Cu")
		(net "GB_VDDA")
	)
	(segment
		(start 125.101858 -85.598)
		(end 124.98197 -85.598)
		(width 0.4572)
		(layer "F.Cu")
		(net "GB_VDDA")
	)
	(segment
		(start 123.35002 -106.350054)
		(end 123.850146 -106.85018)
		(width 0.4572)
		(layer "F.Cu")
		(net "GB_VDDA")
	)
	(segment
		(start 114.349784 -104.350058)
		(end 113.849658 -104.850184)
		(width 0.4572)
		(layer "F.Cu")
		(net "GB_VDDA")
	)
	(segment
		(start 124.350018 -98.35007)
		(end 124.850144 -98.850196)
		(width 0.4572)
		(layer "F.Cu")
		(net "GB_VDDA")
	)
	(segment
		(start 121.350024 -99.350068)
		(end 121.85015 -99.850194)
		(width 0.4572)
		(layer "F.Cu")
		(net "GB_VDDA")
	)
	(segment
		(start 121.350024 -95.350076)
		(end 121.85015 -95.850202)
		(width 0.4572)
		(layer "F.Cu")
		(net "GB_VDDA")
	)
	(segment
		(start 124.350018 -94.349824)
		(end 124.850144 -93.849698)
		(width 0.4572)
		(layer "F.Cu")
		(net "GB_VDDA")
	)
	(segment
		(start 122.350022 -102.350062)
		(end 122.850148 -102.850188)
		(width 0.4572)
		(layer "F.Cu")
		(net "GB_VDDA")
	)
	(segment
		(start 124.350018 -96.350074)
		(end 124.850144 -96.8502)
		(width 0.4572)
		(layer "F.Cu")
		(net "GB_VDDA")
	)
	(segment
		(start 125.84557 -82.854292)
		(end 125.350016 -83.349846)
		(width 0.2032)
		(layer "F.Cu")
		(net "GB_VDDA")
	)
	(segment
		(start 113.349786 -101.350064)
		(end 112.84966 -101.85019)
		(width 0.4572)
		(layer "F.Cu")
		(net "GB_VDDA")
	)
	(segment
		(start 124.350018 -90.349832)
		(end 125.350016 -91.34983)
		(width 0.4572)
		(layer "F.Cu")
		(net "GB_VDDA")
	)
	(segment
		(start 124.350018 -104.350058)
		(end 124.850144 -104.850184)
		(width 0.4572)
		(layer "F.Cu")
		(net "GB_VDDA")
	)
	(segment
		(start 124.350018 -86.229952)
		(end 124.350018 -86.34984)
		(width 0.4572)
		(layer "F.Cu")
		(net "GB_VDDA")
	)
	(segment
		(start 125.850142 -84.849716)
		(end 125.350016 -85.349842)
		(width 0.4572)
		(layer "F.Cu")
		(net "GB_VDDA")
	)
	(segment
		(start 120.350026 -104.350058)
		(end 120.850152 -104.850184)
		(width 0.4572)
		(layer "F.Cu")
		(net "GB_VDDA")
	)
	(segment
		(start 125.84557 -81.8896)
		(end 125.84557 -82.854292)
		(width 0.2032)
		(layer "F.Cu")
		(net "GB_VDDA")
	)
	(segment
		(start 121.350024 -91.34983)
		(end 121.85015 -90.849704)
		(width 0.4572)
		(layer "F.Cu")
		(net "GB_VDDA")
	)
	(segment
		(start 125.350016 -101.350064)
		(end 125.850142 -101.85019)
		(width 0.4572)
		(layer "F.Cu")
		(net "GB_VDDA")
	)
	(segment
		(start 115.350036 -105.352088)
		(end 114.839242 -105.862882)
		(width 0.4572)
		(layer "F.Cu")
		(net "GB_VDDA")
	)
	(segment
		(start 116.350034 -104.350058)
		(end 116.85016 -104.850184)
		(width 0.4572)
		(layer "F.Cu")
		(net "GB_VDDA")
	)
	(segment
		(start 119.350028 -105.350056)
		(end 119.850154 -105.850182)
		(width 0.4572)
		(layer "F.Cu")
		(net "GB_VDDA")
	)
	(segment
		(start 115.350036 -105.350056)
		(end 115.350036 -105.352088)
		(width 0.4572)
		(layer "F.Cu")
		(net "GB_VDDA")
	)
	(segment
		(start 121.350024 -89.349834)
		(end 121.85015 -88.849708)
		(width 0.4572)
		(layer "F.Cu")
		(net "GB_VDDA")
	)
	(segment
		(start 124.98197 -85.598)
		(end 124.350018 -86.229952)
		(width 0.4572)
		(layer "F.Cu")
		(net "GB_VDDA")
	)
	(segment
		(start 117.350032 -105.350056)
		(end 116.85016 -104.850184)
		(width 0.4572)
		(layer "F.Cu")
		(net "GB_VDDA")
	)
	(segment
		(start 112.349788 -104.350058)
		(end 111.849662 -104.850184)
		(width 0.4572)
		(layer "F.Cu")
		(net "GB_VDDA")
	)
	(segment
		(start 125.350016 -97.350072)
		(end 125.850142 -97.850198)
		(width 0.4572)
		(layer "F.Cu")
		(net "GB_VDDA")
	)
	(segment
		(start 125.350016 -85.349842)
		(end 125.101858 -85.598)
		(width 0.4572)
		(layer "F.Cu")
		(net "GB_VDDA")
	)
	(segment
		(start 125.850142 -86.849712)
		(end 125.350016 -87.349838)
		(width 0.4572)
		(layer "F.Cu")
		(net "GB_VDDA")
	)
	(segment
		(start 117.350032 -101.350064)
		(end 117.850158 -101.85019)
		(width 0.4572)
		(layer "F.Cu")
		(net "GB_VDDA")
	)
	(segment
		(start 122.350022 -104.350058)
		(end 122.850148 -104.850184)
		(width 0.4572)
		(layer "F.Cu")
		(net "GB_VDDA")
	)
	(segment
		(start 126.02337 -81.7118)
		(end 125.84557 -81.8896)
		(width 0.2032)
		(layer "F.Cu")
		(net "GB_VDDA")
	)
	(segment
		(start 121.350024 -97.350072)
		(end 121.85015 -97.850198)
		(width 0.4572)
		(layer "F.Cu")
		(net "GB_VDDA")
	)
	(segment
		(start 111.34979 -101.350064)
		(end 110.849664 -101.85019)
		(width 0.4572)
		(layer "F.Cu")
		(net "GB_VDDA")
	)
	(segment
		(start 125.350016 -89.349834)
		(end 124.350018 -88.349836)
		(width 0.4572)
		(layer "F.Cu")
		(net "GB_VDDA")
	)
	(segment
		(start 118.35003 -104.350058)
		(end 118.850156 -104.850184)
		(width 0.4572)
		(layer "F.Cu")
		(net "GB_VDDA")
	)
	(segment
		(start 119.350028 -101.350064)
		(end 119.850154 -101.85019)
		(width 0.4572)
		(layer "F.Cu")
		(net "GB_VDDA")
	)
	(segment
		(start 121.350024 -105.350056)
		(end 121.85015 -105.850182)
		(width 0.4572)
		(layer "F.Cu")
		(net "GB_VDDA")
	)
	(segment
		(start 121.350024 -101.350064)
		(end 121.85015 -101.85019)
		(width 0.4572)
		(layer "F.Cu")
		(net "GB_VDDA")
	)
	(segment
		(start 110.349792 -104.350058)
		(end 109.849666 -104.850184)
		(width 0.4572)
		(layer "F.Cu")
		(net "GB_VDDA")
	)
	(segment
		(start 111.34979 -105.350056)
		(end 111.849662 -104.850184)
		(width 0.4572)
		(layer "F.Cu")
		(net "GB_VDDA")
	)
	(segment
		(start 125.350016 -91.34983)
		(end 124.850144 -91.849702)
		(width 0.4572)
		(layer "F.Cu")
		(net "GB_VDDA")
	)
	(segment
		(start 113.349786 -105.350056)
		(end 113.849658 -104.850184)
		(width 0.4572)
		(layer "F.Cu")
		(net "GB_VDDA")
	)
	(segment
		(start 125.350016 -99.350068)
		(end 125.850142 -99.850194)
		(width 0.4572)
		(layer "F.Cu")
		(net "GB_VDDA")
	)
	(segment
		(start 125.350016 -83.349846)
		(end 124.350018 -84.349844)
		(width 0.3048)
		(layer "F.Cu")
		(net "GB_VDDA")
	)
	(segment
		(start 121.350024 -87.349838)
		(end 121.85015 -86.849712)
		(width 0.4572)
		(layer "F.Cu")
		(net "GB_VDDA")
	)
	(segment
		(start 109.349794 -105.350056)
		(end 109.849666 -104.850184)
		(width 0.4572)
		(layer "F.Cu")
		(net "GB_VDDA")
	)
	(segment
		(start 108.349796 -104.350058)
		(end 107.84967 -104.850184)
		(width 0.4572)
		(layer "F.Cu")
		(net "GB_VDDA")
	)
	(segment
		(start 124.350018 -102.350062)
		(end 124.850144 -102.850188)
		(width 0.4572)
		(layer "F.Cu")
		(net "GB_VDDA")
	)
	(segment
		(start 124.350018 -100.350066)
		(end 124.850144 -100.850192)
		(width 0.4572)
		(layer "F.Cu")
		(net "GB_VDDA")
	)
	(segment
		(start 125.350016 -95.350076)
		(end 125.850142 -95.850202)
		(width 0.4572)
		(layer "F.Cu")
		(net "GB_VDDA")
	)
	(segment
		(start 125.350016 -93.349826)
		(end 124.850144 -93.849698)
		(width 0.4572)
		(layer "F.Cu")
		(net "GB_VDDA")
	)
	(segment
		(start 121.350024 -93.349826)
		(end 121.85015 -92.8497)
		(width 0.4572)
		(layer "F.Cu")
		(net "GB_VDDA")
	)
	(segment
		(start 119.350028 -98.35007)
		(end 119.850154 -98.850196)
		(width 0.4572)
		(layer "F.Cu")
		(net "GB_VDDA")
	)
	(segment
		(start 107.349798 -105.350056)
		(end 107.84967 -104.850184)
		(width 0.4572)
		(layer "F.Cu")
		(net "GB_VDDA")
	)
	(segment
		(start 124.350018 -92.349828)
		(end 124.850144 -91.849702)
		(width 0.4572)
		(layer "F.Cu")
		(net "GB_VDDA")
	)
	(via
		(at 148.8821 -97.282)
		(size 0.7112)
		(drill 0.4064)
		(layers "F.Cu" "B.Cu")
		(net "GB_VDDA")
	)
	(via
		(at 125.850142 -99.850194)
		(size 0.508)
		(drill 0.254)
		(layers "F.Cu" "B.Cu")
		(net "GB_VDDA")
	)
	(via
		(at 107.84967 -104.850184)
		(size 0.508)
		(drill 0.254)
		(layers "F.Cu" "B.Cu")
		(net "GB_VDDA")
	)
	(via
		(at 109.849666 -104.850184)
		(size 0.508)
		(drill 0.254)
		(layers "F.Cu" "B.Cu")
		(net "GB_VDDA")
	)
	(via
		(at 121.85015 -99.850194)
		(size 0.508)
		(drill 0.254)
		(layers "F.Cu" "B.Cu")
		(net "GB_VDDA")
	)
	(via
		(at 110.849664 -101.85019)
		(size 0.508)
		(drill 0.254)
		(layers "F.Cu" "B.Cu")
		(net "GB_VDDA")
	)
	(via
		(at 147.8153 -97.282)
		(size 0.7112)
		(drill 0.4064)
		(layers "F.Cu" "B.Cu")
		(net "GB_VDDA")
	)
	(via
		(at 116.85016 -104.850184)
		(size 0.508)
		(drill 0.254)
		(layers "F.Cu" "B.Cu")
		(net "GB_VDDA")
	)
	(via
		(at 124.850144 -98.850196)
		(size 0.508)
		(drill 0.254)
		(layers "F.Cu" "B.Cu")
		(net "GB_VDDA")
	)
	(via
		(at 114.839242 -105.862882)
		(size 0.508)
		(drill 0.254)
		(layers "F.Cu" "B.Cu")
		(net "GB_VDDA")
	)
	(via
		(at 121.85015 -95.850202)
		(size 0.508)
		(drill 0.254)
		(layers "F.Cu" "B.Cu")
		(net "GB_VDDA")
	)
	(via
		(at 147.8153 -104.013)
		(size 0.7112)
		(drill 0.4064)
		(layers "F.Cu" "B.Cu")
		(net "GB_VDDA")
	)
	(via
		(at 148.8948 -96.139)
		(size 0.7112)
		(drill 0.4064)
		(layers "F.Cu" "B.Cu")
		(net "GB_VDDA")
	)
	(via
		(at 119.850154 -105.850182)
		(size 0.508)
		(drill 0.254)
		(layers "F.Cu" "B.Cu")
		(net "GB_VDDA")
	)
	(via
		(at 121.85015 -86.849712)
		(size 0.508)
		(drill 0.254)
		(layers "F.Cu" "B.Cu")
		(net "GB_VDDA")
	)
	(via
		(at 121.85015 -105.850182)
		(size 0.508)
		(drill 0.254)
		(layers "F.Cu" "B.Cu")
		(net "GB_VDDA")
	)
	(via
		(at 124.850144 -91.849702)
		(size 0.508)
		(drill 0.254)
		(layers "F.Cu" "B.Cu")
		(net "GB_VDDA")
	)
	(via
		(at 117.850158 -101.85019)
		(size 0.508)
		(drill 0.254)
		(layers "F.Cu" "B.Cu")
		(net "GB_VDDA")
	)
	(via
		(at 124.850144 -100.850192)
		(size 0.508)
		(drill 0.254)
		(layers "F.Cu" "B.Cu")
		(net "GB_VDDA")
	)
	(via
		(at 149.987 -107.569)
		(size 0.7112)
		(drill 0.4064)
		(layers "F.Cu" "B.Cu")
		(net "GB_VDDA")
	)
	(via
		(at 147.8788 -111.633)
		(size 0.7112)
		(drill 0.4064)
		(layers "F.Cu" "B.Cu")
		(net "GB_VDDA")
	)
	(via
		(at 123.850146 -106.85018)
		(size 0.508)
		(drill 0.254)
		(layers "F.Cu" "B.Cu")
		(net "GB_VDDA")
	)
	(via
		(at 121.85015 -92.8497)
		(size 0.508)
		(drill 0.254)
		(layers "F.Cu" "B.Cu")
		(net "GB_VDDA")
	)
	(via
		(at 122.850148 -102.850188)
		(size 0.508)
		(drill 0.254)
		(layers "F.Cu" "B.Cu")
		(net "GB_VDDA")
	)
	(via
		(at 121.85015 -97.850198)
		(size 0.508)
		(drill 0.254)
		(layers "F.Cu" "B.Cu")
		(net "GB_VDDA")
	)
	(via
		(at 121.85015 -90.849704)
		(size 0.508)
		(drill 0.254)
		(layers "F.Cu" "B.Cu")
		(net "GB_VDDA")
	)
	(via
		(at 148.0058 -109.601)
		(size 0.7112)
		(drill 0.4064)
		(layers "F.Cu" "B.Cu")
		(net "GB_VDDA")
	)
	(via
		(at 149.987 -97.282)
		(size 0.7112)
		(drill 0.4064)
		(layers "F.Cu" "B.Cu")
		(net "GB_VDDA")
	)
	(via
		(at 121.85015 -101.85019)
		(size 0.508)
		(drill 0.254)
		(layers "F.Cu" "B.Cu")
		(net "GB_VDDA")
	)
	(via
		(at 112.84966 -101.85019)
		(size 0.508)
		(drill 0.254)
		(layers "F.Cu" "B.Cu")
		(net "GB_VDDA")
	)
	(via
		(at 125.850142 -101.85019)
		(size 0.508)
		(drill 0.254)
		(layers "F.Cu" "B.Cu")
		(net "GB_VDDA")
	)
	(via
		(at 124.850144 -104.850184)
		(size 0.508)
		(drill 0.254)
		(layers "F.Cu" "B.Cu")
		(net "GB_VDDA")
	)
	(via
		(at 125.850142 -86.849712)
		(size 0.508)
		(drill 0.254)
		(layers "F.Cu" "B.Cu")
		(net "GB_VDDA")
	)
	(via
		(at 125.850142 -95.850202)
		(size 0.508)
		(drill 0.254)
		(layers "F.Cu" "B.Cu")
		(net "GB_VDDA")
	)
	(via
		(at 113.849658 -104.850184)
		(size 0.508)
		(drill 0.254)
		(layers "F.Cu" "B.Cu")
		(net "GB_VDDA")
	)
	(via
		(at 124.850144 -96.8502)
		(size 0.508)
		(drill 0.254)
		(layers "F.Cu" "B.Cu")
		(net "GB_VDDA")
	)
	(via
		(at 126.02337 -81.7118)
		(size 0.5588)
		(drill 0.3048)
		(layers "F.Cu" "B.Cu")
		(net "GB_VDDA")
	)
	(via
		(at 120.850152 -104.850184)
		(size 0.508)
		(drill 0.254)
		(layers "F.Cu" "B.Cu")
		(net "GB_VDDA")
	)
	(via
		(at 148.8821 -100.584)
		(size 0.7112)
		(drill 0.4064)
		(layers "F.Cu" "B.Cu")
		(net "GB_VDDA")
	)
	(via
		(at 124.850144 -93.849698)
		(size 0.508)
		(drill 0.254)
		(layers "F.Cu" "B.Cu")
		(net "GB_VDDA")
	)
	(via
		(at 123.317 -101.727)
		(size 0.7112)
		(drill 0.3556)
		(layers "F.Cu" "B.Cu")
		(net "GB_VDDA")
	)
	(via
		(at 147.8153 -107.569)
		(size 0.7112)
		(drill 0.4064)
		(layers "F.Cu" "B.Cu")
		(net "GB_VDDA")
	)
	(via
		(at 119.850154 -98.850196)
		(size 0.508)
		(drill 0.254)
		(layers "F.Cu" "B.Cu")
		(net "GB_VDDA")
	)
	(via
		(at 149.098 -109.601)
		(size 0.7112)
		(drill 0.4064)
		(layers "F.Cu" "B.Cu")
		(net "GB_VDDA")
	)
	(via
		(at 111.849662 -104.850184)
		(size 0.508)
		(drill 0.254)
		(layers "F.Cu" "B.Cu")
		(net "GB_VDDA")
	)
	(via
		(at 146.939 -109.601)
		(size 0.7112)
		(drill 0.4064)
		(layers "F.Cu" "B.Cu")
		(net "GB_VDDA")
	)
	(via
		(at 119.850154 -101.85019)
		(size 0.508)
		(drill 0.254)
		(layers "F.Cu" "B.Cu")
		(net "GB_VDDA")
	)
	(via
		(at 121.85015 -88.849708)
		(size 0.508)
		(drill 0.254)
		(layers "F.Cu" "B.Cu")
		(net "GB_VDDA")
	)
	(via
		(at 147.8153 -100.584)
		(size 0.7112)
		(drill 0.4064)
		(layers "F.Cu" "B.Cu")
		(net "GB_VDDA")
	)
	(via
		(at 147.828 -96.139)
		(size 0.7112)
		(drill 0.4064)
		(layers "F.Cu" "B.Cu")
		(net "GB_VDDA")
	)
	(via
		(at 125.33757 -87.63)
		(size 0.7112)
		(drill 0.3556)
		(layers "F.Cu" "B.Cu")
		(net "GB_VDDA")
	)
	(via
		(at 125.850142 -84.849716)
		(size 0.508)
		(drill 0.254)
		(layers "F.Cu" "B.Cu")
		(net "GB_VDDA")
	)
	(via
		(at 149.987 -100.584)
		(size 0.7112)
		(drill 0.4064)
		(layers "F.Cu" "B.Cu")
		(net "GB_VDDA")
	)
	(via
		(at 148.971 -111.633)
		(size 0.7112)
		(drill 0.4064)
		(layers "F.Cu" "B.Cu")
		(net "GB_VDDA")
	)
	(via
		(at 125.850142 -97.850198)
		(size 0.508)
		(drill 0.254)
		(layers "F.Cu" "B.Cu")
		(net "GB_VDDA")
	)
	(via
		(at 124.850144 -102.850188)
		(size 0.508)
		(drill 0.254)
		(layers "F.Cu" "B.Cu")
		(net "GB_VDDA")
	)
	(via
		(at 148.8821 -107.569)
		(size 0.7112)
		(drill 0.4064)
		(layers "F.Cu" "B.Cu")
		(net "GB_VDDA")
	)
	(via
		(at 146.812 -111.633)
		(size 0.7112)
		(drill 0.4064)
		(layers "F.Cu" "B.Cu")
		(net "GB_VDDA")
	)
	(via
		(at 122.850148 -104.850184)
		(size 0.508)
		(drill 0.254)
		(layers "F.Cu" "B.Cu")
		(net "GB_VDDA")
	)
	(via
		(at 149.987 -104.013)
		(size 0.7112)
		(drill 0.4064)
		(layers "F.Cu" "B.Cu")
		(net "GB_VDDA")
	)
	(via
		(at 118.850156 -104.850184)
		(size 0.508)
		(drill 0.254)
		(layers "F.Cu" "B.Cu")
		(net "GB_VDDA")
	)
	(via
		(at 148.8821 -104.013)
		(size 0.7112)
		(drill 0.4064)
		(layers "F.Cu" "B.Cu")
		(net "GB_VDDA")
	)
	(segment
		(start 121.19737 -85.979)
		(end 121.19737 -86.196932)
		(width 0.3048)
		(layer "B.Cu")
		(net "GB_VDDA")
	)
	(segment
		(start 121.19737 -86.196932)
		(end 121.85015 -86.849712)
		(width 0.3048)
		(layer "B.Cu")
		(net "GB_VDDA")
	)
	(segment
		(start 121.57837 -87.503)
		(end 121.57837 -87.121492)
		(width 0.3048)
		(layer "B.Cu")
		(net "GB_VDDA")
	)
	(segment
		(start 117.13337 -102.566978)
		(end 117.850158 -101.85019)
		(width 0.3048)
		(layer "B.Cu")
		(net "GB_VDDA")
	)
	(segment
		(start 124.57557 -94.361)
		(end 124.57557 -94.124272)
		(width 0.3048)
		(layer "B.Cu")
		(net "GB_VDDA")
	)
	(segment
		(start 117.13337 -102.616)
		(end 117.13337 -102.566978)
		(width 0.3048)
		(layer "B.Cu")
		(net "GB_VDDA")
	)
	(segment
		(start 128.79197 -104.7115)
		(end 128.09347 -104.7115)
		(width 0.508)
		(layer "B.Cu")
		(net "GB_VDDA")
	)
	(segment
		(start 124.57557 -94.124272)
		(end 124.850144 -93.849698)
		(width 0.3048)
		(layer "B.Cu")
		(net "GB_VDDA")
	)
	(segment
		(start 121.57837 -87.121492)
		(end 121.85015 -86.849712)
		(width 0.3048)
		(layer "B.Cu")
		(net "GB_VDDA")
	)
	(segment
		(start 113.349786 -88.349836)
		(end 112.84966 -87.84971)
		(width 0.4572)
		(layer "F.Cu")
		(net "SYSPLL_VDDA18")
	)
	(via
		(at 88.011 -86.741)
		(size 0.7112)
		(drill 0.3556)
		(layers "F.Cu" "B.Cu")
		(net "SYSPLL_VDDA18")
	)
	(via
		(at 86.995 -86.36)
		(size 0.5588)
		(drill 0.3048)
		(layers "F.Cu" "B.Cu")
		(net "SYSPLL_VDDA18")
	)
	(via
		(at 112.84966 -87.84971)
		(size 0.508)
		(drill 0.254)
		(layers "F.Cu" "B.Cu")
		(net "SYSPLL_VDDA18")
	)
	(segment
		(start 94.13875 -78.359)
		(end 112.268 -78.359)
		(width 0.508)
		(layer "In2.Cu")
		(net "SYSPLL_VDDA18")
	)
	(segment
		(start 89.82075 -82.677)
		(end 94.13875 -78.359)
		(width 0.508)
		(layer "In2.Cu")
		(net "SYSPLL_VDDA18")
	)
	(segment
		(start 86.017354 -85.738462)
		(end 86.017354 -85.17001)
		(width 0.508)
		(layer "In2.Cu")
		(net "SYSPLL_VDDA18")
	)
	(segment
		(start 87.7062 -83.3628)
		(end 87.896192 -83.3628)
		(width 0.508)
		(layer "In2.Cu")
		(net "SYSPLL_VDDA18")
	)
	(segment
		(start 86.038182 -85.149182)
		(end 86.038182 -85.030818)
		(width 0.508)
		(layer "In2.Cu")
		(net "SYSPLL_VDDA18")
	)
	(segment
		(start 86.418928 -86.140036)
		(end 86.017354 -85.738462)
		(width 0.508)
		(layer "In2.Cu")
		(net "SYSPLL_VDDA18")
	)
	(segment
		(start 87.896192 -83.3628)
		(end 88.581992 -82.677)
		(width 0.508)
		(layer "In2.Cu")
		(net "SYSPLL_VDDA18")
	)
	(segment
		(start 86.995 -86.36)
		(end 86.775036 -86.140036)
		(width 0.508)
		(layer "In2.Cu")
		(net "SYSPLL_VDDA18")
	)
	(segment
		(start 88.581992 -82.677)
		(end 89.82075 -82.677)
		(width 0.508)
		(layer "In2.Cu")
		(net "SYSPLL_VDDA18")
	)
	(segment
		(start 86.775036 -86.140036)
		(end 86.418928 -86.140036)
		(width 0.508)
		(layer "In2.Cu")
		(net "SYSPLL_VDDA18")
	)
	(segment
		(start 86.017354 -85.17001)
		(end 86.038182 -85.149182)
		(width 0.508)
		(layer "In2.Cu")
		(net "SYSPLL_VDDA18")
	)
	(segment
		(start 112.268 -78.359)
		(end 113.792 -79.883)
		(width 0.508)
		(layer "In2.Cu")
		(net "SYSPLL_VDDA18")
	)
	(segment
		(start 113.792 -79.883)
		(end 114.173 -79.883)
		(width 0.508)
		(layer "In2.Cu")
		(net "SYSPLL_VDDA18")
	)
	(segment
		(start 86.038182 -85.030818)
		(end 87.7062 -83.3628)
		(width 0.508)
		(layer "In2.Cu")
		(net "SYSPLL_VDDA18")
	)
	(segment
		(start 127.293116 -87.78621)
		(end 127.048768 -87.78621)
		(width 0.1016)
		(layer "F.Cu")
		(net "3X24_SAS_TX16_N")
	)
	(segment
		(start 126.600712 -87.60079)
		(end 126.350014 -87.349838)
		(width 0.1016)
		(layer "F.Cu")
		(net "3X24_SAS_TX16_N")
	)
	(segment
		(start 128.768348 -87.968836)
		(end 127.73406 -87.968836)
		(width 0.1016)
		(layer "F.Cu")
		(net "3X24_SAS_TX16_N")
	)
	(segment
		(start 129.224024 -88.021414)
		(end 128.820926 -88.021414)
		(width 0.1016)
		(layer "F.Cu")
		(net "3X24_SAS_TX16_N")
	)
	(segment
		(start 130.640074 -87.7189)
		(end 129.954782 -87.7189)
		(width 0.1016)
		(layer "F.Cu")
		(net "3X24_SAS_TX16_N")
	)
	(segment
		(start 128.820926 -88.021414)
		(end 128.768348 -87.968836)
		(width 0.1016)
		(layer "F.Cu")
		(net "3X24_SAS_TX16_N")
	)
	(arc
		(start 127.048768 -87.78621)
		(mid 126.806294 -87.738072)
		(end 126.600712 -87.60079)
		(width 0.1016)
		(layer "F.Cu")
		(net "3X24_SAS_TX16_N")
	)
	(arc
		(start 131.0386 -87.884)
		(mid 130.855755 -87.761827)
		(end 130.640074 -87.7189)
		(width 0.1016)
		(layer "F.Cu")
		(net "3X24_SAS_TX16_N")
	)
	(arc
		(start 127.349504 -87.809578)
		(mid 127.323633 -87.792292)
		(end 127.293116 -87.78621)
		(width 0.1016)
		(layer "F.Cu")
		(net "3X24_SAS_TX16_N")
	)
	(arc
		(start 129.954782 -87.7189)
		(mid 129.820352 -87.74564)
		(end 129.70637 -87.82177)
		(width 0.1016)
		(layer "F.Cu")
		(net "3X24_SAS_TX16_N")
	)
	(arc
		(start 127.73406 -87.968836)
		(mid 127.525951 -87.927441)
		(end 127.349504 -87.809578)
		(width 0.1016)
		(layer "F.Cu")
		(net "3X24_SAS_TX16_N")
	)
	(arc
		(start 129.70637 -87.82177)
		(mid 129.485053 -87.969556)
		(end 129.224024 -88.021414)
		(width 0.1016)
		(layer "F.Cu")
		(net "3X24_SAS_TX16_N")
	)
	(segment
		(start 88.22309 -41.352724)
		(end 88.80729 -40.768524)
		(width 0.1016)
		(layer "F.Cu")
		(net "SAS3008_RAID_TX_C_P6")
	)
	(segment
		(start 87.42045 -41.6433)
		(end 87.521542 -41.6433)
		(width 0.1016)
		(layer "F.Cu")
		(net "SAS3008_RAID_TX_C_P6")
	)
	(segment
		(start 89.214452 -40.599868)
		(end 90.750136 -40.599868)
		(width 0.1016)
		(layer "F.Cu")
		(net "SAS3008_RAID_TX_C_P6")
	)
	(arc
		(start 87.521542 -41.6433)
		(mid 87.901226 -41.567794)
		(end 88.22309 -41.352724)
		(width 0.1016)
		(layer "F.Cu")
		(net "SAS3008_RAID_TX_C_P6")
	)
	(arc
		(start 86.77656 -41.91)
		(mid 87.071979 -41.712607)
		(end 87.42045 -41.6433)
		(width 0.1016)
		(layer "F.Cu")
		(net "SAS3008_RAID_TX_C_P6")
	)
	(arc
		(start 88.80729 -40.768524)
		(mid 88.994098 -40.643703)
		(end 89.214452 -40.599868)
		(width 0.1016)
		(layer "F.Cu")
		(net "SAS3008_RAID_TX_C_P6")
	)
	(segment
		(start 119.350028 -93.349826)
		(end 119.350282 -93.349826)
		(width 0.4572)
		(layer "F.Cu")
		(net "GB_VDDH2")
	)
	(segment
		(start 119.350028 -95.350076)
		(end 119.850154 -95.850202)
		(width 0.4572)
		(layer "F.Cu")
		(net "GB_VDDH2")
	)
	(segment
		(start 119.350028 -89.349834)
		(end 119.850154 -88.849708)
		(width 0.4572)
		(layer "F.Cu")
		(net "GB_VDDH2")
	)
	(segment
		(start 119.350028 -96.350074)
		(end 119.850154 -96.8502)
		(width 0.4572)
		(layer "F.Cu")
		(net "GB_VDDH2")
	)
	(segment
		(start 111.34979 -100.350066)
		(end 110.849664 -100.850192)
		(width 0.4572)
		(layer "F.Cu")
		(net "GB_VDDH2")
	)
	(segment
		(start 119.350028 -94.349824)
		(end 119.850154 -93.849698)
		(width 0.4572)
		(layer "F.Cu")
		(net "GB_VDDH2")
	)
	(segment
		(start 114.349784 -100.350066)
		(end 113.849658 -100.850192)
		(width 0.4572)
		(layer "F.Cu")
		(net "GB_VDDH2")
	)
	(segment
		(start 119.350028 -92.349828)
		(end 119.850154 -91.849702)
		(width 0.4572)
		(layer "F.Cu")
		(net "GB_VDDH2")
	)
	(segment
		(start 112.349788 -100.350066)
		(end 111.849662 -100.850192)
		(width 0.4572)
		(layer "F.Cu")
		(net "GB_VDDH2")
	)
	(segment
		(start 115.350036 -100.350066)
		(end 115.850162 -100.850192)
		(width 0.4572)
		(layer "F.Cu")
		(net "GB_VDDH2")
	)
	(segment
		(start 119.350282 -93.349826)
		(end 119.850154 -93.849698)
		(width 0.4572)
		(layer "F.Cu")
		(net "GB_VDDH2")
	)
	(segment
		(start 113.349786 -100.350066)
		(end 112.84966 -100.850192)
		(width 0.4572)
		(layer "F.Cu")
		(net "GB_VDDH2")
	)
	(segment
		(start 119.350028 -90.349832)
		(end 119.850154 -89.849706)
		(width 0.4572)
		(layer "F.Cu")
		(net "GB_VDDH2")
	)
	(segment
		(start 119.350028 -91.34983)
		(end 119.850154 -90.849704)
		(width 0.4572)
		(layer "F.Cu")
		(net "GB_VDDH2")
	)
	(via
		(at 193.421 -109.474)
		(size 0.7112)
		(drill 0.4064)
		(layers "F.Cu" "B.Cu")
		(net "GB_VDDH2")
	)
	(via
		(at 112.84966 -100.850192)
		(size 0.508)
		(drill 0.254)
		(layers "F.Cu" "B.Cu")
		(net "GB_VDDH2")
	)
	(via
		(at 190.881 -109.474)
		(size 0.7112)
		(drill 0.4064)
		(layers "F.Cu" "B.Cu")
		(net "GB_VDDH2")
	)
	(via
		(at 194.31 -89.281)
		(size 0.7112)
		(drill 0.3556)
		(layers "F.Cu" "B.Cu")
		(net "GB_VDDH2")
	)
	(via
		(at 119.850154 -91.849702)
		(size 0.508)
		(drill 0.254)
		(layers "F.Cu" "B.Cu")
		(net "GB_VDDH2")
	)
	(via
		(at 194.564 -109.474)
		(size 0.7112)
		(drill 0.4064)
		(layers "F.Cu" "B.Cu")
		(net "GB_VDDH2")
	)
	(via
		(at 110.849664 -100.850192)
		(size 0.508)
		(drill 0.254)
		(layers "F.Cu" "B.Cu")
		(net "GB_VDDH2")
	)
	(via
		(at 119.850154 -95.850202)
		(size 0.508)
		(drill 0.254)
		(layers "F.Cu" "B.Cu")
		(net "GB_VDDH2")
	)
	(via
		(at 115.850162 -100.850192)
		(size 0.508)
		(drill 0.254)
		(layers "F.Cu" "B.Cu")
		(net "GB_VDDH2")
	)
	(via
		(at 196.342 -86.233)
		(size 0.7112)
		(drill 0.4064)
		(layers "F.Cu" "B.Cu")
		(net "GB_VDDH2")
	)
	(via
		(at 192.278 -110.617)
		(size 0.7112)
		(drill 0.4064)
		(layers "F.Cu" "B.Cu")
		(net "GB_VDDH2")
	)
	(via
		(at 192.151 -109.474)
		(size 0.7112)
		(drill 0.4064)
		(layers "F.Cu" "B.Cu")
		(net "GB_VDDH2")
	)
	(via
		(at 119.850154 -89.849706)
		(size 0.508)
		(drill 0.254)
		(layers "F.Cu" "B.Cu")
		(net "GB_VDDH2")
	)
	(via
		(at 197.485 -86.233)
		(size 0.7112)
		(drill 0.4064)
		(layers "F.Cu" "B.Cu")
		(net "GB_VDDH2")
	)
	(via
		(at 119.850154 -93.849698)
		(size 0.508)
		(drill 0.254)
		(layers "F.Cu" "B.Cu")
		(net "GB_VDDH2")
	)
	(via
		(at 193.4464 -110.6424)
		(size 0.7112)
		(drill 0.4064)
		(layers "F.Cu" "B.Cu")
		(net "GB_VDDH2")
	)
	(via
		(at 191.0334 -110.6424)
		(size 0.7112)
		(drill 0.4064)
		(layers "F.Cu" "B.Cu")
		(net "GB_VDDH2")
	)
	(via
		(at 119.850154 -90.849704)
		(size 0.508)
		(drill 0.254)
		(layers "F.Cu" "B.Cu")
		(net "GB_VDDH2")
	)
	(via
		(at 198.7296 -86.2076)
		(size 0.7112)
		(drill 0.4064)
		(layers "F.Cu" "B.Cu")
		(net "GB_VDDH2")
	)
	(via
		(at 111.849662 -100.850192)
		(size 0.508)
		(drill 0.254)
		(layers "F.Cu" "B.Cu")
		(net "GB_VDDH2")
	)
	(via
		(at 113.849658 -100.850192)
		(size 0.508)
		(drill 0.254)
		(layers "F.Cu" "B.Cu")
		(net "GB_VDDH2")
	)
	(via
		(at 119.850154 -96.8502)
		(size 0.508)
		(drill 0.254)
		(layers "F.Cu" "B.Cu")
		(net "GB_VDDH2")
	)
	(via
		(at 119.850154 -88.849708)
		(size 0.508)
		(drill 0.254)
		(layers "F.Cu" "B.Cu")
		(net "GB_VDDH2")
	)
	(segment
		(start 114.64417 -100.33)
		(end 114.36985 -100.33)
		(width 0.3048)
		(layer "B.Cu")
		(net "GB_VDDH2")
	)
	(segment
		(start 120.02897 -95.671386)
		(end 119.850154 -95.850202)
		(width 0.3048)
		(layer "B.Cu")
		(net "GB_VDDH2")
	)
	(segment
		(start 120.02897 -94.028514)
		(end 119.850154 -93.849698)
		(width 0.3048)
		(layer "B.Cu")
		(net "GB_VDDH2")
	)
	(segment
		(start 120.02897 -88.670892)
		(end 119.850154 -88.849708)
		(width 0.3556)
		(layer "B.Cu")
		(net "GB_VDDH2")
	)
	(segment
		(start 120.11406 -89.5858)
		(end 119.850154 -89.849706)
		(width 0.3556)
		(layer "B.Cu")
		(net "GB_VDDH2")
	)
	(segment
		(start 120.02897 -95.1992)
		(end 120.02897 -95.671386)
		(width 0.3048)
		(layer "B.Cu")
		(net "GB_VDDH2")
	)
	(segment
		(start 120.02897 -94.615)
		(end 120.02897 -94.028514)
		(width 0.3048)
		(layer "B.Cu")
		(net "GB_VDDH2")
	)
	(segment
		(start 120.02897 -97.029016)
		(end 119.850154 -96.8502)
		(width 0.3048)
		(layer "B.Cu")
		(net "GB_VDDH2")
	)
	(segment
		(start 120.02897 -88.2142)
		(end 120.02897 -88.670892)
		(width 0.3556)
		(layer "B.Cu")
		(net "GB_VDDH2")
	)
	(segment
		(start 120.86717 -89.5858)
		(end 120.11406 -89.5858)
		(width 0.3556)
		(layer "B.Cu")
		(net "GB_VDDH2")
	)
	(segment
		(start 114.61877 -101.1174)
		(end 114.116866 -101.1174)
		(width 0.3048)
		(layer "B.Cu")
		(net "GB_VDDH2")
	)
	(segment
		(start 114.36985 -100.33)
		(end 113.849658 -100.850192)
		(width 0.3048)
		(layer "B.Cu")
		(net "GB_VDDH2")
	)
	(segment
		(start 112.84077 -100.841302)
		(end 112.84966 -100.850192)
		(width 0.3048)
		(layer "B.Cu")
		(net "GB_VDDH2")
	)
	(segment
		(start 120.10517 -92.6846)
		(end 120.10517 -92.104718)
		(width 0.3048)
		(layer "B.Cu")
		(net "GB_VDDH2")
	)
	(segment
		(start 120.10517 -92.104718)
		(end 119.850154 -91.849702)
		(width 0.3048)
		(layer "B.Cu")
		(net "GB_VDDH2")
	)
	(segment
		(start 110.83417 -100.1268)
		(end 110.83417 -100.834698)
		(width 0.3556)
		(layer "B.Cu")
		(net "GB_VDDH2")
	)
	(segment
		(start 112.84077 -100.2284)
		(end 112.84077 -100.841302)
		(width 0.3048)
		(layer "B.Cu")
		(net "GB_VDDH2")
	)
	(segment
		(start 114.116866 -101.1174)
		(end 113.849658 -100.850192)
		(width 0.3048)
		(layer "B.Cu")
		(net "GB_VDDH2")
	)
	(segment
		(start 110.83417 -100.834698)
		(end 110.849664 -100.850192)
		(width 0.3556)
		(layer "B.Cu")
		(net "GB_VDDH2")
	)
	(segment
		(start 120.02897 -97.4852)
		(end 120.02897 -97.029016)
		(width 0.3048)
		(layer "B.Cu")
		(net "GB_VDDH2")
	)
	(segment
		(start 115.582954 -101.1174)
		(end 115.850162 -100.850192)
		(width 0.3048)
		(layer "B.Cu")
		(net "GB_VDDH2")
	)
	(segment
		(start 115.17757 -101.1174)
		(end 115.582954 -101.1174)
		(width 0.3048)
		(layer "B.Cu")
		(net "GB_VDDH2")
	)
	(segment
		(start 117.221 -39.878)
		(end 118.481856 -38.617144)
		(width 0.1143)
		(layer "F.Cu")
		(net "IOC_SCL_4")
	)
	(segment
		(start 202.6793 -42.364914)
		(end 202.057 -41.742614)
		(width 0.1143)
		(layer "F.Cu")
		(net "IOC_SCL_4")
	)
	(segment
		(start 165.779196 -148.045932)
		(end 169.762932 -148.045932)
		(width 0.1143)
		(layer "F.Cu")
		(net "IOC_SCL_4")
	)
	(segment
		(start 220.791532 -61.8744)
		(end 202.6793 -43.762168)
		(width 0.1143)
		(layer "F.Cu")
		(net "IOC_SCL_4")
	)
	(segment
		(start 114.092228 -41.742868)
		(end 114.219736 -41.61536)
		(width 0.1143)
		(layer "F.Cu")
		(net "IOC_SCL_4")
	)
	(segment
		(start 255.5621 -94.587568)
		(end 222.848932 -61.8744)
		(width 0.1143)
		(layer "F.Cu")
		(net "IOC_SCL_4")
	)
	(segment
		(start 260.858 -101.283262)
		(end 255.5621 -95.987362)
		(width 0.1143)
		(layer "F.Cu")
		(net "IOC_SCL_4")
	)
	(segment
		(start 255.5621 -95.987362)
		(end 255.5621 -94.587568)
		(width 0.1143)
		(layer "F.Cu")
		(net "IOC_SCL_4")
	)
	(segment
		(start 114.219736 -41.61536)
		(end 115.348258 -41.61536)
		(width 0.1143)
		(layer "F.Cu")
		(net "IOC_SCL_4")
	)
	(segment
		(start 118.481856 -38.617144)
		(end 118.481856 -38.354)
		(width 0.1143)
		(layer "F.Cu")
		(net "IOC_SCL_4")
	)
	(segment
		(start 169.762932 -148.045932)
		(end 169.926 -147.882864)
		(width 0.1143)
		(layer "F.Cu")
		(net "IOC_SCL_4")
	)
	(segment
		(start 169.926 -147.882864)
		(end 169.926 -147.066)
		(width 0.1143)
		(layer "F.Cu")
		(net "IOC_SCL_4")
	)
	(segment
		(start 117.085618 -39.878)
		(end 117.221 -39.878)
		(width 0.1143)
		(layer "F.Cu")
		(net "IOC_SCL_4")
	)
	(segment
		(start 113.150142 -42.199814)
		(end 113.258346 -42.199814)
		(width 0.1143)
		(layer "F.Cu")
		(net "IOC_SCL_4")
	)
	(segment
		(start 115.348258 -41.61536)
		(end 117.085618 -39.878)
		(width 0.1143)
		(layer "F.Cu")
		(net "IOC_SCL_4")
	)
	(segment
		(start 262.0518 -123.105672)
		(end 260.858 -121.911872)
		(width 0.1143)
		(layer "F.Cu")
		(net "IOC_SCL_4")
	)
	(segment
		(start 113.258346 -42.199814)
		(end 113.715292 -41.742868)
		(width 0.1143)
		(layer "F.Cu")
		(net "IOC_SCL_4")
	)
	(segment
		(start 260.858 -121.911872)
		(end 260.858 -101.283262)
		(width 0.1143)
		(layer "F.Cu")
		(net "IOC_SCL_4")
	)
	(segment
		(start 264.16 -147.066)
		(end 262.0518 -144.9578)
		(width 0.1143)
		(layer "F.Cu")
		(net "IOC_SCL_4")
	)
	(segment
		(start 202.6793 -43.762168)
		(end 202.6793 -42.364914)
		(width 0.1143)
		(layer "F.Cu")
		(net "IOC_SCL_4")
	)
	(segment
		(start 222.848932 -61.8744)
		(end 220.791532 -61.8744)
		(width 0.1143)
		(layer "F.Cu")
		(net "IOC_SCL_4")
	)
	(segment
		(start 202.057 -41.742614)
		(end 202.057 -41.505632)
		(width 0.1143)
		(layer "F.Cu")
		(net "IOC_SCL_4")
	)
	(segment
		(start 113.715292 -41.742868)
		(end 114.092228 -41.742868)
		(width 0.1143)
		(layer "F.Cu")
		(net "IOC_SCL_4")
	)
	(segment
		(start 262.0518 -144.9578)
		(end 262.0518 -123.105672)
		(width 0.1143)
		(layer "F.Cu")
		(net "IOC_SCL_4")
	)
	(via
		(at 118.481856 -38.354)
		(size 0.508)
		(drill 0.254)
		(layers "F.Cu" "B.Cu")
		(net "IOC_SCL_4")
	)
	(via
		(at 202.057 -41.505632)
		(size 0.5588)
		(drill 0.3048)
		(layers "F.Cu" "B.Cu")
		(net "IOC_SCL_4")
	)
	(via
		(at 264.16 -147.066)
		(size 0.5588)
		(drill 0.3048)
		(layers "F.Cu" "B.Cu")
		(net "IOC_SCL_4")
	)
	(via
		(at 117.221 -39.878)
		(size 0.7112)
		(drill 0.3556)
		(layers "F.Cu" "B.Cu")
		(net "IOC_SCL_4")
	)
	(via
		(at 169.926 -147.066)
		(size 0.5588)
		(drill 0.3048)
		(layers "F.Cu" "B.Cu")
		(net "IOC_SCL_4")
	)
	(segment
		(start 118.481856 -37.474144)
		(end 118.481856 -38.354)
		(width 0.1143)
		(layer "B.Cu")
		(net "IOC_SCL_4")
	)
	(segment
		(start 119.253 -36.703)
		(end 118.481856 -37.474144)
		(width 0.1143)
		(layer "B.Cu")
		(net "IOC_SCL_4")
	)
	(segment
		(start 119.5705 -36.703)
		(end 119.253 -36.703)
		(width 0.1143)
		(layer "B.Cu")
		(net "IOC_SCL_4")
	)
	(segment
		(start 184.99455 -146.236182)
		(end 185.180732 -146.05)
		(width 0.127)
		(layer "In2.Cu")
		(net "IOC_SCL_4")
	)
	(segment
		(start 178.852068 -146.558)
		(end 178.991768 -146.6977)
		(width 0.127)
		(layer "In2.Cu")
		(net "IOC_SCL_4")
	)
	(segment
		(start 185.180732 -146.05)
		(end 189.611 -146.05)
		(width 0.127)
		(layer "In2.Cu")
		(net "IOC_SCL_4")
	)
	(segment
		(start 179.402232 -146.6977)
		(end 179.86375 -146.236182)
		(width 0.127)
		(layer "In2.Cu")
		(net "IOC_SCL_4")
	)
	(segment
		(start 206.121 -147.066)
		(end 264.16 -147.066)
		(width 0.127)
		(layer "In2.Cu")
		(net "IOC_SCL_4")
	)
	(segment
		(start 205.450948 -147.736052)
		(end 206.121 -147.066)
		(width 0.127)
		(layer "In2.Cu")
		(net "IOC_SCL_4")
	)
	(segment
		(start 179.86375 -146.236182)
		(end 184.99455 -146.236182)
		(width 0.127)
		(layer "In2.Cu")
		(net "IOC_SCL_4")
	)
	(segment
		(start 169.926 -147.066)
		(end 170.434 -146.558)
		(width 0.127)
		(layer "In2.Cu")
		(net "IOC_SCL_4")
	)
	(segment
		(start 178.991768 -146.6977)
		(end 179.402232 -146.6977)
		(width 0.127)
		(layer "In2.Cu")
		(net "IOC_SCL_4")
	)
	(segment
		(start 170.434 -146.558)
		(end 178.852068 -146.558)
		(width 0.127)
		(layer "In2.Cu")
		(net "IOC_SCL_4")
	)
	(segment
		(start 189.611 -146.05)
		(end 191.297052 -147.736052)
		(width 0.127)
		(layer "In2.Cu")
		(net "IOC_SCL_4")
	)
	(segment
		(start 191.297052 -147.736052)
		(end 205.450948 -147.736052)
		(width 0.127)
		(layer "In2.Cu")
		(net "IOC_SCL_4")
	)
	(segment
		(start 118.535704 -38.407848)
		(end 118.481856 -38.354)
		(width 0.127)
		(layer "In5.Cu")
		(net "IOC_SCL_4")
	)
	(segment
		(start 202.057 -41.505632)
		(end 132.103368 -41.505632)
		(width 0.127)
		(layer "In5.Cu")
		(net "IOC_SCL_4")
	)
	(segment
		(start 118.535704 -39.208456)
		(end 118.535704 -38.407848)
		(width 0.127)
		(layer "In5.Cu")
		(net "IOC_SCL_4")
	)
	(segment
		(start 121.618248 -42.291)
		(end 118.535704 -39.208456)
		(width 0.127)
		(layer "In5.Cu")
		(net "IOC_SCL_4")
	)
	(segment
		(start 132.103368 -41.505632)
		(end 131.318 -42.291)
		(width 0.127)
		(layer "In5.Cu")
		(net "IOC_SCL_4")
	)
	(segment
		(start 131.318 -42.291)
		(end 121.618248 -42.291)
		(width 0.127)
		(layer "In5.Cu")
		(net "IOC_SCL_4")
	)
	(segment
		(start 95.9485 -35.54349)
		(end 95.9485 -35.4076)
		(width 0.1397)
		(layer "F.Cu")
		(net "PCIE_SAS_C_CPU_RX_P1")
	)
	(segment
		(start 96.350074 -35.80003)
		(end 96.173544 -35.80003)
		(width 0.1397)
		(layer "F.Cu")
		(net "PCIE_SAS_C_CPU_RX_P1")
	)
	(segment
		(start 96.083882 -35.762946)
		(end 96.007936 -35.687)
		(width 0.1397)
		(layer "F.Cu")
		(net "PCIE_SAS_C_CPU_RX_P1")
	)
	(via
		(at 95.9485 -35.4076)
		(size 0.508)
		(drill 0.254)
		(layers "F.Cu" "B.Cu")
		(net "PCIE_SAS_C_CPU_RX_P1")
	)
	(arc
		(start 96.007936 -35.687)
		(mid 95.963941 -35.621157)
		(end 95.9485 -35.54349)
		(width 0.1397)
		(layer "F.Cu")
		(net "PCIE_SAS_C_CPU_RX_P1")
	)
	(arc
		(start 96.173544 -35.80003)
		(mid 96.125026 -35.790397)
		(end 96.083882 -35.762946)
		(width 0.1397)
		(layer "F.Cu")
		(net "PCIE_SAS_C_CPU_RX_P1")
	)
	(segment
		(start 96.057974 -34.223452)
		(end 96.057974 -34.976816)
		(width 0.1016)
		(layer "B.Cu")
		(net "PCIE_SAS_C_CPU_RX_P1")
	)
	(segment
		(start 95.521018 -33.17621)
		(end 95.89008 -33.545018)
		(width 0.1397)
		(layer "B.Cu")
		(net "PCIE_SAS_C_CPU_RX_P1")
	)
	(segment
		(start 95.463614 -33.118806)
		(end 95.521018 -33.17621)
		(width 0.1397)
		(layer "B.Cu")
		(net "PCIE_SAS_C_CPU_RX_P1")
	)
	(segment
		(start 96.038924 -34.204402)
		(end 96.057974 -34.223452)
		(width 0.1016)
		(layer "B.Cu")
		(net "PCIE_SAS_C_CPU_RX_P1")
	)
	(segment
		(start 96.057974 -34.976816)
		(end 96.057974 -35.143186)
		(width 0.0889)
		(layer "B.Cu")
		(net "PCIE_SAS_C_CPU_RX_P1")
	)
	(segment
		(start 96.038924 -33.904428)
		(end 96.038924 -34.204402)
		(width 0.1016)
		(layer "B.Cu")
		(net "PCIE_SAS_C_CPU_RX_P1")
	)
	(segment
		(start 95.325946 -32.981392)
		(end 95.463614 -33.118806)
		(width 0.1397)
		(layer "B.Cu")
		(net "PCIE_SAS_C_CPU_RX_P1")
	)
	(arc
		(start 96.014794 -33.749742)
		(mid 96.032842 -33.826151)
		(end 96.038924 -33.904428)
		(width 0.1016)
		(layer "B.Cu")
		(net "PCIE_SAS_C_CPU_RX_P1")
	)
	(arc
		(start 95.89008 -33.545018)
		(mid 95.964701 -33.639912)
		(end 96.014794 -33.749742)
		(width 0.1016)
		(layer "B.Cu")
		(net "PCIE_SAS_C_CPU_RX_P1")
	)
	(arc
		(start 96.026986 -35.291522)
		(mid 95.993237 -35.353277)
		(end 95.9485 -35.4076)
		(width 0.0889)
		(layer "B.Cu")
		(net "PCIE_SAS_C_CPU_RX_P1")
	)
	(arc
		(start 94.87916 -31.9024)
		(mid 94.99522 -32.486344)
		(end 95.325946 -32.981392)
		(width 0.1397)
		(layer "B.Cu")
		(net "PCIE_SAS_C_CPU_RX_P1")
	)
	(arc
		(start 96.057974 -35.143186)
		(mid 96.050057 -35.218935)
		(end 96.026986 -35.291522)
		(width 0.0889)
		(layer "B.Cu")
		(net "PCIE_SAS_C_CPU_RX_P1")
	)
	(segment
		(start 90.910156 -40.256968)
		(end 90.92819 -40.256968)
		(width 0.1016)
		(layer "F.Cu")
		(net "SAS3008_RAID_TX_C_N6")
	)
	(segment
		(start 86.837774 -41.3004)
		(end 87.521288 -41.3004)
		(width 0.1016)
		(layer "F.Cu")
		(net "SAS3008_RAID_TX_C_N6")
	)
	(segment
		(start 87.98052 -41.110154)
		(end 88.56472 -40.525954)
		(width 0.1016)
		(layer "F.Cu")
		(net "SAS3008_RAID_TX_C_N6")
	)
	(segment
		(start 90.602816 -40.244268)
		(end 90.897456 -40.244268)
		(width 0.1016)
		(layer "F.Cu")
		(net "SAS3008_RAID_TX_C_N6")
	)
	(segment
		(start 91.40444 -40.454072)
		(end 91.549982 -40.599868)
		(width 0.1016)
		(layer "F.Cu")
		(net "SAS3008_RAID_TX_C_N6")
	)
	(segment
		(start 90.897456 -40.244268)
		(end 90.910156 -40.256968)
		(width 0.1016)
		(layer "F.Cu")
		(net "SAS3008_RAID_TX_C_N6")
	)
	(segment
		(start 90.590116 -40.256968)
		(end 90.602816 -40.244268)
		(width 0.1016)
		(layer "F.Cu")
		(net "SAS3008_RAID_TX_C_N6")
	)
	(segment
		(start 89.214198 -40.256968)
		(end 90.590116 -40.256968)
		(width 0.1016)
		(layer "F.Cu")
		(net "SAS3008_RAID_TX_C_N6")
	)
	(arc
		(start 87.521288 -41.3004)
		(mid 87.769832 -41.250961)
		(end 87.98052 -41.110154)
		(width 0.1016)
		(layer "F.Cu")
		(net "SAS3008_RAID_TX_C_N6")
	)
	(arc
		(start 90.92819 -40.256968)
		(mid 90.961632 -40.257786)
		(end 90.994992 -40.26027)
		(width 0.1016)
		(layer "F.Cu")
		(net "SAS3008_RAID_TX_C_N6")
	)
	(arc
		(start 86.77656 -41.275)
		(mid 86.804645 -41.293766)
		(end 86.837774 -41.3004)
		(width 0.1016)
		(layer "F.Cu")
		(net "SAS3008_RAID_TX_C_N6")
	)
	(arc
		(start 90.994992 -40.26027)
		(mid 91.216505 -40.321701)
		(end 91.40444 -40.454072)
		(width 0.1016)
		(layer "F.Cu")
		(net "SAS3008_RAID_TX_C_N6")
	)
	(arc
		(start 88.56472 -40.525954)
		(mid 88.862717 -40.326902)
		(end 89.214198 -40.256968)
		(width 0.1016)
		(layer "F.Cu")
		(net "SAS3008_RAID_TX_C_N6")
	)
	(segment
		(start 114.257836 -88.349836)
		(end 113.792 -87.884)
		(width 0.381)
		(layer "F.Cu")
		(net "PLLDDR_VDDA18")
	)
	(segment
		(start 114.349784 -88.349836)
		(end 114.257836 -88.349836)
		(width 0.381)
		(layer "F.Cu")
		(net "PLLDDR_VDDA18")
	)
	(via
		(at 86.976966 -83.185)
		(size 0.7112)
		(drill 0.3556)
		(layers "F.Cu" "B.Cu")
		(net "PLLDDR_VDDA18")
	)
	(via
		(at 113.792 -87.884)
		(size 0.508)
		(drill 0.254)
		(layers "F.Cu" "B.Cu")
		(net "PLLDDR_VDDA18")
	)
	(via
		(at 87.611966 -82.677)
		(size 0.5588)
		(drill 0.3048)
		(layers "F.Cu" "B.Cu")
		(net "PLLDDR_VDDA18")
	)
	(segment
		(start 120.350026 -84.349844)
		(end 120.850152 -83.849718)
		(width 0.4572)
		(layer "F.Cu")
		(net "XTAL_VDDA18")
	)
	(via
		(at 120.850152 -83.849718)
		(size 0.508)
		(drill 0.254)
		(layers "F.Cu" "B.Cu")
		(net "XTAL_VDDA18")
	)
	(via
		(at 120.893078 -81.924398)
		(size 0.7112)
		(drill 0.3556)
		(layers "F.Cu" "B.Cu")
		(net "XTAL_VDDA18")
	)
	(via
		(at 121.0818 -77.1652)
		(size 0.7112)
		(drill 0.3556)
		(layers "F.Cu" "B.Cu")
		(net "XTAL_VDDA18")
	)
	(segment
		(start 112.350042 -44.59986)
		(end 112.354106 -44.59986)
		(width 0.1143)
		(layer "F.Cu")
		(net "IOC_CLK_SEL1")
	)
	(segment
		(start 112.354106 -44.59986)
		(end 112.747298 -44.993052)
		(width 0.1143)
		(layer "F.Cu")
		(net "IOC_CLK_SEL1")
	)
	(via
		(at 112.747298 -44.993052)
		(size 0.508)
		(drill 0.254)
		(layers "F.Cu" "B.Cu")
		(net "IOC_CLK_SEL1")
	)
	(via
		(at 112.376966 -43.561)
		(size 0.7112)
		(drill 0.3556)
		(layers "F.Cu" "B.Cu")
		(net "IOC_CLK_SEL1")
	)
	(segment
		(start 113.421414 -44.993052)
		(end 112.747298 -44.993052)
		(width 0.1143)
		(layer "B.Cu")
		(net "IOC_CLK_SEL1")
	)
	(segment
		(start 113.837466 -44.577)
		(end 113.837466 -43.561)
		(width 0.1143)
		(layer "B.Cu")
		(net "IOC_CLK_SEL1")
	)
	(segment
		(start 113.837466 -43.561)
		(end 112.376966 -43.561)
		(width 0.1143)
		(layer "B.Cu")
		(net "IOC_CLK_SEL1")
	)
	(segment
		(start 113.837466 -44.577)
		(end 113.421414 -44.993052)
		(width 0.1143)
		(layer "B.Cu")
		(net "IOC_CLK_SEL1")
	)
	(segment
		(start 98.762566 -83.394042)
		(end 98.590608 -83.566)
		(width 0.1143)
		(layer "F.Cu")
		(net "EXP_CLK_SEL1")
	)
	(segment
		(start 96.634046 -82.850482)
		(end 96.908874 -82.850482)
		(width 0.1143)
		(layer "F.Cu")
		(net "EXP_CLK_SEL1")
	)
	(segment
		(start 96.908874 -82.850482)
		(end 97.57664 -83.518248)
		(width 0.1143)
		(layer "F.Cu")
		(net "EXP_CLK_SEL1")
	)
	(segment
		(start 96.34347 -83.947)
		(end 96.34347 -82.804)
		(width 0.1143)
		(layer "F.Cu")
		(net "EXP_CLK_SEL1")
	)
	(segment
		(start 106.3498 -87.349838)
		(end 105.849674 -86.849712)
		(width 0.1143)
		(layer "F.Cu")
		(net "EXP_CLK_SEL1")
	)
	(segment
		(start 97.624392 -83.566)
		(end 97.57664 -83.518248)
		(width 0.1143)
		(layer "F.Cu")
		(net "EXP_CLK_SEL1")
	)
	(segment
		(start 98.590608 -83.566)
		(end 97.624392 -83.566)
		(width 0.1143)
		(layer "F.Cu")
		(net "EXP_CLK_SEL1")
	)
	(segment
		(start 96.587564 -82.804)
		(end 96.634046 -82.850482)
		(width 0.1143)
		(layer "F.Cu")
		(net "EXP_CLK_SEL1")
	)
	(segment
		(start 96.34347 -82.804)
		(end 96.587564 -82.804)
		(width 0.1143)
		(layer "F.Cu")
		(net "EXP_CLK_SEL1")
	)
	(via
		(at 105.849674 -86.849712)
		(size 0.508)
		(drill 0.254)
		(layers "F.Cu" "B.Cu")
		(net "EXP_CLK_SEL1")
	)
	(via
		(at 98.762566 -83.394042)
		(size 0.7112)
		(drill 0.3556)
		(layers "F.Cu" "B.Cu")
		(net "EXP_CLK_SEL1")
	)
	(via
		(at 97.57664 -83.518248)
		(size 0.508)
		(drill 0.254)
		(layers "F.Cu" "B.Cu")
		(net "EXP_CLK_SEL1")
	)
	(segment
		(start 102.887018 -84.294218)
		(end 102.66553 -84.294218)
		(width 0.127)
		(layer "In2.Cu")
		(net "EXP_CLK_SEL1")
	)
	(segment
		(start 105.659682 -86.849712)
		(end 105.215182 -86.405212)
		(width 0.127)
		(layer "In2.Cu")
		(net "EXP_CLK_SEL1")
	)
	(segment
		(start 102.66553 -84.294218)
		(end 101.848412 -83.4771)
		(width 0.127)
		(layer "In2.Cu")
		(net "EXP_CLK_SEL1")
	)
	(segment
		(start 99.20097 -83.6803)
		(end 97.738692 -83.6803)
		(width 0.127)
		(layer "In2.Cu")
		(net "EXP_CLK_SEL1")
	)
	(segment
		(start 105.215182 -86.405212)
		(end 104.812338 -86.405212)
		(width 0.127)
		(layer "In2.Cu")
		(net "EXP_CLK_SEL1")
	)
	(segment
		(start 105.849674 -86.849712)
		(end 105.659682 -86.849712)
		(width 0.127)
		(layer "In2.Cu")
		(net "EXP_CLK_SEL1")
	)
	(segment
		(start 104.812338 -86.405212)
		(end 103.29418 -84.887054)
		(width 0.127)
		(layer "In2.Cu")
		(net "EXP_CLK_SEL1")
	)
	(segment
		(start 99.40417 -83.4771)
		(end 99.20097 -83.6803)
		(width 0.127)
		(layer "In2.Cu")
		(net "EXP_CLK_SEL1")
	)
	(segment
		(start 97.738692 -83.6803)
		(end 97.57664 -83.518248)
		(width 0.127)
		(layer "In2.Cu")
		(net "EXP_CLK_SEL1")
	)
	(segment
		(start 103.29418 -84.887054)
		(end 103.29418 -84.70138)
		(width 0.127)
		(layer "In2.Cu")
		(net "EXP_CLK_SEL1")
	)
	(segment
		(start 101.848412 -83.4771)
		(end 99.40417 -83.4771)
		(width 0.127)
		(layer "In2.Cu")
		(net "EXP_CLK_SEL1")
	)
	(segment
		(start 103.29418 -84.70138)
		(end 102.887018 -84.294218)
		(width 0.127)
		(layer "In2.Cu")
		(net "EXP_CLK_SEL1")
	)
	(segment
		(start 222.6564 -62.3824)
		(end 255.0668 -94.7928)
		(width 0.1143)
		(layer "F.Cu")
		(net "IOC_SDA_4")
	)
	(segment
		(start 255.0668 -96.192594)
		(end 260.3627 -101.488494)
		(width 0.1143)
		(layer "F.Cu")
		(net "IOC_SDA_4")
	)
	(segment
		(start 112.350042 -45.406056)
		(end 112.745266 -45.80128)
		(width 0.1143)
		(layer "F.Cu")
		(net "IOC_SDA_4")
	)
	(segment
		(start 260.3627 -122.117104)
		(end 261.5565 -123.310904)
		(width 0.1143)
		(layer "F.Cu")
		(net "IOC_SDA_4")
	)
	(segment
		(start 112.350042 -45.39996)
		(end 112.350042 -45.406056)
		(width 0.1143)
		(layer "F.Cu")
		(net "IOC_SDA_4")
	)
	(segment
		(start 202.184 -44.0182)
		(end 220.5482 -62.3824)
		(width 0.1143)
		(layer "F.Cu")
		(net "IOC_SDA_4")
	)
	(segment
		(start 202.184 -42.5704)
		(end 202.184 -44.0182)
		(width 0.1143)
		(layer "F.Cu")
		(net "IOC_SDA_4")
	)
	(segment
		(start 255.0668 -94.7928)
		(end 255.0668 -96.192594)
		(width 0.1143)
		(layer "F.Cu")
		(net "IOC_SDA_4")
	)
	(segment
		(start 260.3627 -101.488494)
		(end 260.3627 -122.117104)
		(width 0.1143)
		(layer "F.Cu")
		(net "IOC_SDA_4")
	)
	(segment
		(start 220.5482 -62.3824)
		(end 222.6564 -62.3824)
		(width 0.1143)
		(layer "F.Cu")
		(net "IOC_SDA_4")
	)
	(segment
		(start 170.0022 -148.696172)
		(end 171.0182 -147.680172)
		(width 0.1143)
		(layer "F.Cu")
		(net "IOC_SDA_4")
	)
	(segment
		(start 262.1534 -146.5834)
		(end 263.271 -147.701)
		(width 0.1143)
		(layer "F.Cu")
		(net "IOC_SDA_4")
	)
	(segment
		(start 165.779196 -148.696172)
		(end 170.0022 -148.696172)
		(width 0.1143)
		(layer "F.Cu")
		(net "IOC_SDA_4")
	)
	(segment
		(start 171.0182 -147.680172)
		(end 171.0182 -147.066)
		(width 0.1143)
		(layer "F.Cu")
		(net "IOC_SDA_4")
	)
	(segment
		(start 261.5565 -145.9865)
		(end 262.1534 -146.5834)
		(width 0.1143)
		(layer "F.Cu")
		(net "IOC_SDA_4")
	)
	(segment
		(start 261.5565 -123.310904)
		(end 261.5565 -145.9865)
		(width 0.1143)
		(layer "F.Cu")
		(net "IOC_SDA_4")
	)
	(via
		(at 262.1534 -146.5834)
		(size 0.7112)
		(drill 0.3556)
		(layers "F.Cu" "B.Cu")
		(net "IOC_SDA_4")
	)
	(via
		(at 171.0182 -147.066)
		(size 0.5588)
		(drill 0.3048)
		(layers "F.Cu" "B.Cu")
		(net "IOC_SDA_4")
	)
	(via
		(at 263.271 -147.701)
		(size 0.5588)
		(drill 0.3048)
		(layers "F.Cu" "B.Cu")
		(net "IOC_SDA_4")
	)
	(via
		(at 202.184 -42.5704)
		(size 0.5588)
		(drill 0.3048)
		(layers "F.Cu" "B.Cu")
		(net "IOC_SDA_4")
	)
	(via
		(at 112.745266 -45.80128)
		(size 0.508)
		(drill 0.254)
		(layers "F.Cu" "B.Cu")
		(net "IOC_SDA_4")
	)
	(segment
		(start 113.837466 -45.72)
		(end 113.756186 -45.80128)
		(width 0.1143)
		(layer "B.Cu")
		(net "IOC_SDA_4")
	)
	(segment
		(start 113.756186 -45.80128)
		(end 112.745266 -45.80128)
		(width 0.1143)
		(layer "B.Cu")
		(net "IOC_SDA_4")
	)
	(segment
		(start 180.074316 -146.744182)
		(end 185.205116 -146.744182)
		(width 0.127)
		(layer "In2.Cu")
		(net "IOC_SDA_4")
	)
	(segment
		(start 190.154052 -148.244052)
		(end 205.958948 -148.244052)
		(width 0.127)
		(layer "In2.Cu")
		(net "IOC_SDA_4")
	)
	(segment
		(start 179.612798 -147.2057)
		(end 180.074316 -146.744182)
		(width 0.127)
		(layer "In2.Cu")
		(net "IOC_SDA_4")
	)
	(segment
		(start 185.205116 -146.744182)
		(end 185.391298 -146.558)
		(width 0.127)
		(layer "In2.Cu")
		(net "IOC_SDA_4")
	)
	(segment
		(start 178.781202 -147.2057)
		(end 179.612798 -147.2057)
		(width 0.127)
		(layer "In2.Cu")
		(net "IOC_SDA_4")
	)
	(segment
		(start 185.391298 -146.558)
		(end 188.468 -146.558)
		(width 0.127)
		(layer "In2.Cu")
		(net "IOC_SDA_4")
	)
	(segment
		(start 178.641502 -147.066)
		(end 178.781202 -147.2057)
		(width 0.127)
		(layer "In2.Cu")
		(net "IOC_SDA_4")
	)
	(segment
		(start 188.468 -146.558)
		(end 190.154052 -148.244052)
		(width 0.127)
		(layer "In2.Cu")
		(net "IOC_SDA_4")
	)
	(segment
		(start 206.502 -147.701)
		(end 263.271 -147.701)
		(width 0.127)
		(layer "In2.Cu")
		(net "IOC_SDA_4")
	)
	(segment
		(start 171.0182 -147.066)
		(end 178.641502 -147.066)
		(width 0.127)
		(layer "In2.Cu")
		(net "IOC_SDA_4")
	)
	(segment
		(start 205.958948 -148.244052)
		(end 206.502 -147.701)
		(width 0.127)
		(layer "In2.Cu")
		(net "IOC_SDA_4")
	)
	(segment
		(start 119.541798 -44.4373)
		(end 117.2337 -44.4373)
		(width 0.127)
		(layer "In5.Cu")
		(net "IOC_SDA_4")
	)
	(segment
		(start 120.799098 -43.18)
		(end 119.541798 -44.4373)
		(width 0.127)
		(layer "In5.Cu")
		(net "IOC_SDA_4")
	)
	(segment
		(start 132.438648 -42.059352)
		(end 131.318 -43.18)
		(width 0.127)
		(layer "In5.Cu")
		(net "IOC_SDA_4")
	)
	(segment
		(start 113.461546 -45.085)
		(end 112.745266 -45.80128)
		(width 0.127)
		(layer "In5.Cu")
		(net "IOC_SDA_4")
	)
	(segment
		(start 117.2337 -44.4373)
		(end 116.586 -45.085)
		(width 0.127)
		(layer "In5.Cu")
		(net "IOC_SDA_4")
	)
	(segment
		(start 202.184 -42.5704)
		(end 201.672952 -42.059352)
		(width 0.127)
		(layer "In5.Cu")
		(net "IOC_SDA_4")
	)
	(segment
		(start 201.672952 -42.059352)
		(end 132.438648 -42.059352)
		(width 0.127)
		(layer "In5.Cu")
		(net "IOC_SDA_4")
	)
	(segment
		(start 131.318 -43.18)
		(end 120.799098 -43.18)
		(width 0.127)
		(layer "In5.Cu")
		(net "IOC_SDA_4")
	)
	(segment
		(start 116.586 -45.085)
		(end 113.461546 -45.085)
		(width 0.127)
		(layer "In5.Cu")
		(net "IOC_SDA_4")
	)
	(segment
		(start 96.350074 -36.599876)
		(end 95.950278 -36.20008)
		(width 0.1397)
		(layer "F.Cu")
		(net "PCIE_SAS_C_CPU_RX_N1")
	)
	(via
		(at 95.950278 -36.20008)
		(size 0.508)
		(drill 0.254)
		(layers "F.Cu" "B.Cu")
		(net "PCIE_SAS_C_CPU_RX_N1")
	)
	(segment
		(start 96.311974 -33.584134)
		(end 96.311974 -34.95421)
		(width 0.0889)
		(layer "B.Cu")
		(net "PCIE_SAS_C_CPU_RX_N1")
	)
	(segment
		(start 95.51416 -31.9024)
		(end 95.51416 -32.473392)
		(width 0.1397)
		(layer "B.Cu")
		(net "PCIE_SAS_C_CPU_RX_N1")
	)
	(segment
		(start 96.35363 -34.995866)
		(end 96.35363 -35.433)
		(width 0.0889)
		(layer "B.Cu")
		(net "PCIE_SAS_C_CPU_RX_N1")
	)
	(segment
		(start 96.246442 -35.68573)
		(end 96.104456 -35.827462)
		(width 0.0889)
		(layer "B.Cu")
		(net "PCIE_SAS_C_CPU_RX_N1")
	)
	(segment
		(start 96.25076 -35.681412)
		(end 96.246442 -35.68573)
		(width 0.0889)
		(layer "B.Cu")
		(net "PCIE_SAS_C_CPU_RX_N1")
	)
	(segment
		(start 96.311974 -34.95421)
		(end 96.35363 -34.995866)
		(width 0.0889)
		(layer "B.Cu")
		(net "PCIE_SAS_C_CPU_RX_N1")
	)
	(segment
		(start 95.663004 -32.832802)
		(end 96.239584 -33.409382)
		(width 0.1397)
		(layer "B.Cu")
		(net "PCIE_SAS_C_CPU_RX_N1")
	)
	(arc
		(start 95.51416 -32.473392)
		(mid 95.552849 -32.667892)
		(end 95.663004 -32.832802)
		(width 0.1397)
		(layer "B.Cu")
		(net "PCIE_SAS_C_CPU_RX_N1")
	)
	(arc
		(start 96.104456 -35.827462)
		(mid 95.990308 -35.998436)
		(end 95.950278 -36.20008)
		(width 0.0889)
		(layer "B.Cu")
		(net "PCIE_SAS_C_CPU_RX_N1")
	)
	(arc
		(start 96.239584 -33.409382)
		(mid 96.293156 -33.489559)
		(end 96.311974 -33.584134)
		(width 0.1016)
		(layer "B.Cu")
		(net "PCIE_SAS_C_CPU_RX_N1")
	)
	(arc
		(start 96.35363 -35.433)
		(mid 96.32689 -35.56743)
		(end 96.25076 -35.681412)
		(width 0.0889)
		(layer "B.Cu")
		(net "PCIE_SAS_C_CPU_RX_N1")
	)
	(segment
		(start 115.55222 -78.008226)
		(end 115.55222 -79.412846)
		(width 0.1143)
		(layer "F.Cu")
		(net "TEST_MUX_37")
	)
	(segment
		(start 115.55222 -79.412846)
		(end 116.858034 -80.71866)
		(width 0.1143)
		(layer "F.Cu")
		(net "TEST_MUX_37")
	)
	(segment
		(start 116.858034 -80.71866)
		(end 116.858034 -81.85785)
		(width 0.1143)
		(layer "F.Cu")
		(net "TEST_MUX_37")
	)
	(segment
		(start 116.525802 -77.034644)
		(end 115.55222 -78.008226)
		(width 0.1143)
		(layer "F.Cu")
		(net "TEST_MUX_37")
	)
	(segment
		(start 116.586 -76.708)
		(end 116.586 -76.834238)
		(width 0.1143)
		(layer "F.Cu")
		(net "TEST_MUX_37")
	)
	(segment
		(start 116.858034 -81.85785)
		(end 117.350032 -82.349848)
		(width 0.1143)
		(layer "F.Cu")
		(net "TEST_MUX_37")
	)
	(segment
		(start 116.586 -76.834238)
		(end 116.525802 -77.034644)
		(width 0.1143)
		(layer "F.Cu")
		(net "TEST_MUX_37")
	)
	(segment
		(start 96.34855 -85.09)
		(end 97.14357 -84.29498)
		(width 0.1143)
		(layer "F.Cu")
		(net "LSI_T_N")
	)
	(segment
		(start 107.349798 -88.349836)
		(end 106.849672 -87.84971)
		(width 0.1143)
		(layer "F.Cu")
		(net "LSI_T_N")
	)
	(segment
		(start 97.17659 -84.328)
		(end 97.14357 -84.29498)
		(width 0.1143)
		(layer "F.Cu")
		(net "LSI_T_N")
	)
	(segment
		(start 98.18497 -84.582)
		(end 97.93097 -84.328)
		(width 0.1143)
		(layer "F.Cu")
		(net "LSI_T_N")
	)
	(segment
		(start 97.93097 -84.328)
		(end 97.17659 -84.328)
		(width 0.1143)
		(layer "F.Cu")
		(net "LSI_T_N")
	)
	(segment
		(start 96.34347 -85.09)
		(end 96.34855 -85.09)
		(width 0.1143)
		(layer "F.Cu")
		(net "LSI_T_N")
	)
	(via
		(at 106.849672 -87.84971)
		(size 0.508)
		(drill 0.254)
		(layers "F.Cu" "B.Cu")
		(net "LSI_T_N")
	)
	(via
		(at 97.14357 -84.29498)
		(size 0.5588)
		(drill 0.3048)
		(layers "F.Cu" "B.Cu")
		(net "LSI_T_N")
	)
	(segment
		(start 104.294178 -86.88705)
		(end 104.70134 -87.294212)
		(width 0.127)
		(layer "In2.Cu")
		(net "LSI_T_N")
	)
	(segment
		(start 99.579176 -83.8581)
		(end 101.450902 -83.8581)
		(width 0.127)
		(layer "In2.Cu")
		(net "LSI_T_N")
	)
	(segment
		(start 103.533702 -85.9409)
		(end 104.294178 -86.701376)
		(width 0.127)
		(layer "In2.Cu")
		(net "LSI_T_N")
	)
	(segment
		(start 102.294182 -84.70138)
		(end 102.294182 -84.887054)
		(width 0.127)
		(layer "In2.Cu")
		(net "LSI_T_N")
	)
	(segment
		(start 99.142296 -84.29498)
		(end 99.579176 -83.8581)
		(width 0.127)
		(layer "In2.Cu")
		(net "LSI_T_N")
	)
	(segment
		(start 104.70134 -87.294212)
		(end 106.294174 -87.294212)
		(width 0.127)
		(layer "In2.Cu")
		(net "LSI_T_N")
	)
	(segment
		(start 106.294174 -87.294212)
		(end 106.849672 -87.84971)
		(width 0.127)
		(layer "In2.Cu")
		(net "LSI_T_N")
	)
	(segment
		(start 102.294182 -84.887054)
		(end 103.348028 -85.9409)
		(width 0.127)
		(layer "In2.Cu")
		(net "LSI_T_N")
	)
	(segment
		(start 97.14357 -84.29498)
		(end 99.142296 -84.29498)
		(width 0.127)
		(layer "In2.Cu")
		(net "LSI_T_N")
	)
	(segment
		(start 103.348028 -85.9409)
		(end 103.533702 -85.9409)
		(width 0.127)
		(layer "In2.Cu")
		(net "LSI_T_N")
	)
	(segment
		(start 101.450902 -83.8581)
		(end 102.294182 -84.70138)
		(width 0.127)
		(layer "In2.Cu")
		(net "LSI_T_N")
	)
	(segment
		(start 104.294178 -86.701376)
		(end 104.294178 -86.88705)
		(width 0.127)
		(layer "In2.Cu")
		(net "LSI_T_N")
	)
	(segment
		(start 105.28427 -78.7527)
		(end 105.28427 -80.028288)
		(width 0.1143)
		(layer "F.Cu")
		(net "LSI_TRST_N")
	)
	(segment
		(start 106.31297 -76.8985)
		(end 105.16997 -76.8985)
		(width 0.1143)
		(layer "F.Cu")
		(net "LSI_TRST_N")
	)
	(segment
		(start 105.28427 -80.028288)
		(end 104.962452 -80.350106)
		(width 0.1143)
		(layer "F.Cu")
		(net "LSI_TRST_N")
	)
	(segment
		(start 105.16997 -76.8985)
		(end 105.55097 -77.851)
		(width 0.1143)
		(layer "F.Cu")
		(net "LSI_TRST_N")
	)
	(segment
		(start 104.962452 -80.350106)
		(end 104.962452 -82.555334)
		(width 0.1143)
		(layer "F.Cu")
		(net "LSI_TRST_N")
	)
	(segment
		(start 105.80497 -78.232)
		(end 105.28427 -78.7527)
		(width 0.1143)
		(layer "F.Cu")
		(net "LSI_TRST_N")
	)
	(segment
		(start 105.349802 -82.942684)
		(end 105.349802 -83.349846)
		(width 0.1143)
		(layer "F.Cu")
		(net "LSI_TRST_N")
	)
	(segment
		(start 105.55097 -77.851)
		(end 105.80497 -78.105)
		(width 0.1143)
		(layer "F.Cu")
		(net "LSI_TRST_N")
	)
	(segment
		(start 105.80497 -78.105)
		(end 105.80497 -78.232)
		(width 0.1143)
		(layer "F.Cu")
		(net "LSI_TRST_N")
	)
	(segment
		(start 104.962452 -82.555334)
		(end 105.349802 -82.942684)
		(width 0.1143)
		(layer "F.Cu")
		(net "LSI_TRST_N")
	)
	(segment
		(start 111.77016 -32.414972)
		(end 111.77016 -31.75)
		(width 0.1143)
		(layer "F.Cu")
		(net "IOC_UART_0_TX")
	)
	(segment
		(start 111.77016 -31.75)
		(end 111.64316 -31.623)
		(width 0.1143)
		(layer "F.Cu")
		(net "IOC_UART_0_TX")
	)
	(segment
		(start 228.092 -82.843878)
		(end 228.092 -80.264)
		(width 0.1143)
		(layer "F.Cu")
		(net "IOC_UART_0_TX")
	)
	(segment
		(start 111.549942 -33.399984)
		(end 111.549942 -32.72409)
		(width 0.1143)
		(layer "F.Cu")
		(net "IOC_UART_0_TX")
	)
	(segment
		(start 111.549942 -32.72409)
		(end 111.577374 -32.696658)
		(width 0.1143)
		(layer "F.Cu")
		(net "IOC_UART_0_TX")
	)
	(segment
		(start 224.0915 -85.979)
		(end 224.956878 -85.979)
		(width 0.1143)
		(layer "F.Cu")
		(net "IOC_UART_0_TX")
	)
	(segment
		(start 111.577374 -32.696658)
		(end 111.577374 -32.607758)
		(width 0.1143)
		(layer "F.Cu")
		(net "IOC_UART_0_TX")
	)
	(segment
		(start 224.956878 -85.979)
		(end 228.092 -82.843878)
		(width 0.1143)
		(layer "F.Cu")
		(net "IOC_UART_0_TX")
	)
	(segment
		(start 111.577374 -32.607758)
		(end 111.77016 -32.414972)
		(width 0.1143)
		(layer "F.Cu")
		(net "IOC_UART_0_TX")
	)
	(via
		(at 111.64316 -31.623)
		(size 0.508)
		(drill 0.254)
		(layers "F.Cu" "B.Cu")
		(net "IOC_UART_0_TX")
	)
	(via
		(at 228.092 -80.264)
		(size 0.5588)
		(drill 0.3048)
		(layers "F.Cu" "B.Cu")
		(net "IOC_UART_0_TX")
	)
	(segment
		(start 124.795026 -36.576)
		(end 133.726936 -36.576)
		(width 0.127)
		(layer "In2.Cu")
		(net "IOC_UART_0_TX")
	)
	(segment
		(start 111.64316 -31.623)
		(end 111.68126 -31.5849)
		(width 0.127)
		(layer "In2.Cu")
		(net "IOC_UART_0_TX")
	)
	(segment
		(start 167.602916 -61.1759)
		(end 202.395328 -61.1759)
		(width 0.127)
		(layer "In2.Cu")
		(net "IOC_UART_0_TX")
	)
	(segment
		(start 140.330936 -43.18)
		(end 149.607016 -43.18)
		(width 0.127)
		(layer "In2.Cu")
		(net "IOC_UART_0_TX")
	)
	(segment
		(start 218.874594 -60.452)
		(end 227.584 -69.161406)
		(width 0.127)
		(layer "In2.Cu")
		(net "IOC_UART_0_TX")
	)
	(segment
		(start 227.584 -69.161406)
		(end 227.584 -79.756)
		(width 0.127)
		(layer "In2.Cu")
		(net "IOC_UART_0_TX")
	)
	(segment
		(start 133.726936 -36.576)
		(end 140.330936 -43.18)
		(width 0.127)
		(layer "In2.Cu")
		(net "IOC_UART_0_TX")
	)
	(segment
		(start 203.119228 -60.452)
		(end 218.874594 -60.452)
		(width 0.127)
		(layer "In2.Cu")
		(net "IOC_UART_0_TX")
	)
	(segment
		(start 119.803926 -31.5849)
		(end 124.795026 -36.576)
		(width 0.127)
		(layer "In2.Cu")
		(net "IOC_UART_0_TX")
	)
	(segment
		(start 227.584 -79.756)
		(end 228.092 -80.264)
		(width 0.127)
		(layer "In2.Cu")
		(net "IOC_UART_0_TX")
	)
	(segment
		(start 149.607016 -43.18)
		(end 167.602916 -61.1759)
		(width 0.127)
		(layer "In2.Cu")
		(net "IOC_UART_0_TX")
	)
	(segment
		(start 202.395328 -61.1759)
		(end 203.119228 -60.452)
		(width 0.127)
		(layer "In2.Cu")
		(net "IOC_UART_0_TX")
	)
	(segment
		(start 111.68126 -31.5849)
		(end 119.803926 -31.5849)
		(width 0.127)
		(layer "In2.Cu")
		(net "IOC_UART_0_TX")
	)
	(segment
		(start 88.138 -29.509466)
		(end 88.138 -30.49016)
		(width 0.1143)
		(layer "F.Cu")
		(net "CK_100M_EXP_SAS")
	)
	(segment
		(start 86.614 -30.23616)
		(end 86.36 -30.49016)
		(width 0.1143)
		(layer "F.Cu")
		(net "CK_100M_EXP_SAS")
	)
	(segment
		(start 86.614 -29.53766)
		(end 86.614 -30.23616)
		(width 0.1143)
		(layer "F.Cu")
		(net "CK_100M_EXP_SAS")
	)
	(via
		(at 87.0966 -30.49016)
		(size 0.7112)
		(drill 0.3556)
		(layers "F.Cu" "B.Cu")
		(net "CK_100M_EXP_SAS")
	)
	(via
		(at 86.36 -30.49016)
		(size 0.508)
		(drill 0.254)
		(layers "F.Cu" "B.Cu")
		(net "CK_100M_EXP_SAS")
	)
	(via
		(at 88.138 -30.49016)
		(size 0.508)
		(drill 0.254)
		(layers "F.Cu" "B.Cu")
		(net "CK_100M_EXP_SAS")
	)
	(segment
		(start 87.0966 -30.49016)
		(end 88.138 -30.49016)
		(width 0.1143)
		(layer "B.Cu")
		(net "CK_100M_EXP_SAS")
	)
	(segment
		(start 86.614 -29.53766)
		(end 86.614 -30.23616)
		(width 0.1143)
		(layer "B.Cu")
		(net "CK_100M_EXP_SAS")
	)
	(segment
		(start 86.614 -30.23616)
		(end 86.36 -30.49016)
		(width 0.1143)
		(layer "B.Cu")
		(net "CK_100M_EXP_SAS")
	)
	(segment
		(start 87.884 -30.23616)
		(end 88.138 -30.49016)
		(width 0.1143)
		(layer "B.Cu")
		(net "CK_100M_EXP_SAS")
	)
	(segment
		(start 87.884 -29.53766)
		(end 87.884 -30.23616)
		(width 0.1143)
		(layer "B.Cu")
		(net "CK_100M_EXP_SAS")
	)
	(segment
		(start 86.36 -30.49016)
		(end 87.0966 -30.49016)
		(width 0.1143)
		(layer "B.Cu")
		(net "CK_100M_EXP_SAS")
	)
	(segment
		(start 98.98253 -99.576128)
		(end 99.118674 -99.576128)
		(width 0.1143)
		(layer "F.Cu")
		(net "LSI_EFUSE")
	)
	(segment
		(start 106.849672 -97.477072)
		(end 106.849672 -97.850198)
		(width 0.1143)
		(layer "F.Cu")
		(net "LSI_EFUSE")
	)
	(segment
		(start 99.139502 -99.5553)
		(end 99.197922 -99.5553)
		(width 0.1143)
		(layer "F.Cu")
		(net "LSI_EFUSE")
	)
	(segment
		(start 97.903284 -98.496882)
		(end 98.98253 -99.576128)
		(width 0.1143)
		(layer "F.Cu")
		(net "LSI_EFUSE")
	)
	(segment
		(start 97.795842 -98.496882)
		(end 97.903284 -98.496882)
		(width 0.1143)
		(layer "F.Cu")
		(net "LSI_EFUSE")
	)
	(segment
		(start 106.976672 -97.350072)
		(end 106.849672 -97.477072)
		(width 0.1143)
		(layer "F.Cu")
		(net "LSI_EFUSE")
	)
	(segment
		(start 99.118674 -99.576128)
		(end 99.139502 -99.5553)
		(width 0.1143)
		(layer "F.Cu")
		(net "LSI_EFUSE")
	)
	(segment
		(start 107.349798 -97.350072)
		(end 106.976672 -97.350072)
		(width 0.1143)
		(layer "F.Cu")
		(net "LSI_EFUSE")
	)
	(segment
		(start 96.589342 -98.496882)
		(end 97.795842 -98.496882)
		(width 0.1143)
		(layer "F.Cu")
		(net "LSI_EFUSE")
	)
	(via
		(at 106.849672 -97.850198)
		(size 0.508)
		(drill 0.254)
		(layers "F.Cu" "B.Cu")
		(net "LSI_EFUSE")
	)
	(via
		(at 99.197922 -99.5553)
		(size 0.508)
		(drill 0.254)
		(layers "F.Cu" "B.Cu")
		(net "LSI_EFUSE")
	)
	(segment
		(start 101.405182 -98.666046)
		(end 101.665532 -98.405696)
		(width 0.127)
		(layer "In2.Cu")
		(net "LSI_EFUSE")
	)
	(segment
		(start 101.405182 -98.887788)
		(end 101.405182 -98.666046)
		(width 0.127)
		(layer "In2.Cu")
		(net "LSI_EFUSE")
	)
	(segment
		(start 101.887274 -98.405696)
		(end 102.887272 -97.405698)
		(width 0.127)
		(layer "In2.Cu")
		(net "LSI_EFUSE")
	)
	(segment
		(start 106.033824 -97.405698)
		(end 106.478324 -97.850198)
		(width 0.127)
		(layer "In2.Cu")
		(net "LSI_EFUSE")
	)
	(segment
		(start 99.439222 -99.314)
		(end 100.97897 -99.314)
		(width 0.127)
		(layer "In2.Cu")
		(net "LSI_EFUSE")
	)
	(segment
		(start 106.478324 -97.850198)
		(end 106.849672 -97.850198)
		(width 0.127)
		(layer "In2.Cu")
		(net "LSI_EFUSE")
	)
	(segment
		(start 99.197922 -99.5553)
		(end 99.439222 -99.314)
		(width 0.127)
		(layer "In2.Cu")
		(net "LSI_EFUSE")
	)
	(segment
		(start 100.97897 -99.314)
		(end 101.405182 -98.887788)
		(width 0.127)
		(layer "In2.Cu")
		(net "LSI_EFUSE")
	)
	(segment
		(start 101.665532 -98.405696)
		(end 101.887274 -98.405696)
		(width 0.127)
		(layer "In2.Cu")
		(net "LSI_EFUSE")
	)
	(segment
		(start 102.887272 -97.405698)
		(end 106.033824 -97.405698)
		(width 0.127)
		(layer "In2.Cu")
		(net "LSI_EFUSE")
	)
	(segment
		(start 44.702222 -140.892784)
		(end 44.702222 -142.224252)
		(width 0.1143)
		(layer "F.Cu")
		(net "ICE_RESET_N")
	)
	(segment
		(start 58.42 -175.006)
		(end 62.80785 -179.39385)
		(width 0.1143)
		(layer "F.Cu")
		(net "ICE_RESET_N")
	)
	(segment
		(start 63.529972 -180.560472)
		(end 63.5 -180.5305)
		(width 0.1143)
		(layer "F.Cu")
		(net "ICE_RESET_N")
	)
	(segment
		(start 58.42 -172.847)
		(end 58.42 -175.006)
		(width 0.1143)
		(layer "F.Cu")
		(net "ICE_RESET_N")
	)
	(segment
		(start 62.80785 -179.83835)
		(end 63.5 -180.5305)
		(width 0.1143)
		(layer "F.Cu")
		(net "ICE_RESET_N")
	)
	(segment
		(start 63.529972 -185.269886)
		(end 63.529972 -180.560472)
		(width 0.1143)
		(layer "F.Cu")
		(net "ICE_RESET_N")
	)
	(segment
		(start 62.80785 -179.39385)
		(end 62.80785 -179.83835)
		(width 0.1143)
		(layer "F.Cu")
		(net "ICE_RESET_N")
	)
	(via
		(at 44.702222 -142.224252)
		(size 0.5588)
		(drill 0.3048)
		(layers "F.Cu" "B.Cu")
		(net "ICE_RESET_N")
	)
	(via
		(at 58.42 -172.847)
		(size 0.5588)
		(drill 0.3048)
		(layers "F.Cu" "B.Cu")
		(net "ICE_RESET_N")
	)
	(segment
		(start 46.736 -144.25803)
		(end 46.736 -163.322)
		(width 0.1143)
		(layer "B.Cu")
		(net "ICE_RESET_N")
	)
	(segment
		(start 56.261 -172.847)
		(end 58.42 -172.847)
		(width 0.1143)
		(layer "B.Cu")
		(net "ICE_RESET_N")
	)
	(segment
		(start 44.702222 -142.224252)
		(end 46.736 -144.25803)
		(width 0.1143)
		(layer "B.Cu")
		(net "ICE_RESET_N")
	)
	(segment
		(start 46.736 -163.322)
		(end 56.261 -172.847)
		(width 0.1143)
		(layer "B.Cu")
		(net "ICE_RESET_N")
	)
	(segment
		(start 95.1484 -35.44062)
		(end 95.1484 -35.40506)
		(width 0.1397)
		(layer "F.Cu")
		(net "PCIE_SAS_C_CPU_RX_P0")
	)
	(segment
		(start 95.416878 -35.744912)
		(end 95.173546 -35.50158)
		(width 0.1397)
		(layer "F.Cu")
		(net "PCIE_SAS_C_CPU_RX_P0")
	)
	(via
		(at 95.1484 -35.40506)
		(size 0.508)
		(drill 0.254)
		(layers "F.Cu" "B.Cu")
		(net "PCIE_SAS_C_CPU_RX_P0")
	)
	(arc
		(start 95.173546 -35.50158)
		(mid 95.154941 -35.473596)
		(end 95.1484 -35.44062)
		(width 0.1397)
		(layer "F.Cu")
		(net "PCIE_SAS_C_CPU_RX_P0")
	)
	(arc
		(start 95.549974 -35.80003)
		(mid 95.477948 -35.785703)
		(end 95.416878 -35.744912)
		(width 0.1397)
		(layer "F.Cu")
		(net "PCIE_SAS_C_CPU_RX_P0")
	)
	(segment
		(start 95.569024 -34.566606)
		(end 95.569024 -34.590482)
		(width 0.1016)
		(layer "B.Cu")
		(net "PCIE_SAS_C_CPU_RX_P0")
	)
	(segment
		(start 95.150178 -35.287966)
		(end 95.150178 -35.403282)
		(width 0.1016)
		(layer "B.Cu")
		(net "PCIE_SAS_C_CPU_RX_P0")
	)
	(segment
		(start 95.150178 -35.403282)
		(end 95.1484 -35.40506)
		(width 0.1016)
		(layer "B.Cu")
		(net "PCIE_SAS_C_CPU_RX_P0")
	)
	(segment
		(start 95.43923 -34.903664)
		(end 95.29191 -35.05073)
		(width 0.1016)
		(layer "B.Cu")
		(net "PCIE_SAS_C_CPU_RX_P0")
	)
	(segment
		(start 95.291402 -35.050984)
		(end 95.217488 -35.125406)
		(width 0.1016)
		(layer "B.Cu")
		(net "PCIE_SAS_C_CPU_RX_P0")
	)
	(segment
		(start 95.29191 -35.05073)
		(end 95.291402 -35.050984)
		(width 0.1016)
		(layer "B.Cu")
		(net "PCIE_SAS_C_CPU_RX_P0")
	)
	(segment
		(start 93.546676 -32.36468)
		(end 95.442024 -34.260028)
		(width 0.1397)
		(layer "B.Cu")
		(net "PCIE_SAS_C_CPU_RX_P0")
	)
	(arc
		(start 95.551498 -34.445194)
		(mid 95.564561 -34.505278)
		(end 95.569024 -34.566606)
		(width 0.1016)
		(layer "B.Cu")
		(net "PCIE_SAS_C_CPU_RX_P0")
	)
	(arc
		(start 95.217488 -35.125406)
		(mid 95.167653 -35.199989)
		(end 95.150178 -35.287966)
		(width 0.1016)
		(layer "B.Cu")
		(net "PCIE_SAS_C_CPU_RX_P0")
	)
	(arc
		(start 95.442024 -34.260028)
		(mid 95.508421 -34.345716)
		(end 95.551498 -34.445194)
		(width 0.1016)
		(layer "B.Cu")
		(net "PCIE_SAS_C_CPU_RX_P0")
	)
	(arc
		(start 95.569024 -34.590482)
		(mid 95.566225 -34.639169)
		(end 95.558102 -34.687256)
		(width 0.1016)
		(layer "B.Cu")
		(net "PCIE_SAS_C_CPU_RX_P0")
	)
	(arc
		(start 95.495872 -34.833814)
		(mid 95.469336 -34.870187)
		(end 95.43923 -34.903664)
		(width 0.1016)
		(layer "B.Cu")
		(net "PCIE_SAS_C_CPU_RX_P0")
	)
	(arc
		(start 95.558102 -34.687256)
		(mid 95.533645 -34.763363)
		(end 95.495872 -34.833814)
		(width 0.1016)
		(layer "B.Cu")
		(net "PCIE_SAS_C_CPU_RX_P0")
	)
	(arc
		(start 93.35516 -31.9024)
		(mid 93.404927 -32.152597)
		(end 93.546676 -32.36468)
		(width 0.1397)
		(layer "B.Cu")
		(net "PCIE_SAS_C_CPU_RX_P0")
	)
	(segment
		(start 98.23577 -82.8294)
		(end 98.23577 -82.74177)
		(width 0.1143)
		(layer "F.Cu")
		(net "EXP_CPU_MODE_1")
	)
	(segment
		(start 106.3498 -86.34984)
		(end 105.849674 -85.849714)
		(width 0.1143)
		(layer "F.Cu")
		(net "EXP_CPU_MODE_1")
	)
	(segment
		(start 97.155 -81.661)
		(end 97.536 -82.042)
		(width 0.1143)
		(layer "F.Cu")
		(net "EXP_CPU_MODE_1")
	)
	(segment
		(start 96.34347 -81.661)
		(end 97.155 -81.661)
		(width 0.1143)
		(layer "F.Cu")
		(net "EXP_CPU_MODE_1")
	)
	(segment
		(start 98.23577 -82.74177)
		(end 97.536 -82.042)
		(width 0.1143)
		(layer "F.Cu")
		(net "EXP_CPU_MODE_1")
	)
	(via
		(at 97.536 -82.042)
		(size 0.7112)
		(drill 0.3556)
		(layers "F.Cu" "B.Cu")
		(net "EXP_CPU_MODE_1")
	)
	(via
		(at 98.23577 -82.8294)
		(size 0.508)
		(drill 0.254)
		(layers "F.Cu" "B.Cu")
		(net "EXP_CPU_MODE_1")
	)
	(via
		(at 105.849674 -85.849714)
		(size 0.508)
		(drill 0.254)
		(layers "F.Cu" "B.Cu")
		(net "EXP_CPU_MODE_1")
	)
	(segment
		(start 104.405176 -83.998054)
		(end 104.405176 -83.81238)
		(width 0.127)
		(layer "In2.Cu")
		(net "EXP_CPU_MODE_1")
	)
	(segment
		(start 105.849674 -85.849714)
		(end 105.294176 -85.294216)
		(width 0.127)
		(layer "In2.Cu")
		(net "EXP_CPU_MODE_1")
	)
	(segment
		(start 104.405176 -83.81238)
		(end 102.456996 -81.8642)
		(width 0.127)
		(layer "In2.Cu")
		(net "EXP_CPU_MODE_1")
	)
	(segment
		(start 104.812338 -84.405216)
		(end 104.405176 -83.998054)
		(width 0.127)
		(layer "In2.Cu")
		(net "EXP_CPU_MODE_1")
	)
	(segment
		(start 105.294176 -85.294216)
		(end 105.294176 -84.70138)
		(width 0.127)
		(layer "In2.Cu")
		(net "EXP_CPU_MODE_1")
	)
	(segment
		(start 99.200716 -81.8642)
		(end 98.23577 -82.8294)
		(width 0.127)
		(layer "In2.Cu")
		(net "EXP_CPU_MODE_1")
	)
	(segment
		(start 105.294176 -84.70138)
		(end 104.998012 -84.405216)
		(width 0.127)
		(layer "In2.Cu")
		(net "EXP_CPU_MODE_1")
	)
	(segment
		(start 102.456996 -81.8642)
		(end 99.200716 -81.8642)
		(width 0.127)
		(layer "In2.Cu")
		(net "EXP_CPU_MODE_1")
	)
	(segment
		(start 104.998012 -84.405216)
		(end 104.812338 -84.405216)
		(width 0.127)
		(layer "In2.Cu")
		(net "EXP_CPU_MODE_1")
	)
	(segment
		(start 224.0915 -84.963)
		(end 224.536 -84.963)
		(width 0.1143)
		(layer "F.Cu")
		(net "IOC_UART_0_RX")
	)
	(segment
		(start 109.37494 -29.845)
		(end 108.80725 -30.41269)
		(width 0.1143)
		(layer "F.Cu")
		(net "IOC_UART_0_RX")
	)
	(segment
		(start 108.80725 -31.14929)
		(end 108.80725 -33.578038)
		(width 0.1143)
		(layer "F.Cu")
		(net "IOC_UART_0_RX")
	)
	(segment
		(start 109.67466 -29.845)
		(end 109.37494 -29.845)
		(width 0.1143)
		(layer "F.Cu")
		(net "IOC_UART_0_RX")
	)
	(segment
		(start 108.80725 -30.41269)
		(end 108.80725 -31.14929)
		(width 0.1143)
		(layer "F.Cu")
		(net "IOC_UART_0_RX")
	)
	(segment
		(start 228.162358 -79.502)
		(end 228.219 -79.502)
		(width 0.1143)
		(layer "F.Cu")
		(net "IOC_UART_0_RX")
	)
	(segment
		(start 108.80725 -33.578038)
		(end 109.15015 -33.920938)
		(width 0.1143)
		(layer "F.Cu")
		(net "IOC_UART_0_RX")
	)
	(segment
		(start 224.536 -84.963)
		(end 227.076 -82.423)
		(width 0.1143)
		(layer "F.Cu")
		(net "IOC_UART_0_RX")
	)
	(segment
		(start 109.15015 -33.920938)
		(end 109.15015 -34.19983)
		(width 0.1143)
		(layer "F.Cu")
		(net "IOC_UART_0_RX")
	)
	(segment
		(start 227.076 -80.588358)
		(end 228.162358 -79.502)
		(width 0.1143)
		(layer "F.Cu")
		(net "IOC_UART_0_RX")
	)
	(segment
		(start 228.219 -79.502)
		(end 228.346 -79.375)
		(width 0.1143)
		(layer "F.Cu")
		(net "IOC_UART_0_RX")
	)
	(segment
		(start 227.076 -82.423)
		(end 227.076 -80.588358)
		(width 0.1143)
		(layer "F.Cu")
		(net "IOC_UART_0_RX")
	)
	(via
		(at 108.80725 -30.41269)
		(size 0.508)
		(drill 0.254)
		(layers "F.Cu" "B.Cu")
		(net "IOC_UART_0_RX")
	)
	(via
		(at 228.346 -79.375)
		(size 0.5588)
		(drill 0.3048)
		(layers "F.Cu" "B.Cu")
		(net "IOC_UART_0_RX")
	)
	(via
		(at 108.80725 -31.14929)
		(size 0.7112)
		(drill 0.3556)
		(layers "F.Cu" "B.Cu")
		(net "IOC_UART_0_RX")
	)
	(segment
		(start 133.901434 -36.195)
		(end 124.953014 -36.195)
		(width 0.127)
		(layer "In2.Cu")
		(net "IOC_UART_0_RX")
	)
	(segment
		(start 219.032582 -60.071)
		(end 201.803 -60.071)
		(width 0.127)
		(layer "In2.Cu")
		(net "IOC_UART_0_RX")
	)
	(segment
		(start 124.953014 -36.195)
		(end 119.961914 -31.2039)
		(width 0.127)
		(layer "In2.Cu")
		(net "IOC_UART_0_RX")
	)
	(segment
		(start 119.961914 -31.2039)
		(end 112.188498 -31.2039)
		(width 0.127)
		(layer "In2.Cu")
		(net "IOC_UART_0_RX")
	)
	(segment
		(start 167.760904 -60.7949)
		(end 149.765004 -42.799)
		(width 0.127)
		(layer "In2.Cu")
		(net "IOC_UART_0_RX")
	)
	(segment
		(start 140.505434 -42.799)
		(end 133.901434 -36.195)
		(width 0.127)
		(layer "In2.Cu")
		(net "IOC_UART_0_RX")
	)
	(segment
		(start 228.346 -69.384418)
		(end 219.032582 -60.071)
		(width 0.127)
		(layer "In2.Cu")
		(net "IOC_UART_0_RX")
	)
	(segment
		(start 112.188498 -31.2039)
		(end 111.397288 -30.41269)
		(width 0.127)
		(layer "In2.Cu")
		(net "IOC_UART_0_RX")
	)
	(segment
		(start 201.803 -60.071)
		(end 201.0791 -60.7949)
		(width 0.127)
		(layer "In2.Cu")
		(net "IOC_UART_0_RX")
	)
	(segment
		(start 111.397288 -30.41269)
		(end 108.80725 -30.41269)
		(width 0.127)
		(layer "In2.Cu")
		(net "IOC_UART_0_RX")
	)
	(segment
		(start 201.0791 -60.7949)
		(end 167.760904 -60.7949)
		(width 0.127)
		(layer "In2.Cu")
		(net "IOC_UART_0_RX")
	)
	(segment
		(start 149.765004 -42.799)
		(end 140.505434 -42.799)
		(width 0.127)
		(layer "In2.Cu")
		(net "IOC_UART_0_RX")
	)
	(segment
		(start 228.346 -79.375)
		(end 228.346 -69.384418)
		(width 0.127)
		(layer "In2.Cu")
		(net "IOC_UART_0_RX")
	)
	(segment
		(start 97.95002 -35.80003)
		(end 97.940622 -35.80003)
		(width 0.1397)
		(layer "F.Cu")
		(net "PCIE_SAS_C_CPU_RX_P2")
	)
	(segment
		(start 97.940622 -35.80003)
		(end 97.540826 -35.400234)
		(width 0.1397)
		(layer "F.Cu")
		(net "PCIE_SAS_C_CPU_RX_P2")
	)
	(via
		(at 97.540826 -35.400234)
		(size 0.508)
		(drill 0.254)
		(layers "F.Cu" "B.Cu")
		(net "PCIE_SAS_C_CPU_RX_P2")
	)
	(segment
		(start 97.422208 -35.281616)
		(end 97.540826 -35.400234)
		(width 0.1397)
		(layer "B.Cu")
		(net "PCIE_SAS_C_CPU_RX_P2")
	)
	(segment
		(start 96.804226 -33.449514)
		(end 97.159572 -33.804606)
		(width 0.1397)
		(layer "B.Cu")
		(net "PCIE_SAS_C_CPU_RX_P2")
	)
	(segment
		(start 97.263966 -34.05632)
		(end 97.263966 -34.8996)
		(width 0.1397)
		(layer "B.Cu")
		(net "PCIE_SAS_C_CPU_RX_P2")
	)
	(segment
		(start 96.667066 -32.539432)
		(end 96.667066 -33.117282)
		(width 0.1397)
		(layer "B.Cu")
		(net "PCIE_SAS_C_CPU_RX_P2")
	)
	(arc
		(start 96.667066 -33.117282)
		(mid 96.7026 -33.297046)
		(end 96.804226 -33.449514)
		(width 0.1397)
		(layer "B.Cu")
		(net "PCIE_SAS_C_CPU_RX_P2")
	)
	(arc
		(start 96.40316 -31.9024)
		(mid 96.59845 -32.194673)
		(end 96.667066 -32.539432)
		(width 0.1397)
		(layer "B.Cu")
		(net "PCIE_SAS_C_CPU_RX_P2")
	)
	(arc
		(start 97.159572 -33.804606)
		(mid 97.236821 -33.920078)
		(end 97.263966 -34.05632)
		(width 0.1397)
		(layer "B.Cu")
		(net "PCIE_SAS_C_CPU_RX_P2")
	)
	(arc
		(start 97.263966 -34.8996)
		(mid 97.305091 -35.106348)
		(end 97.422208 -35.281616)
		(width 0.1397)
		(layer "B.Cu")
		(net "PCIE_SAS_C_CPU_RX_P2")
	)
	(segment
		(start 92.85351 -101.854)
		(end 93.853 -101.854)
		(width 0.1143)
		(layer "F.Cu")
		(net "UART_CTS")
	)
	(segment
		(start 98.298 -102.20833)
		(end 97.88652 -101.79685)
		(width 0.1143)
		(layer "F.Cu")
		(net "UART_CTS")
	)
	(segment
		(start 98.298 -102.68585)
		(end 98.298 -102.20833)
		(width 0.1143)
		(layer "F.Cu")
		(net "UART_CTS")
	)
	(segment
		(start 92.72651 -101.727)
		(end 92.85351 -101.854)
		(width 0.1143)
		(layer "F.Cu")
		(net "UART_CTS")
	)
	(segment
		(start 97.188782 -101.79685)
		(end 97.131632 -101.854)
		(width 0.1143)
		(layer "F.Cu")
		(net "UART_CTS")
	)
	(segment
		(start 105.349802 -102.350062)
		(end 104.849676 -102.850188)
		(width 0.1143)
		(layer "F.Cu")
		(net "UART_CTS")
	)
	(segment
		(start 97.131632 -101.854)
		(end 93.853 -101.854)
		(width 0.1143)
		(layer "F.Cu")
		(net "UART_CTS")
	)
	(segment
		(start 97.88652 -101.79685)
		(end 97.188782 -101.79685)
		(width 0.1143)
		(layer "F.Cu")
		(net "UART_CTS")
	)
	(via
		(at 104.849676 -102.850188)
		(size 0.508)
		(drill 0.254)
		(layers "F.Cu" "B.Cu")
		(net "UART_CTS")
	)
	(via
		(at 98.298 -102.68585)
		(size 0.508)
		(drill 0.254)
		(layers "F.Cu" "B.Cu")
		(net "UART_CTS")
	)
	(segment
		(start 99.822 -102.68585)
		(end 100.102162 -102.405688)
		(width 0.127)
		(layer "In2.Cu")
		(net "UART_CTS")
	)
	(segment
		(start 104.769158 -102.850188)
		(end 104.849676 -102.850188)
		(width 0.127)
		(layer "In2.Cu")
		(net "UART_CTS")
	)
	(segment
		(start 104.324658 -102.405688)
		(end 104.769158 -102.850188)
		(width 0.127)
		(layer "In2.Cu")
		(net "UART_CTS")
	)
	(segment
		(start 100.102162 -102.405688)
		(end 104.324658 -102.405688)
		(width 0.127)
		(layer "In2.Cu")
		(net "UART_CTS")
	)
	(segment
		(start 98.298 -102.68585)
		(end 99.822 -102.68585)
		(width 0.127)
		(layer "In2.Cu")
		(net "UART_CTS")
	)
	(segment
		(start 95.549974 -36.599876)
		(end 95.150178 -36.20008)
		(width 0.1397)
		(layer "F.Cu")
		(net "PCIE_SAS_C_CPU_RX_N0")
	)
	(via
		(at 95.150178 -36.20008)
		(size 0.508)
		(drill 0.254)
		(layers "F.Cu" "B.Cu")
		(net "PCIE_SAS_C_CPU_RX_N0")
	)
	(segment
		(start 95.670624 -34.003488)
		(end 95.674434 -34.007044)
		(width 0.1016)
		(layer "B.Cu")
		(net "PCIE_SAS_C_CPU_RX_N0")
	)
	(segment
		(start 93.99016 -31.9024)
		(end 93.99016 -31.904178)
		(width 0.1397)
		(layer "B.Cu")
		(net "PCIE_SAS_C_CPU_RX_N0")
	)
	(segment
		(start 95.413322 -35.936682)
		(end 95.396812 -35.953446)
		(width 0.0889)
		(layer "B.Cu")
		(net "PCIE_SAS_C_CPU_RX_N0")
	)
	(segment
		(start 95.54845 -35.30727)
		(end 95.54845 -35.6108)
		(width 0.0889)
		(layer "B.Cu")
		(net "PCIE_SAS_C_CPU_RX_N0")
	)
	(segment
		(start 95.733108 -34.969196)
		(end 95.656908 -35.045396)
		(width 0.0889)
		(layer "B.Cu")
		(net "PCIE_SAS_C_CPU_RX_N0")
	)
	(segment
		(start 95.396812 -35.953446)
		(end 95.150178 -36.20008)
		(width 0.0889)
		(layer "B.Cu")
		(net "PCIE_SAS_C_CPU_RX_N0")
	)
	(segment
		(start 95.823024 -34.3662)
		(end 95.823024 -34.752026)
		(width 0.0889)
		(layer "B.Cu")
		(net "PCIE_SAS_C_CPU_RX_N0")
	)
	(segment
		(start 94.286324 -32.619188)
		(end 95.670624 -34.003488)
		(width 0.1397)
		(layer "B.Cu")
		(net "PCIE_SAS_C_CPU_RX_N0")
	)
	(arc
		(start 95.54845 -35.6108)
		(mid 95.513275 -35.787167)
		(end 95.413322 -35.936682)
		(width 0.0889)
		(layer "B.Cu")
		(net "PCIE_SAS_C_CPU_RX_N0")
	)
	(arc
		(start 95.656908 -35.045396)
		(mid 95.576627 -35.165545)
		(end 95.54845 -35.30727)
		(width 0.0889)
		(layer "B.Cu")
		(net "PCIE_SAS_C_CPU_RX_N0")
	)
	(arc
		(start 95.823024 -34.752026)
		(mid 95.799648 -34.869543)
		(end 95.733108 -34.969196)
		(width 0.0889)
		(layer "B.Cu")
		(net "PCIE_SAS_C_CPU_RX_N0")
	)
	(arc
		(start 95.674434 -34.007044)
		(mid 95.784455 -34.171841)
		(end 95.823024 -34.3662)
		(width 0.0889)
		(layer "B.Cu")
		(net "PCIE_SAS_C_CPU_RX_N0")
	)
	(arc
		(start 93.99016 -31.904178)
		(mid 94.067131 -32.291138)
		(end 94.286324 -32.619188)
		(width 0.1397)
		(layer "B.Cu")
		(net "PCIE_SAS_C_CPU_RX_N0")
	)
	(segment
		(start 116.350034 -85.349842)
		(end 116.350034 -85.349588)
		(width 0.1143)
		(layer "F.Cu")
		(net "TEST_MUX_38")
	)
	(segment
		(start 116.350034 -85.349588)
		(end 115.850162 -84.849716)
		(width 0.1143)
		(layer "F.Cu")
		(net "TEST_MUX_38")
	)
	(via
		(at 115.850162 -84.849716)
		(size 0.508)
		(drill 0.254)
		(layers "F.Cu" "B.Cu")
		(net "TEST_MUX_38")
	)
	(segment
		(start 115.850162 -84.730844)
		(end 115.850162 -84.849716)
		(width 0.1143)
		(layer "B.Cu")
		(net "TEST_MUX_38")
	)
	(segment
		(start 115.83797 -81.661)
		(end 115.412012 -82.086958)
		(width 0.1143)
		(layer "B.Cu")
		(net "TEST_MUX_38")
	)
	(segment
		(start 115.412012 -84.292694)
		(end 115.850162 -84.730844)
		(width 0.1143)
		(layer "B.Cu")
		(net "TEST_MUX_38")
	)
	(segment
		(start 115.412012 -82.086958)
		(end 115.412012 -84.292694)
		(width 0.1143)
		(layer "B.Cu")
		(net "TEST_MUX_38")
	)
	(segment
		(start 89.055448 -38.174422)
		(end 90.688922 -38.174422)
		(width 0.1016)
		(layer "F.Cu")
		(net "SAS3008_RAID_TX_C_P3")
	)
	(segment
		(start 86.77656 -38.608)
		(end 86.856062 -38.528498)
		(width 0.1016)
		(layer "F.Cu")
		(net "SAS3008_RAID_TX_C_P3")
	)
	(segment
		(start 87.154766 -38.4048)
		(end 88.499188 -38.4048)
		(width 0.1016)
		(layer "F.Cu")
		(net "SAS3008_RAID_TX_C_P3")
	)
	(arc
		(start 86.856062 -38.528498)
		(mid 86.993109 -38.436926)
		(end 87.154766 -38.4048)
		(width 0.1016)
		(layer "F.Cu")
		(net "SAS3008_RAID_TX_C_P3")
	)
	(arc
		(start 90.688922 -38.174422)
		(mid 90.722053 -38.18103)
		(end 90.750136 -38.199822)
		(width 0.1016)
		(layer "F.Cu")
		(net "SAS3008_RAID_TX_C_P3")
	)
	(arc
		(start 88.805766 -38.2778)
		(mid 88.920321 -38.201257)
		(end 89.055448 -38.174422)
		(width 0.1016)
		(layer "F.Cu")
		(net "SAS3008_RAID_TX_C_P3")
	)
	(arc
		(start 88.499188 -38.4048)
		(mid 88.665111 -38.371796)
		(end 88.805766 -38.2778)
		(width 0.1016)
		(layer "F.Cu")
		(net "SAS3008_RAID_TX_C_P3")
	)
	(segment
		(start 99.70897 -78.613)
		(end 101.10597 -80.01)
		(width 0.1143)
		(layer "F.Cu")
		(net "EXP_IDDT")
	)
	(segment
		(start 100.47097 -76.8985)
		(end 99.70897 -77.6605)
		(width 0.1143)
		(layer "F.Cu")
		(net "EXP_IDDT")
	)
	(segment
		(start 99.70897 -77.6605)
		(end 99.70897 -78.613)
		(width 0.1143)
		(layer "F.Cu")
		(net "EXP_IDDT")
	)
	(segment
		(start 101.10597 -81.10601)
		(end 103.349806 -83.349846)
		(width 0.1143)
		(layer "F.Cu")
		(net "EXP_IDDT")
	)
	(segment
		(start 101.10597 -80.01)
		(end 101.10597 -81.10601)
		(width 0.1143)
		(layer "F.Cu")
		(net "EXP_IDDT")
	)
	(segment
		(start 100.350066 -35.80003)
		(end 100.350066 -35.790886)
		(width 0.1397)
		(layer "F.Cu")
		(net "PCIE_SAS_C_CPU_RX_P4")
	)
	(segment
		(start 100.350066 -35.790886)
		(end 99.95154 -35.39236)
		(width 0.1397)
		(layer "F.Cu")
		(net "PCIE_SAS_C_CPU_RX_P4")
	)
	(via
		(at 99.95154 -35.39236)
		(size 0.508)
		(drill 0.254)
		(layers "F.Cu" "B.Cu")
		(net "PCIE_SAS_C_CPU_RX_P4")
	)
	(segment
		(start 100.014532 -33.034732)
		(end 100.014532 -35.240214)
		(width 0.1397)
		(layer "B.Cu")
		(net "PCIE_SAS_C_CPU_RX_P4")
	)
	(segment
		(start 99.881182 -32.416496)
		(end 100.005134 -32.540448)
		(width 0.1397)
		(layer "B.Cu")
		(net "PCIE_SAS_C_CPU_RX_P4")
	)
	(segment
		(start 99.45116 -31.9024)
		(end 99.711764 -32.163004)
		(width 0.1397)
		(layer "B.Cu")
		(net "PCIE_SAS_C_CPU_RX_P4")
	)
	(segment
		(start 100.05441 -32.942276)
		(end 100.051616 -32.94507)
		(width 0.1397)
		(layer "B.Cu")
		(net "PCIE_SAS_C_CPU_RX_P4")
	)
	(segment
		(start 100.05441 -32.658812)
		(end 100.05441 -32.942276)
		(width 0.1397)
		(layer "B.Cu")
		(net "PCIE_SAS_C_CPU_RX_P4")
	)
	(arc
		(start 100.005134 -32.540448)
		(mid 100.041611 -32.59471)
		(end 100.05441 -32.658812)
		(width 0.1397)
		(layer "B.Cu")
		(net "PCIE_SAS_C_CPU_RX_P4")
	)
	(arc
		(start 100.014532 -35.240214)
		(mid 99.998156 -35.322544)
		(end 99.95154 -35.39236)
		(width 0.1397)
		(layer "B.Cu")
		(net "PCIE_SAS_C_CPU_RX_P4")
	)
	(arc
		(start 99.711764 -32.163004)
		(mid 99.76027 -32.222094)
		(end 99.796346 -32.289496)
		(width 0.1397)
		(layer "B.Cu")
		(net "PCIE_SAS_C_CPU_RX_P4")
	)
	(arc
		(start 100.051616 -32.94507)
		(mid 100.024183 -32.986221)
		(end 100.014532 -33.034732)
		(width 0.1397)
		(layer "B.Cu")
		(net "PCIE_SAS_C_CPU_RX_P4")
	)
	(arc
		(start 99.796346 -32.289496)
		(mid 99.832491 -32.357186)
		(end 99.881182 -32.416496)
		(width 0.1397)
		(layer "B.Cu")
		(net "PCIE_SAS_C_CPU_RX_P4")
	)
	(segment
		(start 100.350066 -49.39284)
		(end 99.953826 -48.9966)
		(width 0.3048)
		(layer "F.Cu")
		(net "P0V955_C")
	)
	(segment
		(start 106.750104 -46.199806)
		(end 106.750104 -46.190662)
		(width 0.3556)
		(layer "F.Cu")
		(net "P0V955_C")
	)
	(segment
		(start 105.14965 -46.199806)
		(end 104.7496 -45.799756)
		(width 0.3556)
		(layer "F.Cu")
		(net "P0V955_C")
	)
	(segment
		(start 104.35971 -48.599852)
		(end 104.756712 -48.996854)
		(width 0.3556)
		(layer "F.Cu")
		(net "P0V955_C")
	)
	(segment
		(start 104.359456 -43.800014)
		(end 104.756204 -44.196762)
		(width 0.3556)
		(layer "F.Cu")
		(net "P0V955_C")
	)
	(segment
		(start 104.350058 -48.599852)
		(end 104.35971 -48.599852)
		(width 0.3556)
		(layer "F.Cu")
		(net "P0V955_C")
	)
	(segment
		(start 104.359456 -46.999906)
		(end 104.759506 -47.399956)
		(width 0.3556)
		(layer "F.Cu")
		(net "P0V955_C")
	)
	(segment
		(start 98.36912 -48.986186)
		(end 98.351086 -49.00422)
		(width 0.2032)
		(layer "F.Cu")
		(net "P0V955_C")
	)
	(segment
		(start 106.750104 -44.590462)
		(end 106.356404 -44.196762)
		(width 0.3556)
		(layer "F.Cu")
		(net "P0V955_C")
	)
	(segment
		(start 105.150158 -44.59986)
		(end 105.150158 -44.590716)
		(width 0.3556)
		(layer "F.Cu")
		(net "P0V955_C")
	)
	(segment
		(start 98.36912 -48.297846)
		(end 98.36912 -48.986186)
		(width 0.2032)
		(layer "F.Cu")
		(net "P0V955_C")
	)
	(segment
		(start 101.159564 -42.199814)
		(end 101.556058 -42.596308)
		(width 0.3556)
		(layer "F.Cu")
		(net "P0V955_C")
	)
	(segment
		(start 106.750104 -42.990262)
		(end 106.356404 -42.596562)
		(width 0.3556)
		(layer "F.Cu")
		(net "P0V955_C")
	)
	(segment
		(start 105.950004 -46.999906)
		(end 106.350054 -47.399956)
		(width 0.3556)
		(layer "F.Cu")
		(net "P0V955_C")
	)
	(segment
		(start 99.549966 -43.809412)
		(end 99.94646 -44.205906)
		(width 0.3556)
		(layer "F.Cu")
		(net "P0V955_C")
	)
	(segment
		(start 101.950012 -46.190662)
		(end 101.55936 -45.80001)
		(width 0.3556)
		(layer "F.Cu")
		(net "P0V955_C")
	)
	(segment
		(start 105.150158 -47.800006)
		(end 105.150158 -47.790608)
		(width 0.3556)
		(layer "F.Cu")
		(net "P0V955_C")
	)
	(segment
		(start 101.950012 -42.999914)
		(end 101.950012 -42.990262)
		(width 0.3556)
		(layer "F.Cu")
		(net "P0V955_C")
	)
	(segment
		(start 104.350058 -45.39996)
		(end 104.350058 -45.400214)
		(width 0.3556)
		(layer "F.Cu")
		(net "P0V955_C")
	)
	(segment
		(start 100.350066 -47.800006)
		(end 100.350066 -47.790354)
		(width 0.3556)
		(layer "F.Cu")
		(net "P0V955_C")
	)
	(segment
		(start 100.350066 -46.199806)
		(end 100.350066 -46.190662)
		(width 0.3556)
		(layer "F.Cu")
		(net "P0V955_C")
	)
	(segment
		(start 101.150166 -42.199814)
		(end 101.159564 -42.199814)
		(width 0.3556)
		(layer "F.Cu")
		(net "P0V955_C")
	)
	(segment
		(start 106.750104 -41.409366)
		(end 105.959656 -42.199814)
		(width 0.3556)
		(layer "F.Cu")
		(net "P0V955_C")
	)
	(segment
		(start 100.350066 -49.399952)
		(end 100.350066 -49.39284)
		(width 0.3048)
		(layer "F.Cu")
		(net "P0V955_C")
	)
	(segment
		(start 103.549958 -46.199806)
		(end 103.549958 -46.190662)
		(width 0.3556)
		(layer "F.Cu")
		(net "P0V955_C")
	)
	(segment
		(start 105.959656 -42.199814)
		(end 105.950004 -42.199814)
		(width 0.3556)
		(layer "F.Cu")
		(net "P0V955_C")
	)
	(segment
		(start 106.750104 -44.59986)
		(end 106.750104 -44.590462)
		(width 0.3556)
		(layer "F.Cu")
		(net "P0V955_C")
	)
	(segment
		(start 101.950012 -47.790354)
		(end 101.559614 -47.399956)
		(width 0.3556)
		(layer "F.Cu")
		(net "P0V955_C")
	)
	(segment
		(start 102.759256 -45.39996)
		(end 103.159306 -45.80001)
		(width 0.3556)
		(layer "F.Cu")
		(net "P0V955_C")
	)
	(segment
		(start 101.950012 -47.800006)
		(end 101.950012 -47.790354)
		(width 0.3556)
		(layer "F.Cu")
		(net "P0V955_C")
	)
	(segment
		(start 106.750104 -49.390554)
		(end 106.356658 -48.997108)
		(width 0.3556)
		(layer "F.Cu")
		(net "P0V955_C")
	)
	(segment
		(start 103.549958 -41.399968)
		(end 103.549958 -41.390316)
		(width 0.3556)
		(layer "F.Cu")
		(net "P0V955_C")
	)
	(segment
		(start 99.549966 -45.39996)
		(end 99.560126 -45.39996)
		(width 0.3556)
		(layer "F.Cu")
		(net "P0V955_C")
	)
	(segment
		(start 101.150166 -46.999906)
		(end 101.159564 -46.999906)
		(width 0.3556)
		(layer "F.Cu")
		(net "P0V955_C")
	)
	(segment
		(start 101.150166 -48.609504)
		(end 101.546914 -49.006252)
		(width 0.3556)
		(layer "F.Cu")
		(net "P0V955_C")
	)
	(segment
		(start 99.559618 -46.999906)
		(end 99.959668 -47.399956)
		(width 0.3556)
		(layer "F.Cu")
		(net "P0V955_C")
	)
	(segment
		(start 86.614 -24.892)
		(end 85.725 -25.781)
		(width 0.3048)
		(layer "F.Cu")
		(net "P0V955_C")
	)
	(segment
		(start 103.549958 -44.59986)
		(end 103.549958 -44.590716)
		(width 0.3556)
		(layer "F.Cu")
		(net "P0V955_C")
	)
	(segment
		(start 102.759256 -43.800014)
		(end 103.156004 -44.196762)
		(width 0.3556)
		(layer "F.Cu")
		(net "P0V955_C")
	)
	(segment
		(start 106.750104 -47.800006)
		(end 106.350054 -47.399956)
		(width 0.3556)
		(layer "F.Cu")
		(net "P0V955_C")
	)
	(segment
		(start 101.950012 -42.990262)
		(end 101.556058 -42.596308)
		(width 0.3556)
		(layer "F.Cu")
		(net "P0V955_C")
	)
	(segment
		(start 105.150158 -42.999914)
		(end 105.150158 -42.990516)
		(width 0.3556)
		(layer "F.Cu")
		(net "P0V955_C")
	)
	(segment
		(start 103.549958 -41.390316)
		(end 103.156258 -40.996616)
		(width 0.3556)
		(layer "F.Cu")
		(net "P0V955_C")
	)
	(segment
		(start 103.549958 -47.800006)
		(end 103.149654 -47.399702)
		(width 0.3556)
		(layer "F.Cu")
		(net "P0V955_C")
	)
	(segment
		(start 105.959656 -43.800014)
		(end 106.356404 -44.196762)
		(width 0.3556)
		(layer "F.Cu")
		(net "P0V955_C")
	)
	(segment
		(start 100.350066 -42.999914)
		(end 100.350066 -42.990262)
		(width 0.3556)
		(layer "F.Cu")
		(net "P0V955_C")
	)
	(segment
		(start 100.093018 -49.657)
		(end 100.350066 -49.399952)
		(width 0.254)
		(layer "F.Cu")
		(net "P0V955_C")
	)
	(segment
		(start 104.359456 -42.199814)
		(end 104.756204 -42.596562)
		(width 0.3556)
		(layer "F.Cu")
		(net "P0V955_C")
	)
	(segment
		(start 106.750104 -46.190662)
		(end 106.356404 -45.796962)
		(width 0.3556)
		(layer "F.Cu")
		(net "P0V955_C")
	)
	(segment
		(start 100.350066 -47.790354)
		(end 99.959668 -47.399956)
		(width 0.3556)
		(layer "F.Cu")
		(net "P0V955_C")
	)
	(segment
		(start 100.340414 -44.59986)
		(end 99.94646 -44.205906)
		(width 0.3556)
		(layer "F.Cu")
		(net "P0V955_C")
	)
	(segment
		(start 105.150158 -41.399968)
		(end 105.150158 -41.390316)
		(width 0.3556)
		(layer "F.Cu")
		(net "P0V955_C")
	)
	(segment
		(start 105.150158 -47.790608)
		(end 104.759506 -47.399956)
		(width 0.3556)
		(layer "F.Cu")
		(net "P0V955_C")
	)
	(segment
		(start 106.750104 -41.399968)
		(end 106.750104 -41.409366)
		(width 0.3556)
		(layer "F.Cu")
		(net "P0V955_C")
	)
	(segment
		(start 100.350066 -46.190662)
		(end 99.959414 -45.80001)
		(width 0.3556)
		(layer "F.Cu")
		(net "P0V955_C")
	)
	(segment
		(start 104.350058 -46.999906)
		(end 104.359456 -46.999906)
		(width 0.3556)
		(layer "F.Cu")
		(net "P0V955_C")
	)
	(segment
		(start 99.959414 -45.799248)
		(end 99.959414 -45.80001)
		(width 0.3556)
		(layer "F.Cu")
		(net "P0V955_C")
	)
	(segment
		(start 105.150158 -46.199806)
		(end 105.14965 -46.199806)
		(width 0.3556)
		(layer "F.Cu")
		(net "P0V955_C")
	)
	(segment
		(start 105.950004 -43.800014)
		(end 105.959656 -43.800014)
		(width 0.3556)
		(layer "F.Cu")
		(net "P0V955_C")
	)
	(segment
		(start 103.549958 -42.990262)
		(end 103.15956 -42.599864)
		(width 0.3556)
		(layer "F.Cu")
		(net "P0V955_C")
	)
	(segment
		(start 99.560126 -45.39996)
		(end 99.959414 -45.799248)
		(width 0.3556)
		(layer "F.Cu")
		(net "P0V955_C")
	)
	(segment
		(start 103.549958 -44.590716)
		(end 103.156004 -44.196762)
		(width 0.3556)
		(layer "F.Cu")
		(net "P0V955_C")
	)
	(segment
		(start 98.75012 -47.800006)
		(end 98.75012 -47.916846)
		(width 0.2032)
		(layer "F.Cu")
		(net "P0V955_C")
	)
	(segment
		(start 101.950012 -44.59986)
		(end 101.940614 -44.59986)
		(width 0.3556)
		(layer "F.Cu")
		(net "P0V955_C")
	)
	(segment
		(start 99.549966 -50.199798)
		(end 100.092764 -49.657)
		(width 0.254)
		(layer "F.Cu")
		(net "P0V955_C")
	)
	(segment
		(start 106.750104 -49.399952)
		(end 106.750104 -49.390554)
		(width 0.3556)
		(layer "F.Cu")
		(net "P0V955_C")
	)
	(segment
		(start 105.150158 -44.590716)
		(end 104.756204 -44.196762)
		(width 0.3556)
		(layer "F.Cu")
		(net "P0V955_C")
	)
	(segment
		(start 105.959402 -45.39996)
		(end 106.356404 -45.796962)
		(width 0.3556)
		(layer "F.Cu")
		(net "P0V955_C")
	)
	(segment
		(start 105.150158 -42.990516)
		(end 104.756204 -42.596562)
		(width 0.3556)
		(layer "F.Cu")
		(net "P0V955_C")
	)
	(segment
		(start 104.350058 -42.199814)
		(end 104.359456 -42.199814)
		(width 0.3556)
		(layer "F.Cu")
		(net "P0V955_C")
	)
	(segment
		(start 102.750112 -46.999906)
		(end 102.750112 -47.00016)
		(width 0.3556)
		(layer "F.Cu")
		(net "P0V955_C")
	)
	(segment
		(start 105.950004 -45.39996)
		(end 105.959402 -45.39996)
		(width 0.3556)
		(layer "F.Cu")
		(net "P0V955_C")
	)
	(segment
		(start 100.350066 -42.990262)
		(end 99.956112 -42.596308)
		(width 0.3556)
		(layer "F.Cu")
		(net "P0V955_C")
	)
	(segment
		(start 104.350058 -43.800014)
		(end 104.359456 -43.800014)
		(width 0.3556)
		(layer "F.Cu")
		(net "P0V955_C")
	)
	(segment
		(start 104.350058 -45.400214)
		(end 104.7496 -45.799756)
		(width 0.3556)
		(layer "F.Cu")
		(net "P0V955_C")
	)
	(segment
		(start 101.940614 -44.59986)
		(end 101.54666 -44.205906)
		(width 0.3556)
		(layer "F.Cu")
		(net "P0V955_C")
	)
	(segment
		(start 102.750112 -47.00016)
		(end 103.149654 -47.399702)
		(width 0.3556)
		(layer "F.Cu")
		(net "P0V955_C")
	)
	(segment
		(start 101.950012 -46.199806)
		(end 101.950012 -46.190662)
		(width 0.3556)
		(layer "F.Cu")
		(net "P0V955_C")
	)
	(segment
		(start 101.150166 -45.39996)
		(end 101.15931 -45.39996)
		(width 0.3556)
		(layer "F.Cu")
		(net "P0V955_C")
	)
	(segment
		(start 106.356404 -42.596562)
		(end 105.959656 -42.199814)
		(width 0.3556)
		(layer "F.Cu")
		(net "P0V955_C")
	)
	(segment
		(start 102.75951 -42.199814)
		(end 103.15956 -42.599864)
		(width 0.3556)
		(layer "F.Cu")
		(net "P0V955_C")
	)
	(segment
		(start 98.75012 -47.916846)
		(end 98.36912 -48.297846)
		(width 0.2032)
		(layer "F.Cu")
		(net "P0V955_C")
	)
	(segment
		(start 105.950004 -48.599852)
		(end 105.959402 -48.599852)
		(width 0.3556)
		(layer "F.Cu")
		(net "P0V955_C")
	)
	(segment
		(start 99.549966 -46.999906)
		(end 99.559618 -46.999906)
		(width 0.3556)
		(layer "F.Cu")
		(net "P0V955_C")
	)
	(segment
		(start 102.750112 -43.800014)
		(end 102.759256 -43.800014)
		(width 0.3556)
		(layer "F.Cu")
		(net "P0V955_C")
	)
	(segment
		(start 103.549958 -42.999914)
		(end 103.549958 -42.990262)
		(width 0.3556)
		(layer "F.Cu")
		(net "P0V955_C")
	)
	(segment
		(start 102.750112 -42.199814)
		(end 102.75951 -42.199814)
		(width 0.3556)
		(layer "F.Cu")
		(net "P0V955_C")
	)
	(segment
		(start 105.959402 -48.599852)
		(end 106.356658 -48.997108)
		(width 0.3556)
		(layer "F.Cu")
		(net "P0V955_C")
	)
	(segment
		(start 102.750112 -45.39996)
		(end 102.759256 -45.39996)
		(width 0.3556)
		(layer "F.Cu")
		(net "P0V955_C")
	)
	(segment
		(start 101.150166 -43.800014)
		(end 101.150166 -43.809412)
		(width 0.3556)
		(layer "F.Cu")
		(net "P0V955_C")
	)
	(segment
		(start 100.092764 -49.657)
		(end 100.093018 -49.657)
		(width 0.254)
		(layer "F.Cu")
		(net "P0V955_C")
	)
	(segment
		(start 101.150166 -43.809412)
		(end 101.54666 -44.205906)
		(width 0.3556)
		(layer "F.Cu")
		(net "P0V955_C")
	)
	(segment
		(start 101.15931 -45.39996)
		(end 101.55936 -45.80001)
		(width 0.3556)
		(layer "F.Cu")
		(net "P0V955_C")
	)
	(segment
		(start 101.150166 -48.599852)
		(end 101.150166 -48.609504)
		(width 0.3556)
		(layer "F.Cu")
		(net "P0V955_C")
	)
	(segment
		(start 102.750112 -48.599852)
		(end 102.75951 -48.599852)
		(width 0.3556)
		(layer "F.Cu")
		(net "P0V955_C")
	)
	(segment
		(start 100.350066 -44.59986)
		(end 100.340414 -44.59986)
		(width 0.3556)
		(layer "F.Cu")
		(net "P0V955_C")
	)
	(segment
		(start 101.159564 -46.999906)
		(end 101.559614 -47.399956)
		(width 0.3556)
		(layer "F.Cu")
		(net "P0V955_C")
	)
	(segment
		(start 85.725 -25.781)
		(end 85.725 -25.908)
		(width 0.3048)
		(layer "F.Cu")
		(net "P0V955_C")
	)
	(segment
		(start 106.750104 -42.999914)
		(end 106.750104 -42.990262)
		(width 0.3556)
		(layer "F.Cu")
		(net "P0V955_C")
	)
	(segment
		(start 103.549958 -46.190662)
		(end 103.159306 -45.80001)
		(width 0.3556)
		(layer "F.Cu")
		(net "P0V955_C")
	)
	(segment
		(start 86.614 -24.8285)
		(end 86.614 -24.892)
		(width 0.3048)
		(layer "F.Cu")
		(net "P0V955_C")
	)
	(segment
		(start 99.549966 -43.800014)
		(end 99.549966 -43.809412)
		(width 0.3556)
		(layer "F.Cu")
		(net "P0V955_C")
	)
	(segment
		(start 102.75951 -48.599852)
		(end 103.156512 -48.996854)
		(width 0.3556)
		(layer "F.Cu")
		(net "P0V955_C")
	)
	(segment
		(start 105.150158 -41.390316)
		(end 104.756458 -40.996616)
		(width 0.3556)
		(layer "F.Cu")
		(net "P0V955_C")
	)
	(via
		(at 103.156258 -40.996616)
		(size 0.508)
		(drill 0.254)
		(layers "F.Cu" "B.Cu")
		(net "P0V955_C")
	)
	(via
		(at 101.092 -10.033)
		(size 0.7112)
		(drill 0.4064)
		(layers "F.Cu" "B.Cu")
		(net "P0V955_C")
	)
	(via
		(at 88.646 -9.779)
		(size 0.7112)
		(drill 0.4064)
		(layers "F.Cu" "B.Cu")
		(net "P0V955_C")
	)
	(via
		(at 103.15956 -42.599864)
		(size 0.508)
		(drill 0.254)
		(layers "F.Cu" "B.Cu")
		(net "P0V955_C")
	)
	(via
		(at 316.484 -66.929)
		(size 0.7112)
		(drill 0.4064)
		(layers "F.Cu" "B.Cu")
		(net "P0V955_C")
	)
	(via
		(at 76.454 -26.67)
		(size 0.7112)
		(drill 0.4064)
		(layers "F.Cu" "B.Cu")
		(net "P0V955_C")
	)
	(via
		(at 97.7392 -5.1054)
		(size 0.7112)
		(drill 0.4064)
		(layers "F.Cu" "B.Cu")
		(net "P0V955_C")
	)
	(via
		(at 104.756204 -44.196762)
		(size 0.508)
		(drill 0.254)
		(layers "F.Cu" "B.Cu")
		(net "P0V955_C")
	)
	(via
		(at 101.1682 -6.3754)
		(size 0.7112)
		(drill 0.4064)
		(layers "F.Cu" "B.Cu")
		(net "P0V955_C")
	)
	(via
		(at 75.184 -26.67)
		(size 0.7112)
		(drill 0.4064)
		(layers "F.Cu" "B.Cu")
		(net "P0V955_C")
	)
	(via
		(at 103.156004 -44.196762)
		(size 0.508)
		(drill 0.254)
		(layers "F.Cu" "B.Cu")
		(net "P0V955_C")
	)
	(via
		(at 104.7496 -45.799756)
		(size 0.508)
		(drill 0.254)
		(layers "F.Cu" "B.Cu")
		(net "P0V955_C")
	)
	(via
		(at 85.344 -6.858)
		(size 0.7112)
		(drill 0.4064)
		(layers "F.Cu" "B.Cu")
		(net "P0V955_C")
	)
	(via
		(at 98.351086 -49.00422)
		(size 0.508)
		(drill 0.254)
		(layers "F.Cu" "B.Cu")
		(net "P0V955_C")
	)
	(via
		(at 101.556058 -42.596308)
		(size 0.508)
		(drill 0.254)
		(layers "F.Cu" "B.Cu")
		(net "P0V955_C")
	)
	(via
		(at 100.0506 -7.7216)
		(size 0.7112)
		(drill 0.4064)
		(layers "F.Cu" "B.Cu")
		(net "P0V955_C")
	)
	(via
		(at 117.5258 -30.6832)
		(size 0.5588)
		(drill 0.3048)
		(layers "F.Cu" "B.Cu")
		(net "P0V955_C")
	)
	(via
		(at 106.350054 -47.399956)
		(size 0.508)
		(drill 0.254)
		(layers "F.Cu" "B.Cu")
		(net "P0V955_C")
	)
	(via
		(at 99.314 -9.017)
		(size 0.7112)
		(drill 0.4064)
		(layers "F.Cu" "B.Cu")
		(net "P0V955_C")
	)
	(via
		(at 88.646 -8.509)
		(size 0.7112)
		(drill 0.4064)
		(layers "F.Cu" "B.Cu")
		(net "P0V955_C")
	)
	(via
		(at 94.107 -18.3134)
		(size 0.7112)
		(drill 0.4064)
		(layers "F.Cu" "B.Cu")
		(net "P0V955_C")
	)
	(via
		(at 100.0252 -6.3754)
		(size 0.7112)
		(drill 0.4064)
		(layers "F.Cu" "B.Cu")
		(net "P0V955_C")
	)
	(via
		(at 101.1936 -7.7216)
		(size 0.7112)
		(drill 0.4064)
		(layers "F.Cu" "B.Cu")
		(net "P0V955_C")
	)
	(via
		(at 101.546914 -49.006252)
		(size 0.508)
		(drill 0.254)
		(layers "F.Cu" "B.Cu")
		(net "P0V955_C")
	)
	(via
		(at 103.149654 -47.399702)
		(size 0.508)
		(drill 0.254)
		(layers "F.Cu" "B.Cu")
		(net "P0V955_C")
	)
	(via
		(at 103.156512 -48.996854)
		(size 0.508)
		(drill 0.254)
		(layers "F.Cu" "B.Cu")
		(net "P0V955_C")
	)
	(via
		(at 101.559614 -47.399956)
		(size 0.508)
		(drill 0.254)
		(layers "F.Cu" "B.Cu")
		(net "P0V955_C")
	)
	(via
		(at 120.13946 -28.7909)
		(size 0.5588)
		(drill 0.3048)
		(layers "F.Cu" "B.Cu")
		(net "P0V955_C")
	)
	(via
		(at 100.457 -9.017)
		(size 0.7112)
		(drill 0.4064)
		(layers "F.Cu" "B.Cu")
		(net "P0V955_C")
	)
	(via
		(at 106.356404 -45.796962)
		(size 0.508)
		(drill 0.254)
		(layers "F.Cu" "B.Cu")
		(net "P0V955_C")
	)
	(via
		(at 103.159306 -45.80001)
		(size 0.508)
		(drill 0.254)
		(layers "F.Cu" "B.Cu")
		(net "P0V955_C")
	)
	(via
		(at 99.956112 -42.596308)
		(size 0.508)
		(drill 0.254)
		(layers "F.Cu" "B.Cu")
		(net "P0V955_C")
	)
	(via
		(at 98.9076 -7.7216)
		(size 0.7112)
		(drill 0.4064)
		(layers "F.Cu" "B.Cu")
		(net "P0V955_C")
	)
	(via
		(at 106.934 -58.801)
		(size 0.5588)
		(drill 0.3048)
		(layers "F.Cu" "B.Cu")
		(net "P0V955_C")
	)
	(via
		(at 173.99 -38.227)
		(size 0.7112)
		(drill 0.4064)
		(layers "F.Cu" "B.Cu")
		(net "P0V955_C")
	)
	(via
		(at 118.618 -30.099)
		(size 0.7112)
		(drill 0.4064)
		(layers "F.Cu" "B.Cu")
		(net "P0V955_C")
	)
	(via
		(at 83.947 -8.509)
		(size 0.7112)
		(drill 0.4064)
		(layers "F.Cu" "B.Cu")
		(net "P0V955_C")
	)
	(via
		(at 97.7392 -6.3754)
		(size 0.7112)
		(drill 0.4064)
		(layers "F.Cu" "B.Cu")
		(net "P0V955_C")
	)
	(via
		(at 98.8822 -6.3754)
		(size 0.7112)
		(drill 0.4064)
		(layers "F.Cu" "B.Cu")
		(net "P0V955_C")
	)
	(via
		(at 85.725 -25.908)
		(size 0.7112)
		(drill 0.4064)
		(layers "F.Cu" "B.Cu")
		(net "P0V955_C")
	)
	(via
		(at 99.959414 -45.80001)
		(size 0.508)
		(drill 0.254)
		(layers "F.Cu" "B.Cu")
		(net "P0V955_C")
	)
	(via
		(at 180.3654 -46.4058)
		(size 0.508)
		(drill 0.254)
		(layers "F.Cu" "B.Cu")
		(net "P0V955_C")
	)
	(via
		(at 83.947 -9.779)
		(size 0.7112)
		(drill 0.4064)
		(layers "F.Cu" "B.Cu")
		(net "P0V955_C")
	)
	(via
		(at 100.0252 -5.1054)
		(size 0.7112)
		(drill 0.4064)
		(layers "F.Cu" "B.Cu")
		(net "P0V955_C")
	)
	(via
		(at 96.647 -8.763)
		(size 0.7112)
		(drill 0.3556)
		(layers "F.Cu" "B.Cu")
		(net "P0V955_C")
	)
	(via
		(at 99.94646 -44.205906)
		(size 0.508)
		(drill 0.254)
		(layers "F.Cu" "B.Cu")
		(net "P0V955_C")
	)
	(via
		(at 327.533 -181.991)
		(size 0.508)
		(drill 0.254)
		(layers "F.Cu" "B.Cu")
		(net "P0V955_C")
	)
	(via
		(at 101.55936 -45.80001)
		(size 0.508)
		(drill 0.254)
		(layers "F.Cu" "B.Cu")
		(net "P0V955_C")
	)
	(via
		(at 101.54666 -44.205906)
		(size 0.508)
		(drill 0.254)
		(layers "F.Cu" "B.Cu")
		(net "P0V955_C")
	)
	(via
		(at 99.953826 -48.9966)
		(size 0.508)
		(drill 0.254)
		(layers "F.Cu" "B.Cu")
		(net "P0V955_C")
	)
	(via
		(at 101.1682 -5.1054)
		(size 0.7112)
		(drill 0.4064)
		(layers "F.Cu" "B.Cu")
		(net "P0V955_C")
	)
	(via
		(at 77.724 -26.67)
		(size 0.7112)
		(drill 0.4064)
		(layers "F.Cu" "B.Cu")
		(net "P0V955_C")
	)
	(via
		(at 76.6064 -28.0924)
		(size 0.7112)
		(drill 0.3556)
		(layers "F.Cu" "B.Cu")
		(net "P0V955_C")
	)
	(via
		(at 119.126 -28.702)
		(size 0.5588)
		(drill 0.3048)
		(layers "F.Cu" "B.Cu")
		(net "P0V955_C")
	)
	(via
		(at 106.356658 -48.997108)
		(size 0.508)
		(drill 0.254)
		(layers "F.Cu" "B.Cu")
		(net "P0V955_C")
	)
	(via
		(at 104.759506 -47.399956)
		(size 0.508)
		(drill 0.254)
		(layers "F.Cu" "B.Cu")
		(net "P0V955_C")
	)
	(via
		(at 104.756458 -40.996616)
		(size 0.508)
		(drill 0.254)
		(layers "F.Cu" "B.Cu")
		(net "P0V955_C")
	)
	(via
		(at 99.959668 -47.399956)
		(size 0.508)
		(drill 0.254)
		(layers "F.Cu" "B.Cu")
		(net "P0V955_C")
	)
	(via
		(at 101.6 -9.017)
		(size 0.7112)
		(drill 0.4064)
		(layers "F.Cu" "B.Cu")
		(net "P0V955_C")
	)
	(via
		(at 97.7646 -7.7216)
		(size 0.7112)
		(drill 0.4064)
		(layers "F.Cu" "B.Cu")
		(net "P0V955_C")
	)
	(via
		(at 104.756712 -48.996854)
		(size 0.508)
		(drill 0.254)
		(layers "F.Cu" "B.Cu")
		(net "P0V955_C")
	)
	(via
		(at 104.756204 -42.596562)
		(size 0.508)
		(drill 0.254)
		(layers "F.Cu" "B.Cu")
		(net "P0V955_C")
	)
	(via
		(at 87.376 -6.858)
		(size 0.7112)
		(drill 0.4064)
		(layers "F.Cu" "B.Cu")
		(net "P0V955_C")
	)
	(via
		(at 106.356404 -44.196762)
		(size 0.508)
		(drill 0.254)
		(layers "F.Cu" "B.Cu")
		(net "P0V955_C")
	)
	(via
		(at 106.356404 -42.596562)
		(size 0.508)
		(drill 0.254)
		(layers "F.Cu" "B.Cu")
		(net "P0V955_C")
	)
	(via
		(at 98.8822 -5.1054)
		(size 0.7112)
		(drill 0.4064)
		(layers "F.Cu" "B.Cu")
		(net "P0V955_C")
	)
	(segment
		(start 325.374 -181.9275)
		(end 327.4695 -181.9275)
		(width 0.508)
		(layer "B.Cu")
		(net "P0V955_C")
	)
	(segment
		(start 108.3945 -61.214)
		(end 108.3945 -60.2615)
		(width 0.508)
		(layer "B.Cu")
		(net "P0V955_C")
	)
	(segment
		(start 327.4695 -181.9275)
		(end 327.533 -181.991)
		(width 0.508)
		(layer "B.Cu")
		(net "P0V955_C")
	)
	(segment
		(start 108.3945 -60.2615)
		(end 106.934 -58.801)
		(width 0.508)
		(layer "B.Cu")
		(net "P0V955_C")
	)
	(segment
		(start 328.4982 -164.76726)
		(end 328.7268 -164.99586)
		(width 0.508)
		(layer "In2.Cu")
		(net "P0V955_C")
	)
	(segment
		(start 337.646518 -152.712928)
		(end 330.186284 -160.173162)
		(width 0.508)
		(layer "In2.Cu")
		(net "P0V955_C")
	)
	(segment
		(start 109.474 -53.213)
		(end 108.966 -52.705)
		(width 0.508)
		(layer "In2.Cu")
		(net "P0V955_C")
	)
	(segment
		(start 333.5655 -146.615404)
		(end 337.646518 -150.696422)
		(width 0.508)
		(layer "In2.Cu")
		(net "P0V955_C")
	)
	(segment
		(start 105.918 -58.801)
		(end 104.775 -57.658)
		(width 0.508)
		(layer "In2.Cu")
		(net "P0V955_C")
	)
	(segment
		(start 328.7268 -164.99586)
		(end 328.7268 -180.7972)
		(width 0.508)
		(layer "In2.Cu")
		(net "P0V955_C")
	)
	(segment
		(start 326.1868 -132.7912)
		(end 333.5655 -140.1699)
		(width 0.508)
		(layer "In2.Cu")
		(net "P0V955_C")
	)
	(segment
		(start 107.442 -52.705)
		(end 106.356658 -51.619658)
		(width 0.508)
		(layer "In2.Cu")
		(net "P0V955_C")
	)
	(segment
		(start 333.5655 -140.1699)
		(end 333.5655 -146.615404)
		(width 0.508)
		(layer "In2.Cu")
		(net "P0V955_C")
	)
	(segment
		(start 173.99 -40.0304)
		(end 173.99 -38.227)
		(width 0.508)
		(layer "In2.Cu")
		(net "P0V955_C")
	)
	(segment
		(start 106.356658 -51.619658)
		(end 106.356658 -48.997108)
		(width 0.508)
		(layer "In2.Cu")
		(net "P0V955_C")
	)
	(segment
		(start 316.484 -66.929)
		(end 318.438784 -66.929)
		(width 0.508)
		(layer "In2.Cu")
		(net "P0V955_C")
	)
	(segment
		(start 108.966 -54.61)
		(end 109.474 -54.102)
		(width 0.508)
		(layer "In2.Cu")
		(net "P0V955_C")
	)
	(segment
		(start 319.346072 -103.944928)
		(end 319.346072 -118.90248)
		(width 0.508)
		(layer "In2.Cu")
		(net "P0V955_C")
	)
	(segment
		(start 109.474 -54.102)
		(end 109.474 -53.213)
		(width 0.508)
		(layer "In2.Cu")
		(net "P0V955_C")
	)
	(segment
		(start 105.283 -54.61)
		(end 108.966 -54.61)
		(width 0.508)
		(layer "In2.Cu")
		(net "P0V955_C")
	)
	(segment
		(start 322.834 -85.725)
		(end 324.377558 -87.268558)
		(width 0.508)
		(layer "In2.Cu")
		(net "P0V955_C")
	)
	(segment
		(start 324.377558 -98.913442)
		(end 319.346072 -103.944928)
		(width 0.508)
		(layer "In2.Cu")
		(net "P0V955_C")
	)
	(segment
		(start 326.1868 -125.743208)
		(end 326.1868 -132.7912)
		(width 0.508)
		(layer "In2.Cu")
		(net "P0V955_C")
	)
	(segment
		(start 328.7268 -180.7972)
		(end 327.533 -181.991)
		(width 0.508)
		(layer "In2.Cu")
		(net "P0V955_C")
	)
	(segment
		(start 337.646518 -150.696422)
		(end 337.646518 -152.712928)
		(width 0.508)
		(layer "In2.Cu")
		(net "P0V955_C")
	)
	(segment
		(start 180.3654 -46.4058)
		(end 173.99 -40.0304)
		(width 0.508)
		(layer "In2.Cu")
		(net "P0V955_C")
	)
	(segment
		(start 319.346072 -118.90248)
		(end 326.1868 -125.743208)
		(width 0.508)
		(layer "In2.Cu")
		(net "P0V955_C")
	)
	(segment
		(start 328.4982 -161.8615)
		(end 328.4982 -164.76726)
		(width 0.508)
		(layer "In2.Cu")
		(net "P0V955_C")
	)
	(segment
		(start 322.834 -71.324216)
		(end 322.834 -85.725)
		(width 0.508)
		(layer "In2.Cu")
		(net "P0V955_C")
	)
	(segment
		(start 108.966 -52.705)
		(end 107.442 -52.705)
		(width 0.508)
		(layer "In2.Cu")
		(net "P0V955_C")
	)
	(segment
		(start 104.775 -55.118)
		(end 105.283 -54.61)
		(width 0.508)
		(layer "In2.Cu")
		(net "P0V955_C")
	)
	(segment
		(start 318.438784 -66.929)
		(end 322.834 -71.324216)
		(width 0.508)
		(layer "In2.Cu")
		(net "P0V955_C")
	)
	(segment
		(start 106.934 -58.801)
		(end 105.918 -58.801)
		(width 0.508)
		(layer "In2.Cu")
		(net "P0V955_C")
	)
	(segment
		(start 330.186284 -160.173162)
		(end 328.4982 -161.8615)
		(width 0.508)
		(layer "In2.Cu")
		(net "P0V955_C")
	)
	(segment
		(start 324.377558 -87.268558)
		(end 324.377558 -98.913442)
		(width 0.508)
		(layer "In2.Cu")
		(net "P0V955_C")
	)
	(segment
		(start 104.775 -57.658)
		(end 104.775 -55.118)
		(width 0.508)
		(layer "In2.Cu")
		(net "P0V955_C")
	)
	(segment
		(start 301.842932 -67.437)
		(end 305.943 -67.437)
		(width 0.508)
		(layer "In5.Cu")
		(net "P0V955_C")
	)
	(segment
		(start 185.5724 -46.3804)
		(end 201.168 -61.976)
		(width 0.508)
		(layer "In5.Cu")
		(net "P0V955_C")
	)
	(segment
		(start 232.537 -61.976)
		(end 237.4138 -66.8528)
		(width 0.508)
		(layer "In5.Cu")
		(net "P0V955_C")
	)
	(segment
		(start 306.578 -66.802)
		(end 316.357 -66.802)
		(width 0.508)
		(layer "In5.Cu")
		(net "P0V955_C")
	)
	(segment
		(start 95.7326 -19.939)
		(end 119.253 -19.939)
		(width 0.508)
		(layer "In5.Cu")
		(net "P0V955_C")
	)
	(segment
		(start 129.2733 -29.9593)
		(end 133.0833 -29.9593)
		(width 0.508)
		(layer "In5.Cu")
		(net "P0V955_C")
	)
	(segment
		(start 316.357 -66.802)
		(end 316.484 -66.929)
		(width 0.508)
		(layer "In5.Cu")
		(net "P0V955_C")
	)
	(segment
		(start 278.3332 -66.8528)
		(end 278.6888 -66.4972)
		(width 0.508)
		(layer "In5.Cu")
		(net "P0V955_C")
	)
	(segment
		(start 180.3654 -46.4058)
		(end 180.3908 -46.3804)
		(width 0.508)
		(layer "In5.Cu")
		(net "P0V955_C")
	)
	(segment
		(start 237.4138 -66.8528)
		(end 278.3332 -66.8528)
		(width 0.508)
		(layer "In5.Cu")
		(net "P0V955_C")
	)
	(segment
		(start 278.6888 -66.4972)
		(end 294.4622 -66.4972)
		(width 0.508)
		(layer "In5.Cu")
		(net "P0V955_C")
	)
	(segment
		(start 133.0833 -29.9593)
		(end 141.351 -38.227)
		(width 0.508)
		(layer "In5.Cu")
		(net "P0V955_C")
	)
	(segment
		(start 301.207932 -66.802)
		(end 301.842932 -67.437)
		(width 0.508)
		(layer "In5.Cu")
		(net "P0V955_C")
	)
	(segment
		(start 294.4622 -66.4972)
		(end 294.767 -66.802)
		(width 0.508)
		(layer "In5.Cu")
		(net "P0V955_C")
	)
	(segment
		(start 94.107 -18.3134)
		(end 95.7326 -19.939)
		(width 0.508)
		(layer "In5.Cu")
		(net "P0V955_C")
	)
	(segment
		(start 201.168 -61.976)
		(end 232.537 -61.976)
		(width 0.508)
		(layer "In5.Cu")
		(net "P0V955_C")
	)
	(segment
		(start 119.253 -19.939)
		(end 129.2733 -29.9593)
		(width 0.508)
		(layer "In5.Cu")
		(net "P0V955_C")
	)
	(segment
		(start 305.943 -67.437)
		(end 306.578 -66.802)
		(width 0.508)
		(layer "In5.Cu")
		(net "P0V955_C")
	)
	(segment
		(start 294.767 -66.802)
		(end 301.207932 -66.802)
		(width 0.508)
		(layer "In5.Cu")
		(net "P0V955_C")
	)
	(segment
		(start 141.351 -38.227)
		(end 173.99 -38.227)
		(width 0.508)
		(layer "In5.Cu")
		(net "P0V955_C")
	)
	(segment
		(start 180.3908 -46.3804)
		(end 185.5724 -46.3804)
		(width 0.508)
		(layer "In5.Cu")
		(net "P0V955_C")
	)
	(segment
		(start 117.350032 -83.126072)
		(end 117.350032 -83.349846)
		(width 0.1143)
		(layer "F.Cu")
		(net "TEST_MUX_39")
	)
	(segment
		(start 114.82197 -79.042006)
		(end 116.604034 -80.82407)
		(width 0.1143)
		(layer "F.Cu")
		(net "TEST_MUX_39")
	)
	(segment
		(start 114.82197 -78.359)
		(end 114.82197 -79.042006)
		(width 0.1143)
		(layer "F.Cu")
		(net "TEST_MUX_39")
	)
	(segment
		(start 116.604034 -80.82407)
		(end 116.604034 -82.046826)
		(width 0.1143)
		(layer "F.Cu")
		(net "TEST_MUX_39")
	)
	(segment
		(start 116.743734 -82.519774)
		(end 117.350032 -83.126072)
		(width 0.1143)
		(layer "F.Cu")
		(net "TEST_MUX_39")
	)
	(segment
		(start 116.743734 -82.186526)
		(end 116.743734 -82.519774)
		(width 0.1143)
		(layer "F.Cu")
		(net "TEST_MUX_39")
	)
	(segment
		(start 116.604034 -82.046826)
		(end 116.743734 -82.186526)
		(width 0.1143)
		(layer "F.Cu")
		(net "TEST_MUX_39")
	)
	(segment
		(start 55.168038 -133.392672)
		(end 56.558942 -133.392672)
		(width 0.1143)
		(layer "F.Cu")
		(net "RESET_N")
	)
	(segment
		(start 57.899046 -133.392672)
		(end 57.993026 -133.298692)
		(width 0.1143)
		(layer "F.Cu")
		(net "RESET_N")
	)
	(segment
		(start 56.558942 -133.392672)
		(end 57.899046 -133.392672)
		(width 0.1143)
		(layer "F.Cu")
		(net "RESET_N")
	)
	(segment
		(start 54.82209 -136.60882)
		(end 54.82209 -133.73862)
		(width 0.1143)
		(layer "F.Cu")
		(net "RESET_N")
	)
	(segment
		(start 54.28615 -137.14476)
		(end 54.82209 -136.60882)
		(width 0.1143)
		(layer "F.Cu")
		(net "RESET_N")
	)
	(segment
		(start 54.82209 -133.73862)
		(end 55.168038 -133.392672)
		(width 0.1143)
		(layer "F.Cu")
		(net "RESET_N")
	)
	(segment
		(start 102.349808 -83.238848)
		(end 101.732842 -82.621882)
		(width 0.1143)
		(layer "F.Cu")
		(net "RESET_N")
	)
	(segment
		(start 102.349808 -83.349846)
		(end 102.349808 -83.238848)
		(width 0.1143)
		(layer "F.Cu")
		(net "RESET_N")
	)
	(segment
		(start 52.90947 -137.14476)
		(end 54.28615 -137.14476)
		(width 0.1143)
		(layer "F.Cu")
		(net "RESET_N")
	)
	(via
		(at 57.84977 -132.3086)
		(size 0.7112)
		(drill 0.3556)
		(layers "F.Cu" "B.Cu")
		(net "RESET_N")
	)
	(via
		(at 57.993026 -133.298692)
		(size 0.5588)
		(drill 0.3048)
		(layers "F.Cu" "B.Cu")
		(net "RESET_N")
	)
	(via
		(at 101.732842 -82.621882)
		(size 0.508)
		(drill 0.254)
		(layers "F.Cu" "B.Cu")
		(net "RESET_N")
	)
	(segment
		(start 57.993026 -132.451856)
		(end 57.84977 -132.3086)
		(width 0.1143)
		(layer "B.Cu")
		(net "RESET_N")
	)
	(segment
		(start 57.993026 -133.298692)
		(end 57.993026 -132.451856)
		(width 0.1143)
		(layer "B.Cu")
		(net "RESET_N")
	)
	(segment
		(start 57.68467 -113.874296)
		(end 79.610966 -91.948)
		(width 0.127)
		(layer "In2.Cu")
		(net "RESET_N")
	)
	(segment
		(start 98.430588 -83.2993)
		(end 98.633788 -83.0961)
		(width 0.127)
		(layer "In2.Cu")
		(net "RESET_N")
	)
	(segment
		(start 101.161088 -82.621882)
		(end 101.732842 -82.621882)
		(width 0.127)
		(layer "In2.Cu")
		(net "RESET_N")
	)
	(segment
		(start 94.746318 -85.344)
		(end 97.04197 -83.048348)
		(width 0.127)
		(layer "In2.Cu")
		(net "RESET_N")
	)
	(segment
		(start 90.043 -85.344)
		(end 94.746318 -85.344)
		(width 0.127)
		(layer "In2.Cu")
		(net "RESET_N")
	)
	(segment
		(start 57.68467 -132.990336)
		(end 57.68467 -113.874296)
		(width 0.127)
		(layer "In2.Cu")
		(net "RESET_N")
	)
	(segment
		(start 98.633788 -83.0961)
		(end 100.68687 -83.0961)
		(width 0.127)
		(layer "In2.Cu")
		(net "RESET_N")
	)
	(segment
		(start 97.771458 -83.048348)
		(end 98.02241 -83.2993)
		(width 0.127)
		(layer "In2.Cu")
		(net "RESET_N")
	)
	(segment
		(start 84.526628 -89.894156)
		(end 84.943188 -89.894156)
		(width 0.127)
		(layer "In2.Cu")
		(net "RESET_N")
	)
	(segment
		(start 57.993026 -133.298692)
		(end 57.68467 -132.990336)
		(width 0.127)
		(layer "In2.Cu")
		(net "RESET_N")
	)
	(segment
		(start 97.04197 -83.048348)
		(end 97.771458 -83.048348)
		(width 0.127)
		(layer "In2.Cu")
		(net "RESET_N")
	)
	(segment
		(start 82.472784 -91.948)
		(end 84.526628 -89.894156)
		(width 0.127)
		(layer "In2.Cu")
		(net "RESET_N")
	)
	(segment
		(start 100.68687 -83.0961)
		(end 101.161088 -82.621882)
		(width 0.127)
		(layer "In2.Cu")
		(net "RESET_N")
	)
	(segment
		(start 98.02241 -83.2993)
		(end 98.430588 -83.2993)
		(width 0.127)
		(layer "In2.Cu")
		(net "RESET_N")
	)
	(segment
		(start 84.943188 -89.894156)
		(end 87.587836 -87.249508)
		(width 0.127)
		(layer "In2.Cu")
		(net "RESET_N")
	)
	(segment
		(start 88.137492 -87.249508)
		(end 90.043 -85.344)
		(width 0.127)
		(layer "In2.Cu")
		(net "RESET_N")
	)
	(segment
		(start 87.587836 -87.249508)
		(end 88.137492 -87.249508)
		(width 0.127)
		(layer "In2.Cu")
		(net "RESET_N")
	)
	(segment
		(start 79.610966 -91.948)
		(end 82.472784 -91.948)
		(width 0.127)
		(layer "In2.Cu")
		(net "RESET_N")
	)
	(segment
		(start 86.99119 -38.0619)
		(end 88.498934 -38.0619)
		(width 0.1016)
		(layer "F.Cu")
		(net "SAS3008_RAID_TX_C_N3")
	)
	(segment
		(start 89.055702 -37.831522)
		(end 90.838274 -37.831522)
		(width 0.1016)
		(layer "F.Cu")
		(net "SAS3008_RAID_TX_C_N3")
	)
	(segment
		(start 90.887296 -37.851842)
		(end 90.907616 -37.872162)
		(width 0.1016)
		(layer "F.Cu")
		(net "SAS3008_RAID_TX_C_N3")
	)
	(segment
		(start 91.400376 -38.199822)
		(end 91.549982 -38.199822)
		(width 0.1016)
		(layer "F.Cu")
		(net "SAS3008_RAID_TX_C_N3")
	)
	(segment
		(start 91.028012 -37.956744)
		(end 91.17965 -38.108382)
		(width 0.1016)
		(layer "F.Cu")
		(net "SAS3008_RAID_TX_C_N3")
	)
	(arc
		(start 90.838274 -37.831522)
		(mid 90.86481 -37.8368)
		(end 90.887296 -37.851842)
		(width 0.1016)
		(layer "F.Cu")
		(net "SAS3008_RAID_TX_C_N3")
	)
	(arc
		(start 86.77656 -37.973)
		(mid 86.875033 -38.038798)
		(end 86.99119 -38.0619)
		(width 0.1016)
		(layer "F.Cu")
		(net "SAS3008_RAID_TX_C_N3")
	)
	(arc
		(start 90.907616 -37.872162)
		(mid 90.97149 -37.909222)
		(end 91.028012 -37.956744)
		(width 0.1016)
		(layer "F.Cu")
		(net "SAS3008_RAID_TX_C_N3")
	)
	(arc
		(start 91.17965 -38.108382)
		(mid 91.28092 -38.176048)
		(end 91.400376 -38.199822)
		(width 0.1016)
		(layer "F.Cu")
		(net "SAS3008_RAID_TX_C_N3")
	)
	(arc
		(start 88.498934 -38.0619)
		(mid 88.533718 -38.054963)
		(end 88.563196 -38.03523)
		(width 0.1016)
		(layer "F.Cu")
		(net "SAS3008_RAID_TX_C_N3")
	)
	(arc
		(start 88.563196 -38.03523)
		(mid 88.789176 -37.884358)
		(end 89.055702 -37.831522)
		(width 0.1016)
		(layer "F.Cu")
		(net "SAS3008_RAID_TX_C_N3")
	)
	(segment
		(start 116.23421 -48.764444)
		(end 117.4115 -49.941734)
		(width 0.1143)
		(layer "F.Cu")
		(net "SBL_SDA")
	)
	(segment
		(start 243.32946 -48.530256)
		(end 243.332 -48.532796)
		(width 0.1143)
		(layer "F.Cu")
		(net "SBL_SDA")
	)
	(segment
		(start 125.965966 -46.355)
		(end 125.965966 -41.783)
		(width 0.1143)
		(layer "F.Cu")
		(net "SBL_SDA")
	)
	(segment
		(start 121.393966 -50.927)
		(end 125.965966 -46.355)
		(width 0.1143)
		(layer "F.Cu")
		(net "SBL_SDA")
	)
	(segment
		(start 248.939812 -54.502812)
		(end 245.364 -50.927)
		(width 0.1143)
		(layer "F.Cu")
		(net "SBL_SDA")
	)
	(segment
		(start 243.332 -48.895)
		(end 245.364 -50.927)
		(width 0.1143)
		(layer "F.Cu")
		(net "SBL_SDA")
	)
	(segment
		(start 118.3005 -50.927)
		(end 121.393966 -50.927)
		(width 0.1143)
		(layer "F.Cu")
		(net "SBL_SDA")
	)
	(segment
		(start 115.901216 -48.433482)
		(end 116.232178 -48.764444)
		(width 0.1143)
		(layer "F.Cu")
		(net "SBL_SDA")
	)
	(segment
		(start 243.332 -48.532796)
		(end 243.332 -48.895)
		(width 0.1143)
		(layer "F.Cu")
		(net "SBL_SDA")
	)
	(segment
		(start 114.469672 -46.999906)
		(end 115.901216 -48.43145)
		(width 0.1143)
		(layer "F.Cu")
		(net "SBL_SDA")
	)
	(segment
		(start 115.901216 -48.43145)
		(end 115.901216 -48.433482)
		(width 0.1143)
		(layer "F.Cu")
		(net "SBL_SDA")
	)
	(segment
		(start 249.815096 -54.502812)
		(end 248.939812 -54.502812)
		(width 0.1143)
		(layer "F.Cu")
		(net "SBL_SDA")
	)
	(segment
		(start 117.4115 -49.941734)
		(end 117.4115 -50.038)
		(width 0.1143)
		(layer "F.Cu")
		(net "SBL_SDA")
	)
	(segment
		(start 117.4115 -50.038)
		(end 118.3005 -50.927)
		(width 0.1143)
		(layer "F.Cu")
		(net "SBL_SDA")
	)
	(segment
		(start 116.232178 -48.764444)
		(end 116.23421 -48.764444)
		(width 0.1143)
		(layer "F.Cu")
		(net "SBL_SDA")
	)
	(segment
		(start 113.949988 -46.999906)
		(end 114.469672 -46.999906)
		(width 0.1143)
		(layer "F.Cu")
		(net "SBL_SDA")
	)
	(via
		(at 245.364 -50.927)
		(size 0.7112)
		(drill 0.3556)
		(layers "F.Cu" "B.Cu")
		(net "SBL_SDA")
	)
	(via
		(at 243.32946 -48.530256)
		(size 0.5588)
		(drill 0.3048)
		(layers "F.Cu" "B.Cu")
		(net "SBL_SDA")
	)
	(via
		(at 125.965966 -41.783)
		(size 0.5588)
		(drill 0.3048)
		(layers "F.Cu" "B.Cu")
		(net "SBL_SDA")
	)
	(segment
		(start 131.595368 -40.997632)
		(end 130.81 -41.783)
		(width 0.127)
		(layer "In5.Cu")
		(net "SBL_SDA")
	)
	(segment
		(start 130.81 -41.783)
		(end 125.965966 -41.783)
		(width 0.127)
		(layer "In5.Cu")
		(net "SBL_SDA")
	)
	(segment
		(start 243.32946 -48.530256)
		(end 210.836256 -48.530256)
		(width 0.127)
		(layer "In5.Cu")
		(net "SBL_SDA")
	)
	(segment
		(start 210.836256 -48.530256)
		(end 203.303632 -40.997632)
		(width 0.127)
		(layer "In5.Cu")
		(net "SBL_SDA")
	)
	(segment
		(start 203.303632 -40.997632)
		(end 131.595368 -40.997632)
		(width 0.127)
		(layer "In5.Cu")
		(net "SBL_SDA")
	)
	(segment
		(start 100.350066 -36.599876)
		(end 99.95027 -36.20008)
		(width 0.1397)
		(layer "F.Cu")
		(net "PCIE_SAS_C_CPU_RX_N4")
	)
	(via
		(at 99.95027 -36.20008)
		(size 0.508)
		(drill 0.254)
		(layers "F.Cu" "B.Cu")
		(net "PCIE_SAS_C_CPU_RX_N4")
	)
	(segment
		(start 100.159058 -32.209232)
		(end 100.247704 -32.297878)
		(width 0.1397)
		(layer "B.Cu")
		(net "PCIE_SAS_C_CPU_RX_N4")
	)
	(segment
		(start 100.39731 -32.658812)
		(end 100.39731 -33.0708)
		(width 0.1397)
		(layer "B.Cu")
		(net "PCIE_SAS_C_CPU_RX_N4")
	)
	(segment
		(start 100.08616 -31.9024)
		(end 100.08616 -32.03321)
		(width 0.1397)
		(layer "B.Cu")
		(net "PCIE_SAS_C_CPU_RX_N4")
	)
	(segment
		(start 99.95027 -36.078668)
		(end 99.95027 -36.20008)
		(width 0.0889)
		(layer "B.Cu")
		(net "PCIE_SAS_C_CPU_RX_N4")
	)
	(segment
		(start 100.21824 -35.706812)
		(end 100.023676 -35.901376)
		(width 0.0889)
		(layer "B.Cu")
		(net "PCIE_SAS_C_CPU_RX_N4")
	)
	(segment
		(start 100.357432 -33.167066)
		(end 100.357432 -35.052)
		(width 0.1397)
		(layer "B.Cu")
		(net "PCIE_SAS_C_CPU_RX_N4")
	)
	(segment
		(start 100.357432 -35.052)
		(end 100.357432 -35.37077)
		(width 0.0889)
		(layer "B.Cu")
		(net "PCIE_SAS_C_CPU_RX_N4")
	)
	(arc
		(start 100.247704 -32.297878)
		(mid 100.358407 -32.463462)
		(end 100.39731 -32.658812)
		(width 0.1397)
		(layer "B.Cu")
		(net "PCIE_SAS_C_CPU_RX_N4")
	)
	(arc
		(start 100.023676 -35.901376)
		(mid 99.969325 -35.982718)
		(end 99.95027 -36.078668)
		(width 0.0889)
		(layer "B.Cu")
		(net "PCIE_SAS_C_CPU_RX_N4")
	)
	(arc
		(start 100.39731 -33.0708)
		(mid 100.367798 -33.114967)
		(end 100.357432 -33.167066)
		(width 0.1397)
		(layer "B.Cu")
		(net "PCIE_SAS_C_CPU_RX_N4")
	)
	(arc
		(start 100.357432 -35.37077)
		(mid 100.321257 -35.552634)
		(end 100.21824 -35.706812)
		(width 0.0889)
		(layer "B.Cu")
		(net "PCIE_SAS_C_CPU_RX_N4")
	)
	(arc
		(start 100.08616 -32.03321)
		(mid 100.105108 -32.128468)
		(end 100.159058 -32.209232)
		(width 0.1397)
		(layer "B.Cu")
		(net "PCIE_SAS_C_CPU_RX_N4")
	)
	(segment
		(start 117.350032 -86.34984)
		(end 117.850158 -85.849714)
		(width 0.1143)
		(layer "F.Cu")
		(net "TEST_MUX_36")
	)
	(via
		(at 117.850158 -85.849714)
		(size 0.508)
		(drill 0.254)
		(layers "F.Cu" "B.Cu")
		(net "TEST_MUX_36")
	)
	(segment
		(start 118.020084 -85.849714)
		(end 117.850158 -85.849714)
		(width 0.1143)
		(layer "B.Cu")
		(net "TEST_MUX_36")
	)
	(segment
		(start 119.90197 -86.741)
		(end 119.87657 -86.741)
		(width 0.1143)
		(layer "B.Cu")
		(net "TEST_MUX_36")
	)
	(segment
		(start 119.59082 -86.45525)
		(end 118.62562 -86.45525)
		(width 0.1143)
		(layer "B.Cu")
		(net "TEST_MUX_36")
	)
	(segment
		(start 118.62562 -86.45525)
		(end 118.020084 -85.849714)
		(width 0.1143)
		(layer "B.Cu")
		(net "TEST_MUX_36")
	)
	(segment
		(start 119.87657 -86.741)
		(end 119.59082 -86.45525)
		(width 0.1143)
		(layer "B.Cu")
		(net "TEST_MUX_36")
	)
	(segment
		(start 96.15297 -103.759)
		(end 97.537016 -103.759)
		(width 0.1143)
		(layer "F.Cu")
		(net "SDB_R_TX")
	)
	(segment
		(start 97.537016 -103.759)
		(end 97.664016 -103.632)
		(width 0.1143)
		(layer "F.Cu")
		(net "SDB_R_TX")
	)
	(segment
		(start 102.349808 -103.35006)
		(end 102.182168 -103.5177)
		(width 0.1143)
		(layer "F.Cu")
		(net "SDB_R_TX")
	)
	(segment
		(start 102.182168 -103.5177)
		(end 97.905316 -103.5177)
		(width 0.1143)
		(layer "F.Cu")
		(net "SDB_R_TX")
	)
	(segment
		(start 97.791016 -103.632)
		(end 97.664016 -103.632)
		(width 0.1143)
		(layer "F.Cu")
		(net "SDB_R_TX")
	)
	(segment
		(start 97.905316 -103.5177)
		(end 97.791016 -103.632)
		(width 0.1143)
		(layer "F.Cu")
		(net "SDB_R_TX")
	)
	(via
		(at 97.664016 -103.632)
		(size 0.7112)
		(drill 0.3556)
		(layers "F.Cu" "B.Cu")
		(net "SDB_R_TX")
	)
	(segment
		(start 87.899748 -42.996358)
		(end 88.673178 -42.222928)
		(width 0.1016)
		(layer "F.Cu")
		(net "SAS3008_RAID_TX_C_P5")
	)
	(segment
		(start 90.724736 -42.174414)
		(end 90.750136 -42.199814)
		(width 0.1016)
		(layer "F.Cu")
		(net "SAS3008_RAID_TX_C_P5")
	)
	(segment
		(start 86.77656 -43.561)
		(end 86.994746 -43.342814)
		(width 0.1016)
		(layer "F.Cu")
		(net "SAS3008_RAID_TX_C_P5")
	)
	(segment
		(start 87.11184 -43.2943)
		(end 87.18042 -43.2943)
		(width 0.1016)
		(layer "F.Cu")
		(net "SAS3008_RAID_TX_C_P5")
	)
	(segment
		(start 88.790018 -42.174414)
		(end 90.724736 -42.174414)
		(width 0.1016)
		(layer "F.Cu")
		(net "SAS3008_RAID_TX_C_P5")
	)
	(arc
		(start 88.673178 -42.222928)
		(mid 88.72677 -42.187026)
		(end 88.790018 -42.174414)
		(width 0.1016)
		(layer "F.Cu")
		(net "SAS3008_RAID_TX_C_P5")
	)
	(arc
		(start 86.994746 -43.342814)
		(mid 87.048469 -43.306917)
		(end 87.11184 -43.2943)
		(width 0.1016)
		(layer "F.Cu")
		(net "SAS3008_RAID_TX_C_P5")
	)
	(arc
		(start 87.18042 -43.2943)
		(mid 87.569727 -43.21688)
		(end 87.899748 -42.996358)
		(width 0.1016)
		(layer "F.Cu")
		(net "SAS3008_RAID_TX_C_P5")
	)
	(segment
		(start 107.349798 -89.349834)
		(end 106.849672 -88.849708)
		(width 0.1143)
		(layer "F.Cu")
		(net "EXP_CPU_MODE_0")
	)
	(segment
		(start 98.18497 -87.884)
		(end 98.56597 -87.884)
		(width 0.1143)
		(layer "F.Cu")
		(net "EXP_CPU_MODE_0")
	)
	(segment
		(start 98.56597 -87.884)
		(end 100.59797 -85.852)
		(width 0.1143)
		(layer "F.Cu")
		(net "EXP_CPU_MODE_0")
	)
	(segment
		(start 97.80397 -88.265)
		(end 98.18497 -87.884)
		(width 0.1143)
		(layer "F.Cu")
		(net "EXP_CPU_MODE_0")
	)
	(segment
		(start 97.54997 -88.519)
		(end 97.80397 -88.265)
		(width 0.1143)
		(layer "F.Cu")
		(net "EXP_CPU_MODE_0")
	)
	(segment
		(start 96.34347 -88.519)
		(end 97.54997 -88.519)
		(width 0.1143)
		(layer "F.Cu")
		(net "EXP_CPU_MODE_0")
	)
	(via
		(at 97.80397 -88.265)
		(size 0.7112)
		(drill 0.3556)
		(layers "F.Cu" "B.Cu")
		(net "EXP_CPU_MODE_0")
	)
	(via
		(at 100.59797 -85.852)
		(size 0.508)
		(drill 0.254)
		(layers "F.Cu" "B.Cu")
		(net "EXP_CPU_MODE_0")
	)
	(via
		(at 106.849672 -88.849708)
		(size 0.508)
		(drill 0.254)
		(layers "F.Cu" "B.Cu")
		(net "EXP_CPU_MODE_0")
	)
	(segment
		(start 106.849672 -88.849708)
		(end 105.937304 -87.93734)
		(width 0.127)
		(layer "In2.Cu")
		(net "EXP_CPU_MODE_0")
	)
	(segment
		(start 104.059228 -88.26881)
		(end 103.638604 -88.26881)
		(width 0.127)
		(layer "In2.Cu")
		(net "EXP_CPU_MODE_0")
	)
	(segment
		(start 104.390698 -87.93734)
		(end 104.059228 -88.26881)
		(width 0.127)
		(layer "In2.Cu")
		(net "EXP_CPU_MODE_0")
	)
	(segment
		(start 103.638604 -88.26881)
		(end 102.441756 -87.071962)
		(width 0.127)
		(layer "In2.Cu")
		(net "EXP_CPU_MODE_0")
	)
	(segment
		(start 101.406706 -85.758782)
		(end 100.691188 -85.758782)
		(width 0.127)
		(layer "In2.Cu")
		(net "EXP_CPU_MODE_0")
	)
	(segment
		(start 100.691188 -85.758782)
		(end 100.59797 -85.852)
		(width 0.127)
		(layer "In2.Cu")
		(net "EXP_CPU_MODE_0")
	)
	(segment
		(start 102.441756 -87.071962)
		(end 102.441756 -86.793832)
		(width 0.127)
		(layer "In2.Cu")
		(net "EXP_CPU_MODE_0")
	)
	(segment
		(start 105.937304 -87.93734)
		(end 104.390698 -87.93734)
		(width 0.127)
		(layer "In2.Cu")
		(net "EXP_CPU_MODE_0")
	)
	(segment
		(start 102.441756 -86.793832)
		(end 101.406706 -85.758782)
		(width 0.127)
		(layer "In2.Cu")
		(net "EXP_CPU_MODE_0")
	)
	(segment
		(start 117.350032 -85.349842)
		(end 117.350032 -85.349588)
		(width 0.1143)
		(layer "F.Cu")
		(net "TEST_MUX_40")
	)
	(segment
		(start 117.350032 -85.349588)
		(end 116.85016 -84.849716)
		(width 0.1143)
		(layer "F.Cu")
		(net "TEST_MUX_40")
	)
	(via
		(at 116.85016 -84.849716)
		(size 0.508)
		(drill 0.254)
		(layers "F.Cu" "B.Cu")
		(net "TEST_MUX_40")
	)
	(segment
		(start 116.031772 -85.287866)
		(end 116.469922 -84.849716)
		(width 0.1143)
		(layer "B.Cu")
		(net "TEST_MUX_40")
	)
	(segment
		(start 115.302792 -84.642198)
		(end 115.302792 -84.922106)
		(width 0.1143)
		(layer "B.Cu")
		(net "TEST_MUX_40")
	)
	(segment
		(start 115.302792 -84.922106)
		(end 115.668552 -85.287866)
		(width 0.1143)
		(layer "B.Cu")
		(net "TEST_MUX_40")
	)
	(segment
		(start 115.105942 -84.445348)
		(end 115.302792 -84.642198)
		(width 0.1143)
		(layer "B.Cu")
		(net "TEST_MUX_40")
	)
	(segment
		(start 114.94897 -80.391)
		(end 115.105942 -80.547972)
		(width 0.1143)
		(layer "B.Cu")
		(net "TEST_MUX_40")
	)
	(segment
		(start 115.105942 -80.547972)
		(end 115.105942 -84.445348)
		(width 0.1143)
		(layer "B.Cu")
		(net "TEST_MUX_40")
	)
	(segment
		(start 115.668552 -85.287866)
		(end 116.031772 -85.287866)
		(width 0.1143)
		(layer "B.Cu")
		(net "TEST_MUX_40")
	)
	(segment
		(start 116.469922 -84.849716)
		(end 116.85016 -84.849716)
		(width 0.1143)
		(layer "B.Cu")
		(net "TEST_MUX_40")
	)
	(segment
		(start 247.777 -52.07)
		(end 243.459 -47.752)
		(width 0.1143)
		(layer "F.Cu")
		(net "SBL_SCL")
	)
	(segment
		(start 117.456966 -43.815)
		(end 116.672106 -44.59986)
		(width 0.1143)
		(layer "F.Cu")
		(net "SBL_SCL")
	)
	(segment
		(start 116.672106 -44.59986)
		(end 116.440966 -44.59986)
		(width 0.1143)
		(layer "F.Cu")
		(net "SBL_SCL")
	)
	(segment
		(start 117.520466 -43.815)
		(end 117.456966 -43.815)
		(width 0.1143)
		(layer "F.Cu")
		(net "SBL_SCL")
	)
	(segment
		(start 248.939812 -53.232812)
		(end 247.777 -52.07)
		(width 0.1143)
		(layer "F.Cu")
		(net "SBL_SCL")
	)
	(segment
		(start 249.815096 -53.232812)
		(end 248.939812 -53.232812)
		(width 0.1143)
		(layer "F.Cu")
		(net "SBL_SCL")
	)
	(segment
		(start 243.459 -47.752)
		(end 243.459 -47.625)
		(width 0.1143)
		(layer "F.Cu")
		(net "SBL_SCL")
	)
	(segment
		(start 116.440966 -44.59986)
		(end 113.949988 -44.59986)
		(width 0.1143)
		(layer "F.Cu")
		(net "SBL_SCL")
	)
	(via
		(at 247.777 -52.07)
		(size 0.7112)
		(drill 0.3556)
		(layers "F.Cu" "B.Cu")
		(net "SBL_SCL")
	)
	(via
		(at 116.440966 -44.59986)
		(size 0.5588)
		(drill 0.3048)
		(layers "F.Cu" "B.Cu")
		(net "SBL_SCL")
	)
	(via
		(at 243.459 -47.625)
		(size 0.5588)
		(drill 0.3048)
		(layers "F.Cu" "B.Cu")
		(net "SBL_SCL")
	)
	(segment
		(start 121.381266 -37.9603)
		(end 123.794266 -40.3733)
		(width 0.127)
		(layer "In5.Cu")
		(net "SBL_SCL")
	)
	(segment
		(start 203.5683 -40.3733)
		(end 210.82 -47.625)
		(width 0.127)
		(layer "In5.Cu")
		(net "SBL_SCL")
	)
	(segment
		(start 118.287038 -37.8841)
		(end 120.950482 -37.8841)
		(width 0.127)
		(layer "In5.Cu")
		(net "SBL_SCL")
	)
	(segment
		(start 116.440966 -43.93565)
		(end 116.631466 -43.74515)
		(width 0.127)
		(layer "In5.Cu")
		(net "SBL_SCL")
	)
	(segment
		(start 116.440966 -44.59986)
		(end 116.440966 -43.93565)
		(width 0.127)
		(layer "In5.Cu")
		(net "SBL_SCL")
	)
	(segment
		(start 123.794266 -40.3733)
		(end 203.5683 -40.3733)
		(width 0.127)
		(layer "In5.Cu")
		(net "SBL_SCL")
	)
	(segment
		(start 210.82 -47.625)
		(end 243.459 -47.625)
		(width 0.127)
		(layer "In5.Cu")
		(net "SBL_SCL")
	)
	(segment
		(start 116.631466 -39.539672)
		(end 118.287038 -37.8841)
		(width 0.127)
		(layer "In5.Cu")
		(net "SBL_SCL")
	)
	(segment
		(start 121.026682 -37.9603)
		(end 121.381266 -37.9603)
		(width 0.127)
		(layer "In5.Cu")
		(net "SBL_SCL")
	)
	(segment
		(start 120.950482 -37.8841)
		(end 121.026682 -37.9603)
		(width 0.127)
		(layer "In5.Cu")
		(net "SBL_SCL")
	)
	(segment
		(start 116.631466 -43.74515)
		(end 116.631466 -39.539672)
		(width 0.127)
		(layer "In5.Cu")
		(net "SBL_SCL")
	)
	(segment
		(start 91.2876 -41.937686)
		(end 91.407488 -42.057574)
		(width 0.1016)
		(layer "F.Cu")
		(net "SAS3008_RAID_TX_C_N5")
	)
	(segment
		(start 86.837774 -42.9514)
		(end 87.180166 -42.9514)
		(width 0.1016)
		(layer "F.Cu")
		(net "SAS3008_RAID_TX_C_N5")
	)
	(segment
		(start 88.790018 -41.831514)
		(end 91.031314 -41.831514)
		(width 0.1016)
		(layer "F.Cu")
		(net "SAS3008_RAID_TX_C_N5")
	)
	(segment
		(start 87.657178 -42.753788)
		(end 88.430608 -41.980358)
		(width 0.1016)
		(layer "F.Cu")
		(net "SAS3008_RAID_TX_C_N5")
	)
	(segment
		(start 91.407488 -42.057574)
		(end 91.549982 -42.199814)
		(width 0.1016)
		(layer "F.Cu")
		(net "SAS3008_RAID_TX_C_N5")
	)
	(arc
		(start 91.031314 -41.831514)
		(mid 91.170021 -41.859104)
		(end 91.2876 -41.937686)
		(width 0.1016)
		(layer "F.Cu")
		(net "SAS3008_RAID_TX_C_N5")
	)
	(arc
		(start 86.77656 -42.926)
		(mid 86.804645 -42.944766)
		(end 86.837774 -42.9514)
		(width 0.1016)
		(layer "F.Cu")
		(net "SAS3008_RAID_TX_C_N5")
	)
	(arc
		(start 87.180166 -42.9514)
		(mid 87.438333 -42.900047)
		(end 87.657178 -42.753788)
		(width 0.1016)
		(layer "F.Cu")
		(net "SAS3008_RAID_TX_C_N5")
	)
	(arc
		(start 88.430608 -41.980358)
		(mid 88.595507 -41.870176)
		(end 88.790018 -41.831514)
		(width 0.1016)
		(layer "F.Cu")
		(net "SAS3008_RAID_TX_C_N5")
	)
	(segment
		(start 53.848 -180.5305)
		(end 53.848 -181.229)
		(width 0.1143)
		(layer "F.Cu")
		(net "ICE_TDI")
	)
	(segment
		(start 53.848 -181.229)
		(end 51.943 -183.134)
		(width 0.1143)
		(layer "F.Cu")
		(net "ICE_TDI")
	)
	(segment
		(start 50.829972 -184.247028)
		(end 51.943 -183.134)
		(width 0.1143)
		(layer "F.Cu")
		(net "ICE_TDI")
	)
	(segment
		(start 107.349798 -99.350068)
		(end 106.849672 -99.850194)
		(width 0.1143)
		(layer "F.Cu")
		(net "ICE_TDI")
	)
	(segment
		(start 50.829972 -185.269886)
		(end 50.829972 -184.247028)
		(width 0.1143)
		(layer "F.Cu")
		(net "ICE_TDI")
	)
	(via
		(at 106.849672 -99.850194)
		(size 0.508)
		(drill 0.254)
		(layers "F.Cu" "B.Cu")
		(net "ICE_TDI")
	)
	(via
		(at 51.943 -183.134)
		(size 0.5588)
		(drill 0.3048)
		(layers "F.Cu" "B.Cu")
		(net "ICE_TDI")
	)
	(via
		(at 96.901 -135.636)
		(size 0.5588)
		(drill 0.3048)
		(layers "F.Cu" "B.Cu")
		(net "ICE_TDI")
	)
	(segment
		(start 96.901 -139.806934)
		(end 96.901 -135.636)
		(width 0.1143)
		(layer "B.Cu")
		(net "ICE_TDI")
	)
	(segment
		(start 91.712034 -144.9959)
		(end 96.901 -139.806934)
		(width 0.1143)
		(layer "B.Cu")
		(net "ICE_TDI")
	)
	(segment
		(start 57.424574 -182.88)
		(end 68.28155 -172.023024)
		(width 0.1143)
		(layer "B.Cu")
		(net "ICE_TDI")
	)
	(segment
		(start 84.868766 -150.469854)
		(end 84.868766 -149.713696)
		(width 0.1143)
		(layer "B.Cu")
		(net "ICE_TDI")
	)
	(segment
		(start 84.868766 -149.713696)
		(end 89.586562 -144.9959)
		(width 0.1143)
		(layer "B.Cu")
		(net "ICE_TDI")
	)
	(segment
		(start 89.586562 -144.9959)
		(end 91.712034 -144.9959)
		(width 0.1143)
		(layer "B.Cu")
		(net "ICE_TDI")
	)
	(segment
		(start 51.943 -183.134)
		(end 52.197 -182.88)
		(width 0.1143)
		(layer "B.Cu")
		(net "ICE_TDI")
	)
	(segment
		(start 68.28155 -172.023024)
		(end 68.28155 -167.05707)
		(width 0.1143)
		(layer "B.Cu")
		(net "ICE_TDI")
	)
	(segment
		(start 52.197 -182.88)
		(end 57.424574 -182.88)
		(width 0.1143)
		(layer "B.Cu")
		(net "ICE_TDI")
	)
	(segment
		(start 68.28155 -167.05707)
		(end 84.868766 -150.469854)
		(width 0.1143)
		(layer "B.Cu")
		(net "ICE_TDI")
	)
	(segment
		(start 80.31607 -123.067318)
		(end 80.31607 -120.92051)
		(width 0.127)
		(layer "In2.Cu")
		(net "ICE_TDI")
	)
	(segment
		(start 91.693746 -131.825746)
		(end 90.88501 -131.825746)
		(width 0.127)
		(layer "In2.Cu")
		(net "ICE_TDI")
	)
	(segment
		(start 98.884232 -100.8761)
		(end 100.708206 -100.8761)
		(width 0.127)
		(layer "In2.Cu")
		(net "ICE_TDI")
	)
	(segment
		(start 106.059224 -99.431094)
		(end 106.478324 -99.850194)
		(width 0.127)
		(layer "In2.Cu")
		(net "ICE_TDI")
	)
	(segment
		(start 95.529146 -135.661146)
		(end 91.693746 -131.825746)
		(width 0.127)
		(layer "In2.Cu")
		(net "ICE_TDI")
	)
	(segment
		(start 83.380834 -117.855746)
		(end 85.339428 -117.855746)
		(width 0.127)
		(layer "In2.Cu")
		(net "ICE_TDI")
	)
	(segment
		(start 85.339428 -117.855746)
		(end 96.66097 -106.534204)
		(width 0.127)
		(layer "In2.Cu")
		(net "ICE_TDI")
	)
	(segment
		(start 96.875854 -135.661146)
		(end 95.529146 -135.661146)
		(width 0.127)
		(layer "In2.Cu")
		(net "ICE_TDI")
	)
	(segment
		(start 102.153466 -99.431094)
		(end 106.059224 -99.431094)
		(width 0.127)
		(layer "In2.Cu")
		(net "ICE_TDI")
	)
	(segment
		(start 89.71407 -130.654806)
		(end 89.71407 -130.060192)
		(width 0.127)
		(layer "In2.Cu")
		(net "ICE_TDI")
	)
	(segment
		(start 106.478324 -99.850194)
		(end 106.849672 -99.850194)
		(width 0.127)
		(layer "In2.Cu")
		(net "ICE_TDI")
	)
	(segment
		(start 96.901 -135.636)
		(end 96.875854 -135.661146)
		(width 0.127)
		(layer "In2.Cu")
		(net "ICE_TDI")
	)
	(segment
		(start 80.31607 -120.92051)
		(end 83.380834 -117.855746)
		(width 0.127)
		(layer "In2.Cu")
		(net "ICE_TDI")
	)
	(segment
		(start 100.708206 -100.8761)
		(end 101.50856 -100.076)
		(width 0.127)
		(layer "In2.Cu")
		(net "ICE_TDI")
	)
	(segment
		(start 96.66097 -106.534204)
		(end 96.66097 -103.099362)
		(width 0.127)
		(layer "In2.Cu")
		(net "ICE_TDI")
	)
	(segment
		(start 89.71407 -130.060192)
		(end 85.140038 -125.48616)
		(width 0.127)
		(layer "In2.Cu")
		(net "ICE_TDI")
	)
	(segment
		(start 90.88501 -131.825746)
		(end 89.71407 -130.654806)
		(width 0.127)
		(layer "In2.Cu")
		(net "ICE_TDI")
	)
	(segment
		(start 101.50856 -100.076)
		(end 102.153466 -99.431094)
		(width 0.127)
		(layer "In2.Cu")
		(net "ICE_TDI")
	)
	(segment
		(start 96.66097 -103.099362)
		(end 98.884232 -100.8761)
		(width 0.127)
		(layer "In2.Cu")
		(net "ICE_TDI")
	)
	(segment
		(start 85.140038 -125.48616)
		(end 82.734912 -125.48616)
		(width 0.127)
		(layer "In2.Cu")
		(net "ICE_TDI")
	)
	(segment
		(start 82.734912 -125.48616)
		(end 80.31607 -123.067318)
		(width 0.127)
		(layer "In2.Cu")
		(net "ICE_TDI")
	)
	(segment
		(start 188.77915 -149.79015)
		(end 188.849 -149.86)
		(width 0.1143)
		(layer "F.Cu")
		(net "EXP_I2C_SDA_3")
	)
	(segment
		(start 192.501012 -145.574512)
		(end 194.486276 -145.574512)
		(width 0.1143)
		(layer "F.Cu")
		(net "EXP_I2C_SDA_3")
	)
	(segment
		(start 104.349804 -104.350058)
		(end 103.849678 -104.850184)
		(width 0.1143)
		(layer "F.Cu")
		(net "EXP_I2C_SDA_3")
	)
	(segment
		(start 188.15685 -149.360382)
		(end 188.15685 -149.459188)
		(width 0.1143)
		(layer "F.Cu")
		(net "EXP_I2C_SDA_3")
	)
	(segment
		(start 187.198 -148.24456)
		(end 187.23356 -148.24456)
		(width 0.1143)
		(layer "F.Cu")
		(net "EXP_I2C_SDA_3")
	)
	(segment
		(start 196.504052 -146.371564)
		(end 196.504052 -148.554948)
		(width 0.1143)
		(layer "F.Cu")
		(net "EXP_I2C_SDA_3")
	)
	(segment
		(start 195.707 -145.574512)
		(end 196.504052 -146.371564)
		(width 0.1143)
		(layer "F.Cu")
		(net "EXP_I2C_SDA_3")
	)
	(segment
		(start 187.8457 -148.8567)
		(end 187.8457 -149.049232)
		(width 0.1143)
		(layer "F.Cu")
		(net "EXP_I2C_SDA_3")
	)
	(segment
		(start 195.199 -149.86)
		(end 192.405 -149.86)
		(width 0.1143)
		(layer "F.Cu")
		(net "EXP_I2C_SDA_3")
	)
	(segment
		(start 194.486276 -145.574512)
		(end 195.707 -145.574512)
		(width 0.1143)
		(layer "F.Cu")
		(net "EXP_I2C_SDA_3")
	)
	(segment
		(start 187.23356 -148.24456)
		(end 187.8457 -148.8567)
		(width 0.1143)
		(layer "F.Cu")
		(net "EXP_I2C_SDA_3")
	)
	(segment
		(start 188.487812 -149.79015)
		(end 188.77915 -149.79015)
		(width 0.1143)
		(layer "F.Cu")
		(net "EXP_I2C_SDA_3")
	)
	(segment
		(start 191.9605 -145.034)
		(end 192.501012 -145.574512)
		(width 0.1143)
		(layer "F.Cu")
		(net "EXP_I2C_SDA_3")
	)
	(segment
		(start 188.15685 -149.459188)
		(end 188.487812 -149.79015)
		(width 0.1143)
		(layer "F.Cu")
		(net "EXP_I2C_SDA_3")
	)
	(segment
		(start 188.849 -149.86)
		(end 192.405 -149.86)
		(width 0.1143)
		(layer "F.Cu")
		(net "EXP_I2C_SDA_3")
	)
	(segment
		(start 196.504052 -148.554948)
		(end 195.199 -149.86)
		(width 0.1143)
		(layer "F.Cu")
		(net "EXP_I2C_SDA_3")
	)
	(segment
		(start 187.8457 -149.049232)
		(end 188.15685 -149.360382)
		(width 0.1143)
		(layer "F.Cu")
		(net "EXP_I2C_SDA_3")
	)
	(via
		(at 192.405 -149.86)
		(size 0.7112)
		(drill 0.3556)
		(layers "F.Cu" "B.Cu")
		(net "EXP_I2C_SDA_3")
	)
	(via
		(at 187.198 -148.24456)
		(size 0.5588)
		(drill 0.3048)
		(layers "F.Cu" "B.Cu")
		(net "EXP_I2C_SDA_3")
	)
	(via
		(at 103.849678 -104.850184)
		(size 0.508)
		(drill 0.254)
		(layers "F.Cu" "B.Cu")
		(net "EXP_I2C_SDA_3")
	)
	(segment
		(start 87.00389 -119.73687)
		(end 101.890576 -104.850184)
		(width 0.127)
		(layer "In2.Cu")
		(net "EXP_I2C_SDA_3")
	)
	(segment
		(start 83.134454 -124.59716)
		(end 81.242916 -122.705622)
		(width 0.127)
		(layer "In2.Cu")
		(net "EXP_I2C_SDA_3")
	)
	(segment
		(start 94.029784 -132.842)
		(end 85.784944 -124.59716)
		(width 0.127)
		(layer "In2.Cu")
		(net "EXP_I2C_SDA_3")
	)
	(segment
		(start 94.934532 -132.842)
		(end 94.029784 -132.842)
		(width 0.127)
		(layer "In2.Cu")
		(net "EXP_I2C_SDA_3")
	)
	(segment
		(start 187.198 -148.24456)
		(end 185.76544 -148.24456)
		(width 0.127)
		(layer "In2.Cu")
		(net "EXP_I2C_SDA_3")
	)
	(segment
		(start 81.242916 -121.251218)
		(end 82.757264 -119.73687)
		(width 0.127)
		(layer "In2.Cu")
		(net "EXP_I2C_SDA_3")
	)
	(segment
		(start 184.3913 -149.6187)
		(end 111.711232 -149.6187)
		(width 0.127)
		(layer "In2.Cu")
		(net "EXP_I2C_SDA_3")
	)
	(segment
		(start 81.242916 -122.705622)
		(end 81.242916 -121.251218)
		(width 0.127)
		(layer "In2.Cu")
		(net "EXP_I2C_SDA_3")
	)
	(segment
		(start 101.890576 -104.850184)
		(end 103.849678 -104.850184)
		(width 0.127)
		(layer "In2.Cu")
		(net "EXP_I2C_SDA_3")
	)
	(segment
		(start 82.757264 -119.73687)
		(end 87.00389 -119.73687)
		(width 0.127)
		(layer "In2.Cu")
		(net "EXP_I2C_SDA_3")
	)
	(segment
		(start 111.711232 -149.6187)
		(end 94.934532 -132.842)
		(width 0.127)
		(layer "In2.Cu")
		(net "EXP_I2C_SDA_3")
	)
	(segment
		(start 85.784944 -124.59716)
		(end 83.134454 -124.59716)
		(width 0.127)
		(layer "In2.Cu")
		(net "EXP_I2C_SDA_3")
	)
	(segment
		(start 185.76544 -148.24456)
		(end 184.3913 -149.6187)
		(width 0.127)
		(layer "In2.Cu")
		(net "EXP_I2C_SDA_3")
	)
	(segment
		(start 101.150166 -35.80003)
		(end 100.985574 -35.80003)
		(width 0.1397)
		(layer "F.Cu")
		(net "PCIE_SAS_C_CPU_RX_P5")
	)
	(segment
		(start 100.895912 -35.762946)
		(end 100.794566 -35.6616)
		(width 0.1397)
		(layer "F.Cu")
		(net "PCIE_SAS_C_CPU_RX_P5")
	)
	(segment
		(start 100.757482 -35.571938)
		(end 100.757482 -35.397948)
		(width 0.1397)
		(layer "F.Cu")
		(net "PCIE_SAS_C_CPU_RX_P5")
	)
	(via
		(at 100.757482 -35.397948)
		(size 0.508)
		(drill 0.254)
		(layers "F.Cu" "B.Cu")
		(net "PCIE_SAS_C_CPU_RX_P5")
	)
	(arc
		(start 100.794566 -35.6616)
		(mid 100.767133 -35.620449)
		(end 100.757482 -35.571938)
		(width 0.1397)
		(layer "F.Cu")
		(net "PCIE_SAS_C_CPU_RX_P5")
	)
	(arc
		(start 100.985574 -35.80003)
		(mid 100.937056 -35.790397)
		(end 100.895912 -35.762946)
		(width 0.1397)
		(layer "F.Cu")
		(net "PCIE_SAS_C_CPU_RX_P5")
	)
	(segment
		(start 101.124766 -33.302194)
		(end 100.955094 -33.471866)
		(width 0.1397)
		(layer "B.Cu")
		(net "PCIE_SAS_C_CPU_RX_P5")
	)
	(segment
		(start 100.62845 -34.996374)
		(end 100.62845 -35.268916)
		(width 0.1397)
		(layer "B.Cu")
		(net "PCIE_SAS_C_CPU_RX_P5")
	)
	(segment
		(start 100.62845 -35.268916)
		(end 100.757482 -35.397948)
		(width 0.1397)
		(layer "B.Cu")
		(net "PCIE_SAS_C_CPU_RX_P5")
	)
	(segment
		(start 100.75037 -33.965896)
		(end 100.75037 -34.821876)
		(width 0.1397)
		(layer "B.Cu")
		(net "PCIE_SAS_C_CPU_RX_P5")
	)
	(segment
		(start 100.712778 -34.912046)
		(end 100.62845 -34.996374)
		(width 0.1397)
		(layer "B.Cu")
		(net "PCIE_SAS_C_CPU_RX_P5")
	)
	(segment
		(start 101.22916 -32.532574)
		(end 101.22916 -33.05048)
		(width 0.1397)
		(layer "B.Cu")
		(net "PCIE_SAS_C_CPU_RX_P5")
	)
	(arc
		(start 100.955094 -33.471866)
		(mid 100.803613 -33.698528)
		(end 100.75037 -33.965896)
		(width 0.1397)
		(layer "B.Cu")
		(net "PCIE_SAS_C_CPU_RX_P5")
	)
	(arc
		(start 101.22916 -33.05048)
		(mid 101.20197 -33.186703)
		(end 101.124766 -33.302194)
		(width 0.1397)
		(layer "B.Cu")
		(net "PCIE_SAS_C_CPU_RX_P5")
	)
	(arc
		(start 100.738178 -34.875724)
		(mid 100.738051 -34.875978)
		(end 100.737924 -34.876232)
		(width 0.1397)
		(layer "B.Cu")
		(net "PCIE_SAS_C_CPU_RX_P5")
	)
	(arc
		(start 100.97516 -31.919418)
		(mid 101.163131 -32.200736)
		(end 101.22916 -32.532574)
		(width 0.1397)
		(layer "B.Cu")
		(net "PCIE_SAS_C_CPU_RX_P5")
	)
	(arc
		(start 100.737924 -34.876232)
		(mid 100.726911 -34.895234)
		(end 100.712778 -34.912046)
		(width 0.1397)
		(layer "B.Cu")
		(net "PCIE_SAS_C_CPU_RX_P5")
	)
	(arc
		(start 100.75037 -34.821876)
		(mid 100.747218 -34.849464)
		(end 100.738178 -34.875724)
		(width 0.1397)
		(layer "B.Cu")
		(net "PCIE_SAS_C_CPU_RX_P5")
	)
	(segment
		(start 117.350286 -88.349836)
		(end 117.82425 -88.8238)
		(width 0.1143)
		(layer "F.Cu")
		(net "TEST_MUX_41")
	)
	(segment
		(start 117.350032 -88.349836)
		(end 117.350286 -88.349836)
		(width 0.1143)
		(layer "F.Cu")
		(net "TEST_MUX_41")
	)
	(segment
		(start 117.82425 -88.8238)
		(end 117.84203 -88.8238)
		(width 0.1143)
		(layer "F.Cu")
		(net "TEST_MUX_41")
	)
	(via
		(at 117.84203 -88.8238)
		(size 0.5588)
		(drill 0.3048)
		(layers "F.Cu" "B.Cu")
		(net "TEST_MUX_41")
	)
	(segment
		(start 117.48897 -88.47074)
		(end 117.84203 -88.8238)
		(width 0.1143)
		(layer "B.Cu")
		(net "TEST_MUX_41")
	)
	(segment
		(start 117.48897 -87.884)
		(end 117.48897 -88.47074)
		(width 0.1143)
		(layer "B.Cu")
		(net "TEST_MUX_41")
	)
	(segment
		(start 192.008252 -146.224752)
		(end 194.486276 -146.224752)
		(width 0.1143)
		(layer "F.Cu")
		(net "EXP_I2C_SCL_3")
	)
	(segment
		(start 188.341 -148.844)
		(end 188.341 -147.9423)
		(width 0.1143)
		(layer "F.Cu")
		(net "EXP_I2C_SCL_3")
	)
	(segment
		(start 196.008752 -146.576796)
		(end 196.008752 -148.349716)
		(width 0.1143)
		(layer "F.Cu")
		(net "EXP_I2C_SCL_3")
	)
	(segment
		(start 102.96779 -106.85018)
		(end 102.84968 -106.85018)
		(width 0.1143)
		(layer "F.Cu")
		(net "EXP_I2C_SCL_3")
	)
	(segment
		(start 195.133468 -149.225)
		(end 188.722 -149.225)
		(width 0.1143)
		(layer "F.Cu")
		(net "EXP_I2C_SCL_3")
	)
	(segment
		(start 188.722 -149.225)
		(end 188.341 -148.844)
		(width 0.1143)
		(layer "F.Cu")
		(net "EXP_I2C_SCL_3")
	)
	(segment
		(start 103.349806 -106.468164)
		(end 102.96779 -106.85018)
		(width 0.1143)
		(layer "F.Cu")
		(net "EXP_I2C_SCL_3")
	)
	(segment
		(start 195.656708 -146.224752)
		(end 196.008752 -146.576796)
		(width 0.1143)
		(layer "F.Cu")
		(net "EXP_I2C_SCL_3")
	)
	(segment
		(start 103.349806 -106.350054)
		(end 103.349806 -106.468164)
		(width 0.1143)
		(layer "F.Cu")
		(net "EXP_I2C_SCL_3")
	)
	(segment
		(start 196.008752 -148.349716)
		(end 195.133468 -149.225)
		(width 0.1143)
		(layer "F.Cu")
		(net "EXP_I2C_SCL_3")
	)
	(segment
		(start 194.486276 -146.224752)
		(end 195.656708 -146.224752)
		(width 0.1143)
		(layer "F.Cu")
		(net "EXP_I2C_SCL_3")
	)
	(segment
		(start 191.9605 -146.177)
		(end 192.008252 -146.224752)
		(width 0.1143)
		(layer "F.Cu")
		(net "EXP_I2C_SCL_3")
	)
	(via
		(at 102.84968 -106.85018)
		(size 0.508)
		(drill 0.254)
		(layers "F.Cu" "B.Cu")
		(net "EXP_I2C_SCL_3")
	)
	(via
		(at 188.722 -149.225)
		(size 0.7112)
		(drill 0.3556)
		(layers "F.Cu" "B.Cu")
		(net "EXP_I2C_SCL_3")
	)
	(via
		(at 188.341 -147.9423)
		(size 0.5588)
		(drill 0.3048)
		(layers "F.Cu" "B.Cu")
		(net "EXP_I2C_SCL_3")
	)
	(segment
		(start 168.148 -147.574)
		(end 178.430936 -147.574)
		(width 0.127)
		(layer "In2.Cu")
		(net "EXP_I2C_SCL_3")
	)
	(segment
		(start 179.848764 -147.6883)
		(end 188.087 -147.6883)
		(width 0.127)
		(layer "In2.Cu")
		(net "EXP_I2C_SCL_3")
	)
	(segment
		(start 92.446856 -127.521462)
		(end 112.245394 -147.32)
		(width 0.127)
		(layer "In2.Cu")
		(net "EXP_I2C_SCL_3")
	)
	(segment
		(start 87.214456 -120.24487)
		(end 82.96783 -120.24487)
		(width 0.127)
		(layer "In2.Cu")
		(net "EXP_I2C_SCL_3")
	)
	(segment
		(start 179.823364 -147.7137)
		(end 179.848764 -147.6883)
		(width 0.127)
		(layer "In2.Cu")
		(net "EXP_I2C_SCL_3")
	)
	(segment
		(start 102.84968 -106.85018)
		(end 100.609146 -106.85018)
		(width 0.127)
		(layer "In2.Cu")
		(net "EXP_I2C_SCL_3")
	)
	(segment
		(start 82.96783 -120.24487)
		(end 81.750916 -121.461784)
		(width 0.127)
		(layer "In2.Cu")
		(net "EXP_I2C_SCL_3")
	)
	(segment
		(start 112.245394 -147.32)
		(end 167.894 -147.32)
		(width 0.127)
		(layer "In2.Cu")
		(net "EXP_I2C_SCL_3")
	)
	(segment
		(start 178.430936 -147.574)
		(end 178.570636 -147.7137)
		(width 0.127)
		(layer "In2.Cu")
		(net "EXP_I2C_SCL_3")
	)
	(segment
		(start 87.685118 -124.08916)
		(end 91.11742 -127.521462)
		(width 0.127)
		(layer "In2.Cu")
		(net "EXP_I2C_SCL_3")
	)
	(segment
		(start 188.087 -147.6883)
		(end 188.341 -147.9423)
		(width 0.127)
		(layer "In2.Cu")
		(net "EXP_I2C_SCL_3")
	)
	(segment
		(start 100.609146 -106.85018)
		(end 87.214456 -120.24487)
		(width 0.127)
		(layer "In2.Cu")
		(net "EXP_I2C_SCL_3")
	)
	(segment
		(start 178.570636 -147.7137)
		(end 179.823364 -147.7137)
		(width 0.127)
		(layer "In2.Cu")
		(net "EXP_I2C_SCL_3")
	)
	(segment
		(start 81.750916 -121.461784)
		(end 81.750916 -122.495056)
		(width 0.127)
		(layer "In2.Cu")
		(net "EXP_I2C_SCL_3")
	)
	(segment
		(start 81.750916 -122.495056)
		(end 83.34502 -124.08916)
		(width 0.127)
		(layer "In2.Cu")
		(net "EXP_I2C_SCL_3")
	)
	(segment
		(start 83.34502 -124.08916)
		(end 87.685118 -124.08916)
		(width 0.127)
		(layer "In2.Cu")
		(net "EXP_I2C_SCL_3")
	)
	(segment
		(start 167.894 -147.32)
		(end 168.148 -147.574)
		(width 0.127)
		(layer "In2.Cu")
		(net "EXP_I2C_SCL_3")
	)
	(segment
		(start 91.11742 -127.521462)
		(end 92.446856 -127.521462)
		(width 0.127)
		(layer "In2.Cu")
		(net "EXP_I2C_SCL_3")
	)
	(segment
		(start 115.51793 -46.482)
		(end 116.619528 -46.482)
		(width 0.1143)
		(layer "F.Cu")
		(net "IOC_CLK_SEL0")
	)
	(segment
		(start 120.624346 -46.3804)
		(end 120.704864 -46.460918)
		(width 0.1143)
		(layer "F.Cu")
		(net "IOC_CLK_SEL0")
	)
	(segment
		(start 113.464848 -46.199806)
		(end 113.807748 -45.856906)
		(width 0.1143)
		(layer "F.Cu")
		(net "IOC_CLK_SEL0")
	)
	(segment
		(start 113.807748 -45.856906)
		(end 114.892836 -45.856906)
		(width 0.1143)
		(layer "F.Cu")
		(net "IOC_CLK_SEL0")
	)
	(segment
		(start 119.5832 -46.99)
		(end 120.1928 -46.3804)
		(width 0.1143)
		(layer "F.Cu")
		(net "IOC_CLK_SEL0")
	)
	(segment
		(start 116.702078 -46.39945)
		(end 117.70995 -46.39945)
		(width 0.1143)
		(layer "F.Cu")
		(net "IOC_CLK_SEL0")
	)
	(segment
		(start 116.619528 -46.482)
		(end 116.702078 -46.39945)
		(width 0.1143)
		(layer "F.Cu")
		(net "IOC_CLK_SEL0")
	)
	(segment
		(start 120.1928 -46.3804)
		(end 120.624346 -46.3804)
		(width 0.1143)
		(layer "F.Cu")
		(net "IOC_CLK_SEL0")
	)
	(segment
		(start 118.3005 -46.99)
		(end 119.5832 -46.99)
		(width 0.1143)
		(layer "F.Cu")
		(net "IOC_CLK_SEL0")
	)
	(segment
		(start 117.70995 -46.39945)
		(end 118.3005 -46.99)
		(width 0.1143)
		(layer "F.Cu")
		(net "IOC_CLK_SEL0")
	)
	(segment
		(start 114.892836 -45.856906)
		(end 115.51793 -46.482)
		(width 0.1143)
		(layer "F.Cu")
		(net "IOC_CLK_SEL0")
	)
	(segment
		(start 113.150142 -46.199806)
		(end 113.464848 -46.199806)
		(width 0.1143)
		(layer "F.Cu")
		(net "IOC_CLK_SEL0")
	)
	(via
		(at 119.888 -46.863)
		(size 0.7112)
		(drill 0.3556)
		(layers "F.Cu" "B.Cu")
		(net "IOC_CLK_SEL0")
	)
	(via
		(at 120.704864 -46.460918)
		(size 0.5588)
		(drill 0.3048)
		(layers "F.Cu" "B.Cu")
		(net "IOC_CLK_SEL0")
	)
	(segment
		(start 120.9675 -47.302674)
		(end 120.704864 -47.040038)
		(width 0.1143)
		(layer "B.Cu")
		(net "IOC_CLK_SEL0")
	)
	(segment
		(start 119.888 -46.863)
		(end 120.290082 -46.460918)
		(width 0.1143)
		(layer "B.Cu")
		(net "IOC_CLK_SEL0")
	)
	(segment
		(start 120.290082 -46.460918)
		(end 120.704864 -46.460918)
		(width 0.1143)
		(layer "B.Cu")
		(net "IOC_CLK_SEL0")
	)
	(segment
		(start 120.704864 -47.040038)
		(end 120.704864 -46.460918)
		(width 0.1143)
		(layer "B.Cu")
		(net "IOC_CLK_SEL0")
	)
	(segment
		(start 106.3498 -100.350066)
		(end 105.849674 -100.850192)
		(width 0.1143)
		(layer "F.Cu")
		(net "ICE_TDO")
	)
	(segment
		(start 60.989972 -179.480972)
		(end 60.579 -179.07)
		(width 0.1143)
		(layer "F.Cu")
		(net "ICE_TDO")
	)
	(segment
		(start 60.989972 -185.269886)
		(end 60.989972 -179.480972)
		(width 0.1143)
		(layer "F.Cu")
		(net "ICE_TDO")
	)
	(via
		(at 60.579 -179.07)
		(size 0.508)
		(drill 0.254)
		(layers "F.Cu" "B.Cu")
		(net "ICE_TDO")
	)
	(via
		(at 105.849674 -100.850192)
		(size 0.508)
		(drill 0.254)
		(layers "F.Cu" "B.Cu")
		(net "ICE_TDO")
	)
	(via
		(at 96.266 -134.874)
		(size 0.5588)
		(drill 0.3048)
		(layers "F.Cu" "B.Cu")
		(net "ICE_TDO")
	)
	(segment
		(start 91.55938 -144.6276)
		(end 96.266 -139.92098)
		(width 0.1143)
		(layer "B.Cu")
		(net "ICE_TDO")
	)
	(segment
		(start 60.579 -179.07)
		(end 67.818 -171.831)
		(width 0.1143)
		(layer "B.Cu")
		(net "ICE_TDO")
	)
	(segment
		(start 84.500466 -149.561042)
		(end 89.433908 -144.6276)
		(width 0.1143)
		(layer "B.Cu")
		(net "ICE_TDO")
	)
	(segment
		(start 84.500466 -150.3172)
		(end 84.500466 -149.561042)
		(width 0.1143)
		(layer "B.Cu")
		(net "ICE_TDO")
	)
	(segment
		(start 89.433908 -144.6276)
		(end 91.55938 -144.6276)
		(width 0.1143)
		(layer "B.Cu")
		(net "ICE_TDO")
	)
	(segment
		(start 67.818 -166.999666)
		(end 84.500466 -150.3172)
		(width 0.1143)
		(layer "B.Cu")
		(net "ICE_TDO")
	)
	(segment
		(start 67.818 -171.831)
		(end 67.818 -166.999666)
		(width 0.1143)
		(layer "B.Cu")
		(net "ICE_TDO")
	)
	(segment
		(start 96.266 -139.92098)
		(end 96.266 -134.874)
		(width 0.1143)
		(layer "B.Cu")
		(net "ICE_TDO")
	)
	(segment
		(start 105.16997 -101.346)
		(end 105.665778 -100.850192)
		(width 0.127)
		(layer "In2.Cu")
		(net "ICE_TDO")
	)
	(segment
		(start 90.09507 -129.902204)
		(end 85.298026 -125.10516)
		(width 0.127)
		(layer "In2.Cu")
		(net "ICE_TDO")
	)
	(segment
		(start 80.69707 -122.90933)
		(end 80.69707 -121.078498)
		(width 0.127)
		(layer "In2.Cu")
		(net "ICE_TDO")
	)
	(segment
		(start 91.536012 -131.444492)
		(end 91.535758 -131.444746)
		(width 0.127)
		(layer "In2.Cu")
		(net "ICE_TDO")
	)
	(segment
		(start 91.85148 -131.444492)
		(end 91.536012 -131.444492)
		(width 0.127)
		(layer "In2.Cu")
		(net "ICE_TDO")
	)
	(segment
		(start 83.538822 -118.236746)
		(end 85.497416 -118.236746)
		(width 0.127)
		(layer "In2.Cu")
		(net "ICE_TDO")
	)
	(segment
		(start 90.09507 -130.496818)
		(end 90.09507 -129.902204)
		(width 0.127)
		(layer "In2.Cu")
		(net "ICE_TDO")
	)
	(segment
		(start 101.61397 -101.346)
		(end 105.16997 -101.346)
		(width 0.127)
		(layer "In2.Cu")
		(net "ICE_TDO")
	)
	(segment
		(start 91.535758 -131.444746)
		(end 91.042998 -131.444746)
		(width 0.127)
		(layer "In2.Cu")
		(net "ICE_TDO")
	)
	(segment
		(start 95.280988 -134.874)
		(end 91.85148 -131.444492)
		(width 0.127)
		(layer "In2.Cu")
		(net "ICE_TDO")
	)
	(segment
		(start 96.266 -134.874)
		(end 95.280988 -134.874)
		(width 0.127)
		(layer "In2.Cu")
		(net "ICE_TDO")
	)
	(segment
		(start 97.663 -106.071162)
		(end 97.663 -102.656132)
		(width 0.127)
		(layer "In2.Cu")
		(net "ICE_TDO")
	)
	(segment
		(start 97.663 -102.656132)
		(end 98.103182 -102.21595)
		(width 0.127)
		(layer "In2.Cu")
		(net "ICE_TDO")
	)
	(segment
		(start 82.8929 -125.10516)
		(end 80.69707 -122.90933)
		(width 0.127)
		(layer "In2.Cu")
		(net "ICE_TDO")
	)
	(segment
		(start 91.042998 -131.444746)
		(end 90.09507 -130.496818)
		(width 0.127)
		(layer "In2.Cu")
		(net "ICE_TDO")
	)
	(segment
		(start 99.905312 -102.024688)
		(end 100.935282 -102.024688)
		(width 0.127)
		(layer "In2.Cu")
		(net "ICE_TDO")
	)
	(segment
		(start 98.103182 -102.21595)
		(end 99.71405 -102.21595)
		(width 0.127)
		(layer "In2.Cu")
		(net "ICE_TDO")
	)
	(segment
		(start 100.935282 -102.024688)
		(end 101.61397 -101.346)
		(width 0.127)
		(layer "In2.Cu")
		(net "ICE_TDO")
	)
	(segment
		(start 85.497416 -118.236746)
		(end 97.663 -106.071162)
		(width 0.127)
		(layer "In2.Cu")
		(net "ICE_TDO")
	)
	(segment
		(start 85.298026 -125.10516)
		(end 82.8929 -125.10516)
		(width 0.127)
		(layer "In2.Cu")
		(net "ICE_TDO")
	)
	(segment
		(start 105.665778 -100.850192)
		(end 105.849674 -100.850192)
		(width 0.127)
		(layer "In2.Cu")
		(net "ICE_TDO")
	)
	(segment
		(start 99.71405 -102.21595)
		(end 99.905312 -102.024688)
		(width 0.127)
		(layer "In2.Cu")
		(net "ICE_TDO")
	)
	(segment
		(start 80.69707 -121.078498)
		(end 83.538822 -118.236746)
		(width 0.127)
		(layer "In2.Cu")
		(net "ICE_TDO")
	)
	(segment
		(start 75.184 -23.1775)
		(end 75.184 -23.9268)
		(width 0.1143)
		(layer "F.Cu")
		(net "BMC_EN_0V955_C")
	)
	(segment
		(start 75.184 -23.9268)
		(end 75.2348 -23.9776)
		(width 0.1143)
		(layer "F.Cu")
		(net "BMC_EN_0V955_C")
	)
	(via
		(at 243.8146 -45.8978)
		(size 0.508)
		(drill 0.254)
		(layers "F.Cu" "B.Cu")
		(net "BMC_EN_0V955_C")
	)
	(via
		(at 75.2348 -23.9776)
		(size 0.5588)
		(drill 0.3048)
		(layers "F.Cu" "B.Cu")
		(net "BMC_EN_0V955_C")
	)
	(via
		(at 259.588 -125.095)
		(size 0.508)
		(drill 0.254)
		(layers "F.Cu" "B.Cu")
		(net "BMC_EN_0V955_C")
	)
	(via
		(at 272.282158 -160.02)
		(size 0.7112)
		(drill 0.3556)
		(layers "F.Cu" "B.Cu")
		(net "BMC_EN_0V955_C")
	)
	(segment
		(start 271.977358 -160.02)
		(end 272.282158 -160.02)
		(width 0.1143)
		(layer "B.Cu")
		(net "BMC_EN_0V955_C")
	)
	(segment
		(start 258.078478 -148.91512)
		(end 264.484358 -155.321)
		(width 0.1143)
		(layer "B.Cu")
		(net "BMC_EN_0V955_C")
	)
	(segment
		(start 259.207 -145.669)
		(end 258.078478 -146.797522)
		(width 0.1143)
		(layer "B.Cu")
		(net "BMC_EN_0V955_C")
	)
	(segment
		(start 272.282158 -160.02)
		(end 275.9075 -160.02)
		(width 0.1143)
		(layer "B.Cu")
		(net "BMC_EN_0V955_C")
	)
	(segment
		(start 264.484358 -155.321)
		(end 267.278358 -155.321)
		(width 0.1143)
		(layer "B.Cu")
		(net "BMC_EN_0V955_C")
	)
	(segment
		(start 267.278358 -155.321)
		(end 271.977358 -160.02)
		(width 0.1143)
		(layer "B.Cu")
		(net "BMC_EN_0V955_C")
	)
	(segment
		(start 258.078478 -146.797522)
		(end 258.078478 -148.91512)
		(width 0.1143)
		(layer "B.Cu")
		(net "BMC_EN_0V955_C")
	)
	(segment
		(start 259.588 -125.095)
		(end 259.588 -125.476)
		(width 0.1143)
		(layer "B.Cu")
		(net "BMC_EN_0V955_C")
	)
	(segment
		(start 259.207 -125.857)
		(end 259.207 -145.669)
		(width 0.1143)
		(layer "B.Cu")
		(net "BMC_EN_0V955_C")
	)
	(segment
		(start 259.588 -125.476)
		(end 259.207 -125.857)
		(width 0.1143)
		(layer "B.Cu")
		(net "BMC_EN_0V955_C")
	)
	(segment
		(start 249.65914 -48.452278)
		(end 247.104662 -45.8978)
		(width 0.127)
		(layer "In2.Cu")
		(net "BMC_EN_0V955_C")
	)
	(segment
		(start 247.104662 -45.8978)
		(end 243.8146 -45.8978)
		(width 0.127)
		(layer "In2.Cu")
		(net "BMC_EN_0V955_C")
	)
	(segment
		(start 259.588 -123.952)
		(end 257.949954 -122.313954)
		(width 0.127)
		(layer "In2.Cu")
		(net "BMC_EN_0V955_C")
	)
	(segment
		(start 256.781046 -121.710958)
		(end 256.781046 -117.335046)
		(width 0.127)
		(layer "In2.Cu")
		(net "BMC_EN_0V955_C")
	)
	(segment
		(start 255.7653 -116.3193)
		(end 255.7653 -111.8997)
		(width 0.127)
		(layer "In2.Cu")
		(net "BMC_EN_0V955_C")
	)
	(segment
		(start 249.65914 -68.93814)
		(end 249.65914 -48.452278)
		(width 0.127)
		(layer "In2.Cu")
		(net "BMC_EN_0V955_C")
	)
	(segment
		(start 257.949954 -122.313954)
		(end 257.384042 -122.313954)
		(width 0.127)
		(layer "In2.Cu")
		(net "BMC_EN_0V955_C")
	)
	(segment
		(start 257.384042 -122.313954)
		(end 256.781046 -121.710958)
		(width 0.127)
		(layer "In2.Cu")
		(net "BMC_EN_0V955_C")
	)
	(segment
		(start 264.8839 -84.1629)
		(end 249.65914 -68.93814)
		(width 0.127)
		(layer "In2.Cu")
		(net "BMC_EN_0V955_C")
	)
	(segment
		(start 256.781046 -117.335046)
		(end 255.7653 -116.3193)
		(width 0.127)
		(layer "In2.Cu")
		(net "BMC_EN_0V955_C")
	)
	(segment
		(start 264.8839 -102.7811)
		(end 264.8839 -84.1629)
		(width 0.127)
		(layer "In2.Cu")
		(net "BMC_EN_0V955_C")
	)
	(segment
		(start 255.7653 -111.8997)
		(end 264.8839 -102.7811)
		(width 0.127)
		(layer "In2.Cu")
		(net "BMC_EN_0V955_C")
	)
	(segment
		(start 259.588 -125.095)
		(end 259.588 -123.952)
		(width 0.127)
		(layer "In2.Cu")
		(net "BMC_EN_0V955_C")
	)
	(segment
		(start 75.7936 -23.9776)
		(end 76.2635 -24.4475)
		(width 0.127)
		(layer "In5.Cu")
		(net "BMC_EN_0V955_C")
	)
	(segment
		(start 76.2635 -24.4475)
		(end 77.038962 -24.4475)
		(width 0.127)
		(layer "In5.Cu")
		(net "BMC_EN_0V955_C")
	)
	(segment
		(start 174.117 -37.338)
		(end 175.641 -38.862)
		(width 0.127)
		(layer "In5.Cu")
		(net "BMC_EN_0V955_C")
	)
	(segment
		(start 75.2348 -23.9776)
		(end 75.7936 -23.9776)
		(width 0.127)
		(layer "In5.Cu")
		(net "BMC_EN_0V955_C")
	)
	(segment
		(start 119.383048 -18.545048)
		(end 126.238 -25.4)
		(width 0.127)
		(layer "In5.Cu")
		(net "BMC_EN_0V955_C")
	)
	(segment
		(start 202.883262 -38.862)
		(end 209.919062 -45.8978)
		(width 0.127)
		(layer "In5.Cu")
		(net "BMC_EN_0V955_C")
	)
	(segment
		(start 77.6732 -23.813262)
		(end 84.45627 -23.813262)
		(width 0.127)
		(layer "In5.Cu")
		(net "BMC_EN_0V955_C")
	)
	(segment
		(start 95.434404 -18.545048)
		(end 119.383048 -18.545048)
		(width 0.127)
		(layer "In5.Cu")
		(net "BMC_EN_0V955_C")
	)
	(segment
		(start 84.45627 -23.813262)
		(end 85.0773 -23.192232)
		(width 0.127)
		(layer "In5.Cu")
		(net "BMC_EN_0V955_C")
	)
	(segment
		(start 144.936718 -37.338)
		(end 174.117 -37.338)
		(width 0.127)
		(layer "In5.Cu")
		(net "BMC_EN_0V955_C")
	)
	(segment
		(start 175.641 -38.862)
		(end 202.883262 -38.862)
		(width 0.127)
		(layer "In5.Cu")
		(net "BMC_EN_0V955_C")
	)
	(segment
		(start 132.998718 -25.4)
		(end 144.936718 -37.338)
		(width 0.127)
		(layer "In5.Cu")
		(net "BMC_EN_0V955_C")
	)
	(segment
		(start 85.0773 -22.944074)
		(end 90.279474 -17.7419)
		(width 0.127)
		(layer "In5.Cu")
		(net "BMC_EN_0V955_C")
	)
	(segment
		(start 126.238 -25.4)
		(end 132.998718 -25.4)
		(width 0.127)
		(layer "In5.Cu")
		(net "BMC_EN_0V955_C")
	)
	(segment
		(start 90.279474 -17.7419)
		(end 94.631256 -17.7419)
		(width 0.127)
		(layer "In5.Cu")
		(net "BMC_EN_0V955_C")
	)
	(segment
		(start 94.631256 -17.7419)
		(end 95.434404 -18.545048)
		(width 0.127)
		(layer "In5.Cu")
		(net "BMC_EN_0V955_C")
	)
	(segment
		(start 85.0773 -23.192232)
		(end 85.0773 -22.944074)
		(width 0.127)
		(layer "In5.Cu")
		(net "BMC_EN_0V955_C")
	)
	(segment
		(start 77.038962 -24.4475)
		(end 77.6732 -23.813262)
		(width 0.127)
		(layer "In5.Cu")
		(net "BMC_EN_0V955_C")
	)
	(segment
		(start 209.919062 -45.8978)
		(end 243.8146 -45.8978)
		(width 0.127)
		(layer "In5.Cu")
		(net "BMC_EN_0V955_C")
	)
	(segment
		(start 101.150166 -36.599876)
		(end 100.75037 -36.20008)
		(width 0.1397)
		(layer "F.Cu")
		(net "PCIE_SAS_C_CPU_RX_N5")
	)
	(via
		(at 100.75037 -36.20008)
		(size 0.508)
		(drill 0.254)
		(layers "F.Cu" "B.Cu")
		(net "PCIE_SAS_C_CPU_RX_N5")
	)
	(segment
		(start 101.57206 -32.011366)
		(end 101.57206 -33.05048)
		(width 0.1397)
		(layer "B.Cu")
		(net "PCIE_SAS_C_CPU_RX_N5")
	)
	(segment
		(start 100.988876 -35.961574)
		(end 100.75037 -36.20008)
		(width 0.0889)
		(layer "B.Cu")
		(net "PCIE_SAS_C_CPU_RX_N5")
	)
	(segment
		(start 101.15804 -35.10788)
		(end 101.15804 -35.4203)
		(width 0.0889)
		(layer "B.Cu")
		(net "PCIE_SAS_C_CPU_RX_N5")
	)
	(segment
		(start 101.09327 -33.96615)
		(end 101.09327 -35.04311)
		(width 0.1397)
		(layer "B.Cu")
		(net "PCIE_SAS_C_CPU_RX_N5")
	)
	(segment
		(start 101.367336 -33.544764)
		(end 101.197664 -33.714436)
		(width 0.1397)
		(layer "B.Cu")
		(net "PCIE_SAS_C_CPU_RX_N5")
	)
	(arc
		(start 101.09327 -35.04311)
		(mid 101.139069 -35.062081)
		(end 101.15804 -35.10788)
		(width 0.1397)
		(layer "B.Cu")
		(net "PCIE_SAS_C_CPU_RX_N5")
	)
	(arc
		(start 101.57206 -33.05048)
		(mid 101.518851 -33.317979)
		(end 101.367336 -33.544764)
		(width 0.1397)
		(layer "B.Cu")
		(net "PCIE_SAS_C_CPU_RX_N5")
	)
	(arc
		(start 101.15804 -35.4203)
		(mid 101.142864 -35.562307)
		(end 101.098096 -35.697922)
		(width 0.0889)
		(layer "B.Cu")
		(net "PCIE_SAS_C_CPU_RX_N5")
	)
	(arc
		(start 101.61016 -31.919418)
		(mid 101.582991 -31.95902)
		(end 101.57206 -32.005778)
		(width 0.1397)
		(layer "B.Cu")
		(net "PCIE_SAS_C_CPU_RX_N5")
	)
	(arc
		(start 101.57206 -32.005778)
		(mid 101.57203 -32.008572)
		(end 101.57206 -32.011366)
		(width 0.1397)
		(layer "B.Cu")
		(net "PCIE_SAS_C_CPU_RX_N5")
	)
	(arc
		(start 101.197664 -33.714436)
		(mid 101.120415 -33.829908)
		(end 101.09327 -33.96615)
		(width 0.1397)
		(layer "B.Cu")
		(net "PCIE_SAS_C_CPU_RX_N5")
	)
	(arc
		(start 101.098096 -35.697922)
		(mid 101.069713 -35.840614)
		(end 100.988876 -35.961574)
		(width 0.0889)
		(layer "B.Cu")
		(net "PCIE_SAS_C_CPU_RX_N5")
	)
	(segment
		(start 117.93093 -82.930746)
		(end 118.35003 -83.349846)
		(width 0.1143)
		(layer "F.Cu")
		(net "TEST_MUX_42")
	)
	(segment
		(start 116.09197 -79.593186)
		(end 117.93093 -81.432146)
		(width 0.1143)
		(layer "F.Cu")
		(net "TEST_MUX_42")
	)
	(segment
		(start 116.09197 -78.232)
		(end 116.09197 -79.593186)
		(width 0.1143)
		(layer "F.Cu")
		(net "TEST_MUX_42")
	)
	(segment
		(start 117.93093 -81.432146)
		(end 117.93093 -82.930746)
		(width 0.1143)
		(layer "F.Cu")
		(net "TEST_MUX_42")
	)
	(segment
		(start 92.350082 -34.19983)
		(end 92.350082 -33.974786)
		(width 0.2032)
		(layer "F.Cu")
		(net "SAS0_AVDD")
	)
	(segment
		(start 95.549974 -42.999914)
		(end 95.944944 -43.394884)
		(width 0.3556)
		(layer "F.Cu")
		(net "SAS0_AVDD")
	)
	(segment
		(start 97.150174 -42.990516)
		(end 96.755712 -42.596054)
		(width 0.3556)
		(layer "F.Cu")
		(net "SAS0_AVDD")
	)
	(segment
		(start 95.540576 -39.800022)
		(end 95.14078 -40.199818)
		(width 0.3556)
		(layer "F.Cu")
		(net "SAS0_AVDD")
	)
	(segment
		(start 97.150174 -42.999914)
		(end 97.150174 -42.990516)
		(width 0.3556)
		(layer "F.Cu")
		(net "SAS0_AVDD")
	)
	(segment
		(start 93.150182 -41.399968)
		(end 93.150182 -41.391078)
		(width 0.3556)
		(layer "F.Cu")
		(net "SAS0_AVDD")
	)
	(segment
		(start 92.756482 -33.568386)
		(end 92.756482 -33.231582)
		(width 0.2032)
		(layer "F.Cu")
		(net "SAS0_AVDD")
	)
	(segment
		(start 95.549974 -38.207188)
		(end 95.950786 -38.608)
		(width 0.3556)
		(layer "F.Cu")
		(net "SAS0_AVDD")
	)
	(segment
		(start 92.747084 -38.599364)
		(end 93.147642 -38.999922)
		(width 0.381)
		(layer "F.Cu")
		(net "SAS0_AVDD")
	)
	(segment
		(start 93.150182 -41.391078)
		(end 92.754704 -40.9956)
		(width 0.3556)
		(layer "F.Cu")
		(net "SAS0_AVDD")
	)
	(segment
		(start 95.549974 -41.399968)
		(end 95.540576 -41.399968)
		(width 0.3556)
		(layer "F.Cu")
		(net "SAS0_AVDD")
	)
	(segment
		(start 92.350082 -33.974786)
		(end 92.756482 -33.568386)
		(width 0.2032)
		(layer "F.Cu")
		(net "SAS0_AVDD")
	)
	(segment
		(start 95.944944 -43.394884)
		(end 95.9485 -43.394884)
		(width 0.3556)
		(layer "F.Cu")
		(net "SAS0_AVDD")
	)
	(segment
		(start 95.540576 -41.399968)
		(end 95.142558 -41.797986)
		(width 0.3556)
		(layer "F.Cu")
		(net "SAS0_AVDD")
	)
	(segment
		(start 93.150182 -36.599876)
		(end 93.150182 -36.597082)
		(width 0.3556)
		(layer "F.Cu")
		(net "SAS0_AVDD")
	)
	(segment
		(start 95.549974 -38.199822)
		(end 95.549974 -38.207188)
		(width 0.3556)
		(layer "F.Cu")
		(net "SAS0_AVDD")
	)
	(segment
		(start 92.747084 -38.593268)
		(end 92.747084 -38.599364)
		(width 0.381)
		(layer "F.Cu")
		(net "SAS0_AVDD")
	)
	(segment
		(start 95.549974 -39.800022)
		(end 95.540576 -39.800022)
		(width 0.3556)
		(layer "F.Cu")
		(net "SAS0_AVDD")
	)
	(segment
		(start 92.743782 -33.218882)
		(end 92.743782 -32.799782)
		(width 0.2032)
		(layer "F.Cu")
		(net "SAS0_AVDD")
	)
	(segment
		(start 93.150182 -36.597082)
		(end 92.756228 -36.203128)
		(width 0.3556)
		(layer "F.Cu")
		(net "SAS0_AVDD")
	)
	(segment
		(start 92.756482 -33.231582)
		(end 92.743782 -33.218882)
		(width 0.2032)
		(layer "F.Cu")
		(net "SAS0_AVDD")
	)
	(segment
		(start 93.147642 -38.999922)
		(end 93.150182 -38.999922)
		(width 0.381)
		(layer "F.Cu")
		(net "SAS0_AVDD")
	)
	(via
		(at 82.785966 -30.099)
		(size 0.5588)
		(drill 0.3048)
		(layers "F.Cu" "B.Cu")
		(net "SAS0_AVDD")
	)
	(via
		(at 92.743782 -32.799782)
		(size 0.508)
		(drill 0.254)
		(layers "F.Cu" "B.Cu")
		(net "SAS0_AVDD")
	)
	(via
		(at 95.14078 -40.199818)
		(size 0.508)
		(drill 0.254)
		(layers "F.Cu" "B.Cu")
		(net "SAS0_AVDD")
	)
	(via
		(at 84.963 -30.099)
		(size 0.5588)
		(drill 0.3048)
		(layers "F.Cu" "B.Cu")
		(net "SAS0_AVDD")
	)
	(via
		(at 95.9485 -43.394884)
		(size 0.508)
		(drill 0.254)
		(layers "F.Cu" "B.Cu")
		(net "SAS0_AVDD")
	)
	(via
		(at 92.756228 -36.203128)
		(size 0.508)
		(drill 0.254)
		(layers "F.Cu" "B.Cu")
		(net "SAS0_AVDD")
	)
	(via
		(at 83.82 -30.099)
		(size 0.5588)
		(drill 0.3048)
		(layers "F.Cu" "B.Cu")
		(net "SAS0_AVDD")
	)
	(via
		(at 92.754704 -40.9956)
		(size 0.508)
		(drill 0.254)
		(layers "F.Cu" "B.Cu")
		(net "SAS0_AVDD")
	)
	(via
		(at 81.661 -30.099)
		(size 0.5588)
		(drill 0.3048)
		(layers "F.Cu" "B.Cu")
		(net "SAS0_AVDD")
	)
	(via
		(at 96.755712 -42.596054)
		(size 0.508)
		(drill 0.254)
		(layers "F.Cu" "B.Cu")
		(net "SAS0_AVDD")
	)
	(via
		(at 92.747084 -38.593268)
		(size 0.508)
		(drill 0.254)
		(layers "F.Cu" "B.Cu")
		(net "SAS0_AVDD")
	)
	(via
		(at 95.950786 -38.608)
		(size 0.508)
		(drill 0.254)
		(layers "F.Cu" "B.Cu")
		(net "SAS0_AVDD")
	)
	(via
		(at 81.407 -31.496)
		(size 0.7112)
		(drill 0.3556)
		(layers "F.Cu" "B.Cu")
		(net "SAS0_AVDD")
	)
	(via
		(at 95.142558 -41.797986)
		(size 0.508)
		(drill 0.254)
		(layers "F.Cu" "B.Cu")
		(net "SAS0_AVDD")
	)
	(segment
		(start 95.155766 -43.4594)
		(end 95.837248 -43.4594)
		(width 0.3556)
		(layer "B.Cu")
		(net "SAS0_AVDD")
	)
	(segment
		(start 95.901764 -43.394884)
		(end 95.9485 -43.394884)
		(width 0.3556)
		(layer "B.Cu")
		(net "SAS0_AVDD")
	)
	(segment
		(start 92.336366 -35.783266)
		(end 92.756228 -36.203128)
		(width 0.3048)
		(layer "B.Cu")
		(net "SAS0_AVDD")
	)
	(segment
		(start 91.193366 -32.639)
		(end 91.193366 -31.623)
		(width 0.3048)
		(layer "B.Cu")
		(net "SAS0_AVDD")
	)
	(segment
		(start 92.590366 -36.36899)
		(end 92.756228 -36.203128)
		(width 0.3048)
		(layer "B.Cu")
		(net "SAS0_AVDD")
	)
	(segment
		(start 92.583 -32.639)
		(end 91.193366 -32.639)
		(width 0.3048)
		(layer "B.Cu")
		(net "SAS0_AVDD")
	)
	(segment
		(start 95.160592 -41.81602)
		(end 95.142558 -41.797986)
		(width 0.3556)
		(layer "B.Cu")
		(net "SAS0_AVDD")
	)
	(segment
		(start 95.837248 -43.4594)
		(end 95.901764 -43.394884)
		(width 0.3556)
		(layer "B.Cu")
		(net "SAS0_AVDD")
	)
	(segment
		(start 95.225362 -40.2844)
		(end 95.14078 -40.199818)
		(width 0.3556)
		(layer "B.Cu")
		(net "SAS0_AVDD")
	)
	(segment
		(start 96.060006 -41.81602)
		(end 95.160592 -41.81602)
		(width 0.3556)
		(layer "B.Cu")
		(net "SAS0_AVDD")
	)
	(segment
		(start 96.070166 -40.2844)
		(end 95.225362 -40.2844)
		(width 0.3556)
		(layer "B.Cu")
		(net "SAS0_AVDD")
	)
	(segment
		(start 92.743782 -32.799782)
		(end 92.583 -32.639)
		(width 0.3048)
		(layer "B.Cu")
		(net "SAS0_AVDD")
	)
	(segment
		(start 92.590366 -37.084)
		(end 92.590366 -36.36899)
		(width 0.3048)
		(layer "B.Cu")
		(net "SAS0_AVDD")
	)
	(segment
		(start 92.336366 -35.433)
		(end 92.336366 -35.783266)
		(width 0.3048)
		(layer "B.Cu")
		(net "SAS0_AVDD")
	)
	(segment
		(start 103.549958 -35.80003)
		(end 103.150162 -35.400234)
		(width 0.1397)
		(layer "F.Cu")
		(net "PCIE_SAS_C_CPU_RX_P7")
	)
	(via
		(at 103.150162 -35.400234)
		(size 0.508)
		(drill 0.254)
		(layers "F.Cu" "B.Cu")
		(net "PCIE_SAS_C_CPU_RX_P7")
	)
	(segment
		(start 103.207312 -35.054032)
		(end 103.207312 -35.290506)
		(width 0.1397)
		(layer "B.Cu")
		(net "PCIE_SAS_C_CPU_RX_P7")
	)
	(segment
		(start 104.15016 -32.208978)
		(end 104.15016 -33.731454)
		(width 0.1397)
		(layer "B.Cu")
		(net "PCIE_SAS_C_CPU_RX_P7")
	)
	(segment
		(start 103.308912 -34.899854)
		(end 103.244396 -34.96437)
		(width 0.1397)
		(layer "B.Cu")
		(net "PCIE_SAS_C_CPU_RX_P7")
	)
	(segment
		(start 103.309166 -34.899346)
		(end 103.308912 -34.899854)
		(width 0.1397)
		(layer "B.Cu")
		(net "PCIE_SAS_C_CPU_RX_P7")
	)
	(segment
		(start 103.345234 -34.812732)
		(end 103.309166 -34.899346)
		(width 0.1397)
		(layer "B.Cu")
		(net "PCIE_SAS_C_CPU_RX_P7")
	)
	(segment
		(start 103.160322 -35.389566)
		(end 103.150162 -35.400234)
		(width 0.1397)
		(layer "B.Cu")
		(net "PCIE_SAS_C_CPU_RX_P7")
	)
	(segment
		(start 103.170228 -35.379914)
		(end 103.160322 -35.389566)
		(width 0.1397)
		(layer "B.Cu")
		(net "PCIE_SAS_C_CPU_RX_P7")
	)
	(segment
		(start 103.954326 -34.20364)
		(end 103.345234 -34.812732)
		(width 0.1397)
		(layer "B.Cu")
		(net "PCIE_SAS_C_CPU_RX_P7")
	)
	(arc
		(start 104.02316 -31.9024)
		(mid 104.117145 -32.043059)
		(end 104.15016 -32.208978)
		(width 0.1397)
		(layer "B.Cu")
		(net "PCIE_SAS_C_CPU_RX_P7")
	)
	(arc
		(start 103.203502 -35.3187)
		(mid 103.201903 -35.325478)
		(end 103.199946 -35.332162)
		(width 0.1397)
		(layer "B.Cu")
		(net "PCIE_SAS_C_CPU_RX_P7")
	)
	(arc
		(start 103.244396 -34.96437)
		(mid 103.216963 -35.005521)
		(end 103.207312 -35.054032)
		(width 0.1397)
		(layer "B.Cu")
		(net "PCIE_SAS_C_CPU_RX_P7")
	)
	(arc
		(start 103.205026 -35.312604)
		(mid 103.2043 -35.315661)
		(end 103.203502 -35.3187)
		(width 0.1397)
		(layer "B.Cu")
		(net "PCIE_SAS_C_CPU_RX_P7")
	)
	(arc
		(start 103.207312 -35.290506)
		(mid 103.206646 -35.301604)
		(end 103.205026 -35.312604)
		(width 0.1397)
		(layer "B.Cu")
		(net "PCIE_SAS_C_CPU_RX_P7")
	)
	(arc
		(start 103.199946 -35.332162)
		(mid 103.18778 -35.357716)
		(end 103.170228 -35.379914)
		(width 0.1397)
		(layer "B.Cu")
		(net "PCIE_SAS_C_CPU_RX_P7")
	)
	(arc
		(start 104.15016 -33.731454)
		(mid 104.099159 -33.987001)
		(end 103.954326 -34.20364)
		(width 0.1397)
		(layer "B.Cu")
		(net "PCIE_SAS_C_CPU_RX_P7")
	)
	(segment
		(start 97.29597 -104.902)
		(end 98.31197 -103.886)
		(width 0.1143)
		(layer "F.Cu")
		(net "SMART_TX")
	)
	(segment
		(start 97.155 -104.902)
		(end 97.29597 -104.902)
		(width 0.1143)
		(layer "F.Cu")
		(net "SMART_TX")
	)
	(segment
		(start 96.15297 -104.902)
		(end 97.155 -104.902)
		(width 0.1143)
		(layer "F.Cu")
		(net "SMART_TX")
	)
	(segment
		(start 102.813866 -103.886)
		(end 103.349806 -103.35006)
		(width 0.1143)
		(layer "F.Cu")
		(net "SMART_TX")
	)
	(segment
		(start 98.31197 -103.886)
		(end 102.813866 -103.886)
		(width 0.1143)
		(layer "F.Cu")
		(net "SMART_TX")
	)
	(via
		(at 97.155 -104.902)
		(size 0.7112)
		(drill 0.3556)
		(layers "F.Cu" "B.Cu")
		(net "SMART_TX")
	)
	(segment
		(start 104.350058 -33.328102)
		(end 105.03916 -32.639)
		(width 0.3048)
		(layer "F.Cu")
		(net "PCE_AVDD")
	)
	(segment
		(start 97.150174 -33.078166)
		(end 97.45472 -32.77362)
		(width 0.3048)
		(layer "F.Cu")
		(net "PCE_AVDD")
	)
	(segment
		(start 101.950774 -38.199822)
		(end 102.346252 -38.5953)
		(width 0.3556)
		(layer "F.Cu")
		(net "PCE_AVDD")
	)
	(segment
		(start 97.150174 -33.399984)
		(end 97.150174 -33.078166)
		(width 0.3048)
		(layer "F.Cu")
		(net "PCE_AVDD")
	)
	(segment
		(start 101.950012 -33.399984)
		(end 101.950012 -33.172908)
		(width 0.3048)
		(layer "F.Cu")
		(net "PCE_AVDD")
	)
	(segment
		(start 98.75012 -38.209474)
		(end 99.146106 -38.60546)
		(width 0.3556)
		(layer "F.Cu")
		(net "PCE_AVDD")
	)
	(segment
		(start 104.350058 -33.399984)
		(end 104.350058 -33.328102)
		(width 0.3048)
		(layer "F.Cu")
		(net "PCE_AVDD")
	)
	(segment
		(start 97.150174 -38.199568)
		(end 96.745552 -37.794946)
		(width 0.3556)
		(layer "F.Cu")
		(net "PCE_AVDD")
	)
	(segment
		(start 101.950012 -38.199822)
		(end 101.950774 -38.199822)
		(width 0.3556)
		(layer "F.Cu")
		(net "PCE_AVDD")
	)
	(segment
		(start 98.75012 -38.199822)
		(end 98.75012 -38.209474)
		(width 0.3556)
		(layer "F.Cu")
		(net "PCE_AVDD")
	)
	(segment
		(start 98.75012 -38.999922)
		(end 98.751644 -38.999922)
		(width 0.3556)
		(layer "F.Cu")
		(net "PCE_AVDD")
	)
	(segment
		(start 94.750128 -33.399984)
		(end 94.750128 -33.403032)
		(width 0.3048)
		(layer "F.Cu")
		(net "PCE_AVDD")
	)
	(segment
		(start 99.549966 -32.844994)
		(end 99.62896 -32.766)
		(width 0.3048)
		(layer "F.Cu")
		(net "PCE_AVDD")
	)
	(segment
		(start 101.950012 -33.172908)
		(end 102.3112 -32.81172)
		(width 0.3048)
		(layer "F.Cu")
		(net "PCE_AVDD")
	)
	(segment
		(start 100.350066 -38.20922)
		(end 100.746306 -38.60546)
		(width 0.3556)
		(layer "F.Cu")
		(net "PCE_AVDD")
	)
	(segment
		(start 100.350066 -38.199822)
		(end 100.350066 -38.20922)
		(width 0.3556)
		(layer "F.Cu")
		(net "PCE_AVDD")
	)
	(segment
		(start 97.150174 -38.199822)
		(end 97.150174 -38.199568)
		(width 0.3556)
		(layer "F.Cu")
		(net "PCE_AVDD")
	)
	(segment
		(start 94.750128 -33.403032)
		(end 94.356428 -33.796732)
		(width 0.3048)
		(layer "F.Cu")
		(net "PCE_AVDD")
	)
	(segment
		(start 99.549966 -33.399984)
		(end 99.549966 -32.844994)
		(width 0.3048)
		(layer "F.Cu")
		(net "PCE_AVDD")
	)
	(segment
		(start 98.751644 -38.999922)
		(end 99.146106 -38.60546)
		(width 0.3556)
		(layer "F.Cu")
		(net "PCE_AVDD")
	)
	(via
		(at 100.746306 -38.60546)
		(size 0.508)
		(drill 0.254)
		(layers "F.Cu" "B.Cu")
		(net "PCE_AVDD")
	)
	(via
		(at 96.901 -14.732)
		(size 0.7112)
		(drill 0.4064)
		(layers "F.Cu" "B.Cu")
		(net "PCE_AVDD")
	)
	(via
		(at 98.044 -13.462)
		(size 0.7112)
		(drill 0.4064)
		(layers "F.Cu" "B.Cu")
		(net "PCE_AVDD")
	)
	(via
		(at 105.03916 -32.639)
		(size 0.508)
		(drill 0.254)
		(layers "F.Cu" "B.Cu")
		(net "PCE_AVDD")
	)
	(via
		(at 102.346252 -38.5953)
		(size 0.508)
		(drill 0.254)
		(layers "F.Cu" "B.Cu")
		(net "PCE_AVDD")
	)
	(via
		(at 99.62896 -32.766)
		(size 0.508)
		(drill 0.254)
		(layers "F.Cu" "B.Cu")
		(net "PCE_AVDD")
	)
	(via
		(at 96.745552 -37.794946)
		(size 0.508)
		(drill 0.254)
		(layers "F.Cu" "B.Cu")
		(net "PCE_AVDD")
	)
	(via
		(at 99.146106 -38.60546)
		(size 0.508)
		(drill 0.254)
		(layers "F.Cu" "B.Cu")
		(net "PCE_AVDD")
	)
	(via
		(at 102.3112 -32.81172)
		(size 0.508)
		(drill 0.254)
		(layers "F.Cu" "B.Cu")
		(net "PCE_AVDD")
	)
	(via
		(at 94.356428 -33.796732)
		(size 0.508)
		(drill 0.254)
		(layers "F.Cu" "B.Cu")
		(net "PCE_AVDD")
	)
	(via
		(at 97.45472 -32.77362)
		(size 0.508)
		(drill 0.254)
		(layers "F.Cu" "B.Cu")
		(net "PCE_AVDD")
	)
	(via
		(at 96.774 -16.129)
		(size 0.7112)
		(drill 0.3556)
		(layers "F.Cu" "B.Cu")
		(net "PCE_AVDD")
	)
	(via
		(at 96.901 -13.462)
		(size 0.7112)
		(drill 0.4064)
		(layers "F.Cu" "B.Cu")
		(net "PCE_AVDD")
	)
	(segment
		(start 98.305366 -38.7604)
		(end 98.460306 -38.60546)
		(width 0.3556)
		(layer "B.Cu")
		(net "PCE_AVDD")
	)
	(segment
		(start 105.137966 -32.737806)
		(end 105.03916 -32.639)
		(width 0.3048)
		(layer "B.Cu")
		(net "PCE_AVDD")
	)
	(segment
		(start 105.137966 -33.3756)
		(end 105.137966 -32.737806)
		(width 0.3048)
		(layer "B.Cu")
		(net "PCE_AVDD")
	)
	(segment
		(start 96.923606 -37.973)
		(end 96.745552 -37.794946)
		(width 0.254)
		(layer "B.Cu")
		(net "PCE_AVDD")
	)
	(segment
		(start 92.844366 -33.401)
		(end 93.199966 -33.401)
		(width 0.3048)
		(layer "B.Cu")
		(net "PCE_AVDD")
	)
	(segment
		(start 93.415612 -33.185354)
		(end 93.74505 -33.185354)
		(width 0.3048)
		(layer "B.Cu")
		(net "PCE_AVDD")
	)
	(segment
		(start 98.460306 -38.60546)
		(end 99.146106 -38.60546)
		(width 0.3556)
		(layer "B.Cu")
		(net "PCE_AVDD")
	)
	(segment
		(start 101.9556 -37.719)
		(end 101.9556 -38.204648)
		(width 0.254)
		(layer "B.Cu")
		(net "PCE_AVDD")
	)
	(segment
		(start 103.230426 -38.53434)
		(end 102.823772 -38.53434)
		(width 0.3556)
		(layer "B.Cu")
		(net "PCE_AVDD")
	)
	(segment
		(start 96.715326 -38.66896)
		(end 96.715326 -37.825172)
		(width 0.3556)
		(layer "B.Cu")
		(net "PCE_AVDD")
	)
	(segment
		(start 99.27336 -33.1216)
		(end 99.62896 -32.766)
		(width 0.3048)
		(layer "B.Cu")
		(net "PCE_AVDD")
	)
	(segment
		(start 96.715326 -37.825172)
		(end 96.745552 -37.794946)
		(width 0.3556)
		(layer "B.Cu")
		(net "PCE_AVDD")
	)
	(segment
		(start 103.258366 -38.5064)
		(end 103.230426 -38.53434)
		(width 0.3556)
		(layer "B.Cu")
		(net "PCE_AVDD")
	)
	(segment
		(start 93.199966 -33.401)
		(end 93.415612 -33.185354)
		(width 0.3048)
		(layer "B.Cu")
		(net "PCE_AVDD")
	)
	(segment
		(start 92.8624 -33.419034)
		(end 92.844366 -33.401)
		(width 0.254)
		(layer "B.Cu")
		(net "PCE_AVDD")
	)
	(segment
		(start 101.9556 -38.204648)
		(end 102.346252 -38.5953)
		(width 0.254)
		(layer "B.Cu")
		(net "PCE_AVDD")
	)
	(segment
		(start 93.74505 -33.185354)
		(end 94.356428 -33.796732)
		(width 0.3048)
		(layer "B.Cu")
		(net "PCE_AVDD")
	)
	(segment
		(start 102.358952 -38.5826)
		(end 102.346252 -38.5953)
		(width 0.3556)
		(layer "B.Cu")
		(net "PCE_AVDD")
	)
	(segment
		(start 98.94316 -33.1216)
		(end 99.27336 -33.1216)
		(width 0.3048)
		(layer "B.Cu")
		(net "PCE_AVDD")
	)
	(segment
		(start 97.3836 -37.973)
		(end 96.923606 -37.973)
		(width 0.254)
		(layer "B.Cu")
		(net "PCE_AVDD")
	)
	(segment
		(start 92.8624 -34.163)
		(end 92.8624 -33.419034)
		(width 0.254)
		(layer "B.Cu")
		(net "PCE_AVDD")
	)
	(segment
		(start 102.823772 -38.53434)
		(end 102.358952 -38.5826)
		(width 0.3556)
		(layer "B.Cu")
		(net "PCE_AVDD")
	)
	(segment
		(start 97.95002 -36.599876)
		(end 97.550224 -36.20008)
		(width 0.1397)
		(layer "F.Cu")
		(net "PCIE_SAS_C_CPU_RX_N2")
	)
	(via
		(at 97.550224 -36.20008)
		(size 0.508)
		(drill 0.254)
		(layers "F.Cu" "B.Cu")
		(net "PCIE_SAS_C_CPU_RX_N2")
	)
	(segment
		(start 97.764092 -34.794952)
		(end 97.845626 -34.876486)
		(width 0.1397)
		(layer "B.Cu")
		(net "PCIE_SAS_C_CPU_RX_N2")
	)
	(segment
		(start 97.608898 -34.462466)
		(end 97.608898 -34.46272)
		(width 0.1397)
		(layer "B.Cu")
		(net "PCIE_SAS_C_CPU_RX_N2")
	)
	(segment
		(start 97.831402 -35.67557)
		(end 97.62998 -35.876992)
		(width 0.0889)
		(layer "B.Cu")
		(net "PCIE_SAS_C_CPU_RX_N2")
	)
	(segment
		(start 97.606866 -34.05632)
		(end 97.606866 -34.415476)
		(width 0.1397)
		(layer "B.Cu")
		(net "PCIE_SAS_C_CPU_RX_N2")
	)
	(segment
		(start 97.940876 -35.106356)
		(end 97.940876 -35.41141)
		(width 0.0889)
		(layer "B.Cu")
		(net "PCIE_SAS_C_CPU_RX_N2")
	)
	(segment
		(start 97.009966 -31.970472)
		(end 97.009966 -33.117282)
		(width 0.1397)
		(layer "B.Cu")
		(net "PCIE_SAS_C_CPU_RX_N2")
	)
	(segment
		(start 97.04705 -33.206944)
		(end 97.402142 -33.562036)
		(width 0.1397)
		(layer "B.Cu")
		(net "PCIE_SAS_C_CPU_RX_N2")
	)
	(segment
		(start 97.550224 -36.069524)
		(end 97.550224 -36.20008)
		(width 0.0889)
		(layer "B.Cu")
		(net "PCIE_SAS_C_CPU_RX_N2")
	)
	(arc
		(start 97.677732 -34.682176)
		(mid 97.679626 -34.685358)
		(end 97.681542 -34.688526)
		(width 0.1397)
		(layer "B.Cu")
		(net "PCIE_SAS_C_CPU_RX_N2")
	)
	(arc
		(start 97.03816 -31.9024)
		(mid 97.017292 -31.933632)
		(end 97.009966 -31.970472)
		(width 0.1397)
		(layer "B.Cu")
		(net "PCIE_SAS_C_CPU_RX_N2")
	)
	(arc
		(start 97.681542 -34.688526)
		(mid 97.692743 -34.706663)
		(end 97.704656 -34.72434)
		(width 0.1397)
		(layer "B.Cu")
		(net "PCIE_SAS_C_CPU_RX_N2")
	)
	(arc
		(start 97.608898 -34.46272)
		(mid 97.615455 -34.51138)
		(end 97.626424 -34.55924)
		(width 0.1397)
		(layer "B.Cu")
		(net "PCIE_SAS_C_CPU_RX_N2")
	)
	(arc
		(start 97.402142 -33.562036)
		(mid 97.553671 -33.788815)
		(end 97.606866 -34.05632)
		(width 0.1397)
		(layer "B.Cu")
		(net "PCIE_SAS_C_CPU_RX_N2")
	)
	(arc
		(start 97.714054 -34.737548)
		(mid 97.715574 -34.739456)
		(end 97.717102 -34.741358)
		(width 0.1397)
		(layer "B.Cu")
		(net "PCIE_SAS_C_CPU_RX_N2")
	)
	(arc
		(start 97.704656 -34.72434)
		(mid 97.704783 -34.724594)
		(end 97.70491 -34.724848)
		(width 0.1397)
		(layer "B.Cu")
		(net "PCIE_SAS_C_CPU_RX_N2")
	)
	(arc
		(start 97.940876 -35.41141)
		(mid 97.91242 -35.554379)
		(end 97.831402 -35.67557)
		(width 0.0889)
		(layer "B.Cu")
		(net "PCIE_SAS_C_CPU_RX_N2")
	)
	(arc
		(start 97.009966 -33.117282)
		(mid 97.019599 -33.1658)
		(end 97.04705 -33.206944)
		(width 0.1397)
		(layer "B.Cu")
		(net "PCIE_SAS_C_CPU_RX_N2")
	)
	(arc
		(start 97.75317 -34.783776)
		(mid 97.75859 -34.789404)
		(end 97.764092 -34.794952)
		(width 0.1397)
		(layer "B.Cu")
		(net "PCIE_SAS_C_CPU_RX_N2")
	)
	(arc
		(start 97.626424 -34.55924)
		(mid 97.638822 -34.59799)
		(end 97.65411 -34.635694)
		(width 0.1397)
		(layer "B.Cu")
		(net "PCIE_SAS_C_CPU_RX_N2")
	)
	(arc
		(start 97.65411 -34.635694)
		(mid 97.66028 -34.648988)
		(end 97.66681 -34.66211)
		(width 0.1397)
		(layer "B.Cu")
		(net "PCIE_SAS_C_CPU_RX_N2")
	)
	(arc
		(start 97.62998 -35.876992)
		(mid 97.570957 -35.965326)
		(end 97.550224 -36.069524)
		(width 0.0889)
		(layer "B.Cu")
		(net "PCIE_SAS_C_CPU_RX_N2")
	)
	(arc
		(start 97.66681 -34.66211)
		(mid 97.669947 -34.668226)
		(end 97.67316 -34.674302)
		(width 0.1397)
		(layer "B.Cu")
		(net "PCIE_SAS_C_CPU_RX_N2")
	)
	(arc
		(start 97.606866 -34.415476)
		(mid 97.607371 -34.438993)
		(end 97.608898 -34.462466)
		(width 0.1397)
		(layer "B.Cu")
		(net "PCIE_SAS_C_CPU_RX_N2")
	)
	(arc
		(start 97.845626 -34.876486)
		(mid 97.916096 -34.981951)
		(end 97.940876 -35.106356)
		(width 0.0889)
		(layer "B.Cu")
		(net "PCIE_SAS_C_CPU_RX_N2")
	)
	(arc
		(start 97.67316 -34.674302)
		(mid 97.675429 -34.678249)
		(end 97.677732 -34.682176)
		(width 0.1397)
		(layer "B.Cu")
		(net "PCIE_SAS_C_CPU_RX_N2")
	)
	(arc
		(start 97.717102 -34.741358)
		(mid 97.734586 -34.763035)
		(end 97.75317 -34.783776)
		(width 0.1397)
		(layer "B.Cu")
		(net "PCIE_SAS_C_CPU_RX_N2")
	)
	(arc
		(start 97.70491 -34.724848)
		(mid 97.709435 -34.731231)
		(end 97.714054 -34.737548)
		(width 0.1397)
		(layer "B.Cu")
		(net "PCIE_SAS_C_CPU_RX_N2")
	)
	(segment
		(start 98.42881 -93.35516)
		(end 98.42881 -92.837)
		(width 0.1143)
		(layer "F.Cu")
		(net "LSI_SCAN_ENABLE")
	)
	(segment
		(start 108.349796 -89.349834)
		(end 107.84967 -88.849708)
		(width 0.1143)
		(layer "F.Cu")
		(net "LSI_SCAN_ENABLE")
	)
	(segment
		(start 96.34347 -94.234)
		(end 97.54997 -94.234)
		(width 0.1143)
		(layer "F.Cu")
		(net "LSI_SCAN_ENABLE")
	)
	(segment
		(start 97.54997 -94.234)
		(end 98.42881 -93.35516)
		(width 0.1143)
		(layer "F.Cu")
		(net "LSI_SCAN_ENABLE")
	)
	(segment
		(start 96.34347 -93.091)
		(end 96.34347 -94.234)
		(width 0.1143)
		(layer "F.Cu")
		(net "LSI_SCAN_ENABLE")
	)
	(via
		(at 98.42881 -92.837)
		(size 0.508)
		(drill 0.254)
		(layers "F.Cu" "B.Cu")
		(net "LSI_SCAN_ENABLE")
	)
	(via
		(at 107.84967 -88.849708)
		(size 0.508)
		(drill 0.254)
		(layers "F.Cu" "B.Cu")
		(net "LSI_SCAN_ENABLE")
	)
	(segment
		(start 98.429826 -92.835984)
		(end 98.429826 -92.83446)
		(width 0.127)
		(layer "In5.Cu")
		(net "LSI_SCAN_ENABLE")
	)
	(segment
		(start 98.42881 -92.837)
		(end 98.429826 -92.835984)
		(width 0.127)
		(layer "In5.Cu")
		(net "LSI_SCAN_ENABLE")
	)
	(segment
		(start 101.238304 -89.4715)
		(end 101.383084 -89.32672)
		(width 0.127)
		(layer "In5.Cu")
		(net "LSI_SCAN_ENABLE")
	)
	(segment
		(start 107.33405 -89.32672)
		(end 107.811062 -88.849708)
		(width 0.127)
		(layer "In5.Cu")
		(net "LSI_SCAN_ENABLE")
	)
	(segment
		(start 98.431096 -91.526106)
		(end 100.485702 -89.4715)
		(width 0.127)
		(layer "In5.Cu")
		(net "LSI_SCAN_ENABLE")
	)
	(segment
		(start 98.429826 -92.83446)
		(end 98.431096 -92.83319)
		(width 0.127)
		(layer "In5.Cu")
		(net "LSI_SCAN_ENABLE")
	)
	(segment
		(start 107.811062 -88.849708)
		(end 107.84967 -88.849708)
		(width 0.127)
		(layer "In5.Cu")
		(net "LSI_SCAN_ENABLE")
	)
	(segment
		(start 98.431096 -92.83319)
		(end 98.431096 -91.526106)
		(width 0.127)
		(layer "In5.Cu")
		(net "LSI_SCAN_ENABLE")
	)
	(segment
		(start 100.485702 -89.4715)
		(end 101.238304 -89.4715)
		(width 0.127)
		(layer "In5.Cu")
		(net "LSI_SCAN_ENABLE")
	)
	(segment
		(start 101.383084 -89.32672)
		(end 107.33405 -89.32672)
		(width 0.127)
		(layer "In5.Cu")
		(net "LSI_SCAN_ENABLE")
	)
	(segment
		(start 102.108 -61.087)
		(end 102.24135 -60.95365)
		(width 0.3556)
		(layer "F.Cu")
		(net "HM40ADC_VDDA")
	)
	(segment
		(start 101.943916 -59.265566)
		(end 101.943916 -58.523886)
		(width 0.3556)
		(layer "F.Cu")
		(net "HM40ADC_VDDA")
	)
	(segment
		(start 102.902766 -65.8876)
		(end 102.902766 -63.8556)
		(width 0.508)
		(layer "F.Cu")
		(net "HM40ADC_VDDA")
	)
	(segment
		(start 102.24135 -59.827414)
		(end 102.051612 -59.637676)
		(width 0.3556)
		(layer "F.Cu")
		(net "HM40ADC_VDDA")
	)
	(segment
		(start 102.051612 -59.373262)
		(end 101.943916 -59.265566)
		(width 0.3556)
		(layer "F.Cu")
		(net "HM40ADC_VDDA")
	)
	(segment
		(start 101.943916 -58.523886)
		(end 101.328474 -57.90819)
		(width 0.3556)
		(layer "F.Cu")
		(net "HM40ADC_VDDA")
	)
	(segment
		(start 101.328474 -56.778144)
		(end 101.150166 -56.599836)
		(width 0.3556)
		(layer "F.Cu")
		(net "HM40ADC_VDDA")
	)
	(segment
		(start 101.328474 -57.90819)
		(end 101.328474 -56.778144)
		(width 0.3556)
		(layer "F.Cu")
		(net "HM40ADC_VDDA")
	)
	(segment
		(start 102.24135 -60.95365)
		(end 102.24135 -59.827414)
		(width 0.3556)
		(layer "F.Cu")
		(net "HM40ADC_VDDA")
	)
	(segment
		(start 102.051612 -59.637676)
		(end 102.051612 -59.373262)
		(width 0.3556)
		(layer "F.Cu")
		(net "HM40ADC_VDDA")
	)
	(via
		(at 101.962966 -62.0776)
		(size 0.7112)
		(drill 0.3556)
		(layers "F.Cu" "B.Cu")
		(net "HM40ADC_VDDA")
	)
	(segment
		(start 88.461596 -39.800022)
		(end 90.750136 -39.800022)
		(width 0.1016)
		(layer "F.Cu")
		(net "SAS3008_RAID_TX_C_P7")
	)
	(segment
		(start 87.327486 -39.9923)
		(end 87.99703 -39.9923)
		(width 0.1016)
		(layer "F.Cu")
		(net "SAS3008_RAID_TX_C_P7")
	)
	(segment
		(start 86.77656 -40.259)
		(end 86.842092 -40.193468)
		(width 0.1016)
		(layer "F.Cu")
		(net "SAS3008_RAID_TX_C_P7")
	)
	(arc
		(start 87.99703 -39.9923)
		(mid 88.194831 -39.953124)
		(end 88.362536 -39.84117)
		(width 0.1016)
		(layer "F.Cu")
		(net "SAS3008_RAID_TX_C_P7")
	)
	(arc
		(start 86.842092 -40.193468)
		(mid 87.064778 -40.044581)
		(end 87.327486 -39.9923)
		(width 0.1016)
		(layer "F.Cu")
		(net "SAS3008_RAID_TX_C_P7")
	)
	(arc
		(start 88.362536 -39.84117)
		(mid 88.40797 -39.810719)
		(end 88.461596 -39.800022)
		(width 0.1016)
		(layer "F.Cu")
		(net "SAS3008_RAID_TX_C_P7")
	)
	(segment
		(start 88.119204 -36.623244)
		(end 88.479122 -36.983162)
		(width 0.1016)
		(layer "F.Cu")
		(net "SAS3008_RAID_TX_C_N2")
	)
	(segment
		(start 87.144606 -36.4744)
		(end 87.75954 -36.4744)
		(width 0.1016)
		(layer "F.Cu")
		(net "SAS3008_RAID_TX_C_N2")
	)
	(segment
		(start 88.595962 -37.031676)
		(end 90.726006 -37.031676)
		(width 0.1016)
		(layer "F.Cu")
		(net "SAS3008_RAID_TX_C_N2")
	)
	(segment
		(start 91.028012 -37.156898)
		(end 91.17965 -37.308536)
		(width 0.1016)
		(layer "F.Cu")
		(net "SAS3008_RAID_TX_C_N2")
	)
	(segment
		(start 91.400376 -37.399976)
		(end 91.549982 -37.399976)
		(width 0.1016)
		(layer "F.Cu")
		(net "SAS3008_RAID_TX_C_N2")
	)
	(arc
		(start 90.726006 -37.031676)
		(mid 90.889445 -37.06428)
		(end 91.028012 -37.156898)
		(width 0.1016)
		(layer "F.Cu")
		(net "SAS3008_RAID_TX_C_N2")
	)
	(arc
		(start 87.75954 -36.4744)
		(mid 87.954191 -36.513025)
		(end 88.119204 -36.623244)
		(width 0.1016)
		(layer "F.Cu")
		(net "SAS3008_RAID_TX_C_N2")
	)
	(arc
		(start 88.479122 -36.983162)
		(mid 88.532714 -37.019064)
		(end 88.595962 -37.031676)
		(width 0.1016)
		(layer "F.Cu")
		(net "SAS3008_RAID_TX_C_N2")
	)
	(arc
		(start 86.77656 -36.322)
		(mid 86.945421 -36.434829)
		(end 87.144606 -36.4744)
		(width 0.1016)
		(layer "F.Cu")
		(net "SAS3008_RAID_TX_C_N2")
	)
	(arc
		(start 91.17965 -37.308536)
		(mid 91.28092 -37.376202)
		(end 91.400376 -37.399976)
		(width 0.1016)
		(layer "F.Cu")
		(net "SAS3008_RAID_TX_C_N2")
	)
	(segment
		(start 118.18493 -81.29016)
		(end 118.18493 -82.184748)
		(width 0.1143)
		(layer "F.Cu")
		(net "TEST_MUX_43")
	)
	(segment
		(start 118.18493 -82.184748)
		(end 118.35003 -82.349848)
		(width 0.1143)
		(layer "F.Cu")
		(net "TEST_MUX_43")
	)
	(segment
		(start 117.26545 -79.65948)
		(end 117.26545 -80.37068)
		(width 0.1143)
		(layer "F.Cu")
		(net "TEST_MUX_43")
	)
	(segment
		(start 117.26545 -80.37068)
		(end 118.18493 -81.29016)
		(width 0.1143)
		(layer "F.Cu")
		(net "TEST_MUX_43")
	)
	(segment
		(start 116.85397 -79.248)
		(end 117.26545 -79.65948)
		(width 0.1143)
		(layer "F.Cu")
		(net "TEST_MUX_43")
	)
	(segment
		(start 108.35005 -40.599868)
		(end 108.749846 -40.999664)
		(width 0.3556)
		(layer "F.Cu")
		(net "PLL_VDD")
	)
	(via
		(at 108.749846 -40.999664)
		(size 0.508)
		(drill 0.254)
		(layers "F.Cu" "B.Cu")
		(net "PLL_VDD")
	)
	(via
		(at 122.536966 -35.306)
		(size 0.7112)
		(drill 0.4064)
		(layers "F.Cu" "B.Cu")
		(net "PLL_VDD")
	)
	(via
		(at 125.686566 -35.687)
		(size 0.7112)
		(drill 0.3556)
		(layers "F.Cu" "B.Cu")
		(net "PLL_VDD")
	)
	(segment
		(start 108.749846 -40.937434)
		(end 109.297216 -40.390064)
		(width 0.508)
		(layer "In2.Cu")
		(net "PLL_VDD")
	)
	(segment
		(start 119.45874 -33.2232)
		(end 120.027192 -33.2232)
		(width 0.508)
		(layer "In2.Cu")
		(net "PLL_VDD")
	)
	(segment
		(start 109.297216 -40.390064)
		(end 111.402368 -40.390064)
		(width 0.508)
		(layer "In2.Cu")
		(net "PLL_VDD")
	)
	(segment
		(start 116.769896 -33.2486)
		(end 119.43334 -33.2486)
		(width 0.508)
		(layer "In2.Cu")
		(net "PLL_VDD")
	)
	(segment
		(start 112.493298 -43.214798)
		(end 112.998758 -43.214798)
		(width 0.508)
		(layer "In2.Cu")
		(net "PLL_VDD")
	)
	(segment
		(start 116.061236 -33.0454)
		(end 116.566696 -33.0454)
		(width 0.508)
		(layer "In2.Cu")
		(net "PLL_VDD")
	)
	(segment
		(start 113.590578 -42.622978)
		(end 113.590578 -35.516058)
		(width 0.508)
		(layer "In2.Cu")
		(net "PLL_VDD")
	)
	(segment
		(start 112.998758 -43.214798)
		(end 113.590578 -42.622978)
		(width 0.508)
		(layer "In2.Cu")
		(net "PLL_VDD")
	)
	(segment
		(start 111.759492 -40.747188)
		(end 111.759492 -42.480992)
		(width 0.508)
		(layer "In2.Cu")
		(net "PLL_VDD")
	)
	(segment
		(start 111.759492 -42.480992)
		(end 112.493298 -43.214798)
		(width 0.508)
		(layer "In2.Cu")
		(net "PLL_VDD")
	)
	(segment
		(start 108.749846 -40.999664)
		(end 108.749846 -40.937434)
		(width 0.508)
		(layer "In2.Cu")
		(net "PLL_VDD")
	)
	(segment
		(start 113.590578 -35.516058)
		(end 116.061236 -33.0454)
		(width 0.508)
		(layer "In2.Cu")
		(net "PLL_VDD")
	)
	(segment
		(start 120.027192 -33.2232)
		(end 122.109992 -35.306)
		(width 0.508)
		(layer "In2.Cu")
		(net "PLL_VDD")
	)
	(segment
		(start 116.566696 -33.0454)
		(end 116.769896 -33.2486)
		(width 0.508)
		(layer "In2.Cu")
		(net "PLL_VDD")
	)
	(segment
		(start 111.402368 -40.390064)
		(end 111.759492 -40.747188)
		(width 0.508)
		(layer "In2.Cu")
		(net "PLL_VDD")
	)
	(segment
		(start 122.109992 -35.306)
		(end 122.536966 -35.306)
		(width 0.508)
		(layer "In2.Cu")
		(net "PLL_VDD")
	)
	(segment
		(start 119.43334 -33.2486)
		(end 119.45874 -33.2232)
		(width 0.508)
		(layer "In2.Cu")
		(net "PLL_VDD")
	)
	(segment
		(start 91.079066 -39.5351)
		(end 91.282266 -39.7383)
		(width 0.1016)
		(layer "F.Cu")
		(net "SAS3008_RAID_TX_C_N7")
	)
	(segment
		(start 86.837774 -39.6494)
		(end 87.997284 -39.6494)
		(width 0.1016)
		(layer "F.Cu")
		(net "SAS3008_RAID_TX_C_N7")
	)
	(segment
		(start 91.431364 -39.800022)
		(end 91.549982 -39.800022)
		(width 0.1016)
		(layer "F.Cu")
		(net "SAS3008_RAID_TX_C_N7")
	)
	(segment
		(start 88.461596 -39.457122)
		(end 90.890852 -39.457122)
		(width 0.1016)
		(layer "F.Cu")
		(net "SAS3008_RAID_TX_C_N7")
	)
	(arc
		(start 88.119966 -39.5986)
		(mid 88.276707 -39.493869)
		(end 88.461596 -39.457122)
		(width 0.1016)
		(layer "F.Cu")
		(net "SAS3008_RAID_TX_C_N7")
	)
	(arc
		(start 87.997284 -39.6494)
		(mid 88.063673 -39.636194)
		(end 88.119966 -39.5986)
		(width 0.1016)
		(layer "F.Cu")
		(net "SAS3008_RAID_TX_C_N7")
	)
	(arc
		(start 91.282266 -39.7383)
		(mid 91.350673 -39.784008)
		(end 91.431364 -39.800022)
		(width 0.1016)
		(layer "F.Cu")
		(net "SAS3008_RAID_TX_C_N7")
	)
	(arc
		(start 90.890852 -39.457122)
		(mid 90.992719 -39.477385)
		(end 91.079066 -39.5351)
		(width 0.1016)
		(layer "F.Cu")
		(net "SAS3008_RAID_TX_C_N7")
	)
	(arc
		(start 86.77656 -39.624)
		(mid 86.804645 -39.642766)
		(end 86.837774 -39.6494)
		(width 0.1016)
		(layer "F.Cu")
		(net "SAS3008_RAID_TX_C_N7")
	)
	(segment
		(start 103.549958 -36.599876)
		(end 103.150162 -36.20008)
		(width 0.1397)
		(layer "F.Cu")
		(net "PCIE_SAS_C_CPU_RX_N7")
	)
	(via
		(at 103.150162 -36.20008)
		(size 0.508)
		(drill 0.254)
		(layers "F.Cu" "B.Cu")
		(net "PCIE_SAS_C_CPU_RX_N7")
	)
	(segment
		(start 103.63581 -35.007296)
		(end 103.621332 -35.042094)
		(width 0.1397)
		(layer "B.Cu")
		(net "PCIE_SAS_C_CPU_RX_N7")
	)
	(segment
		(start 103.150162 -36.07435)
		(end 103.150162 -36.20008)
		(width 0.0889)
		(layer "B.Cu")
		(net "PCIE_SAS_C_CPU_RX_N7")
	)
	(segment
		(start 104.49306 -32.300926)
		(end 104.49306 -33.7312)
		(width 0.1397)
		(layer "B.Cu")
		(net "PCIE_SAS_C_CPU_RX_N7")
	)
	(segment
		(start 103.432864 -35.683698)
		(end 103.43261 -35.683698)
		(width 0.0889)
		(layer "B.Cu")
		(net "PCIE_SAS_C_CPU_RX_N7")
	)
	(segment
		(start 103.550212 -35.213798)
		(end 103.550212 -35.400742)
		(width 0.0889)
		(layer "B.Cu")
		(net "PCIE_SAS_C_CPU_RX_N7")
	)
	(segment
		(start 104.196896 -34.44621)
		(end 103.63581 -35.007296)
		(width 0.1397)
		(layer "B.Cu")
		(net "PCIE_SAS_C_CPU_RX_N7")
	)
	(segment
		(start 103.433118 -35.683444)
		(end 103.432864 -35.683698)
		(width 0.0889)
		(layer "B.Cu")
		(net "PCIE_SAS_C_CPU_RX_N7")
	)
	(segment
		(start 103.43261 -35.683698)
		(end 103.226616 -35.889692)
		(width 0.0889)
		(layer "B.Cu")
		(net "PCIE_SAS_C_CPU_RX_N7")
	)
	(arc
		(start 103.550212 -35.400742)
		(mid 103.519779 -35.553737)
		(end 103.433118 -35.683444)
		(width 0.0889)
		(layer "B.Cu")
		(net "PCIE_SAS_C_CPU_RX_N7")
	)
	(arc
		(start 104.65816 -31.9024)
		(mid 104.535987 -32.085245)
		(end 104.49306 -32.300926)
		(width 0.1397)
		(layer "B.Cu")
		(net "PCIE_SAS_C_CPU_RX_N7")
	)
	(arc
		(start 104.49306 -33.7312)
		(mid 104.416089 -34.11816)
		(end 104.196896 -34.44621)
		(width 0.1397)
		(layer "B.Cu")
		(net "PCIE_SAS_C_CPU_RX_N7")
	)
	(arc
		(start 103.226616 -35.889692)
		(mid 103.170007 -35.974414)
		(end 103.150162 -36.07435)
		(width 0.0889)
		(layer "B.Cu")
		(net "PCIE_SAS_C_CPU_RX_N7")
	)
	(arc
		(start 103.621332 -35.042094)
		(mid 103.568694 -35.120872)
		(end 103.550212 -35.213798)
		(width 0.0889)
		(layer "B.Cu")
		(net "PCIE_SAS_C_CPU_RX_N7")
	)
	(segment
		(start 98.490024 -103.1494)
		(end 98.76155 -102.877874)
		(width 0.1143)
		(layer "F.Cu")
		(net "SDB_R_RX")
	)
	(segment
		(start 96.14535 -102.56012)
		(end 96.47047 -102.235)
		(width 0.1143)
		(layer "F.Cu")
		(net "SDB_R_RX")
	)
	(segment
		(start 97.42297 -102.362)
		(end 97.42297 -102.50297)
		(width 0.1143)
		(layer "F.Cu")
		(net "SDB_R_RX")
	)
	(segment
		(start 97.42297 -102.50297)
		(end 98.0694 -103.1494)
		(width 0.1143)
		(layer "F.Cu")
		(net "SDB_R_RX")
	)
	(segment
		(start 98.0694 -103.1494)
		(end 98.490024 -103.1494)
		(width 0.1143)
		(layer "F.Cu")
		(net "SDB_R_RX")
	)
	(segment
		(start 106.3498 -99.350068)
		(end 105.849674 -99.850194)
		(width 0.1143)
		(layer "F.Cu")
		(net "SDB_R_RX")
	)
	(segment
		(start 96.47047 -102.235)
		(end 97.29597 -102.235)
		(width 0.1143)
		(layer "F.Cu")
		(net "SDB_R_RX")
	)
	(segment
		(start 98.76155 -101.93655)
		(end 98.679 -101.854)
		(width 0.1143)
		(layer "F.Cu")
		(net "SDB_R_RX")
	)
	(segment
		(start 98.679 -101.854)
		(end 98.679 -101.74605)
		(width 0.1143)
		(layer "F.Cu")
		(net "SDB_R_RX")
	)
	(segment
		(start 98.76155 -102.877874)
		(end 98.76155 -101.93655)
		(width 0.1143)
		(layer "F.Cu")
		(net "SDB_R_RX")
	)
	(segment
		(start 97.29597 -102.235)
		(end 97.42297 -102.362)
		(width 0.1143)
		(layer "F.Cu")
		(net "SDB_R_RX")
	)
	(via
		(at 97.42297 -102.362)
		(size 0.7112)
		(drill 0.3556)
		(layers "F.Cu" "B.Cu")
		(net "SDB_R_RX")
	)
	(via
		(at 105.849674 -99.850194)
		(size 0.508)
		(drill 0.254)
		(layers "F.Cu" "B.Cu")
		(net "SDB_R_RX")
	)
	(via
		(at 98.679 -101.74605)
		(size 0.508)
		(drill 0.254)
		(layers "F.Cu" "B.Cu")
		(net "SDB_R_RX")
	)
	(segment
		(start 101.61397 -100.33)
		(end 105.04297 -100.33)
		(width 0.127)
		(layer "In2.Cu")
		(net "SDB_R_RX")
	)
	(segment
		(start 105.522776 -99.850194)
		(end 105.849674 -99.850194)
		(width 0.127)
		(layer "In2.Cu")
		(net "SDB_R_RX")
	)
	(segment
		(start 100.59797 -101.346)
		(end 101.61397 -100.33)
		(width 0.127)
		(layer "In2.Cu")
		(net "SDB_R_RX")
	)
	(segment
		(start 105.04297 -100.33)
		(end 105.522776 -99.850194)
		(width 0.127)
		(layer "In2.Cu")
		(net "SDB_R_RX")
	)
	(segment
		(start 98.78695 -101.74605)
		(end 99.187 -101.346)
		(width 0.127)
		(layer "In2.Cu")
		(net "SDB_R_RX")
	)
	(segment
		(start 99.187 -101.346)
		(end 100.59797 -101.346)
		(width 0.127)
		(layer "In2.Cu")
		(net "SDB_R_RX")
	)
	(segment
		(start 98.679 -101.74605)
		(end 98.78695 -101.74605)
		(width 0.127)
		(layer "In2.Cu")
		(net "SDB_R_RX")
	)
	(segment
		(start 97.95002 -43.800014)
		(end 97.95002 -43.79468)
		(width 0.3048)
		(layer "F.Cu")
		(net "SHELL_PLL_VDD")
	)
	(segment
		(start 97.549462 -43.4086)
		(end 97.546414 -43.405552)
		(width 0.3048)
		(layer "F.Cu")
		(net "SHELL_PLL_VDD")
	)
	(segment
		(start 97.56394 -43.4086)
		(end 97.549462 -43.4086)
		(width 0.3048)
		(layer "F.Cu")
		(net "SHELL_PLL_VDD")
	)
	(segment
		(start 97.95002 -43.79468)
		(end 97.56394 -43.4086)
		(width 0.3048)
		(layer "F.Cu")
		(net "SHELL_PLL_VDD")
	)
	(via
		(at 80.296766 -54.102)
		(size 0.5588)
		(drill 0.3048)
		(layers "F.Cu" "B.Cu")
		(net "SHELL_PLL_VDD")
	)
	(via
		(at 98.589846 -58.36412)
		(size 0.5588)
		(drill 0.3048)
		(layers "F.Cu" "B.Cu")
		(net "SHELL_PLL_VDD")
	)
	(via
		(at 97.06102 -58.36412)
		(size 0.7112)
		(drill 0.3556)
		(layers "F.Cu" "B.Cu")
		(net "SHELL_PLL_VDD")
	)
	(via
		(at 97.546414 -43.405552)
		(size 0.508)
		(drill 0.254)
		(layers "F.Cu" "B.Cu")
		(net "SHELL_PLL_VDD")
	)
	(segment
		(start 98.589846 -58.36412)
		(end 97.06102 -58.36412)
		(width 0.508)
		(layer "B.Cu")
		(net "SHELL_PLL_VDD")
	)
	(segment
		(start 97.06102 -58.36412)
		(end 87.302086 -58.36412)
		(width 0.508)
		(layer "B.Cu")
		(net "SHELL_PLL_VDD")
	)
	(segment
		(start 83.039966 -54.102)
		(end 80.296766 -54.102)
		(width 0.508)
		(layer "B.Cu")
		(net "SHELL_PLL_VDD")
	)
	(segment
		(start 87.302086 -58.36412)
		(end 83.039966 -54.102)
		(width 0.508)
		(layer "B.Cu")
		(net "SHELL_PLL_VDD")
	)
	(segment
		(start 94.342966 -48.610774)
		(end 94.342966 -51.627278)
		(width 0.508)
		(layer "In2.Cu")
		(net "SHELL_PLL_VDD")
	)
	(segment
		(start 94.540324 -48.413416)
		(end 94.342966 -48.610774)
		(width 0.508)
		(layer "In2.Cu")
		(net "SHELL_PLL_VDD")
	)
	(segment
		(start 96.70034 -44.1198)
		(end 96.70034 -46.2534)
		(width 0.508)
		(layer "In2.Cu")
		(net "SHELL_PLL_VDD")
	)
	(segment
		(start 96.70034 -46.2534)
		(end 95.363538 -47.590202)
		(width 0.508)
		(layer "In2.Cu")
		(net "SHELL_PLL_VDD")
	)
	(segment
		(start 97.252028 -58.36412)
		(end 98.589846 -58.36412)
		(width 0.508)
		(layer "In2.Cu")
		(net "SHELL_PLL_VDD")
	)
	(segment
		(start 93.580966 -54.693058)
		(end 97.252028 -58.36412)
		(width 0.508)
		(layer "In2.Cu")
		(net "SHELL_PLL_VDD")
	)
	(segment
		(start 97.414588 -43.405552)
		(end 96.70034 -44.1198)
		(width 0.508)
		(layer "In2.Cu")
		(net "SHELL_PLL_VDD")
	)
	(segment
		(start 97.546414 -43.405552)
		(end 97.414588 -43.405552)
		(width 0.508)
		(layer "In2.Cu")
		(net "SHELL_PLL_VDD")
	)
	(segment
		(start 94.897194 -47.590202)
		(end 94.540324 -47.947072)
		(width 0.508)
		(layer "In2.Cu")
		(net "SHELL_PLL_VDD")
	)
	(segment
		(start 94.540324 -47.947072)
		(end 94.540324 -48.413416)
		(width 0.508)
		(layer "In2.Cu")
		(net "SHELL_PLL_VDD")
	)
	(segment
		(start 95.363538 -47.590202)
		(end 94.897194 -47.590202)
		(width 0.508)
		(layer "In2.Cu")
		(net "SHELL_PLL_VDD")
	)
	(segment
		(start 93.580966 -53.467)
		(end 93.580966 -54.693058)
		(width 0.508)
		(layer "In2.Cu")
		(net "SHELL_PLL_VDD")
	)
	(arc
		(start 94.342966 -51.627278)
		(mid 94.144922 -52.622914)
		(end 93.580966 -53.467)
		(width 0.508)
		(layer "In2.Cu")
		(net "SHELL_PLL_VDD")
	)
	(segment
		(start 91.41841 -34.99993)
		(end 91.549982 -34.99993)
		(width 0.1016)
		(layer "F.Cu")
		(net "SAS3008_RAID_TX_C_N0")
	)
	(segment
		(start 91.075002 -34.767774)
		(end 91.228418 -34.92119)
		(width 0.1016)
		(layer "F.Cu")
		(net "SAS3008_RAID_TX_C_N0")
	)
	(segment
		(start 87.898224 -33.295844)
		(end 89.001346 -34.398966)
		(width 0.1016)
		(layer "F.Cu")
		(net "SAS3008_RAID_TX_C_N0")
	)
	(segment
		(start 86.77656 -33.02)
		(end 86.847172 -33.090612)
		(width 0.1016)
		(layer "F.Cu")
		(net "SAS3008_RAID_TX_C_N0")
	)
	(segment
		(start 86.9442 -33.142682)
		(end 86.944454 -33.142936)
		(width 0.1016)
		(layer "F.Cu")
		(net "SAS3008_RAID_TX_C_N0")
	)
	(segment
		(start 89.53246 -34.61893)
		(end 90.715592 -34.61893)
		(width 0.1016)
		(layer "F.Cu")
		(net "SAS3008_RAID_TX_C_N0")
	)
	(segment
		(start 86.983316 -33.147)
		(end 87.53856 -33.147)
		(width 0.1016)
		(layer "F.Cu")
		(net "SAS3008_RAID_TX_C_N0")
	)
	(arc
		(start 86.944454 -33.142936)
		(mid 86.946231 -33.143198)
		(end 86.94801 -33.143444)
		(width 0.1016)
		(layer "F.Cu")
		(net "SAS3008_RAID_TX_C_N0")
	)
	(arc
		(start 87.53856 -33.147)
		(mid 87.733211 -33.185625)
		(end 87.898224 -33.295844)
		(width 0.1016)
		(layer "F.Cu")
		(net "SAS3008_RAID_TX_C_N0")
	)
	(arc
		(start 89.001346 -34.398966)
		(mid 89.245023 -34.561786)
		(end 89.53246 -34.61893)
		(width 0.1016)
		(layer "F.Cu")
		(net "SAS3008_RAID_TX_C_N0")
	)
	(arc
		(start 86.94801 -33.143444)
		(mid 86.965207 -33.145882)
		(end 86.982554 -33.146746)
		(width 0.1016)
		(layer "F.Cu")
		(net "SAS3008_RAID_TX_C_N0")
	)
	(arc
		(start 91.228418 -34.92119)
		(mid 91.315573 -34.979488)
		(end 91.41841 -34.99993)
		(width 0.1016)
		(layer "F.Cu")
		(net "SAS3008_RAID_TX_C_N0")
	)
	(arc
		(start 86.982554 -33.146746)
		(mid 86.982935 -33.146873)
		(end 86.983316 -33.147)
		(width 0.1016)
		(layer "F.Cu")
		(net "SAS3008_RAID_TX_C_N0")
	)
	(arc
		(start 86.847172 -33.090612)
		(mid 86.891885 -33.123727)
		(end 86.9442 -33.142682)
		(width 0.1016)
		(layer "F.Cu")
		(net "SAS3008_RAID_TX_C_N0")
	)
	(arc
		(start 90.715592 -34.61893)
		(mid 90.910092 -34.657619)
		(end 91.075002 -34.767774)
		(width 0.1016)
		(layer "F.Cu")
		(net "SAS3008_RAID_TX_C_N0")
	)
	(segment
		(start 119.350028 -85.349842)
		(end 119.350028 -85.349588)
		(width 0.1143)
		(layer "F.Cu")
		(net "TEST_MUX_44")
	)
	(segment
		(start 119.350028 -85.349588)
		(end 118.850156 -84.849716)
		(width 0.1143)
		(layer "F.Cu")
		(net "TEST_MUX_44")
	)
	(via
		(at 118.850156 -84.849716)
		(size 0.508)
		(drill 0.254)
		(layers "F.Cu" "B.Cu")
		(net "TEST_MUX_44")
	)
	(segment
		(start 119.29872 -84.16925)
		(end 118.850156 -84.617814)
		(width 0.1143)
		(layer "B.Cu")
		(net "TEST_MUX_44")
	)
	(segment
		(start 118.850156 -84.617814)
		(end 118.850156 -84.849716)
		(width 0.1143)
		(layer "B.Cu")
		(net "TEST_MUX_44")
	)
	(segment
		(start 119.01297 -82.3341)
		(end 119.29872 -82.61985)
		(width 0.1143)
		(layer "B.Cu")
		(net "TEST_MUX_44")
	)
	(segment
		(start 119.01297 -82.042)
		(end 119.01297 -82.3341)
		(width 0.1143)
		(layer "B.Cu")
		(net "TEST_MUX_44")
	)
	(segment
		(start 119.29872 -82.61985)
		(end 119.29872 -84.16925)
		(width 0.1143)
		(layer "B.Cu")
		(net "TEST_MUX_44")
	)
	(segment
		(start 107.54995 -48.599852)
		(end 107.949746 -48.999648)
		(width 0.3556)
		(layer "F.Cu")
		(net "VDDIO_15")
	)
	(via
		(at 107.949746 -48.999648)
		(size 0.508)
		(drill 0.254)
		(layers "F.Cu" "B.Cu")
		(net "VDDIO_15")
	)
	(segment
		(start 108.312966 -49.784)
		(end 108.058966 -49.53)
		(width 0.508)
		(layer "B.Cu")
		(net "VDDIO_15")
	)
	(segment
		(start 108.058966 -49.108868)
		(end 107.949746 -48.999648)
		(width 0.508)
		(layer "B.Cu")
		(net "VDDIO_15")
	)
	(segment
		(start 108.058966 -49.53)
		(end 108.058966 -49.108868)
		(width 0.508)
		(layer "B.Cu")
		(net "VDDIO_15")
	)
	(segment
		(start 102.762304 -104.937306)
		(end 103.349806 -104.350058)
		(width 0.1143)
		(layer "F.Cu")
		(net "SMART_RX")
	)
	(segment
		(start 96.15297 -106.045)
		(end 99.314 -106.045)
		(width 0.1143)
		(layer "F.Cu")
		(net "SMART_RX")
	)
	(segment
		(start 100.943664 -104.937306)
		(end 102.762304 -104.937306)
		(width 0.1143)
		(layer "F.Cu")
		(net "SMART_RX")
	)
	(segment
		(start 99.314 -106.045)
		(end 99.83597 -106.045)
		(width 0.1143)
		(layer "F.Cu")
		(net "SMART_RX")
	)
	(segment
		(start 99.83597 -106.045)
		(end 100.943664 -104.937306)
		(width 0.1143)
		(layer "F.Cu")
		(net "SMART_RX")
	)
	(via
		(at 99.314 -106.045)
		(size 0.7112)
		(drill 0.3556)
		(layers "F.Cu" "B.Cu")
		(net "SMART_RX")
	)
	(segment
		(start 97.150174 -44.59986)
		(end 97.159572 -44.609258)
		(width 0.3556)
		(layer "F.Cu")
		(net "SYS_PLL_VDD")
	)
	(segment
		(start 97.164398 -44.609258)
		(end 97.54362 -44.98848)
		(width 0.3556)
		(layer "F.Cu")
		(net "SYS_PLL_VDD")
	)
	(segment
		(start 97.159572 -44.609258)
		(end 97.164398 -44.609258)
		(width 0.3556)
		(layer "F.Cu")
		(net "SYS_PLL_VDD")
	)
	(via
		(at 94.869 -59.7408)
		(size 0.7112)
		(drill 0.3556)
		(layers "F.Cu" "B.Cu")
		(net "SYS_PLL_VDD")
	)
	(via
		(at 97.54362 -44.98848)
		(size 0.508)
		(drill 0.254)
		(layers "F.Cu" "B.Cu")
		(net "SYS_PLL_VDD")
	)
	(via
		(at 81.846166 -55.5752)
		(size 0.5588)
		(drill 0.3048)
		(layers "F.Cu" "B.Cu")
		(net "SYS_PLL_VDD")
	)
	(via
		(at 98.552 -59.309)
		(size 0.5588)
		(drill 0.3048)
		(layers "F.Cu" "B.Cu")
		(net "SYS_PLL_VDD")
	)
	(segment
		(start 98.552 -59.309)
		(end 98.1202 -59.7408)
		(width 0.508)
		(layer "B.Cu")
		(net "SYS_PLL_VDD")
	)
	(segment
		(start 86.392766 -59.7408)
		(end 82.227166 -55.5752)
		(width 0.508)
		(layer "B.Cu")
		(net "SYS_PLL_VDD")
	)
	(segment
		(start 82.227166 -55.5752)
		(end 81.846166 -55.5752)
		(width 0.508)
		(layer "B.Cu")
		(net "SYS_PLL_VDD")
	)
	(segment
		(start 94.869 -59.7408)
		(end 86.392766 -59.7408)
		(width 0.508)
		(layer "B.Cu")
		(net "SYS_PLL_VDD")
	)
	(segment
		(start 98.1202 -59.7408)
		(end 94.869 -59.7408)
		(width 0.508)
		(layer "B.Cu")
		(net "SYS_PLL_VDD")
	)
	(segment
		(start 98.15957 -52.965604)
		(end 98.15957 -56.871616)
		(width 0.508)
		(layer "In2.Cu")
		(net "SYS_PLL_VDD")
	)
	(segment
		(start 97.54362 -44.98848)
		(end 97.54362 -46.39818)
		(width 0.508)
		(layer "In2.Cu")
		(net "SYS_PLL_VDD")
	)
	(segment
		(start 96.753172 -47.188628)
		(end 96.753172 -51.559206)
		(width 0.508)
		(layer "In2.Cu")
		(net "SYS_PLL_VDD")
	)
	(segment
		(start 99.224846 -58.636154)
		(end 98.552 -59.309)
		(width 0.508)
		(layer "In2.Cu")
		(net "SYS_PLL_VDD")
	)
	(segment
		(start 97.54362 -46.39818)
		(end 96.753172 -47.188628)
		(width 0.508)
		(layer "In2.Cu")
		(net "SYS_PLL_VDD")
	)
	(segment
		(start 98.15957 -56.871616)
		(end 99.224846 -57.936892)
		(width 0.508)
		(layer "In2.Cu")
		(net "SYS_PLL_VDD")
	)
	(segment
		(start 99.224846 -57.936892)
		(end 99.224846 -58.636154)
		(width 0.508)
		(layer "In2.Cu")
		(net "SYS_PLL_VDD")
	)
	(segment
		(start 96.753172 -51.559206)
		(end 98.15957 -52.965604)
		(width 0.508)
		(layer "In2.Cu")
		(net "SYS_PLL_VDD")
	)
	(segment
		(start 90.724736 -37.374576)
		(end 90.750136 -37.399976)
		(width 0.1016)
		(layer "F.Cu")
		(net "SAS3008_RAID_TX_C_P2")
	)
	(segment
		(start 87.113872 -36.8173)
		(end 87.75954 -36.8173)
		(width 0.1016)
		(layer "F.Cu")
		(net "SAS3008_RAID_TX_C_P2")
	)
	(segment
		(start 87.876634 -36.865814)
		(end 88.236552 -37.225732)
		(width 0.1016)
		(layer "F.Cu")
		(net "SAS3008_RAID_TX_C_P2")
	)
	(segment
		(start 88.595962 -37.374576)
		(end 90.724736 -37.374576)
		(width 0.1016)
		(layer "F.Cu")
		(net "SAS3008_RAID_TX_C_P2")
	)
	(arc
		(start 87.75954 -36.8173)
		(mid 87.822915 -36.829906)
		(end 87.876634 -36.865814)
		(width 0.1016)
		(layer "F.Cu")
		(net "SAS3008_RAID_TX_C_P2")
	)
	(arc
		(start 88.236552 -37.225732)
		(mid 88.401451 -37.335914)
		(end 88.595962 -37.374576)
		(width 0.1016)
		(layer "F.Cu")
		(net "SAS3008_RAID_TX_C_P2")
	)
	(arc
		(start 86.77656 -36.957)
		(mid 86.93132 -36.853593)
		(end 87.113872 -36.8173)
		(width 0.1016)
		(layer "F.Cu")
		(net "SAS3008_RAID_TX_C_P2")
	)
	(segment
		(start 91.4908 -20.5232)
		(end 91.4908 -19.6596)
		(width 0.254)
		(layer "F.Cu")
		(net "VT235_VDES_RC")
	)
	(segment
		(start 90.4875 -21.5265)
		(end 91.4908 -20.5232)
		(width 0.254)
		(layer "F.Cu")
		(net "VT235_VDES_RC")
	)
	(segment
		(start 91.4908 -18.75028)
		(end 91.4908 -19.6596)
		(width 0.254)
		(layer "F.Cu")
		(net "VT235_VDES_RC")
	)
	(segment
		(start 89.662 -21.5265)
		(end 90.4875 -21.5265)
		(width 0.254)
		(layer "F.Cu")
		(net "VT235_VDES_RC")
	)
	(segment
		(start 89.662 -18.034)
		(end 90.77452 -18.034)
		(width 0.254)
		(layer "F.Cu")
		(net "VT235_VDES_RC")
	)
	(segment
		(start 90.77452 -18.034)
		(end 91.4908 -18.75028)
		(width 0.254)
		(layer "F.Cu")
		(net "VT235_VDES_RC")
	)
	(via
		(at 91.4908 -19.6596)
		(size 0.7112)
		(drill 0.3556)
		(layers "F.Cu" "B.Cu")
		(net "VT235_VDES_RC")
	)
	(segment
		(start 118.35003 -85.349588)
		(end 117.850158 -84.849716)
		(width 0.1143)
		(layer "F.Cu")
		(net "TEST_MUX_45")
	)
	(segment
		(start 118.35003 -85.349842)
		(end 118.35003 -85.349588)
		(width 0.1143)
		(layer "F.Cu")
		(net "TEST_MUX_45")
	)
	(via
		(at 117.850158 -84.849716)
		(size 0.508)
		(drill 0.254)
		(layers "F.Cu" "B.Cu")
		(net "TEST_MUX_45")
	)
	(segment
		(start 117.61597 -82.296)
		(end 117.28831 -82.62366)
		(width 0.1143)
		(layer "B.Cu")
		(net "TEST_MUX_45")
	)
	(segment
		(start 117.28831 -84.287868)
		(end 117.850158 -84.849716)
		(width 0.1143)
		(layer "B.Cu")
		(net "TEST_MUX_45")
	)
	(segment
		(start 117.61597 -81.915)
		(end 117.61597 -82.296)
		(width 0.1143)
		(layer "B.Cu")
		(net "TEST_MUX_45")
	)
	(segment
		(start 117.28831 -82.62366)
		(end 117.28831 -84.287868)
		(width 0.1143)
		(layer "B.Cu")
		(net "TEST_MUX_45")
	)
	(segment
		(start 90.750136 -43.800014)
		(end 90.191336 -43.800014)
		(width 0.3048)
		(layer "F.Cu")
		(net "SAS0_VDDH")
	)
	(segment
		(start 90.750136 -36.599876)
		(end 90.750136 -36.53917)
		(width 0.3556)
		(layer "F.Cu")
		(net "SAS0_VDDH")
	)
	(segment
		(start 94.740476 -38.999922)
		(end 94.350078 -39.39032)
		(width 0.3556)
		(layer "F.Cu")
		(net "SAS0_VDDH")
	)
	(segment
		(start 90.750136 -36.53917)
		(end 90.532966 -36.322)
		(width 0.3556)
		(layer "F.Cu")
		(net "SAS0_VDDH")
	)
	(segment
		(start 90.750136 -41.399968)
		(end 89.591134 -41.399968)
		(width 0.3048)
		(layer "F.Cu")
		(net "SAS0_VDDH")
	)
	(segment
		(start 90.713814 -38.9636)
		(end 90.750136 -38.999922)
		(width 0.254)
		(layer "F.Cu")
		(net "SAS0_VDDH")
	)
	(segment
		(start 94.750128 -38.999922)
		(end 94.740476 -38.999922)
		(width 0.3556)
		(layer "F.Cu")
		(net "SAS0_VDDH")
	)
	(segment
		(start 94.750128 -41.399968)
		(end 94.750128 -41.390316)
		(width 0.3556)
		(layer "F.Cu")
		(net "SAS0_VDDH")
	)
	(segment
		(start 94.750128 -41.390316)
		(end 95.143828 -40.996616)
		(width 0.3556)
		(layer "F.Cu")
		(net "SAS0_VDDH")
	)
	(segment
		(start 90.532966 -36.322)
		(end 89.41816 -36.322)
		(width 0.3556)
		(layer "F.Cu")
		(net "SAS0_VDDH")
	)
	(segment
		(start 90.750136 -34.19983)
		(end 90.19159 -34.19983)
		(width 0.3048)
		(layer "F.Cu")
		(net "SAS0_VDDH")
	)
	(segment
		(start 88.856566 -38.9636)
		(end 90.713814 -38.9636)
		(width 0.254)
		(layer "F.Cu")
		(net "SAS0_VDDH")
	)
	(segment
		(start 89.591134 -41.399968)
		(end 89.389966 -41.1988)
		(width 0.3048)
		(layer "F.Cu")
		(net "SAS0_VDDH")
	)
	(segment
		(start 90.19159 -34.19983)
		(end 89.84996 -33.8582)
		(width 0.3048)
		(layer "F.Cu")
		(net "SAS0_VDDH")
	)
	(via
		(at 89.41816 -36.322)
		(size 0.508)
		(drill 0.254)
		(layers "F.Cu" "B.Cu")
		(net "SAS0_VDDH")
	)
	(via
		(at 89.389966 -41.1988)
		(size 0.508)
		(drill 0.254)
		(layers "F.Cu" "B.Cu")
		(net "SAS0_VDDH")
	)
	(via
		(at 89.84996 -33.8582)
		(size 0.508)
		(drill 0.254)
		(layers "F.Cu" "B.Cu")
		(net "SAS0_VDDH")
	)
	(via
		(at 72.5932 -45.9232)
		(size 0.7112)
		(drill 0.4064)
		(layers "F.Cu" "B.Cu")
		(net "SAS0_VDDH")
	)
	(via
		(at 71.6026 -45.339)
		(size 0.7112)
		(drill 0.4064)
		(layers "F.Cu" "B.Cu")
		(net "SAS0_VDDH")
	)
	(via
		(at 71.5772 -47.879)
		(size 0.7112)
		(drill 0.4064)
		(layers "F.Cu" "B.Cu")
		(net "SAS0_VDDH")
	)
	(via
		(at 72.5424 -47.2694)
		(size 0.7112)
		(drill 0.4064)
		(layers "F.Cu" "B.Cu")
		(net "SAS0_VDDH")
	)
	(via
		(at 88.856566 -38.9636)
		(size 0.508)
		(drill 0.254)
		(layers "F.Cu" "B.Cu")
		(net "SAS0_VDDH")
	)
	(via
		(at 94.350078 -39.39032)
		(size 0.508)
		(drill 0.254)
		(layers "F.Cu" "B.Cu")
		(net "SAS0_VDDH")
	)
	(via
		(at 70.358 -49.403)
		(size 0.7112)
		(drill 0.3556)
		(layers "F.Cu" "B.Cu")
		(net "SAS0_VDDH")
	)
	(via
		(at 95.143828 -40.996616)
		(size 0.508)
		(drill 0.254)
		(layers "F.Cu" "B.Cu")
		(net "SAS0_VDDH")
	)
	(via
		(at 90.191336 -43.800014)
		(size 0.508)
		(drill 0.254)
		(layers "F.Cu" "B.Cu")
		(net "SAS0_VDDH")
	)
	(via
		(at 71.5772 -46.6598)
		(size 0.7112)
		(drill 0.4064)
		(layers "F.Cu" "B.Cu")
		(net "SAS0_VDDH")
	)
	(segment
		(start 90.91676 -34.417)
		(end 90.40876 -34.417)
		(width 0.3048)
		(layer "B.Cu")
		(net "SAS0_VDDH")
	)
	(segment
		(start 90.02776 -36.9316)
		(end 89.41816 -36.322)
		(width 0.3048)
		(layer "B.Cu")
		(net "SAS0_VDDH")
	)
	(segment
		(start 90.02776 -37.084)
		(end 90.02776 -36.9316)
		(width 0.3048)
		(layer "B.Cu")
		(net "SAS0_VDDH")
	)
	(segment
		(start 89.440766 -41.148)
		(end 89.389966 -41.1988)
		(width 0.3048)
		(layer "B.Cu")
		(net "SAS0_VDDH")
	)
	(segment
		(start 90.40876 -39.37)
		(end 89.262966 -39.37)
		(width 0.3048)
		(layer "B.Cu")
		(net "SAS0_VDDH")
	)
	(segment
		(start 90.40876 -41.148)
		(end 89.440766 -41.148)
		(width 0.3048)
		(layer "B.Cu")
		(net "SAS0_VDDH")
	)
	(segment
		(start 89.262966 -39.37)
		(end 88.856566 -38.9636)
		(width 0.3048)
		(layer "B.Cu")
		(net "SAS0_VDDH")
	)
	(segment
		(start 90.40876 -34.417)
		(end 89.84996 -33.8582)
		(width 0.3048)
		(layer "B.Cu")
		(net "SAS0_VDDH")
	)
	(segment
		(start 98.75012 -35.80003)
		(end 98.740468 -35.80003)
		(width 0.1397)
		(layer "F.Cu")
		(net "PCIE_SAS_C_CPU_RX_P3")
	)
	(segment
		(start 98.740468 -35.80003)
		(end 98.341942 -35.401504)
		(width 0.1397)
		(layer "F.Cu")
		(net "PCIE_SAS_C_CPU_RX_P3")
	)
	(via
		(at 98.341942 -35.401504)
		(size 0.508)
		(drill 0.254)
		(layers "F.Cu" "B.Cu")
		(net "PCIE_SAS_C_CPU_RX_P3")
	)
	(segment
		(start 98.025966 -32.140906)
		(end 98.025966 -34.334958)
		(width 0.1397)
		(layer "B.Cu")
		(net "PCIE_SAS_C_CPU_RX_P3")
	)
	(segment
		(start 98.341942 -34.866072)
		(end 98.341942 -35.401504)
		(width 0.1397)
		(layer "B.Cu")
		(net "PCIE_SAS_C_CPU_RX_P3")
	)
	(segment
		(start 98.177858 -34.701988)
		(end 98.341942 -34.866072)
		(width 0.1397)
		(layer "B.Cu")
		(net "PCIE_SAS_C_CPU_RX_P3")
	)
	(arc
		(start 98.025966 -34.334958)
		(mid 98.065384 -34.533595)
		(end 98.177858 -34.701988)
		(width 0.1397)
		(layer "B.Cu")
		(net "PCIE_SAS_C_CPU_RX_P3")
	)
	(arc
		(start 97.92716 -31.9024)
		(mid 98.000277 -32.011827)
		(end 98.025966 -32.140906)
		(width 0.1397)
		(layer "B.Cu")
		(net "PCIE_SAS_C_CPU_RX_P3")
	)
	(segment
		(start 79.375 -21.463)
		(end 79.5655 -21.6535)
		(width 0.254)
		(layer "F.Cu")
		(net "VT235_IRIP")
	)
	(segment
		(start 80.548226 -21.3868)
		(end 80.5307 -21.3868)
		(width 0.254)
		(layer "F.Cu")
		(net "VT235_IRIP")
	)
	(segment
		(start 80.679798 -21.255228)
		(end 80.548226 -21.3868)
		(width 0.254)
		(layer "F.Cu")
		(net "VT235_IRIP")
	)
	(segment
		(start 78.74 -21.463)
		(end 79.375 -21.463)
		(width 0.254)
		(layer "F.Cu")
		(net "VT235_IRIP")
	)
	(segment
		(start 80.4545 -21.463)
		(end 79.756 -21.463)
		(width 0.254)
		(layer "F.Cu")
		(net "VT235_IRIP")
	)
	(segment
		(start 80.5307 -21.3868)
		(end 80.4545 -21.463)
		(width 0.254)
		(layer "F.Cu")
		(net "VT235_IRIP")
	)
	(segment
		(start 81.034128 -21.255228)
		(end 80.679798 -21.255228)
		(width 0.254)
		(layer "F.Cu")
		(net "VT235_IRIP")
	)
	(segment
		(start 79.756 -21.463)
		(end 79.5655 -21.6535)
		(width 0.254)
		(layer "F.Cu")
		(net "VT235_IRIP")
	)
	(via
		(at 79.5655 -21.6535)
		(size 0.5588)
		(drill 0.3048)
		(layers "F.Cu" "B.Cu")
		(net "VT235_IRIP")
	)
	(via
		(at 78.74 -21.463)
		(size 0.7112)
		(drill 0.3556)
		(layers "F.Cu" "B.Cu")
		(net "VT235_IRIP")
	)
	(segment
		(start 79.5655 -21.6535)
		(end 80.518 -21.6535)
		(width 0.254)
		(layer "B.Cu")
		(net "VT235_IRIP")
	)
	(segment
		(start 230.378 -118.1227)
		(end 238.1123 -125.857)
		(width 0.1778)
		(layer "F.Cu")
		(net "3D3V_ICE")
	)
	(segment
		(start 229.743 -19.304)
		(end 230.505 -19.304)
		(width 0.1778)
		(layer "F.Cu")
		(net "3D3V_ICE")
	)
	(segment
		(start 229.743 -18.0975)
		(end 229.743 -19.304)
		(width 0.1778)
		(layer "F.Cu")
		(net "3D3V_ICE")
	)
	(segment
		(start 240.665 -29.464)
		(end 240.665 -38.862)
		(width 0.1778)
		(layer "F.Cu")
		(net "3D3V_ICE")
	)
	(segment
		(start 230.505 -19.304)
		(end 240.665 -29.464)
		(width 0.1778)
		(layer "F.Cu")
		(net "3D3V_ICE")
	)
	(segment
		(start 238.1123 -172.4787)
		(end 223.774 -186.817)
		(width 0.1778)
		(layer "F.Cu")
		(net "3D3V_ICE")
	)
	(segment
		(start 223.774 -186.817)
		(end 223.774 -187.071)
		(width 0.1778)
		(layer "F.Cu")
		(net "3D3V_ICE")
	)
	(segment
		(start 238.1123 -125.857)
		(end 238.1123 -172.4787)
		(width 0.1778)
		(layer "F.Cu")
		(net "3D3V_ICE")
	)
	(segment
		(start 45.749972 -187.809886)
		(end 45.749972 -185.269886)
		(width 0.1778)
		(layer "F.Cu")
		(net "3D3V_ICE")
	)
	(via
		(at 230.378 -118.1227)
		(size 0.5588)
		(drill 0.3048)
		(layers "F.Cu" "B.Cu")
		(net "3D3V_ICE")
	)
	(via
		(at 240.665 -38.862)
		(size 0.508)
		(drill 0.254)
		(layers "F.Cu" "B.Cu")
		(net "3D3V_ICE")
	)
	(via
		(at 223.774 -187.071)
		(size 0.508)
		(drill 0.254)
		(layers "F.Cu" "B.Cu")
		(net "3D3V_ICE")
	)
	(segment
		(start 218.690444 -187.9473)
		(end 223.0247 -187.9473)
		(width 0.1778)
		(layer "In2.Cu")
		(net "3D3V_ICE")
	)
	(segment
		(start 218.665044 -187.9727)
		(end 218.690444 -187.9473)
		(width 0.1778)
		(layer "In2.Cu")
		(net "3D3V_ICE")
	)
	(segment
		(start 248.261378 -68.964048)
		(end 264.2743 -84.97697)
		(width 0.1778)
		(layer "In2.Cu")
		(net "3D3V_ICE")
	)
	(segment
		(start 249.66295 -111.1123)
		(end 237.3884 -111.1123)
		(width 0.1778)
		(layer "In2.Cu")
		(net "3D3V_ICE")
	)
	(segment
		(start 240.665 -38.862)
		(end 240.792 -38.989)
		(width 0.1778)
		(layer "In2.Cu")
		(net "3D3V_ICE")
	)
	(segment
		(start 240.792 -43.638978)
		(end 244.016022 -46.863)
		(width 0.1778)
		(layer "In2.Cu")
		(net "3D3V_ICE")
	)
	(segment
		(start 237.3884 -111.1123)
		(end 230.378 -118.1227)
		(width 0.1778)
		(layer "In2.Cu")
		(net "3D3V_ICE")
	)
	(segment
		(start 240.792 -38.989)
		(end 240.792 -43.638978)
		(width 0.1778)
		(layer "In2.Cu")
		(net "3D3V_ICE")
	)
	(segment
		(start 264.2743 -84.97697)
		(end 264.2743 -101.613208)
		(width 0.1778)
		(layer "In2.Cu")
		(net "3D3V_ICE")
	)
	(segment
		(start 248.261378 -47.916846)
		(end 248.261378 -68.964048)
		(width 0.1778)
		(layer "In2.Cu")
		(net "3D3V_ICE")
	)
	(segment
		(start 161.652204 -180.611272)
		(end 169.013632 -187.9727)
		(width 0.1778)
		(layer "In2.Cu")
		(net "3D3V_ICE")
	)
	(segment
		(start 223.0247 -187.9473)
		(end 223.774 -187.198)
		(width 0.1778)
		(layer "In2.Cu")
		(net "3D3V_ICE")
	)
	(segment
		(start 264.2743 -101.613208)
		(end 254.254508 -111.633)
		(width 0.1778)
		(layer "In2.Cu")
		(net "3D3V_ICE")
	)
	(segment
		(start 250.18365 -111.633)
		(end 249.66295 -111.1123)
		(width 0.1778)
		(layer "In2.Cu")
		(net "3D3V_ICE")
	)
	(segment
		(start 254.254508 -111.633)
		(end 250.18365 -111.633)
		(width 0.1778)
		(layer "In2.Cu")
		(net "3D3V_ICE")
	)
	(segment
		(start 169.013632 -187.9727)
		(end 218.665044 -187.9727)
		(width 0.1778)
		(layer "In2.Cu")
		(net "3D3V_ICE")
	)
	(segment
		(start 50.408586 -180.611272)
		(end 161.652204 -180.611272)
		(width 0.1778)
		(layer "In2.Cu")
		(net "3D3V_ICE")
	)
	(segment
		(start 223.774 -187.198)
		(end 223.774 -187.071)
		(width 0.1778)
		(layer "In2.Cu")
		(net "3D3V_ICE")
	)
	(segment
		(start 244.016022 -46.863)
		(end 247.207532 -46.863)
		(width 0.1778)
		(layer "In2.Cu")
		(net "3D3V_ICE")
	)
	(segment
		(start 247.207532 -46.863)
		(end 248.261378 -47.916846)
		(width 0.1778)
		(layer "In2.Cu")
		(net "3D3V_ICE")
	)
	(segment
		(start 45.749972 -185.269886)
		(end 50.408586 -180.611272)
		(width 0.1778)
		(layer "In2.Cu")
		(net "3D3V_ICE")
	)
	(segment
		(start 98.75012 -42.99966)
		(end 98.35007 -42.59961)
		(width 0.3556)
		(layer "F.Cu")
		(net "VDDA_SAS_REF_CLK")
	)
	(segment
		(start 98.75012 -42.999914)
		(end 98.75012 -42.99966)
		(width 0.3556)
		(layer "F.Cu")
		(net "VDDA_SAS_REF_CLK")
	)
	(via
		(at 80.3656 -56.515)
		(size 0.7112)
		(drill 0.3556)
		(layers "F.Cu" "B.Cu")
		(net "VDDA_SAS_REF_CLK")
	)
	(via
		(at 98.35007 -42.59961)
		(size 0.508)
		(drill 0.254)
		(layers "F.Cu" "B.Cu")
		(net "VDDA_SAS_REF_CLK")
	)
	(via
		(at 80.652366 -61.3664)
		(size 0.7112)
		(drill 0.3556)
		(layers "F.Cu" "B.Cu")
		(net "VDDA_SAS_REF_CLK")
	)
	(via
		(at 101.0666 -58.8772)
		(size 0.5588)
		(drill 0.3048)
		(layers "F.Cu" "B.Cu")
		(net "VDDA_SAS_REF_CLK")
	)
	(segment
		(start 78.220062 -61.735208)
		(end 78.740762 -62.255908)
		(width 0.508)
		(layer "B.Cu")
		(net "VDDA_SAS_REF_CLK")
	)
	(segment
		(start 80.958944 -57.108344)
		(end 80.3656 -56.515)
		(width 0.508)
		(layer "B.Cu")
		(net "VDDA_SAS_REF_CLK")
	)
	(segment
		(start 101.0666 -58.8772)
		(end 100.8888 -59.055)
		(width 0.508)
		(layer "B.Cu")
		(net "VDDA_SAS_REF_CLK")
	)
	(segment
		(start 98.298 -60.579)
		(end 85.325966 -60.579)
		(width 0.508)
		(layer "B.Cu")
		(net "VDDA_SAS_REF_CLK")
	)
	(segment
		(start 99.822 -59.055)
		(end 98.298 -60.579)
		(width 0.508)
		(layer "B.Cu")
		(net "VDDA_SAS_REF_CLK")
	)
	(segment
		(start 78.740762 -62.255908)
		(end 79.871062 -62.255908)
		(width 0.508)
		(layer "B.Cu")
		(net "VDDA_SAS_REF_CLK")
	)
	(segment
		(start 81.85531 -57.108344)
		(end 80.958944 -57.108344)
		(width 0.508)
		(layer "B.Cu")
		(net "VDDA_SAS_REF_CLK")
	)
	(segment
		(start 85.325966 -60.579)
		(end 81.85531 -57.108344)
		(width 0.508)
		(layer "B.Cu")
		(net "VDDA_SAS_REF_CLK")
	)
	(segment
		(start 100.8888 -59.055)
		(end 99.822 -59.055)
		(width 0.508)
		(layer "B.Cu")
		(net "VDDA_SAS_REF_CLK")
	)
	(segment
		(start 100.711 -55.29834)
		(end 100.16617 -54.75351)
		(width 0.508)
		(layer "In2.Cu")
		(net "VDDA_SAS_REF_CLK")
	)
	(segment
		(start 101.0666 -56.8706)
		(end 100.711 -56.515)
		(width 0.508)
		(layer "In2.Cu")
		(net "VDDA_SAS_REF_CLK")
	)
	(segment
		(start 100.711 -56.515)
		(end 100.711 -55.29834)
		(width 0.508)
		(layer "In2.Cu")
		(net "VDDA_SAS_REF_CLK")
	)
	(segment
		(start 98.35007 -42.742104)
		(end 98.35007 -42.59961)
		(width 0.508)
		(layer "In2.Cu")
		(net "VDDA_SAS_REF_CLK")
	)
	(segment
		(start 98.959416 -46.737778)
		(end 98.959416 -43.35145)
		(width 0.508)
		(layer "In2.Cu")
		(net "VDDA_SAS_REF_CLK")
	)
	(segment
		(start 98.960686 -48.063404)
		(end 98.549968 -47.652686)
		(width 0.508)
		(layer "In2.Cu")
		(net "VDDA_SAS_REF_CLK")
	)
	(segment
		(start 99.66579 -54.737)
		(end 98.960686 -54.031896)
		(width 0.508)
		(layer "In2.Cu")
		(net "VDDA_SAS_REF_CLK")
	)
	(segment
		(start 98.549968 -47.147226)
		(end 98.959416 -46.737778)
		(width 0.508)
		(layer "In2.Cu")
		(net "VDDA_SAS_REF_CLK")
	)
	(segment
		(start 98.960686 -54.031896)
		(end 98.960686 -48.063404)
		(width 0.508)
		(layer "In2.Cu")
		(net "VDDA_SAS_REF_CLK")
	)
	(segment
		(start 98.959416 -43.35145)
		(end 98.35007 -42.742104)
		(width 0.508)
		(layer "In2.Cu")
		(net "VDDA_SAS_REF_CLK")
	)
	(segment
		(start 100.086922 -54.737)
		(end 99.66579 -54.737)
		(width 0.508)
		(layer "In2.Cu")
		(net "VDDA_SAS_REF_CLK")
	)
	(segment
		(start 98.549968 -47.652686)
		(end 98.549968 -47.147226)
		(width 0.508)
		(layer "In2.Cu")
		(net "VDDA_SAS_REF_CLK")
	)
	(segment
		(start 101.0666 -58.8772)
		(end 101.0666 -56.8706)
		(width 0.508)
		(layer "In2.Cu")
		(net "VDDA_SAS_REF_CLK")
	)
	(segment
		(start 100.16617 -54.75351)
		(end 100.086922 -54.737)
		(width 0.508)
		(layer "In2.Cu")
		(net "VDDA_SAS_REF_CLK")
	)
	(segment
		(start 98.75012 -36.599876)
		(end 98.350324 -36.20008)
		(width 0.1397)
		(layer "F.Cu")
		(net "PCIE_SAS_C_CPU_RX_N3")
	)
	(via
		(at 98.350324 -36.20008)
		(size 0.508)
		(drill 0.254)
		(layers "F.Cu" "B.Cu")
		(net "PCIE_SAS_C_CPU_RX_N3")
	)
	(segment
		(start 98.420428 -34.459418)
		(end 98.684842 -34.723832)
		(width 0.1397)
		(layer "B.Cu")
		(net "PCIE_SAS_C_CPU_RX_N3")
	)
	(segment
		(start 98.684842 -34.849562)
		(end 98.75012 -34.91484)
		(width 0.1397)
		(layer "B.Cu")
		(net "PCIE_SAS_C_CPU_RX_N3")
	)
	(segment
		(start 98.56216 -31.9024)
		(end 98.455734 -32.008826)
		(width 0.1397)
		(layer "B.Cu")
		(net "PCIE_SAS_C_CPU_RX_N3")
	)
	(segment
		(start 98.350324 -36.07435)
		(end 98.350324 -36.20008)
		(width 0.0889)
		(layer "B.Cu")
		(net "PCIE_SAS_C_CPU_RX_N3")
	)
	(segment
		(start 98.368866 -32.21863)
		(end 98.368866 -34.334958)
		(width 0.1397)
		(layer "B.Cu")
		(net "PCIE_SAS_C_CPU_RX_N3")
	)
	(segment
		(start 98.610928 -35.705542)
		(end 98.426778 -35.889692)
		(width 0.0889)
		(layer "B.Cu")
		(net "PCIE_SAS_C_CPU_RX_N3")
	)
	(segment
		(start 98.684842 -34.723832)
		(end 98.684842 -34.849562)
		(width 0.1397)
		(layer "B.Cu")
		(net "PCIE_SAS_C_CPU_RX_N3")
	)
	(segment
		(start 98.75012 -34.91484)
		(end 98.75012 -35.3695)
		(width 0.0889)
		(layer "B.Cu")
		(net "PCIE_SAS_C_CPU_RX_N3")
	)
	(arc
		(start 98.455734 -32.008826)
		(mid 98.391416 -32.105085)
		(end 98.368866 -32.21863)
		(width 0.1397)
		(layer "B.Cu")
		(net "PCIE_SAS_C_CPU_RX_N3")
	)
	(arc
		(start 98.426778 -35.889692)
		(mid 98.370169 -35.974414)
		(end 98.350324 -36.07435)
		(width 0.0889)
		(layer "B.Cu")
		(net "PCIE_SAS_C_CPU_RX_N3")
	)
	(arc
		(start 98.75012 -35.3695)
		(mid 98.713945 -35.551364)
		(end 98.610928 -35.705542)
		(width 0.0889)
		(layer "B.Cu")
		(net "PCIE_SAS_C_CPU_RX_N3")
	)
	(arc
		(start 98.368866 -34.334958)
		(mid 98.382265 -34.402319)
		(end 98.420428 -34.459418)
		(width 0.1397)
		(layer "B.Cu")
		(net "PCIE_SAS_C_CPU_RX_N3")
	)
	(segment
		(start 81.4705 -23.749)
		(end 81.418176 -23.696676)
		(width 0.254)
		(layer "F.Cu")
		(net "VT235_VDES_RR")
	)
	(segment
		(start 81.418176 -23.696676)
		(end 80.555338 -23.696676)
		(width 0.254)
		(layer "F.Cu")
		(net "VT235_VDES_RR")
	)
	(segment
		(start 81.4705 -24.892)
		(end 81.4705 -23.749)
		(width 0.254)
		(layer "F.Cu")
		(net "VT235_VDES_RR")
	)
	(via
		(at 80.555338 -23.696676)
		(size 0.7112)
		(drill 0.3556)
		(layers "F.Cu" "B.Cu")
		(net "VT235_VDES_RR")
	)
	(segment
		(start 106.352086 -56.202072)
		(end 105.950004 -55.79999)
		(width 0.1143)
		(layer "F.Cu")
		(net "XM_F_RST_N")
	)
	(segment
		(start 144.30248 -47.086774)
		(end 144.30248 -47.126906)
		(width 0.1143)
		(layer "F.Cu")
		(net "XM_F_RST_N")
	)
	(segment
		(start 144.227042 -47.011336)
		(end 144.30248 -47.086774)
		(width 0.1143)
		(layer "F.Cu")
		(net "XM_F_RST_N")
	)
	(segment
		(start 144.30248 -47.126906)
		(end 144.79905 -47.623476)
		(width 0.1143)
		(layer "F.Cu")
		(net "XM_F_RST_N")
	)
	(segment
		(start 145.3769 -48.779684)
		(end 145.3769 -51.733958)
		(width 0.1143)
		(layer "F.Cu")
		(net "XM_F_RST_N")
	)
	(segment
		(start 144.79905 -48.208692)
		(end 145.085308 -48.49495)
		(width 0.1143)
		(layer "F.Cu")
		(net "XM_F_RST_N")
	)
	(segment
		(start 142.098776 -44.689776)
		(end 144.227042 -46.818042)
		(width 0.1143)
		(layer "F.Cu")
		(net "XM_F_RST_N")
	)
	(segment
		(start 144.79905 -47.623476)
		(end 144.79905 -48.208692)
		(width 0.1143)
		(layer "F.Cu")
		(net "XM_F_RST_N")
	)
	(segment
		(start 106.357166 -56.202072)
		(end 106.352086 -56.202072)
		(width 0.1143)
		(layer "F.Cu")
		(net "XM_F_RST_N")
	)
	(segment
		(start 145.3769 -51.733958)
		(end 146.15795 -52.515008)
		(width 0.1143)
		(layer "F.Cu")
		(net "XM_F_RST_N")
	)
	(segment
		(start 142.098776 -42.7101)
		(end 142.098776 -44.689776)
		(width 0.1143)
		(layer "F.Cu")
		(net "XM_F_RST_N")
	)
	(segment
		(start 144.227042 -46.818042)
		(end 144.227042 -47.011336)
		(width 0.1143)
		(layer "F.Cu")
		(net "XM_F_RST_N")
	)
	(segment
		(start 146.15795 -52.515008)
		(end 146.15795 -58.04027)
		(width 0.1143)
		(layer "F.Cu")
		(net "XM_F_RST_N")
	)
	(segment
		(start 145.085308 -48.49495)
		(end 145.092166 -48.49495)
		(width 0.1143)
		(layer "F.Cu")
		(net "XM_F_RST_N")
	)
	(segment
		(start 145.092166 -48.49495)
		(end 145.3769 -48.779684)
		(width 0.1143)
		(layer "F.Cu")
		(net "XM_F_RST_N")
	)
	(via
		(at 146.15795 -58.04027)
		(size 0.5588)
		(drill 0.3048)
		(layers "F.Cu" "B.Cu")
		(net "XM_F_RST_N")
	)
	(via
		(at 144.272 -60.706)
		(size 0.7112)
		(drill 0.3556)
		(layers "F.Cu" "B.Cu")
		(net "XM_F_RST_N")
	)
	(via
		(at 106.357166 -56.202072)
		(size 0.508)
		(drill 0.254)
		(layers "F.Cu" "B.Cu")
		(net "XM_F_RST_N")
	)
	(segment
		(start 144.145 -60.706)
		(end 144.272 -60.706)
		(width 0.1143)
		(layer "B.Cu")
		(net "XM_F_RST_N")
	)
	(segment
		(start 144.272 -60.706)
		(end 144.890998 -60.706)
		(width 0.1143)
		(layer "B.Cu")
		(net "XM_F_RST_N")
	)
	(segment
		(start 110.70717 -57.88025)
		(end 111.29772 -57.88025)
		(width 0.1143)
		(layer "B.Cu")
		(net "XM_F_RST_N")
	)
	(segment
		(start 106.357166 -56.202072)
		(end 106.79049 -56.202072)
		(width 0.1143)
		(layer "B.Cu")
		(net "XM_F_RST_N")
	)
	(segment
		(start 113.43005 -57.93105)
		(end 114.907568 -59.408568)
		(width 0.1143)
		(layer "B.Cu")
		(net "XM_F_RST_N")
	)
	(segment
		(start 136.781032 -59.408568)
		(end 138.250676 -60.878212)
		(width 0.1143)
		(layer "B.Cu")
		(net "XM_F_RST_N")
	)
	(segment
		(start 138.250676 -60.878212)
		(end 143.972788 -60.878212)
		(width 0.1143)
		(layer "B.Cu")
		(net "XM_F_RST_N")
	)
	(segment
		(start 111.34852 -57.93105)
		(end 113.43005 -57.93105)
		(width 0.1143)
		(layer "B.Cu")
		(net "XM_F_RST_N")
	)
	(segment
		(start 114.907568 -59.408568)
		(end 136.781032 -59.408568)
		(width 0.1143)
		(layer "B.Cu")
		(net "XM_F_RST_N")
	)
	(segment
		(start 146.076416 -58.121804)
		(end 146.15795 -58.04027)
		(width 0.1143)
		(layer "B.Cu")
		(net "XM_F_RST_N")
	)
	(segment
		(start 109.635544 -58.017156)
		(end 110.570264 -58.017156)
		(width 0.1143)
		(layer "B.Cu")
		(net "XM_F_RST_N")
	)
	(segment
		(start 144.890998 -60.706)
		(end 146.076416 -59.520582)
		(width 0.1143)
		(layer "B.Cu")
		(net "XM_F_RST_N")
	)
	(segment
		(start 107.730036 -57.141618)
		(end 108.760006 -57.141618)
		(width 0.1143)
		(layer "B.Cu")
		(net "XM_F_RST_N")
	)
	(segment
		(start 106.79049 -56.202072)
		(end 107.730036 -57.141618)
		(width 0.1143)
		(layer "B.Cu")
		(net "XM_F_RST_N")
	)
	(segment
		(start 111.29772 -57.88025)
		(end 111.34852 -57.93105)
		(width 0.1143)
		(layer "B.Cu")
		(net "XM_F_RST_N")
	)
	(segment
		(start 146.076416 -59.520582)
		(end 146.076416 -58.121804)
		(width 0.1143)
		(layer "B.Cu")
		(net "XM_F_RST_N")
	)
	(segment
		(start 108.760006 -57.141618)
		(end 109.635544 -58.017156)
		(width 0.1143)
		(layer "B.Cu")
		(net "XM_F_RST_N")
	)
	(segment
		(start 110.570264 -58.017156)
		(end 110.70717 -57.88025)
		(width 0.1143)
		(layer "B.Cu")
		(net "XM_F_RST_N")
	)
	(segment
		(start 143.972788 -60.878212)
		(end 144.145 -60.706)
		(width 0.1143)
		(layer "B.Cu")
		(net "XM_F_RST_N")
	)
	(segment
		(start 96.34347 -89.662)
		(end 97.42297 -89.662)
		(width 0.1143)
		(layer "F.Cu")
		(net "EXP_CLK_SEL0")
	)
	(segment
		(start 109.2708 -91.34983)
		(end 108.849668 -90.928698)
		(width 0.1143)
		(layer "F.Cu")
		(net "EXP_CLK_SEL0")
	)
	(segment
		(start 96.34347 -90.805)
		(end 96.34347 -89.662)
		(width 0.1143)
		(layer "F.Cu")
		(net "EXP_CLK_SEL0")
	)
	(segment
		(start 97.42297 -89.662)
		(end 99.925886 -87.159084)
		(width 0.1143)
		(layer "F.Cu")
		(net "EXP_CLK_SEL0")
	)
	(segment
		(start 109.349794 -91.34983)
		(end 109.2708 -91.34983)
		(width 0.1143)
		(layer "F.Cu")
		(net "EXP_CLK_SEL0")
	)
	(segment
		(start 99.925886 -87.159084)
		(end 101.61397 -87.159084)
		(width 0.1143)
		(layer "F.Cu")
		(net "EXP_CLK_SEL0")
	)
	(segment
		(start 108.849668 -90.928698)
		(end 108.849668 -90.849704)
		(width 0.1143)
		(layer "F.Cu")
		(net "EXP_CLK_SEL0")
	)
	(via
		(at 108.849668 -90.849704)
		(size 0.508)
		(drill 0.254)
		(layers "F.Cu" "B.Cu")
		(net "EXP_CLK_SEL0")
	)
	(via
		(at 101.61397 -87.159084)
		(size 0.508)
		(drill 0.254)
		(layers "F.Cu" "B.Cu")
		(net "EXP_CLK_SEL0")
	)
	(via
		(at 97.42297 -89.662)
		(size 0.7112)
		(drill 0.3556)
		(layers "F.Cu" "B.Cu")
		(net "EXP_CLK_SEL0")
	)
	(segment
		(start 104.266238 -88.80221)
		(end 103.257096 -88.80221)
		(width 0.127)
		(layer "In2.Cu")
		(net "EXP_CLK_SEL0")
	)
	(segment
		(start 105.028746 -88.44534)
		(end 104.623108 -88.44534)
		(width 0.127)
		(layer "In2.Cu")
		(net "EXP_CLK_SEL0")
	)
	(segment
		(start 106.812334 -90.405204)
		(end 106.294174 -89.887044)
		(width 0.127)
		(layer "In2.Cu")
		(net "EXP_CLK_SEL0")
	)
	(segment
		(start 104.623108 -88.44534)
		(end 104.266238 -88.80221)
		(width 0.127)
		(layer "In2.Cu")
		(net "EXP_CLK_SEL0")
	)
	(segment
		(start 106.294174 -89.887044)
		(end 106.294174 -89.70137)
		(width 0.127)
		(layer "In2.Cu")
		(net "EXP_CLK_SEL0")
	)
	(segment
		(start 107.675934 -91.268804)
		(end 107.268772 -90.861642)
		(width 0.127)
		(layer "In2.Cu")
		(net "EXP_CLK_SEL0")
	)
	(segment
		(start 103.257096 -88.80221)
		(end 101.61397 -87.159084)
		(width 0.127)
		(layer "In2.Cu")
		(net "EXP_CLK_SEL0")
	)
	(segment
		(start 105.29951 -88.716104)
		(end 105.028746 -88.44534)
		(width 0.127)
		(layer "In2.Cu")
		(net "EXP_CLK_SEL0")
	)
	(segment
		(start 107.268772 -90.861642)
		(end 107.268772 -90.675968)
		(width 0.127)
		(layer "In2.Cu")
		(net "EXP_CLK_SEL0")
	)
	(segment
		(start 107.268772 -90.675968)
		(end 106.998008 -90.405204)
		(width 0.127)
		(layer "In2.Cu")
		(net "EXP_CLK_SEL0")
	)
	(segment
		(start 108.430568 -91.268804)
		(end 107.675934 -91.268804)
		(width 0.127)
		(layer "In2.Cu")
		(net "EXP_CLK_SEL0")
	)
	(segment
		(start 106.998008 -90.405204)
		(end 106.812334 -90.405204)
		(width 0.127)
		(layer "In2.Cu")
		(net "EXP_CLK_SEL0")
	)
	(segment
		(start 105.99801 -89.405206)
		(end 105.75036 -89.405206)
		(width 0.127)
		(layer "In2.Cu")
		(net "EXP_CLK_SEL0")
	)
	(segment
		(start 105.75036 -89.405206)
		(end 105.29951 -88.954356)
		(width 0.127)
		(layer "In2.Cu")
		(net "EXP_CLK_SEL0")
	)
	(segment
		(start 106.294174 -89.70137)
		(end 105.99801 -89.405206)
		(width 0.127)
		(layer "In2.Cu")
		(net "EXP_CLK_SEL0")
	)
	(segment
		(start 105.29951 -88.954356)
		(end 105.29951 -88.716104)
		(width 0.127)
		(layer "In2.Cu")
		(net "EXP_CLK_SEL0")
	)
	(segment
		(start 108.849668 -90.849704)
		(end 108.430568 -91.268804)
		(width 0.127)
		(layer "In2.Cu")
		(net "EXP_CLK_SEL0")
	)
	(segment
		(start 145.587466 -59.525662)
		(end 145.587466 -59.31789)
		(width 0.1143)
		(layer "F.Cu")
		(net "XM_DATA_8")
	)
	(segment
		(start 106.750104 -54.99989)
		(end 107.1499 -55.399686)
		(width 0.1143)
		(layer "F.Cu")
		(net "XM_DATA_8")
	)
	(segment
		(start 145.598896 -59.537092)
		(end 145.587466 -59.525662)
		(width 0.1143)
		(layer "F.Cu")
		(net "XM_DATA_8")
	)
	(segment
		(start 145.598896 -61.9379)
		(end 145.598896 -59.537092)
		(width 0.1143)
		(layer "F.Cu")
		(net "XM_DATA_8")
	)
	(via
		(at 113.03 -56.642)
		(size 0.7112)
		(drill 0.3556)
		(layers "F.Cu" "B.Cu")
		(net "XM_DATA_8")
	)
	(via
		(at 107.1499 -55.399686)
		(size 0.508)
		(drill 0.254)
		(layers "F.Cu" "B.Cu")
		(net "XM_DATA_8")
	)
	(via
		(at 145.587466 -59.31789)
		(size 0.5588)
		(drill 0.3048)
		(layers "F.Cu" "B.Cu")
		(net "XM_DATA_8")
	)
	(segment
		(start 124.367544 -57.692544)
		(end 121.327672 -57.692544)
		(width 0.1143)
		(layer "B.Cu")
		(net "XM_DATA_8")
	)
	(segment
		(start 120.756172 -57.912)
		(end 120.756172 -57.806844)
		(width 0.1143)
		(layer "B.Cu")
		(net "XM_DATA_8")
	)
	(segment
		(start 142.435326 -59.900312)
		(end 141.902688 -59.900312)
		(width 0.1143)
		(layer "B.Cu")
		(net "XM_DATA_8")
	)
	(segment
		(start 113.411 -56.642)
		(end 113.03 -56.642)
		(width 0.1143)
		(layer "B.Cu")
		(net "XM_DATA_8")
	)
	(segment
		(start 113.03 -56.642)
		(end 112.776 -56.642)
		(width 0.1143)
		(layer "B.Cu")
		(net "XM_DATA_8")
	)
	(segment
		(start 121.213372 -57.912)
		(end 121.086372 -58.039)
		(width 0.1143)
		(layer "B.Cu")
		(net "XM_DATA_8")
	)
	(segment
		(start 107.75823 -56.705246)
		(end 107.1499 -56.096916)
		(width 0.1143)
		(layer "B.Cu")
		(net "XM_DATA_8")
	)
	(segment
		(start 115.50015 -56.6801)
		(end 113.4491 -56.6801)
		(width 0.1143)
		(layer "B.Cu")
		(net "XM_DATA_8")
	)
	(segment
		(start 141.80185 -60.00115)
		(end 138.559286 -60.00115)
		(width 0.1143)
		(layer "B.Cu")
		(net "XM_DATA_8")
	)
	(segment
		(start 112.328706 -56.194706)
		(end 109.786928 -56.194706)
		(width 0.1143)
		(layer "B.Cu")
		(net "XM_DATA_8")
	)
	(segment
		(start 120.756172 -57.806844)
		(end 120.641872 -57.692544)
		(width 0.1143)
		(layer "B.Cu")
		(net "XM_DATA_8")
	)
	(segment
		(start 138.559286 -60.00115)
		(end 137.105136 -58.547)
		(width 0.1143)
		(layer "B.Cu")
		(net "XM_DATA_8")
	)
	(segment
		(start 120.641872 -57.692544)
		(end 117.512084 -57.692544)
		(width 0.1143)
		(layer "B.Cu")
		(net "XM_DATA_8")
	)
	(segment
		(start 109.786928 -56.194706)
		(end 109.276388 -56.705246)
		(width 0.1143)
		(layer "B.Cu")
		(net "XM_DATA_8")
	)
	(segment
		(start 121.327672 -57.692544)
		(end 121.213372 -57.806844)
		(width 0.1143)
		(layer "B.Cu")
		(net "XM_DATA_8")
	)
	(segment
		(start 107.1499 -56.096916)
		(end 107.1499 -55.399686)
		(width 0.1143)
		(layer "B.Cu")
		(net "XM_DATA_8")
	)
	(segment
		(start 115.568222 -56.612028)
		(end 115.50015 -56.6801)
		(width 0.1143)
		(layer "B.Cu")
		(net "XM_DATA_8")
	)
	(segment
		(start 141.902688 -59.900312)
		(end 141.80185 -60.00115)
		(width 0.1143)
		(layer "B.Cu")
		(net "XM_DATA_8")
	)
	(segment
		(start 125.222 -58.547)
		(end 124.367544 -57.692544)
		(width 0.1143)
		(layer "B.Cu")
		(net "XM_DATA_8")
	)
	(segment
		(start 109.276388 -56.705246)
		(end 107.75823 -56.705246)
		(width 0.1143)
		(layer "B.Cu")
		(net "XM_DATA_8")
	)
	(segment
		(start 137.105136 -58.547)
		(end 125.222 -58.547)
		(width 0.1143)
		(layer "B.Cu")
		(net "XM_DATA_8")
	)
	(segment
		(start 113.4491 -56.6801)
		(end 113.411 -56.642)
		(width 0.1143)
		(layer "B.Cu")
		(net "XM_DATA_8")
	)
	(segment
		(start 120.883172 -58.039)
		(end 120.756172 -57.912)
		(width 0.1143)
		(layer "B.Cu")
		(net "XM_DATA_8")
	)
	(segment
		(start 142.550388 -60.015374)
		(end 142.435326 -59.900312)
		(width 0.1143)
		(layer "B.Cu")
		(net "XM_DATA_8")
	)
	(segment
		(start 144.889982 -60.015374)
		(end 142.550388 -60.015374)
		(width 0.1143)
		(layer "B.Cu")
		(net "XM_DATA_8")
	)
	(segment
		(start 116.431568 -56.612028)
		(end 115.568222 -56.612028)
		(width 0.1143)
		(layer "B.Cu")
		(net "XM_DATA_8")
	)
	(segment
		(start 117.512084 -57.692544)
		(end 116.431568 -56.612028)
		(width 0.1143)
		(layer "B.Cu")
		(net "XM_DATA_8")
	)
	(segment
		(start 145.587466 -59.31789)
		(end 144.889982 -60.015374)
		(width 0.1143)
		(layer "B.Cu")
		(net "XM_DATA_8")
	)
	(segment
		(start 112.776 -56.642)
		(end 112.328706 -56.194706)
		(width 0.1143)
		(layer "B.Cu")
		(net "XM_DATA_8")
	)
	(segment
		(start 121.086372 -58.039)
		(end 120.883172 -58.039)
		(width 0.1143)
		(layer "B.Cu")
		(net "XM_DATA_8")
	)
	(segment
		(start 121.213372 -57.806844)
		(end 121.213372 -57.912)
		(width 0.1143)
		(layer "B.Cu")
		(net "XM_DATA_8")
	)
	(via
		(at 88.265 -16.764)
		(size 0.7112)
		(drill 0.3556)
		(layers "F.Cu" "B.Cu")
		(net "VT235_VX")
	)
	(segment
		(start 52.705 -180.5305)
		(end 52.705 -180.594)
		(width 0.1143)
		(layer "F.Cu")
		(net "ICE_TRST_N")
	)
	(segment
		(start 48.289972 -185.269886)
		(end 48.289972 -185.009028)
		(width 0.1143)
		(layer "F.Cu")
		(net "ICE_TRST_N")
	)
	(segment
		(start 48.289972 -185.009028)
		(end 49.403 -183.896)
		(width 0.1143)
		(layer "F.Cu")
		(net "ICE_TRST_N")
	)
	(segment
		(start 104.349804 -102.350062)
		(end 103.849678 -102.850188)
		(width 0.1143)
		(layer "F.Cu")
		(net "ICE_TRST_N")
	)
	(segment
		(start 52.705 -180.594)
		(end 49.403 -183.896)
		(width 0.1143)
		(layer "F.Cu")
		(net "ICE_TRST_N")
	)
	(via
		(at 93.86697 -119.5832)
		(size 0.7112)
		(drill 0.3556)
		(layers "F.Cu" "B.Cu")
		(net "ICE_TRST_N")
	)
	(via
		(at 103.849678 -102.850188)
		(size 0.508)
		(drill 0.254)
		(layers "F.Cu" "B.Cu")
		(net "ICE_TRST_N")
	)
	(via
		(at 49.403 -183.896)
		(size 0.5588)
		(drill 0.3048)
		(layers "F.Cu" "B.Cu")
		(net "ICE_TRST_N")
	)
	(segment
		(start 93.86697 -120.02897)
		(end 95.74022 -121.90222)
		(width 0.1143)
		(layer "B.Cu")
		(net "ICE_TRST_N")
	)
	(segment
		(start 103.665782 -102.850188)
		(end 97.21977 -109.2962)
		(width 0.1143)
		(layer "B.Cu")
		(net "ICE_TRST_N")
	)
	(segment
		(start 91.406726 -144.2593)
		(end 89.281254 -144.2593)
		(width 0.1143)
		(layer "B.Cu")
		(net "ICE_TRST_N")
	)
	(segment
		(start 50.8 -182.499)
		(end 49.403 -183.896)
		(width 0.1143)
		(layer "B.Cu")
		(net "ICE_TRST_N")
	)
	(segment
		(start 56.40705 -182.47995)
		(end 50.818796 -182.47995)
		(width 0.1143)
		(layer "B.Cu")
		(net "ICE_TRST_N")
	)
	(segment
		(start 97.21977 -113.9444)
		(end 93.86697 -117.2972)
		(width 0.1143)
		(layer "B.Cu")
		(net "ICE_TRST_N")
	)
	(segment
		(start 95.74022 -139.925806)
		(end 91.406726 -144.2593)
		(width 0.1143)
		(layer "B.Cu")
		(net "ICE_TRST_N")
	)
	(segment
		(start 67.4497 -166.847012)
		(end 67.4497 -171.4373)
		(width 0.1143)
		(layer "B.Cu")
		(net "ICE_TRST_N")
	)
	(segment
		(start 97.21977 -109.2962)
		(end 97.21977 -113.9444)
		(width 0.1143)
		(layer "B.Cu")
		(net "ICE_TRST_N")
	)
	(segment
		(start 50.818796 -182.47995)
		(end 50.8 -182.499)
		(width 0.1143)
		(layer "B.Cu")
		(net "ICE_TRST_N")
	)
	(segment
		(start 84.132166 -150.164546)
		(end 67.4497 -166.847012)
		(width 0.1143)
		(layer "B.Cu")
		(net "ICE_TRST_N")
	)
	(segment
		(start 95.74022 -121.90222)
		(end 95.74022 -139.925806)
		(width 0.1143)
		(layer "B.Cu")
		(net "ICE_TRST_N")
	)
	(segment
		(start 93.86697 -117.2972)
		(end 93.86697 -119.5832)
		(width 0.1143)
		(layer "B.Cu")
		(net "ICE_TRST_N")
	)
	(segment
		(start 93.86697 -119.5832)
		(end 93.86697 -120.02897)
		(width 0.1143)
		(layer "B.Cu")
		(net "ICE_TRST_N")
	)
	(segment
		(start 103.849678 -102.850188)
		(end 103.665782 -102.850188)
		(width 0.1143)
		(layer "B.Cu")
		(net "ICE_TRST_N")
	)
	(segment
		(start 89.281254 -144.2593)
		(end 84.132166 -149.408388)
		(width 0.1143)
		(layer "B.Cu")
		(net "ICE_TRST_N")
	)
	(segment
		(start 84.132166 -149.408388)
		(end 84.132166 -150.164546)
		(width 0.1143)
		(layer "B.Cu")
		(net "ICE_TRST_N")
	)
	(segment
		(start 67.4497 -171.4373)
		(end 56.40705 -182.47995)
		(width 0.1143)
		(layer "B.Cu")
		(net "ICE_TRST_N")
	)
	(segment
		(start 144.599406 -59.500262)
		(end 144.607788 -59.49188)
		(width 0.1143)
		(layer "F.Cu")
		(net "XM_DATA_9")
	)
	(segment
		(start 144.599406 -61.9379)
		(end 144.599406 -59.500262)
		(width 0.1143)
		(layer "F.Cu")
		(net "XM_DATA_9")
	)
	(segment
		(start 110.750096 -54.99989)
		(end 111.149892 -55.399686)
		(width 0.1143)
		(layer "F.Cu")
		(net "XM_DATA_9")
	)
	(via
		(at 144.607788 -59.49188)
		(size 0.5588)
		(drill 0.3048)
		(layers "F.Cu" "B.Cu")
		(net "XM_DATA_9")
	)
	(via
		(at 117.475 -56.261)
		(size 0.7112)
		(drill 0.3556)
		(layers "F.Cu" "B.Cu")
		(net "XM_DATA_9")
	)
	(via
		(at 140.31849 -58.9661)
		(size 0.7112)
		(drill 0.3556)
		(layers "F.Cu" "B.Cu")
		(net "XM_DATA_9")
	)
	(via
		(at 111.149892 -55.399686)
		(size 0.508)
		(drill 0.254)
		(layers "F.Cu" "B.Cu")
		(net "XM_DATA_9")
	)
	(segment
		(start 134.2263 -57.531)
		(end 133.9977 -57.531)
		(width 0.1143)
		(layer "B.Cu")
		(net "XM_DATA_9")
	)
	(segment
		(start 133.8834 -56.915304)
		(end 133.7691 -56.801004)
		(width 0.1143)
		(layer "B.Cu")
		(net "XM_DATA_9")
	)
	(segment
		(start 134.7978 -56.915304)
		(end 134.6835 -56.801004)
		(width 0.1143)
		(layer "B.Cu")
		(net "XM_DATA_9")
	)
	(segment
		(start 138.906758 -59.16295)
		(end 137.274808 -57.531)
		(width 0.1143)
		(layer "B.Cu")
		(net "XM_DATA_9")
	)
	(segment
		(start 132.969 -57.4167)
		(end 132.969 -56.915304)
		(width 0.1143)
		(layer "B.Cu")
		(net "XM_DATA_9")
	)
	(segment
		(start 134.6835 -56.801004)
		(end 134.4549 -56.801004)
		(width 0.1143)
		(layer "B.Cu")
		(net "XM_DATA_9")
	)
	(segment
		(start 133.9977 -57.531)
		(end 133.8834 -57.4167)
		(width 0.1143)
		(layer "B.Cu")
		(net "XM_DATA_9")
	)
	(segment
		(start 131.5974 -57.4167)
		(end 131.4831 -57.531)
		(width 0.1143)
		(layer "B.Cu")
		(net "XM_DATA_9")
	)
	(segment
		(start 135.3312 -57.531)
		(end 134.9121 -57.531)
		(width 0.1143)
		(layer "B.Cu")
		(net "XM_DATA_9")
	)
	(segment
		(start 132.0546 -57.4167)
		(end 132.0546 -56.915304)
		(width 0.1143)
		(layer "B.Cu")
		(net "XM_DATA_9")
	)
	(segment
		(start 137.274808 -57.531)
		(end 136.017 -57.531)
		(width 0.1143)
		(layer "B.Cu")
		(net "XM_DATA_9")
	)
	(segment
		(start 135.5598 -56.801004)
		(end 135.4455 -56.915304)
		(width 0.1143)
		(layer "B.Cu")
		(net "XM_DATA_9")
	)
	(segment
		(start 117.475 -56.261)
		(end 117.464586 -56.261)
		(width 0.1143)
		(layer "B.Cu")
		(net "XM_DATA_9")
	)
	(segment
		(start 132.1689 -57.531)
		(end 132.0546 -57.4167)
		(width 0.1143)
		(layer "B.Cu")
		(net "XM_DATA_9")
	)
	(segment
		(start 133.5405 -56.801004)
		(end 133.4262 -56.915304)
		(width 0.1143)
		(layer "B.Cu")
		(net "XM_DATA_9")
	)
	(segment
		(start 132.8547 -56.801004)
		(end 132.6261 -56.801004)
		(width 0.1143)
		(layer "B.Cu")
		(net "XM_DATA_9")
	)
	(segment
		(start 115.892326 -55.763414)
		(end 115.418362 -55.28945)
		(width 0.1143)
		(layer "B.Cu")
		(net "XM_DATA_9")
	)
	(segment
		(start 135.4455 -56.915304)
		(end 135.4455 -57.4167)
		(width 0.1143)
		(layer "B.Cu")
		(net "XM_DATA_9")
	)
	(segment
		(start 131.5974 -56.915304)
		(end 131.5974 -57.4167)
		(width 0.1143)
		(layer "B.Cu")
		(net "XM_DATA_9")
	)
	(segment
		(start 132.3975 -57.531)
		(end 132.1689 -57.531)
		(width 0.1143)
		(layer "B.Cu")
		(net "XM_DATA_9")
	)
	(segment
		(start 135.9027 -57.4167)
		(end 135.9027 -56.915304)
		(width 0.1143)
		(layer "B.Cu")
		(net "XM_DATA_9")
	)
	(segment
		(start 131.9403 -56.801004)
		(end 131.7117 -56.801004)
		(width 0.1143)
		(layer "B.Cu")
		(net "XM_DATA_9")
	)
	(segment
		(start 140.31849 -58.9661)
		(end 139.591542 -58.9661)
		(width 0.1143)
		(layer "B.Cu")
		(net "XM_DATA_9")
	)
	(segment
		(start 133.8834 -57.4167)
		(end 133.8834 -56.915304)
		(width 0.1143)
		(layer "B.Cu")
		(net "XM_DATA_9")
	)
	(segment
		(start 144.607788 -59.49188)
		(end 144.082008 -58.9661)
		(width 0.1143)
		(layer "B.Cu")
		(net "XM_DATA_9")
	)
	(segment
		(start 132.969 -56.915304)
		(end 132.8547 -56.801004)
		(width 0.1143)
		(layer "B.Cu")
		(net "XM_DATA_9")
	)
	(segment
		(start 115.07597 -55.28945)
		(end 114.965734 -55.399686)
		(width 0.1143)
		(layer "B.Cu")
		(net "XM_DATA_9")
	)
	(segment
		(start 115.418362 -55.28945)
		(end 115.07597 -55.28945)
		(width 0.1143)
		(layer "B.Cu")
		(net "XM_DATA_9")
	)
	(segment
		(start 133.4262 -56.915304)
		(end 133.4262 -57.4167)
		(width 0.1143)
		(layer "B.Cu")
		(net "XM_DATA_9")
	)
	(segment
		(start 134.9121 -57.531)
		(end 134.7978 -57.4167)
		(width 0.1143)
		(layer "B.Cu")
		(net "XM_DATA_9")
	)
	(segment
		(start 133.7691 -56.801004)
		(end 133.5405 -56.801004)
		(width 0.1143)
		(layer "B.Cu")
		(net "XM_DATA_9")
	)
	(segment
		(start 135.4455 -57.4167)
		(end 135.3312 -57.531)
		(width 0.1143)
		(layer "B.Cu")
		(net "XM_DATA_9")
	)
	(segment
		(start 139.394692 -59.16295)
		(end 138.906758 -59.16295)
		(width 0.1143)
		(layer "B.Cu")
		(net "XM_DATA_9")
	)
	(segment
		(start 131.064 -57.531)
		(end 130.334004 -56.801004)
		(width 0.1143)
		(layer "B.Cu")
		(net "XM_DATA_9")
	)
	(segment
		(start 134.4549 -56.801004)
		(end 134.3406 -56.915304)
		(width 0.1143)
		(layer "B.Cu")
		(net "XM_DATA_9")
	)
	(segment
		(start 116.967 -55.763414)
		(end 115.892326 -55.763414)
		(width 0.1143)
		(layer "B.Cu")
		(net "XM_DATA_9")
	)
	(segment
		(start 114.965734 -55.399686)
		(end 111.149892 -55.399686)
		(width 0.1143)
		(layer "B.Cu")
		(net "XM_DATA_9")
	)
	(segment
		(start 132.5118 -57.4167)
		(end 132.3975 -57.531)
		(width 0.1143)
		(layer "B.Cu")
		(net "XM_DATA_9")
	)
	(segment
		(start 117.464586 -56.261)
		(end 116.967 -55.763414)
		(width 0.1143)
		(layer "B.Cu")
		(net "XM_DATA_9")
	)
	(segment
		(start 133.0833 -57.531)
		(end 132.969 -57.4167)
		(width 0.1143)
		(layer "B.Cu")
		(net "XM_DATA_9")
	)
	(segment
		(start 136.017 -57.531)
		(end 135.9027 -57.4167)
		(width 0.1143)
		(layer "B.Cu")
		(net "XM_DATA_9")
	)
	(segment
		(start 134.7978 -57.4167)
		(end 134.7978 -56.915304)
		(width 0.1143)
		(layer "B.Cu")
		(net "XM_DATA_9")
	)
	(segment
		(start 131.7117 -56.801004)
		(end 131.5974 -56.915304)
		(width 0.1143)
		(layer "B.Cu")
		(net "XM_DATA_9")
	)
	(segment
		(start 134.3406 -56.915304)
		(end 134.3406 -57.4167)
		(width 0.1143)
		(layer "B.Cu")
		(net "XM_DATA_9")
	)
	(segment
		(start 131.4831 -57.531)
		(end 131.064 -57.531)
		(width 0.1143)
		(layer "B.Cu")
		(net "XM_DATA_9")
	)
	(segment
		(start 132.5118 -56.915304)
		(end 132.5118 -57.4167)
		(width 0.1143)
		(layer "B.Cu")
		(net "XM_DATA_9")
	)
	(segment
		(start 139.591542 -58.9661)
		(end 139.394692 -59.16295)
		(width 0.1143)
		(layer "B.Cu")
		(net "XM_DATA_9")
	)
	(segment
		(start 144.082008 -58.9661)
		(end 140.31849 -58.9661)
		(width 0.1143)
		(layer "B.Cu")
		(net "XM_DATA_9")
	)
	(segment
		(start 134.3406 -57.4167)
		(end 134.2263 -57.531)
		(width 0.1143)
		(layer "B.Cu")
		(net "XM_DATA_9")
	)
	(segment
		(start 130.334004 -56.801004)
		(end 118.015004 -56.801004)
		(width 0.1143)
		(layer "B.Cu")
		(net "XM_DATA_9")
	)
	(segment
		(start 135.9027 -56.915304)
		(end 135.7884 -56.801004)
		(width 0.1143)
		(layer "B.Cu")
		(net "XM_DATA_9")
	)
	(segment
		(start 135.7884 -56.801004)
		(end 135.5598 -56.801004)
		(width 0.1143)
		(layer "B.Cu")
		(net "XM_DATA_9")
	)
	(segment
		(start 132.6261 -56.801004)
		(end 132.5118 -56.915304)
		(width 0.1143)
		(layer "B.Cu")
		(net "XM_DATA_9")
	)
	(segment
		(start 132.0546 -56.915304)
		(end 131.9403 -56.801004)
		(width 0.1143)
		(layer "B.Cu")
		(net "XM_DATA_9")
	)
	(segment
		(start 118.015004 -56.801004)
		(end 117.475 -56.261)
		(width 0.1143)
		(layer "B.Cu")
		(net "XM_DATA_9")
	)
	(segment
		(start 133.3119 -57.531)
		(end 133.0833 -57.531)
		(width 0.1143)
		(layer "B.Cu")
		(net "XM_DATA_9")
	)
	(segment
		(start 133.4262 -57.4167)
		(end 133.3119 -57.531)
		(width 0.1143)
		(layer "B.Cu")
		(net "XM_DATA_9")
	)
	(segment
		(start 98.927666 -104.350058)
		(end 102.349808 -104.350058)
		(width 0.1143)
		(layer "F.Cu")
		(net "UART_RTS")
	)
	(segment
		(start 98.557842 -104.719882)
		(end 98.927666 -104.350058)
		(width 0.1143)
		(layer "F.Cu")
		(net "UART_RTS")
	)
	(segment
		(start 142.602966 -44.177966)
		(end 142.599156 -44.174156)
		(width 0.1143)
		(layer "F.Cu")
		(net "XM_ADDR_22")
	)
	(segment
		(start 116.205 -50.673)
		(end 116.205 -50.284634)
		(width 0.1143)
		(layer "F.Cu")
		(net "XM_ADDR_22")
	)
	(segment
		(start 113.150142 -50.199798)
		(end 113.408968 -50.199798)
		(width 0.1143)
		(layer "F.Cu")
		(net "XM_ADDR_22")
	)
	(segment
		(start 142.599156 -41.783)
		(end 142.599156 -42.7101)
		(width 0.1143)
		(layer "F.Cu")
		(net "XM_ADDR_22")
	)
	(segment
		(start 113.408968 -50.199798)
		(end 113.828068 -49.780698)
		(width 0.1143)
		(layer "F.Cu")
		(net "XM_ADDR_22")
	)
	(segment
		(start 142.602966 -44.308014)
		(end 142.602966 -44.177966)
		(width 0.1143)
		(layer "F.Cu")
		(net "XM_ADDR_22")
	)
	(segment
		(start 142.599156 -44.174156)
		(end 142.599156 -42.7101)
		(width 0.1143)
		(layer "F.Cu")
		(net "XM_ADDR_22")
	)
	(segment
		(start 116.205 -50.284634)
		(end 115.882166 -49.9618)
		(width 0.1143)
		(layer "F.Cu")
		(net "XM_ADDR_22")
	)
	(segment
		(start 141.986 -41.169844)
		(end 142.599156 -41.783)
		(width 0.1143)
		(layer "F.Cu")
		(net "XM_ADDR_22")
	)
	(segment
		(start 141.986 -39.3065)
		(end 141.986 -41.169844)
		(width 0.1143)
		(layer "F.Cu")
		(net "XM_ADDR_22")
	)
	(segment
		(start 115.701064 -49.780698)
		(end 115.882166 -49.9618)
		(width 0.1143)
		(layer "F.Cu")
		(net "XM_ADDR_22")
	)
	(segment
		(start 113.828068 -49.780698)
		(end 115.701064 -49.780698)
		(width 0.1143)
		(layer "F.Cu")
		(net "XM_ADDR_22")
	)
	(via
		(at 116.205 -50.673)
		(size 0.7112)
		(drill 0.3556)
		(layers "F.Cu" "B.Cu")
		(net "XM_ADDR_22")
	)
	(via
		(at 115.882166 -49.9618)
		(size 0.508)
		(drill 0.254)
		(layers "F.Cu" "B.Cu")
		(net "XM_ADDR_22")
	)
	(via
		(at 142.602966 -44.308014)
		(size 0.5588)
		(drill 0.3048)
		(layers "F.Cu" "B.Cu")
		(net "XM_ADDR_22")
	)
	(segment
		(start 137.827766 -42.698416)
		(end 137.700766 -42.571416)
		(width 0.127)
		(layer "In5.Cu")
		(net "XM_ADDR_22")
	)
	(segment
		(start 123.675648 -45.2628)
		(end 123.675648 -45.6819)
		(width 0.127)
		(layer "In5.Cu")
		(net "XM_ADDR_22")
	)
	(segment
		(start 119.525542 -48.61433)
		(end 119.828564 -48.917352)
		(width 0.127)
		(layer "In5.Cu")
		(net "XM_ADDR_22")
	)
	(segment
		(start 135.236966 -42.571416)
		(end 135.109966 -42.698416)
		(width 0.127)
		(layer "In5.Cu")
		(net "XM_ADDR_22")
	)
	(segment
		(start 117.812566 -48.768)
		(end 117.812566 -48.514)
		(width 0.127)
		(layer "In5.Cu")
		(net "XM_ADDR_22")
	)
	(segment
		(start 124.183648 -45.2628)
		(end 124.056648 -45.1358)
		(width 0.127)
		(layer "In5.Cu")
		(net "XM_ADDR_22")
	)
	(segment
		(start 124.310648 -45.8089)
		(end 124.183648 -45.6819)
		(width 0.127)
		(layer "In5.Cu")
		(net "XM_ADDR_22")
	)
	(segment
		(start 117.044978 -48.895)
		(end 117.685566 -48.895)
		(width 0.127)
		(layer "In5.Cu")
		(net "XM_ADDR_22")
	)
	(segment
		(start 120.187974 -48.557942)
		(end 119.884952 -48.25492)
		(width 0.127)
		(layer "In5.Cu")
		(net "XM_ADDR_22")
	)
	(segment
		(start 124.564648 -45.8089)
		(end 124.310648 -45.8089)
		(width 0.127)
		(layer "In5.Cu")
		(net "XM_ADDR_22")
	)
	(segment
		(start 136.811766 -42.698416)
		(end 136.684766 -42.571416)
		(width 0.127)
		(layer "In5.Cu")
		(net "XM_ADDR_22")
	)
	(segment
		(start 119.969534 -47.188374)
		(end 119.969534 -47.368206)
		(width 0.127)
		(layer "In5.Cu")
		(net "XM_ADDR_22")
	)
	(segment
		(start 139.478766 -42.571416)
		(end 139.351766 -42.698416)
		(width 0.127)
		(layer "In5.Cu")
		(net "XM_ADDR_22")
	)
	(segment
		(start 136.811766 -43.04919)
		(end 136.811766 -42.698416)
		(width 0.127)
		(layer "In5.Cu")
		(net "XM_ADDR_22")
	)
	(segment
		(start 138.462766 -42.571416)
		(end 138.335766 -42.698416)
		(width 0.127)
		(layer "In5.Cu")
		(net "XM_ADDR_22")
	)
	(segment
		(start 119.969534 -47.368206)
		(end 120.673622 -48.072294)
		(width 0.127)
		(layer "In5.Cu")
		(net "XM_ADDR_22")
	)
	(segment
		(start 134.982966 -44.577)
		(end 132.860034 -44.577)
		(width 0.127)
		(layer "In5.Cu")
		(net "XM_ADDR_22")
	)
	(segment
		(start 123.548648 -45.8089)
		(end 123.116848 -45.8089)
		(width 0.127)
		(layer "In5.Cu")
		(net "XM_ADDR_22")
	)
	(segment
		(start 137.319766 -42.698416)
		(end 137.319766 -43.04919)
		(width 0.127)
		(layer "In5.Cu")
		(net "XM_ADDR_22")
	)
	(segment
		(start 132.860034 -44.577)
		(end 132.301234 -45.1358)
		(width 0.127)
		(layer "In5.Cu")
		(net "XM_ADDR_22")
	)
	(segment
		(start 138.970766 -43.17619)
		(end 138.843766 -43.04919)
		(width 0.127)
		(layer "In5.Cu")
		(net "XM_ADDR_22")
	)
	(segment
		(start 126.342648 -45.8089)
		(end 126.215648 -45.6819)
		(width 0.127)
		(layer "In5.Cu")
		(net "XM_ADDR_22")
	)
	(segment
		(start 136.430766 -42.571416)
		(end 136.303766 -42.698416)
		(width 0.127)
		(layer "In5.Cu")
		(net "XM_ADDR_22")
	)
	(segment
		(start 116.910104 -48.26)
		(end 116.910104 -48.006)
		(width 0.127)
		(layer "In5.Cu")
		(net "XM_ADDR_22")
	)
	(segment
		(start 137.319766 -43.04919)
		(end 137.192766 -43.17619)
		(width 0.127)
		(layer "In5.Cu")
		(net "XM_ADDR_22")
	)
	(segment
		(start 139.351766 -42.698416)
		(end 139.351766 -43.04919)
		(width 0.127)
		(layer "In5.Cu")
		(net "XM_ADDR_22")
	)
	(segment
		(start 125.707648 -45.6819)
		(end 125.580648 -45.8089)
		(width 0.127)
		(layer "In5.Cu")
		(net "XM_ADDR_22")
	)
	(segment
		(start 118.895876 -47.0789)
		(end 118.768876 -46.9519)
		(width 0.127)
		(layer "In5.Cu")
		(net "XM_ADDR_22")
	)
	(segment
		(start 125.326648 -45.8089)
		(end 125.199648 -45.6819)
		(width 0.127)
		(layer "In5.Cu")
		(net "XM_ADDR_22")
	)
	(segment
		(start 119.525542 -48.434498)
		(end 119.525542 -48.61433)
		(width 0.127)
		(layer "In5.Cu")
		(net "XM_ADDR_22")
	)
	(segment
		(start 135.109966 -44.45)
		(end 134.982966 -44.577)
		(width 0.127)
		(layer "In5.Cu")
		(net "XM_ADDR_22")
	)
	(segment
		(start 137.954766 -43.17619)
		(end 137.827766 -43.04919)
		(width 0.127)
		(layer "In5.Cu")
		(net "XM_ADDR_22")
	)
	(segment
		(start 136.303766 -43.04919)
		(end 136.176766 -43.17619)
		(width 0.127)
		(layer "In5.Cu")
		(net "XM_ADDR_22")
	)
	(segment
		(start 117.685566 -48.387)
		(end 117.037104 -48.387)
		(width 0.127)
		(layer "In5.Cu")
		(net "XM_ADDR_22")
	)
	(segment
		(start 136.938766 -43.17619)
		(end 136.811766 -43.04919)
		(width 0.127)
		(layer "In5.Cu")
		(net "XM_ADDR_22")
	)
	(segment
		(start 127.94869 -45.1358)
		(end 127.27559 -45.8089)
		(width 0.127)
		(layer "In5.Cu")
		(net "XM_ADDR_22")
	)
	(segment
		(start 137.192766 -43.17619)
		(end 136.938766 -43.17619)
		(width 0.127)
		(layer "In5.Cu")
		(net "XM_ADDR_22")
	)
	(segment
		(start 124.691648 -45.6819)
		(end 124.564648 -45.8089)
		(width 0.127)
		(layer "In5.Cu")
		(net "XM_ADDR_22")
	)
	(segment
		(start 135.795766 -42.698416)
		(end 135.668766 -42.571416)
		(width 0.127)
		(layer "In5.Cu")
		(net "XM_ADDR_22")
	)
	(segment
		(start 142.475966 -42.571416)
		(end 139.478766 -42.571416)
		(width 0.127)
		(layer "In5.Cu")
		(net "XM_ADDR_22")
	)
	(segment
		(start 125.834648 -45.1358)
		(end 125.707648 -45.2628)
		(width 0.127)
		(layer "In5.Cu")
		(net "XM_ADDR_22")
	)
	(segment
		(start 123.802648 -45.1358)
		(end 123.675648 -45.2628)
		(width 0.127)
		(layer "In5.Cu")
		(net "XM_ADDR_22")
	)
	(segment
		(start 118.895876 -47.752)
		(end 118.895876 -47.0789)
		(width 0.127)
		(layer "In5.Cu")
		(net "XM_ADDR_22")
	)
	(segment
		(start 139.224766 -43.17619)
		(end 138.970766 -43.17619)
		(width 0.127)
		(layer "In5.Cu")
		(net "XM_ADDR_22")
	)
	(segment
		(start 117.044978 -49.403)
		(end 116.917978 -49.276)
		(width 0.127)
		(layer "In5.Cu")
		(net "XM_ADDR_22")
	)
	(segment
		(start 116.3828 -47.641002)
		(end 116.3828 -49.276)
		(width 0.127)
		(layer "In5.Cu")
		(net "XM_ADDR_22")
	)
	(segment
		(start 116.3828 -49.276)
		(end 116.2558 -49.403)
		(width 0.127)
		(layer "In5.Cu")
		(net "XM_ADDR_22")
	)
	(segment
		(start 124.056648 -45.1358)
		(end 123.802648 -45.1358)
		(width 0.127)
		(layer "In5.Cu")
		(net "XM_ADDR_22")
	)
	(segment
		(start 125.072648 -45.1358)
		(end 124.818648 -45.1358)
		(width 0.127)
		(layer "In5.Cu")
		(net "XM_ADDR_22")
	)
	(segment
		(start 142.602966 -42.698416)
		(end 142.475966 -42.571416)
		(width 0.127)
		(layer "In5.Cu")
		(net "XM_ADDR_22")
	)
	(segment
		(start 119.70512 -48.25492)
		(end 119.525542 -48.434498)
		(width 0.127)
		(layer "In5.Cu")
		(net "XM_ADDR_22")
	)
	(segment
		(start 126.088648 -45.1358)
		(end 125.834648 -45.1358)
		(width 0.127)
		(layer "In5.Cu")
		(net "XM_ADDR_22")
	)
	(segment
		(start 119.828564 -49.097184)
		(end 119.522748 -49.403)
		(width 0.127)
		(layer "In5.Cu")
		(net "XM_ADDR_22")
	)
	(segment
		(start 125.707648 -45.2628)
		(end 125.707648 -45.6819)
		(width 0.127)
		(layer "In5.Cu")
		(net "XM_ADDR_22")
	)
	(segment
		(start 138.335766 -43.04919)
		(end 138.208766 -43.17619)
		(width 0.127)
		(layer "In5.Cu")
		(net "XM_ADDR_22")
	)
	(segment
		(start 116.910104 -48.006)
		(end 117.037104 -47.879)
		(width 0.127)
		(layer "In5.Cu")
		(net "XM_ADDR_22")
	)
	(segment
		(start 116.009166 -49.403)
		(end 115.882166 -49.53)
		(width 0.127)
		(layer "In5.Cu")
		(net "XM_ADDR_22")
	)
	(segment
		(start 124.691648 -45.2628)
		(end 124.691648 -45.6819)
		(width 0.127)
		(layer "In5.Cu")
		(net "XM_ADDR_22")
	)
	(segment
		(start 137.827766 -43.04919)
		(end 137.827766 -42.698416)
		(width 0.127)
		(layer "In5.Cu")
		(net "XM_ADDR_22")
	)
	(segment
		(start 118.768876 -46.9519)
		(end 117.071902 -46.9519)
		(width 0.127)
		(layer "In5.Cu")
		(net "XM_ADDR_22")
	)
	(segment
		(start 138.716766 -42.571416)
		(end 138.462766 -42.571416)
		(width 0.127)
		(layer "In5.Cu")
		(net "XM_ADDR_22")
	)
	(segment
		(start 117.812566 -48.514)
		(end 117.685566 -48.387)
		(width 0.127)
		(layer "In5.Cu")
		(net "XM_ADDR_22")
	)
	(segment
		(start 123.675648 -45.6819)
		(end 123.548648 -45.8089)
		(width 0.127)
		(layer "In5.Cu")
		(net "XM_ADDR_22")
	)
	(segment
		(start 136.176766 -43.17619)
		(end 135.922766 -43.17619)
		(width 0.127)
		(layer "In5.Cu")
		(net "XM_ADDR_22")
	)
	(segment
		(start 126.215648 -45.2628)
		(end 126.088648 -45.1358)
		(width 0.127)
		(layer "In5.Cu")
		(net "XM_ADDR_22")
	)
	(segment
		(start 136.684766 -42.571416)
		(end 136.430766 -42.571416)
		(width 0.127)
		(layer "In5.Cu")
		(net "XM_ADDR_22")
	)
	(segment
		(start 117.685566 -48.895)
		(end 117.812566 -48.768)
		(width 0.127)
		(layer "In5.Cu")
		(net "XM_ADDR_22")
	)
	(segment
		(start 116.917978 -49.276)
		(end 116.917978 -49.022)
		(width 0.127)
		(layer "In5.Cu")
		(net "XM_ADDR_22")
	)
	(segment
		(start 132.301234 -45.1358)
		(end 127.94869 -45.1358)
		(width 0.127)
		(layer "In5.Cu")
		(net "XM_ADDR_22")
	)
	(segment
		(start 117.037104 -48.387)
		(end 116.910104 -48.26)
		(width 0.127)
		(layer "In5.Cu")
		(net "XM_ADDR_22")
	)
	(segment
		(start 135.109966 -42.698416)
		(end 135.109966 -44.45)
		(width 0.127)
		(layer "In5.Cu")
		(net "XM_ADDR_22")
	)
	(segment
		(start 119.522748 -49.403)
		(end 117.044978 -49.403)
		(width 0.127)
		(layer "In5.Cu")
		(net "XM_ADDR_22")
	)
	(segment
		(start 142.602966 -44.308014)
		(end 142.602966 -42.698416)
		(width 0.127)
		(layer "In5.Cu")
		(net "XM_ADDR_22")
	)
	(segment
		(start 127.27559 -45.8089)
		(end 126.342648 -45.8089)
		(width 0.127)
		(layer "In5.Cu")
		(net "XM_ADDR_22")
	)
	(segment
		(start 138.843766 -43.04919)
		(end 138.843766 -42.698416)
		(width 0.127)
		(layer "In5.Cu")
		(net "XM_ADDR_22")
	)
	(segment
		(start 121.212864 -47.712884)
		(end 121.033032 -47.712884)
		(width 0.127)
		(layer "In5.Cu")
		(net "XM_ADDR_22")
	)
	(segment
		(start 120.367806 -48.557942)
		(end 120.187974 -48.557942)
		(width 0.127)
		(layer "In5.Cu")
		(net "XM_ADDR_22")
	)
	(segment
		(start 115.882166 -49.53)
		(end 115.882166 -49.9618)
		(width 0.127)
		(layer "In5.Cu")
		(net "XM_ADDR_22")
	)
	(segment
		(start 138.843766 -42.698416)
		(end 138.716766 -42.571416)
		(width 0.127)
		(layer "In5.Cu")
		(net "XM_ADDR_22")
	)
	(segment
		(start 116.917978 -49.022)
		(end 117.044978 -48.895)
		(width 0.127)
		(layer "In5.Cu")
		(net "XM_ADDR_22")
	)
	(segment
		(start 123.116848 -45.8089)
		(end 121.212864 -47.712884)
		(width 0.127)
		(layer "In5.Cu")
		(net "XM_ADDR_22")
	)
	(segment
		(start 117.037104 -47.879)
		(end 118.768876 -47.879)
		(width 0.127)
		(layer "In5.Cu")
		(net "XM_ADDR_22")
	)
	(segment
		(start 139.351766 -43.04919)
		(end 139.224766 -43.17619)
		(width 0.127)
		(layer "In5.Cu")
		(net "XM_ADDR_22")
	)
	(segment
		(start 135.795766 -43.04919)
		(end 135.795766 -42.698416)
		(width 0.127)
		(layer "In5.Cu")
		(net "XM_ADDR_22")
	)
	(segment
		(start 124.183648 -45.6819)
		(end 124.183648 -45.2628)
		(width 0.127)
		(layer "In5.Cu")
		(net "XM_ADDR_22")
	)
	(segment
		(start 138.335766 -42.698416)
		(end 138.335766 -43.04919)
		(width 0.127)
		(layer "In5.Cu")
		(net "XM_ADDR_22")
	)
	(segment
		(start 120.673622 -48.072294)
		(end 120.673622 -48.252126)
		(width 0.127)
		(layer "In5.Cu")
		(net "XM_ADDR_22")
	)
	(segment
		(start 137.446766 -42.571416)
		(end 137.319766 -42.698416)
		(width 0.127)
		(layer "In5.Cu")
		(net "XM_ADDR_22")
	)
	(segment
		(start 121.033032 -47.712884)
		(end 120.328944 -47.008796)
		(width 0.127)
		(layer "In5.Cu")
		(net "XM_ADDR_22")
	)
	(segment
		(start 125.580648 -45.8089)
		(end 125.326648 -45.8089)
		(width 0.127)
		(layer "In5.Cu")
		(net "XM_ADDR_22")
	)
	(segment
		(start 135.668766 -42.571416)
		(end 135.236966 -42.571416)
		(width 0.127)
		(layer "In5.Cu")
		(net "XM_ADDR_22")
	)
	(segment
		(start 138.208766 -43.17619)
		(end 137.954766 -43.17619)
		(width 0.127)
		(layer "In5.Cu")
		(net "XM_ADDR_22")
	)
	(segment
		(start 120.673622 -48.252126)
		(end 120.367806 -48.557942)
		(width 0.127)
		(layer "In5.Cu")
		(net "XM_ADDR_22")
	)
	(segment
		(start 118.768876 -47.879)
		(end 118.895876 -47.752)
		(width 0.127)
		(layer "In5.Cu")
		(net "XM_ADDR_22")
	)
	(segment
		(start 125.199648 -45.2628)
		(end 125.072648 -45.1358)
		(width 0.127)
		(layer "In5.Cu")
		(net "XM_ADDR_22")
	)
	(segment
		(start 120.149112 -47.008796)
		(end 119.969534 -47.188374)
		(width 0.127)
		(layer "In5.Cu")
		(net "XM_ADDR_22")
	)
	(segment
		(start 120.328944 -47.008796)
		(end 120.149112 -47.008796)
		(width 0.127)
		(layer "In5.Cu")
		(net "XM_ADDR_22")
	)
	(segment
		(start 124.818648 -45.1358)
		(end 124.691648 -45.2628)
		(width 0.127)
		(layer "In5.Cu")
		(net "XM_ADDR_22")
	)
	(segment
		(start 137.700766 -42.571416)
		(end 137.446766 -42.571416)
		(width 0.127)
		(layer "In5.Cu")
		(net "XM_ADDR_22")
	)
	(segment
		(start 119.884952 -48.25492)
		(end 119.70512 -48.25492)
		(width 0.127)
		(layer "In5.Cu")
		(net "XM_ADDR_22")
	)
	(segment
		(start 136.303766 -42.698416)
		(end 136.303766 -43.04919)
		(width 0.127)
		(layer "In5.Cu")
		(net "XM_ADDR_22")
	)
	(segment
		(start 125.199648 -45.6819)
		(end 125.199648 -45.2628)
		(width 0.127)
		(layer "In5.Cu")
		(net "XM_ADDR_22")
	)
	(segment
		(start 135.922766 -43.17619)
		(end 135.795766 -43.04919)
		(width 0.127)
		(layer "In5.Cu")
		(net "XM_ADDR_22")
	)
	(segment
		(start 117.071902 -46.9519)
		(end 116.3828 -47.641002)
		(width 0.127)
		(layer "In5.Cu")
		(net "XM_ADDR_22")
	)
	(segment
		(start 116.2558 -49.403)
		(end 116.009166 -49.403)
		(width 0.127)
		(layer "In5.Cu")
		(net "XM_ADDR_22")
	)
	(segment
		(start 126.215648 -45.6819)
		(end 126.215648 -45.2628)
		(width 0.127)
		(layer "In5.Cu")
		(net "XM_ADDR_22")
	)
	(segment
		(start 119.828564 -48.917352)
		(end 119.828564 -49.097184)
		(width 0.127)
		(layer "In5.Cu")
		(net "XM_ADDR_22")
	)
	(segment
		(start 87.326978 -35.137598)
		(end 87.37219 -35.149028)
		(width 0.1016)
		(layer "F.Cu")
		(net "SAS3008_RAID_TX_C_P1")
	)
	(segment
		(start 87.396574 -35.167316)
		(end 87.397082 -35.167824)
		(width 0.1016)
		(layer "F.Cu")
		(net "SAS3008_RAID_TX_C_P1")
	)
	(segment
		(start 87.400384 -35.170872)
		(end 87.52586 -35.296094)
		(width 0.1016)
		(layer "F.Cu")
		(net "SAS3008_RAID_TX_C_P1")
	)
	(segment
		(start 87.372698 -35.149282)
		(end 87.396574 -35.167316)
		(width 0.1016)
		(layer "F.Cu")
		(net "SAS3008_RAID_TX_C_P1")
	)
	(segment
		(start 87.183214 -35.137598)
		(end 87.326978 -35.137598)
		(width 0.1016)
		(layer "F.Cu")
		(net "SAS3008_RAID_TX_C_P1")
	)
	(segment
		(start 87.52586 -35.296094)
		(end 87.77478 -35.545014)
		(width 0.1016)
		(layer "F.Cu")
		(net "SAS3008_RAID_TX_C_P1")
	)
	(segment
		(start 88.329516 -35.77463)
		(end 90.688922 -35.77463)
		(width 0.1016)
		(layer "F.Cu")
		(net "SAS3008_RAID_TX_C_P1")
	)
	(segment
		(start 87.37219 -35.149028)
		(end 87.372698 -35.149282)
		(width 0.1016)
		(layer "F.Cu")
		(net "SAS3008_RAID_TX_C_P1")
	)
	(arc
		(start 90.688922 -35.77463)
		(mid 90.722053 -35.781238)
		(end 90.750136 -35.80003)
		(width 0.1016)
		(layer "F.Cu")
		(net "SAS3008_RAID_TX_C_P1")
	)
	(arc
		(start 87.397082 -35.167824)
		(mid 87.398747 -35.169333)
		(end 87.400384 -35.170872)
		(width 0.1016)
		(layer "F.Cu")
		(net "SAS3008_RAID_TX_C_P1")
	)
	(arc
		(start 86.77656 -35.306)
		(mid 86.963134 -35.181335)
		(end 87.183214 -35.137598)
		(width 0.1016)
		(layer "F.Cu")
		(net "SAS3008_RAID_TX_C_P1")
	)
	(arc
		(start 87.77478 -35.545014)
		(mid 88.02931 -35.714993)
		(end 88.329516 -35.77463)
		(width 0.1016)
		(layer "F.Cu")
		(net "SAS3008_RAID_TX_C_P1")
	)
	(segment
		(start 84.534248 -21.255228)
		(end 84.534248 -21.669248)
		(width 0.254)
		(layer "F.Cu")
		(net "VT235_PGIN")
	)
	(segment
		(start 85.598 -23.9395)
		(end 85.598 -22.987)
		(width 0.254)
		(layer "F.Cu")
		(net "VT235_PGIN")
	)
	(segment
		(start 85.598 -22.733)
		(end 85.598 -22.987)
		(width 0.254)
		(layer "F.Cu")
		(net "VT235_PGIN")
	)
	(segment
		(start 86.614 -23.9395)
		(end 85.598 -23.9395)
		(width 0.254)
		(layer "F.Cu")
		(net "VT235_PGIN")
	)
	(segment
		(start 84.534248 -21.669248)
		(end 85.598 -22.733)
		(width 0.254)
		(layer "F.Cu")
		(net "VT235_PGIN")
	)
	(via
		(at 85.598 -22.987)
		(size 0.7112)
		(drill 0.3556)
		(layers "F.Cu" "B.Cu")
		(net "VT235_PGIN")
	)
	(segment
		(start 106.16438 -59.04738)
		(end 106.16438 -58.898536)
		(width 0.1143)
		(layer "F.Cu")
		(net "XM_CS0_N")
	)
	(segment
		(start 105.150158 -55.809388)
		(end 105.150158 -55.79999)
		(width 0.1143)
		(layer "F.Cu")
		(net "XM_CS0_N")
	)
	(segment
		(start 106.883454 -60.2234)
		(end 106.39425 -59.734196)
		(width 0.1143)
		(layer "F.Cu")
		(net "XM_CS0_N")
	)
	(segment
		(start 106.39425 -59.734196)
		(end 106.39425 -59.27725)
		(width 0.1143)
		(layer "F.Cu")
		(net "XM_CS0_N")
	)
	(segment
		(start 110.872524 -61.976)
		(end 110.218474 -61.32195)
		(width 0.1143)
		(layer "F.Cu")
		(net "XM_CS0_N")
	)
	(segment
		(start 106.16438 -58.898536)
		(end 105.334816 -58.068972)
		(width 0.1143)
		(layer "F.Cu")
		(net "XM_CS0_N")
	)
	(segment
		(start 105.486708 -56.145938)
		(end 105.150158 -55.809388)
		(width 0.1143)
		(layer "F.Cu")
		(net "XM_CS0_N")
	)
	(segment
		(start 106.39425 -59.27725)
		(end 106.16438 -59.04738)
		(width 0.1143)
		(layer "F.Cu")
		(net "XM_CS0_N")
	)
	(segment
		(start 110.218474 -61.32195)
		(end 109.44225 -61.32195)
		(width 0.1143)
		(layer "F.Cu")
		(net "XM_CS0_N")
	)
	(segment
		(start 105.334816 -58.068972)
		(end 105.334816 -57.733184)
		(width 0.1143)
		(layer "F.Cu")
		(net "XM_CS0_N")
	)
	(segment
		(start 105.486708 -57.581292)
		(end 105.486708 -56.145938)
		(width 0.1143)
		(layer "F.Cu")
		(net "XM_CS0_N")
	)
	(segment
		(start 105.334816 -57.733184)
		(end 105.486708 -57.581292)
		(width 0.1143)
		(layer "F.Cu")
		(net "XM_CS0_N")
	)
	(segment
		(start 107.3404 -60.2234)
		(end 106.883454 -60.2234)
		(width 0.1143)
		(layer "F.Cu")
		(net "XM_CS0_N")
	)
	(segment
		(start 108.790486 -60.670186)
		(end 107.787186 -60.670186)
		(width 0.1143)
		(layer "F.Cu")
		(net "XM_CS0_N")
	)
	(segment
		(start 111.4425 -61.976)
		(end 110.872524 -61.976)
		(width 0.1143)
		(layer "F.Cu")
		(net "XM_CS0_N")
	)
	(segment
		(start 107.787186 -60.670186)
		(end 107.3404 -60.2234)
		(width 0.1143)
		(layer "F.Cu")
		(net "XM_CS0_N")
	)
	(segment
		(start 109.44225 -61.32195)
		(end 108.790486 -60.670186)
		(width 0.1143)
		(layer "F.Cu")
		(net "XM_CS0_N")
	)
	(via
		(at 106.16438 -58.898536)
		(size 0.7112)
		(drill 0.3556)
		(layers "F.Cu" "B.Cu")
		(net "XM_CS0_N")
	)
	(segment
		(start 86.659466 -61.341)
		(end 86.659466 -60.325)
		(width 0.1397)
		(layer "F.Cu")
		(net "REF_CLK")
	)
	(segment
		(start 86.659466 -63.0555)
		(end 86.659466 -61.341)
		(width 0.1397)
		(layer "F.Cu")
		(net "REF_CLK")
	)
	(segment
		(start 86.621366 -63.0936)
		(end 86.659466 -63.0555)
		(width 0.1397)
		(layer "F.Cu")
		(net "REF_CLK")
	)
	(segment
		(start 265.360404 -146.568922)
		(end 265.360404 -158.680404)
		(width 0.254)
		(layer "F.Cu")
		(net "P0V9_E_PG")
	)
	(segment
		(start 256.12725 -94.35338)
		(end 256.12725 -95.753174)
		(width 0.254)
		(layer "F.Cu")
		(net "P0V9_E_PG")
	)
	(segment
		(start 169.37355 -112.22355)
		(end 168.030652 -110.880652)
		(width 0.254)
		(layer "F.Cu")
		(net "P0V9_E_PG")
	)
	(segment
		(start 184.5056 -54.3052)
		(end 183.3753 -53.1749)
		(width 0.254)
		(layer "F.Cu")
		(net "P0V9_E_PG")
	)
	(segment
		(start 269.295372 -55.698136)
		(end 267.97 -55.698136)
		(width 0.254)
		(layer "F.Cu")
		(net "P0V9_E_PG")
	)
	(segment
		(start 183.3753 -53.1749)
		(end 183.3753 -53.086)
		(width 0.254)
		(layer "F.Cu")
		(net "P0V9_E_PG")
	)
	(segment
		(start 263.25195 -122.60834)
		(end 263.25195 -144.460468)
		(width 0.254)
		(layer "F.Cu")
		(net "P0V9_E_PG")
	)
	(segment
		(start 265.360404 -158.680404)
		(end 271.272 -164.592)
		(width 0.254)
		(layer "F.Cu")
		(net "P0V9_E_PG")
	)
	(segment
		(start 262.255 -101.891338)
		(end 262.255 -121.61139)
		(width 0.254)
		(layer "F.Cu")
		(net "P0V9_E_PG")
	)
	(segment
		(start 218.5416 -58.674)
		(end 221.0308 -61.1632)
		(width 0.254)
		(layer "F.Cu")
		(net "P0V9_E_PG")
	)
	(segment
		(start 271.272 -164.592)
		(end 273.7485 -164.592)
		(width 0.254)
		(layer "F.Cu")
		(net "P0V9_E_PG")
	)
	(segment
		(start 262.255 -121.61139)
		(end 263.25195 -122.60834)
		(width 0.254)
		(layer "F.Cu")
		(net "P0V9_E_PG")
	)
	(segment
		(start 169.432224 -113.492534)
		(end 169.432224 -112.488472)
		(width 0.254)
		(layer "F.Cu")
		(net "P0V9_E_PG")
	)
	(segment
		(start 222.93707 -61.1632)
		(end 256.12725 -94.35338)
		(width 0.254)
		(layer "F.Cu")
		(net "P0V9_E_PG")
	)
	(segment
		(start 169.432224 -112.488472)
		(end 169.37355 -112.429798)
		(width 0.254)
		(layer "F.Cu")
		(net "P0V9_E_PG")
	)
	(segment
		(start 263.25195 -144.460468)
		(end 265.360404 -146.568922)
		(width 0.254)
		(layer "F.Cu")
		(net "P0V9_E_PG")
	)
	(segment
		(start 168.030652 -110.880652)
		(end 167.767 -110.880652)
		(width 0.254)
		(layer "F.Cu")
		(net "P0V9_E_PG")
	)
	(segment
		(start 262.13435 -101.760274)
		(end 262.13435 -101.770688)
		(width 0.254)
		(layer "F.Cu")
		(net "P0V9_E_PG")
	)
	(segment
		(start 262.13435 -101.770688)
		(end 262.255 -101.891338)
		(width 0.254)
		(layer "F.Cu")
		(net "P0V9_E_PG")
	)
	(segment
		(start 256.12725 -95.753174)
		(end 262.13435 -101.760274)
		(width 0.254)
		(layer "F.Cu")
		(net "P0V9_E_PG")
	)
	(segment
		(start 166.678356 -109.864652)
		(end 166.678356 -110.880652)
		(width 0.254)
		(layer "F.Cu")
		(net "P0V9_E_PG")
	)
	(segment
		(start 166.678356 -110.880652)
		(end 167.767 -110.880652)
		(width 0.254)
		(layer "F.Cu")
		(net "P0V9_E_PG")
	)
	(segment
		(start 184.9374 -54.3052)
		(end 184.5056 -54.3052)
		(width 0.254)
		(layer "F.Cu")
		(net "P0V9_E_PG")
	)
	(segment
		(start 221.0308 -61.1632)
		(end 222.93707 -61.1632)
		(width 0.254)
		(layer "F.Cu")
		(net "P0V9_E_PG")
	)
	(segment
		(start 169.37355 -112.429798)
		(end 169.37355 -112.22355)
		(width 0.254)
		(layer "F.Cu")
		(net "P0V9_E_PG")
	)
	(via
		(at 175.6156 -58.6994)
		(size 0.508)
		(drill 0.254)
		(layers "F.Cu" "B.Cu")
		(net "P0V9_E_PG")
	)
	(via
		(at 218.5416 -58.674)
		(size 0.5588)
		(drill 0.3048)
		(layers "F.Cu" "B.Cu")
		(net "P0V9_E_PG")
	)
	(via
		(at 267.97 -55.698136)
		(size 0.5588)
		(drill 0.3048)
		(layers "F.Cu" "B.Cu")
		(net "P0V9_E_PG")
	)
	(via
		(at 184.9374 -54.3052)
		(size 0.5588)
		(drill 0.3048)
		(layers "F.Cu" "B.Cu")
		(net "P0V9_E_PG")
	)
	(via
		(at 167.767 -110.880652)
		(size 0.5588)
		(drill 0.3048)
		(layers "F.Cu" "B.Cu")
		(net "P0V9_E_PG")
	)
	(via
		(at 167.5638 -109.8804)
		(size 0.7112)
		(drill 0.3556)
		(layers "F.Cu" "B.Cu")
		(net "P0V9_E_PG")
	)
	(segment
		(start 218.5416 -58.674)
		(end 224.028 -58.674)
		(width 0.254)
		(layer "B.Cu")
		(net "P0V9_E_PG")
	)
	(segment
		(start 224.917 -59.563)
		(end 263.930638 -59.563)
		(width 0.254)
		(layer "B.Cu")
		(net "P0V9_E_PG")
	)
	(segment
		(start 176.012348 -110.880652)
		(end 167.767 -110.880652)
		(width 0.254)
		(layer "B.Cu")
		(net "P0V9_E_PG")
	)
	(segment
		(start 267.839698 -55.828438)
		(end 267.97 -55.698136)
		(width 0.254)
		(layer "B.Cu")
		(net "P0V9_E_PG")
	)
	(segment
		(start 167.767 -110.880652)
		(end 167.767 -110.0836)
		(width 0.254)
		(layer "B.Cu")
		(net "P0V9_E_PG")
	)
	(segment
		(start 177.292 -83.439)
		(end 177.292 -109.601)
		(width 0.254)
		(layer "B.Cu")
		(net "P0V9_E_PG")
	)
	(segment
		(start 175.514 -79.883)
		(end 175.514 -81.661)
		(width 0.254)
		(layer "B.Cu")
		(net "P0V9_E_PG")
	)
	(segment
		(start 263.930638 -59.563)
		(end 267.6652 -55.828438)
		(width 0.254)
		(layer "B.Cu")
		(net "P0V9_E_PG")
	)
	(segment
		(start 174.625 -75.184)
		(end 174.625 -78.994)
		(width 0.254)
		(layer "B.Cu")
		(net "P0V9_E_PG")
	)
	(segment
		(start 175.6156 -58.6994)
		(end 175.514 -58.801)
		(width 0.254)
		(layer "B.Cu")
		(net "P0V9_E_PG")
	)
	(segment
		(start 166.33825 -110.4265)
		(end 166.88435 -109.8804)
		(width 0.254)
		(layer "B.Cu")
		(net "P0V9_E_PG")
	)
	(segment
		(start 177.292 -109.601)
		(end 176.012348 -110.880652)
		(width 0.254)
		(layer "B.Cu")
		(net "P0V9_E_PG")
	)
	(segment
		(start 175.514 -74.295)
		(end 174.625 -75.184)
		(width 0.254)
		(layer "B.Cu")
		(net "P0V9_E_PG")
	)
	(segment
		(start 174.625 -78.994)
		(end 175.514 -79.883)
		(width 0.254)
		(layer "B.Cu")
		(net "P0V9_E_PG")
	)
	(segment
		(start 267.6652 -55.828438)
		(end 267.839698 -55.828438)
		(width 0.254)
		(layer "B.Cu")
		(net "P0V9_E_PG")
	)
	(segment
		(start 167.767 -110.0836)
		(end 167.5638 -109.8804)
		(width 0.254)
		(layer "B.Cu")
		(net "P0V9_E_PG")
	)
	(segment
		(start 166.88435 -109.8804)
		(end 167.5638 -109.8804)
		(width 0.254)
		(layer "B.Cu")
		(net "P0V9_E_PG")
	)
	(segment
		(start 175.514 -81.661)
		(end 177.292 -83.439)
		(width 0.254)
		(layer "B.Cu")
		(net "P0V9_E_PG")
	)
	(segment
		(start 224.028 -58.674)
		(end 224.917 -59.563)
		(width 0.254)
		(layer "B.Cu")
		(net "P0V9_E_PG")
	)
	(segment
		(start 175.514 -58.801)
		(end 175.514 -74.295)
		(width 0.254)
		(layer "B.Cu")
		(net "P0V9_E_PG")
	)
	(segment
		(start 175.641 -58.674)
		(end 218.5416 -58.674)
		(width 0.254)
		(layer "In2.Cu")
		(net "P0V9_E_PG")
	)
	(segment
		(start 175.6156 -58.6994)
		(end 175.641 -58.674)
		(width 0.254)
		(layer "In2.Cu")
		(net "P0V9_E_PG")
	)
	(segment
		(start 175.6156 -58.6994)
		(end 180.0098 -54.3052)
		(width 0.254)
		(layer "In5.Cu")
		(net "P0V9_E_PG")
	)
	(segment
		(start 180.0098 -54.3052)
		(end 184.9374 -54.3052)
		(width 0.254)
		(layer "In5.Cu")
		(net "P0V9_E_PG")
	)
	(segment
		(start 79.55534 -18.86966)
		(end 82.096356 -18.86966)
		(width 0.254)
		(layer "F.Cu")
		(net "VT235_VDDH")
	)
	(via
		(at 79.121 -18.161)
		(size 0.7112)
		(drill 0.3556)
		(layers "F.Cu" "B.Cu")
		(net "VT235_VDDH")
	)
	(segment
		(start 106.299 -57.63387)
		(end 106.426 -57.76087)
		(width 0.1143)
		(layer "F.Cu")
		(net "XM_NOR_CS_N")
	)
	(segment
		(start 147.69084 -58.76036)
		(end 147.500086 -58.951114)
		(width 0.1143)
		(layer "F.Cu")
		(net "XM_NOR_CS_N")
	)
	(segment
		(start 106.750104 -56.599836)
		(end 106.299 -57.05094)
		(width 0.1143)
		(layer "F.Cu")
		(net "XM_NOR_CS_N")
	)
	(segment
		(start 147.599146 -61.9379)
		(end 147.599146 -60.46724)
		(width 0.1143)
		(layer "F.Cu")
		(net "XM_NOR_CS_N")
	)
	(segment
		(start 147.599146 -60.46724)
		(end 147.585684 -60.453778)
		(width 0.1143)
		(layer "F.Cu")
		(net "XM_NOR_CS_N")
	)
	(segment
		(start 106.299 -57.05094)
		(end 106.299 -57.63387)
		(width 0.1143)
		(layer "F.Cu")
		(net "XM_NOR_CS_N")
	)
	(segment
		(start 147.585684 -60.453778)
		(end 147.585684 -59.036712)
		(width 0.1143)
		(layer "F.Cu")
		(net "XM_NOR_CS_N")
	)
	(segment
		(start 148.68144 -58.76036)
		(end 147.69084 -58.76036)
		(width 0.1143)
		(layer "F.Cu")
		(net "XM_NOR_CS_N")
	)
	(segment
		(start 149.6568 -57.785)
		(end 148.68144 -58.76036)
		(width 0.1143)
		(layer "F.Cu")
		(net "XM_NOR_CS_N")
	)
	(segment
		(start 147.585684 -59.036712)
		(end 147.500086 -58.951114)
		(width 0.1143)
		(layer "F.Cu")
		(net "XM_NOR_CS_N")
	)
	(segment
		(start 151.5745 -57.785)
		(end 149.6568 -57.785)
		(width 0.1143)
		(layer "F.Cu")
		(net "XM_NOR_CS_N")
	)
	(via
		(at 106.426 -57.76087)
		(size 0.508)
		(drill 0.254)
		(layers "F.Cu" "B.Cu")
		(net "XM_NOR_CS_N")
	)
	(via
		(at 147.500086 -58.951114)
		(size 0.5588)
		(drill 0.3048)
		(layers "F.Cu" "B.Cu")
		(net "XM_NOR_CS_N")
	)
	(via
		(at 133.096 -61.849)
		(size 0.7112)
		(drill 0.3556)
		(layers "F.Cu" "B.Cu")
		(net "XM_NOR_CS_N")
	)
	(segment
		(start 147.585684 -60.069222)
		(end 147.500086 -59.983624)
		(width 0.1143)
		(layer "B.Cu")
		(net "XM_NOR_CS_N")
	)
	(segment
		(start 146.190208 -61.849)
		(end 147.585684 -60.453524)
		(width 0.1143)
		(layer "B.Cu")
		(net "XM_NOR_CS_N")
	)
	(segment
		(start 147.500086 -59.983624)
		(end 147.500086 -58.951114)
		(width 0.1143)
		(layer "B.Cu")
		(net "XM_NOR_CS_N")
	)
	(segment
		(start 128.112012 -61.849)
		(end 126.87808 -60.615068)
		(width 0.1143)
		(layer "B.Cu")
		(net "XM_NOR_CS_N")
	)
	(segment
		(start 133.096 -61.849)
		(end 146.190208 -61.849)
		(width 0.1143)
		(layer "B.Cu")
		(net "XM_NOR_CS_N")
	)
	(segment
		(start 109.570774 -60.615068)
		(end 106.716576 -57.76087)
		(width 0.1143)
		(layer "B.Cu")
		(net "XM_NOR_CS_N")
	)
	(segment
		(start 133.096 -61.849)
		(end 128.112012 -61.849)
		(width 0.1143)
		(layer "B.Cu")
		(net "XM_NOR_CS_N")
	)
	(segment
		(start 147.585684 -60.453524)
		(end 147.585684 -60.069222)
		(width 0.1143)
		(layer "B.Cu")
		(net "XM_NOR_CS_N")
	)
	(segment
		(start 106.716576 -57.76087)
		(end 106.426 -57.76087)
		(width 0.1143)
		(layer "B.Cu")
		(net "XM_NOR_CS_N")
	)
	(segment
		(start 126.87808 -60.615068)
		(end 109.570774 -60.615068)
		(width 0.1143)
		(layer "B.Cu")
		(net "XM_NOR_CS_N")
	)
	(segment
		(start 86.614 -27.63266)
		(end 86.614 -28.64866)
		(width 0.1397)
		(layer "F.Cu")
		(net "CLK_100M_PCIE_P")
	)
	(segment
		(start 86.614 -28.64866)
		(end 87.14867 -29.18333)
		(width 0.1397)
		(layer "F.Cu")
		(net "CLK_100M_PCIE_P")
	)
	(segment
		(start 88.138 -31.2928)
		(end 91.951048 -31.2928)
		(width 0.1397)
		(layer "F.Cu")
		(net "CLK_100M_PCIE_P")
	)
	(segment
		(start 87.2871 -29.517594)
		(end 87.2871 -30.388052)
		(width 0.1397)
		(layer "F.Cu")
		(net "CLK_100M_PCIE_P")
	)
	(segment
		(start 93.220286 -32.689038)
		(end 93.220286 -33.23082)
		(width 0.1397)
		(layer "F.Cu")
		(net "CLK_100M_PCIE_P")
	)
	(segment
		(start 92.04071 -31.329884)
		(end 93.093286 -32.38246)
		(width 0.1397)
		(layer "F.Cu")
		(net "CLK_100M_PCIE_P")
	)
	(segment
		(start 87.52586 -30.964886)
		(end 87.65286 -31.091886)
		(width 0.1397)
		(layer "F.Cu")
		(net "CLK_100M_PCIE_P")
	)
	(arc
		(start 87.2871 -30.388052)
		(mid 87.3491 -30.70022)
		(end 87.52586 -30.964886)
		(width 0.1397)
		(layer "F.Cu")
		(net "CLK_100M_PCIE_P")
	)
	(arc
		(start 93.220286 -33.23082)
		(mid 93.202073 -33.322384)
		(end 93.150182 -33.399984)
		(width 0.1397)
		(layer "F.Cu")
		(net "CLK_100M_PCIE_P")
	)
	(arc
		(start 93.093286 -32.38246)
		(mid 93.187271 -32.523119)
		(end 93.220286 -32.689038)
		(width 0.1397)
		(layer "F.Cu")
		(net "CLK_100M_PCIE_P")
	)
	(arc
		(start 91.951048 -31.2928)
		(mid 91.999566 -31.302433)
		(end 92.04071 -31.329884)
		(width 0.1397)
		(layer "F.Cu")
		(net "CLK_100M_PCIE_P")
	)
	(arc
		(start 87.14867 -29.18333)
		(mid 87.251143 -29.336692)
		(end 87.2871 -29.517594)
		(width 0.1397)
		(layer "F.Cu")
		(net "CLK_100M_PCIE_P")
	)
	(arc
		(start 87.65286 -31.091886)
		(mid 87.875458 -31.240558)
		(end 88.138 -31.2928)
		(width 0.1397)
		(layer "F.Cu")
		(net "CLK_100M_PCIE_P")
	)
	(segment
		(start 223.5835 -120.65)
		(end 222.631 -120.65)
		(width 0.254)
		(layer "F.Cu")
		(net "P1V8_C_B")
	)
	(segment
		(start 223.647 -120.7135)
		(end 223.5835 -120.65)
		(width 0.254)
		(layer "F.Cu")
		(net "P1V8_C_B")
	)
	(segment
		(start 222.631 -120.65)
		(end 221.3102 -120.65)
		(width 0.254)
		(layer "F.Cu")
		(net "P1V8_C_B")
	)
	(via
		(at 222.631 -120.65)
		(size 0.7112)
		(drill 0.3556)
		(layers "F.Cu" "B.Cu")
		(net "P1V8_C_B")
	)
	(segment
		(start 82.3468 -25.8826)
		(end 82.3595 -25.8699)
		(width 0.254)
		(layer "F.Cu")
		(net "VT235_VDES_RCC")
	)
	(segment
		(start 88.392 -19.431)
		(end 88.519 -19.558)
		(width 0.254)
		(layer "F.Cu")
		(net "VT235_VDES_RCC")
	)
	(segment
		(start 90.424 -19.558)
		(end 90.805 -19.177)
		(width 0.254)
		(layer "F.Cu")
		(net "VT235_VDES_RCC")
	)
	(segment
		(start 82.423 -24.8285)
		(end 82.3595 -24.892)
		(width 0.254)
		(layer "F.Cu")
		(net "VT235_VDES_RCC")
	)
	(segment
		(start 82.3595 -25.8699)
		(end 82.3595 -24.892)
		(width 0.254)
		(layer "F.Cu")
		(net "VT235_VDES_RCC")
	)
	(segment
		(start 88.519 -19.558)
		(end 89.662 -19.558)
		(width 0.254)
		(layer "F.Cu")
		(net "VT235_VDES_RCC")
	)
	(segment
		(start 83.439 -24.8285)
		(end 82.423 -24.8285)
		(width 0.254)
		(layer "F.Cu")
		(net "VT235_VDES_RCC")
	)
	(segment
		(start 89.662 -19.558)
		(end 90.424 -19.558)
		(width 0.254)
		(layer "F.Cu")
		(net "VT235_VDES_RCC")
	)
	(via
		(at 90.805 -19.177)
		(size 0.5588)
		(drill 0.3048)
		(layers "F.Cu" "B.Cu")
		(net "VT235_VDES_RCC")
	)
	(via
		(at 117.856 -61.849)
		(size 0.7112)
		(drill 0.3556)
		(layers "F.Cu" "B.Cu")
		(net "VT235_VDES_RCC")
	)
	(via
		(at 127.889 -38.989)
		(size 0.5588)
		(drill 0.3048)
		(layers "F.Cu" "B.Cu")
		(net "VT235_VDES_RCC")
	)
	(via
		(at 116.84 -61.849)
		(size 0.5588)
		(drill 0.3048)
		(layers "F.Cu" "B.Cu")
		(net "VT235_VDES_RCC")
	)
	(via
		(at 82.3468 -25.8826)
		(size 0.5588)
		(drill 0.3048)
		(layers "F.Cu" "B.Cu")
		(net "VT235_VDES_RCC")
	)
	(segment
		(start 115.824 -62.865)
		(end 116.84 -61.849)
		(width 0.254)
		(layer "B.Cu")
		(net "VT235_VDES_RCC")
	)
	(segment
		(start 117.856 -61.849)
		(end 116.84 -61.849)
		(width 0.254)
		(layer "B.Cu")
		(net "VT235_VDES_RCC")
	)
	(segment
		(start 109.855 -62.23)
		(end 110.49 -62.865)
		(width 0.254)
		(layer "B.Cu")
		(net "VT235_VDES_RCC")
	)
	(segment
		(start 110.49 -62.865)
		(end 115.824 -62.865)
		(width 0.254)
		(layer "B.Cu")
		(net "VT235_VDES_RCC")
	)
	(segment
		(start 109.2835 -62.23)
		(end 109.855 -62.23)
		(width 0.254)
		(layer "B.Cu")
		(net "VT235_VDES_RCC")
	)
	(segment
		(start 127.889 -38.989)
		(end 127.889 -39.751)
		(width 0.254)
		(layer "In2.Cu")
		(net "VT235_VDES_RCC")
	)
	(segment
		(start 128.651 -40.513)
		(end 128.651 -46.393862)
		(width 0.254)
		(layer "In2.Cu")
		(net "VT235_VDES_RCC")
	)
	(segment
		(start 116.713 -58.331862)
		(end 116.713 -61.722)
		(width 0.254)
		(layer "In2.Cu")
		(net "VT235_VDES_RCC")
	)
	(segment
		(start 128.651 -46.393862)
		(end 116.713 -58.331862)
		(width 0.254)
		(layer "In2.Cu")
		(net "VT235_VDES_RCC")
	)
	(segment
		(start 116.713 -61.722)
		(end 116.84 -61.849)
		(width 0.254)
		(layer "In2.Cu")
		(net "VT235_VDES_RCC")
	)
	(segment
		(start 127.889 -39.751)
		(end 128.651 -40.513)
		(width 0.254)
		(layer "In2.Cu")
		(net "VT235_VDES_RCC")
	)
	(segment
		(start 127.762 -37.973)
		(end 127.762 -38.862)
		(width 0.254)
		(layer "In5.Cu")
		(net "VT235_VDES_RCC")
	)
	(segment
		(start 126.591314 -29.543248)
		(end 126.591314 -36.802314)
		(width 0.254)
		(layer "In5.Cu")
		(net "VT235_VDES_RCC")
	)
	(segment
		(start 89.760552 -19.177)
		(end 85.725 -23.212552)
		(width 0.254)
		(layer "In5.Cu")
		(net "VT235_VDES_RCC")
	)
	(segment
		(start 83.4644 -24.765)
		(end 82.3468 -25.8826)
		(width 0.254)
		(layer "In5.Cu")
		(net "VT235_VDES_RCC")
	)
	(segment
		(start 127.762 -38.862)
		(end 127.889 -38.989)
		(width 0.254)
		(layer "In5.Cu")
		(net "VT235_VDES_RCC")
	)
	(segment
		(start 84.42071 -24.765)
		(end 83.4644 -24.765)
		(width 0.254)
		(layer "In5.Cu")
		(net "VT235_VDES_RCC")
	)
	(segment
		(start 85.725 -23.212552)
		(end 85.725 -23.46071)
		(width 0.254)
		(layer "In5.Cu")
		(net "VT235_VDES_RCC")
	)
	(segment
		(start 93.18244 -21.55444)
		(end 118.602506 -21.55444)
		(width 0.254)
		(layer "In5.Cu")
		(net "VT235_VDES_RCC")
	)
	(segment
		(start 85.725 -23.46071)
		(end 84.42071 -24.765)
		(width 0.254)
		(layer "In5.Cu")
		(net "VT235_VDES_RCC")
	)
	(segment
		(start 126.591314 -36.802314)
		(end 127.762 -37.973)
		(width 0.254)
		(layer "In5.Cu")
		(net "VT235_VDES_RCC")
	)
	(segment
		(start 118.602506 -21.55444)
		(end 126.591314 -29.543248)
		(width 0.254)
		(layer "In5.Cu")
		(net "VT235_VDES_RCC")
	)
	(segment
		(start 90.805 -19.177)
		(end 89.760552 -19.177)
		(width 0.254)
		(layer "In5.Cu")
		(net "VT235_VDES_RCC")
	)
	(segment
		(start 90.805 -19.177)
		(end 93.18244 -21.55444)
		(width 0.254)
		(layer "In5.Cu")
		(net "VT235_VDES_RCC")
	)
	(segment
		(start 118.35003 -86.34984)
		(end 118.850156 -85.849714)
		(width 0.1143)
		(layer "F.Cu")
		(net "TEST_MUX_46")
	)
	(segment
		(start 118.6942 -81.3054)
		(end 118.12397 -80.73517)
		(width 0.1143)
		(layer "F.Cu")
		(net "TEST_MUX_46")
	)
	(segment
		(start 118.12397 -80.73517)
		(end 118.12397 -79.629)
		(width 0.1143)
		(layer "F.Cu")
		(net "TEST_MUX_46")
	)
	(segment
		(start 117.221 -76.12253)
		(end 117.221 -78.72603)
		(width 0.1143)
		(layer "F.Cu")
		(net "TEST_MUX_46")
	)
	(segment
		(start 117.221 -78.72603)
		(end 118.12397 -79.629)
		(width 0.1143)
		(layer "F.Cu")
		(net "TEST_MUX_46")
	)
	(segment
		(start 116.47297 -75.3745)
		(end 117.221 -76.12253)
		(width 0.1143)
		(layer "F.Cu")
		(net "TEST_MUX_46")
	)
	(via
		(at 118.850156 -85.849714)
		(size 0.508)
		(drill 0.254)
		(layers "F.Cu" "B.Cu")
		(net "TEST_MUX_46")
	)
	(via
		(at 118.6942 -81.3054)
		(size 0.508)
		(drill 0.254)
		(layers "F.Cu" "B.Cu")
		(net "TEST_MUX_46")
	)
	(segment
		(start 119.288306 -84.521294)
		(end 119.288306 -85.031326)
		(width 0.1143)
		(layer "B.Cu")
		(net "TEST_MUX_46")
	)
	(segment
		(start 120.288304 -81.668112)
		(end 120.288304 -83.521042)
		(width 0.1143)
		(layer "B.Cu")
		(net "TEST_MUX_46")
	)
	(segment
		(start 118.850156 -85.469476)
		(end 118.850156 -85.849714)
		(width 0.1143)
		(layer "B.Cu")
		(net "TEST_MUX_46")
	)
	(segment
		(start 120.027192 -81.407)
		(end 120.288304 -81.668112)
		(width 0.1143)
		(layer "B.Cu")
		(net "TEST_MUX_46")
	)
	(segment
		(start 119.288306 -85.031326)
		(end 118.850156 -85.469476)
		(width 0.1143)
		(layer "B.Cu")
		(net "TEST_MUX_46")
	)
	(segment
		(start 119.54002 -84.269326)
		(end 119.288306 -84.521294)
		(width 0.1143)
		(layer "B.Cu")
		(net "TEST_MUX_46")
	)
	(segment
		(start 120.288304 -83.521042)
		(end 119.54002 -84.269326)
		(width 0.1143)
		(layer "B.Cu")
		(net "TEST_MUX_46")
	)
	(segment
		(start 118.6942 -81.3054)
		(end 118.7958 -81.407)
		(width 0.1143)
		(layer "B.Cu")
		(net "TEST_MUX_46")
	)
	(segment
		(start 118.7958 -81.407)
		(end 120.027192 -81.407)
		(width 0.1143)
		(layer "B.Cu")
		(net "TEST_MUX_46")
	)
	(segment
		(start 143.598646 -61.9379)
		(end 143.598646 -59.708796)
		(width 0.1143)
		(layer "F.Cu")
		(net "XM_DATA_10")
	)
	(segment
		(start 143.598646 -59.708796)
		(end 143.416274 -59.526424)
		(width 0.1143)
		(layer "F.Cu")
		(net "XM_DATA_10")
	)
	(segment
		(start 109.949996 -54.99989)
		(end 110.349792 -55.399686)
		(width 0.1143)
		(layer "F.Cu")
		(net "XM_DATA_10")
	)
	(via
		(at 114.173 -56.11495)
		(size 0.7112)
		(drill 0.3556)
		(layers "F.Cu" "B.Cu")
		(net "XM_DATA_10")
	)
	(via
		(at 110.349792 -55.399686)
		(size 0.508)
		(drill 0.254)
		(layers "F.Cu" "B.Cu")
		(net "XM_DATA_10")
	)
	(via
		(at 143.416274 -59.526424)
		(size 0.5588)
		(drill 0.3048)
		(layers "F.Cu" "B.Cu")
		(net "XM_DATA_10")
	)
	(segment
		(start 112.360456 -55.953406)
		(end 112.219486 -55.812436)
		(width 0.1143)
		(layer "B.Cu")
		(net "XM_DATA_10")
	)
	(segment
		(start 126.875032 -57.9247)
		(end 126.760732 -58.039)
		(width 0.1143)
		(layer "B.Cu")
		(net "XM_DATA_10")
	)
	(segment
		(start 112.428782 -55.953406)
		(end 112.360456 -55.953406)
		(width 0.1143)
		(layer "B.Cu")
		(net "XM_DATA_10")
	)
	(segment
		(start 127.675132 -58.039)
		(end 127.446532 -58.039)
		(width 0.1143)
		(layer "B.Cu")
		(net "XM_DATA_10")
	)
	(segment
		(start 125.960632 -57.334404)
		(end 125.960632 -57.9247)
		(width 0.1143)
		(layer "B.Cu")
		(net "XM_DATA_10")
	)
	(segment
		(start 125.960632 -57.9247)
		(end 125.846332 -58.039)
		(width 0.1143)
		(layer "B.Cu")
		(net "XM_DATA_10")
	)
	(segment
		(start 128.703832 -57.9247)
		(end 128.589532 -58.039)
		(width 0.1143)
		(layer "B.Cu")
		(net "XM_DATA_10")
	)
	(segment
		(start 126.417832 -57.334404)
		(end 126.303532 -57.220104)
		(width 0.1143)
		(layer "B.Cu")
		(net "XM_DATA_10")
	)
	(segment
		(start 127.789432 -57.334404)
		(end 127.789432 -57.9247)
		(width 0.1143)
		(layer "B.Cu")
		(net "XM_DATA_10")
	)
	(segment
		(start 143.416274 -59.526424)
		(end 143.371062 -59.481212)
		(width 0.1143)
		(layer "B.Cu")
		(net "XM_DATA_10")
	)
	(segment
		(start 129.161032 -57.334404)
		(end 129.046732 -57.220104)
		(width 0.1143)
		(layer "B.Cu")
		(net "XM_DATA_10")
	)
	(segment
		(start 129.618232 -57.9247)
		(end 129.503932 -58.039)
		(width 0.1143)
		(layer "B.Cu")
		(net "XM_DATA_10")
	)
	(segment
		(start 129.732532 -57.220104)
		(end 129.618232 -57.334404)
		(width 0.1143)
		(layer "B.Cu")
		(net "XM_DATA_10")
	)
	(segment
		(start 128.703832 -57.334404)
		(end 128.703832 -57.9247)
		(width 0.1143)
		(layer "B.Cu")
		(net "XM_DATA_10")
	)
	(segment
		(start 143.371062 -59.481212)
		(end 141.680184 -59.481212)
		(width 0.1143)
		(layer "B.Cu")
		(net "XM_DATA_10")
	)
	(segment
		(start 128.360932 -58.039)
		(end 128.246632 -57.9247)
		(width 0.1143)
		(layer "B.Cu")
		(net "XM_DATA_10")
	)
	(segment
		(start 129.961132 -57.220104)
		(end 129.732532 -57.220104)
		(width 0.1143)
		(layer "B.Cu")
		(net "XM_DATA_10")
	)
	(segment
		(start 127.789432 -57.9247)
		(end 127.675132 -58.039)
		(width 0.1143)
		(layer "B.Cu")
		(net "XM_DATA_10")
	)
	(segment
		(start 127.217932 -57.220104)
		(end 126.989332 -57.220104)
		(width 0.1143)
		(layer "B.Cu")
		(net "XM_DATA_10")
	)
	(segment
		(start 112.552226 -56.07685)
		(end 112.428782 -55.953406)
		(width 0.1143)
		(layer "B.Cu")
		(net "XM_DATA_10")
	)
	(segment
		(start 129.618232 -57.334404)
		(end 129.618232 -57.9247)
		(width 0.1143)
		(layer "B.Cu")
		(net "XM_DATA_10")
	)
	(segment
		(start 128.246632 -57.334404)
		(end 128.132332 -57.220104)
		(width 0.1143)
		(layer "B.Cu")
		(net "XM_DATA_10")
	)
	(segment
		(start 125.349 -58.039)
		(end 124.583444 -57.273444)
		(width 0.1143)
		(layer "B.Cu")
		(net "XM_DATA_10")
	)
	(segment
		(start 126.989332 -57.220104)
		(end 126.875032 -57.334404)
		(width 0.1143)
		(layer "B.Cu")
		(net "XM_DATA_10")
	)
	(segment
		(start 127.332232 -57.334404)
		(end 127.217932 -57.220104)
		(width 0.1143)
		(layer "B.Cu")
		(net "XM_DATA_10")
	)
	(segment
		(start 129.275332 -58.039)
		(end 129.161032 -57.9247)
		(width 0.1143)
		(layer "B.Cu")
		(net "XM_DATA_10")
	)
	(segment
		(start 141.680184 -59.481212)
		(end 141.579346 -59.58205)
		(width 0.1143)
		(layer "B.Cu")
		(net "XM_DATA_10")
	)
	(segment
		(start 129.046732 -57.220104)
		(end 128.818132 -57.220104)
		(width 0.1143)
		(layer "B.Cu")
		(net "XM_DATA_10")
	)
	(segment
		(start 126.532132 -58.039)
		(end 126.417832 -57.9247)
		(width 0.1143)
		(layer "B.Cu")
		(net "XM_DATA_10")
	)
	(segment
		(start 110.861602 -55.812436)
		(end 110.448852 -55.399686)
		(width 0.1143)
		(layer "B.Cu")
		(net "XM_DATA_10")
	)
	(segment
		(start 137.189972 -58.039)
		(end 130.189732 -58.039)
		(width 0.1143)
		(layer "B.Cu")
		(net "XM_DATA_10")
	)
	(segment
		(start 117.68582 -57.273444)
		(end 116.527326 -56.11495)
		(width 0.1143)
		(layer "B.Cu")
		(net "XM_DATA_10")
	)
	(segment
		(start 129.161032 -57.9247)
		(end 129.161032 -57.334404)
		(width 0.1143)
		(layer "B.Cu")
		(net "XM_DATA_10")
	)
	(segment
		(start 126.875032 -57.334404)
		(end 126.875032 -57.9247)
		(width 0.1143)
		(layer "B.Cu")
		(net "XM_DATA_10")
	)
	(segment
		(start 130.075432 -57.334404)
		(end 129.961132 -57.220104)
		(width 0.1143)
		(layer "B.Cu")
		(net "XM_DATA_10")
	)
	(segment
		(start 128.132332 -57.220104)
		(end 127.903732 -57.220104)
		(width 0.1143)
		(layer "B.Cu")
		(net "XM_DATA_10")
	)
	(segment
		(start 127.903732 -57.220104)
		(end 127.789432 -57.334404)
		(width 0.1143)
		(layer "B.Cu")
		(net "XM_DATA_10")
	)
	(segment
		(start 128.589532 -58.039)
		(end 128.360932 -58.039)
		(width 0.1143)
		(layer "B.Cu")
		(net "XM_DATA_10")
	)
	(segment
		(start 129.503932 -58.039)
		(end 129.275332 -58.039)
		(width 0.1143)
		(layer "B.Cu")
		(net "XM_DATA_10")
	)
	(segment
		(start 141.579346 -59.58205)
		(end 138.733022 -59.58205)
		(width 0.1143)
		(layer "B.Cu")
		(net "XM_DATA_10")
	)
	(segment
		(start 130.075432 -57.9247)
		(end 130.075432 -57.334404)
		(width 0.1143)
		(layer "B.Cu")
		(net "XM_DATA_10")
	)
	(segment
		(start 113.264188 -56.07685)
		(end 112.552226 -56.07685)
		(width 0.1143)
		(layer "B.Cu")
		(net "XM_DATA_10")
	)
	(segment
		(start 138.733022 -59.58205)
		(end 137.189972 -58.039)
		(width 0.1143)
		(layer "B.Cu")
		(net "XM_DATA_10")
	)
	(segment
		(start 127.446532 -58.039)
		(end 127.332232 -57.9247)
		(width 0.1143)
		(layer "B.Cu")
		(net "XM_DATA_10")
	)
	(segment
		(start 125.846332 -58.039)
		(end 125.349 -58.039)
		(width 0.1143)
		(layer "B.Cu")
		(net "XM_DATA_10")
	)
	(segment
		(start 126.760732 -58.039)
		(end 126.532132 -58.039)
		(width 0.1143)
		(layer "B.Cu")
		(net "XM_DATA_10")
	)
	(segment
		(start 124.583444 -57.273444)
		(end 117.68582 -57.273444)
		(width 0.1143)
		(layer "B.Cu")
		(net "XM_DATA_10")
	)
	(segment
		(start 128.818132 -57.220104)
		(end 128.703832 -57.334404)
		(width 0.1143)
		(layer "B.Cu")
		(net "XM_DATA_10")
	)
	(segment
		(start 116.527326 -56.11495)
		(end 114.173 -56.11495)
		(width 0.1143)
		(layer "B.Cu")
		(net "XM_DATA_10")
	)
	(segment
		(start 126.417832 -57.9247)
		(end 126.417832 -57.334404)
		(width 0.1143)
		(layer "B.Cu")
		(net "XM_DATA_10")
	)
	(segment
		(start 130.189732 -58.039)
		(end 130.075432 -57.9247)
		(width 0.1143)
		(layer "B.Cu")
		(net "XM_DATA_10")
	)
	(segment
		(start 114.173 -56.11495)
		(end 113.302288 -56.11495)
		(width 0.1143)
		(layer "B.Cu")
		(net "XM_DATA_10")
	)
	(segment
		(start 127.332232 -57.9247)
		(end 127.332232 -57.334404)
		(width 0.1143)
		(layer "B.Cu")
		(net "XM_DATA_10")
	)
	(segment
		(start 126.303532 -57.220104)
		(end 126.074932 -57.220104)
		(width 0.1143)
		(layer "B.Cu")
		(net "XM_DATA_10")
	)
	(segment
		(start 113.302288 -56.11495)
		(end 113.264188 -56.07685)
		(width 0.1143)
		(layer "B.Cu")
		(net "XM_DATA_10")
	)
	(segment
		(start 126.074932 -57.220104)
		(end 125.960632 -57.334404)
		(width 0.1143)
		(layer "B.Cu")
		(net "XM_DATA_10")
	)
	(segment
		(start 110.448852 -55.399686)
		(end 110.349792 -55.399686)
		(width 0.1143)
		(layer "B.Cu")
		(net "XM_DATA_10")
	)
	(segment
		(start 112.219486 -55.812436)
		(end 110.861602 -55.812436)
		(width 0.1143)
		(layer "B.Cu")
		(net "XM_DATA_10")
	)
	(segment
		(start 128.246632 -57.9247)
		(end 128.246632 -57.334404)
		(width 0.1143)
		(layer "B.Cu")
		(net "XM_DATA_10")
	)
	(segment
		(start 91.028012 -35.556952)
		(end 91.17965 -35.70859)
		(width 0.1016)
		(layer "F.Cu")
		(net "SAS3008_RAID_TX_C_N1")
	)
	(segment
		(start 87.630762 -34.915856)
		(end 88.01735 -35.302444)
		(width 0.1016)
		(layer "F.Cu")
		(net "SAS3008_RAID_TX_C_N1")
	)
	(segment
		(start 87.538306 -34.844482)
		(end 87.540592 -34.846006)
		(width 0.1016)
		(layer "F.Cu")
		(net "SAS3008_RAID_TX_C_N1")
	)
	(segment
		(start 87.542116 -34.847276)
		(end 87.553038 -34.855404)
		(width 0.1016)
		(layer "F.Cu")
		(net "SAS3008_RAID_TX_C_N1")
	)
	(segment
		(start 90.724736 -35.433)
		(end 90.726006 -35.43173)
		(width 0.1016)
		(layer "F.Cu")
		(net "SAS3008_RAID_TX_C_N1")
	)
	(segment
		(start 87.564468 -34.86404)
		(end 87.617554 -34.904426)
		(width 0.1016)
		(layer "F.Cu")
		(net "SAS3008_RAID_TX_C_N1")
	)
	(segment
		(start 87.540592 -34.846006)
		(end 87.542116 -34.847276)
		(width 0.1016)
		(layer "F.Cu")
		(net "SAS3008_RAID_TX_C_N1")
	)
	(segment
		(start 91.400376 -35.80003)
		(end 91.549982 -35.80003)
		(width 0.1016)
		(layer "F.Cu")
		(net "SAS3008_RAID_TX_C_N1")
	)
	(segment
		(start 86.77656 -34.671)
		(end 87.11946 -34.671)
		(width 0.1016)
		(layer "F.Cu")
		(net "SAS3008_RAID_TX_C_N1")
	)
	(segment
		(start 88.329516 -35.43173)
		(end 90.688922 -35.43173)
		(width 0.1016)
		(layer "F.Cu")
		(net "SAS3008_RAID_TX_C_N1")
	)
	(segment
		(start 87.553038 -34.855404)
		(end 87.564468 -34.86404)
		(width 0.1016)
		(layer "F.Cu")
		(net "SAS3008_RAID_TX_C_N1")
	)
	(arc
		(start 87.11946 -34.671)
		(mid 87.287533 -34.695421)
		(end 87.441786 -34.766504)
		(width 0.1016)
		(layer "F.Cu")
		(net "SAS3008_RAID_TX_C_N1")
	)
	(arc
		(start 87.617554 -34.904426)
		(mid 87.624361 -34.909907)
		(end 87.630762 -34.915856)
		(width 0.1016)
		(layer "F.Cu")
		(net "SAS3008_RAID_TX_C_N1")
	)
	(arc
		(start 90.724736 -35.43173)
		(mid 90.724744 -35.432365)
		(end 90.724736 -35.433)
		(width 0.1016)
		(layer "F.Cu")
		(net "SAS3008_RAID_TX_C_N1")
	)
	(arc
		(start 90.688922 -35.43173)
		(mid 90.706829 -35.431352)
		(end 90.724736 -35.43173)
		(width 0.1016)
		(layer "F.Cu")
		(net "SAS3008_RAID_TX_C_N1")
	)
	(arc
		(start 91.17965 -35.70859)
		(mid 91.28092 -35.776256)
		(end 91.400376 -35.80003)
		(width 0.1016)
		(layer "F.Cu")
		(net "SAS3008_RAID_TX_C_N1")
	)
	(arc
		(start 88.01735 -35.302444)
		(mid 88.160573 -35.398143)
		(end 88.329516 -35.43173)
		(width 0.1016)
		(layer "F.Cu")
		(net "SAS3008_RAID_TX_C_N1")
	)
	(arc
		(start 87.441786 -34.766504)
		(mid 87.492095 -34.802957)
		(end 87.538306 -34.844482)
		(width 0.1016)
		(layer "F.Cu")
		(net "SAS3008_RAID_TX_C_N1")
	)
	(arc
		(start 90.726006 -35.43173)
		(mid 90.889445 -35.464334)
		(end 91.028012 -35.556952)
		(width 0.1016)
		(layer "F.Cu")
		(net "SAS3008_RAID_TX_C_N1")
	)
	(segment
		(start 76.327 -22.2885)
		(end 75.184 -22.2885)
		(width 0.254)
		(layer "F.Cu")
		(net "VT235_EN")
	)
	(segment
		(start 81.534254 -21.716746)
		(end 81.153 -22.098)
		(width 0.254)
		(layer "F.Cu")
		(net "VT235_EN")
	)
	(segment
		(start 80.01 -22.606)
		(end 79.8195 -22.4155)
		(width 0.254)
		(layer "F.Cu")
		(net "VT235_EN")
	)
	(segment
		(start 76.327 -22.2885)
		(end 77.47 -22.2885)
		(width 0.254)
		(layer "F.Cu")
		(net "VT235_EN")
	)
	(segment
		(start 80.518 -22.098)
		(end 80.01 -22.606)
		(width 0.254)
		(layer "F.Cu")
		(net "VT235_EN")
	)
	(segment
		(start 78.613 -22.4155)
		(end 77.47 -22.2885)
		(width 0.254)
		(layer "F.Cu")
		(net "VT235_EN")
	)
	(segment
		(start 81.153 -22.098)
		(end 80.518 -22.098)
		(width 0.254)
		(layer "F.Cu")
		(net "VT235_EN")
	)
	(segment
		(start 79.8195 -22.4155)
		(end 78.613 -22.4155)
		(width 0.254)
		(layer "F.Cu")
		(net "VT235_EN")
	)
	(segment
		(start 81.534254 -21.255228)
		(end 81.534254 -21.716746)
		(width 0.254)
		(layer "F.Cu")
		(net "VT235_EN")
	)
	(via
		(at 80.01 -22.606)
		(size 0.7112)
		(drill 0.3556)
		(layers "F.Cu" "B.Cu")
		(net "VT235_EN")
	)
	(segment
		(start 104.349804 -84.349844)
		(end 103.849678 -83.849718)
		(width 0.1143)
		(layer "F.Cu")
		(net "SOFT_RESET_N")
	)
	(via
		(at 103.849678 -83.849718)
		(size 0.508)
		(drill 0.254)
		(layers "F.Cu" "B.Cu")
		(net "SOFT_RESET_N")
	)
	(via
		(at 104.22382 -82.931)
		(size 0.7112)
		(drill 0.3556)
		(layers "F.Cu" "B.Cu")
		(net "SOFT_RESET_N")
	)
	(segment
		(start 103.26497 -83.26501)
		(end 103.26497 -82.9945)
		(width 0.1143)
		(layer "B.Cu")
		(net "SOFT_RESET_N")
	)
	(segment
		(start 103.849678 -83.849718)
		(end 103.26497 -83.26501)
		(width 0.1143)
		(layer "B.Cu")
		(net "SOFT_RESET_N")
	)
	(segment
		(start 103.32847 -82.931)
		(end 104.22382 -82.931)
		(width 0.1143)
		(layer "B.Cu")
		(net "SOFT_RESET_N")
	)
	(segment
		(start 103.26497 -82.9945)
		(end 103.32847 -82.931)
		(width 0.1143)
		(layer "B.Cu")
		(net "SOFT_RESET_N")
	)
	(segment
		(start 136.4615 -39.3065)
		(end 136.099296 -39.668704)
		(width 0.1143)
		(layer "F.Cu")
		(net "XM_ADDR_23")
	)
	(segment
		(start 136.099296 -42.7101)
		(end 136.099296 -44.323)
		(width 0.1143)
		(layer "F.Cu")
		(net "XM_ADDR_23")
	)
	(segment
		(start 136.525 -39.3065)
		(end 138.176 -39.3065)
		(width 0.1143)
		(layer "F.Cu")
		(net "XM_ADDR_23")
	)
	(segment
		(start 133.096 -44.323)
		(end 133.096 -43.815)
		(width 0.1143)
		(layer "F.Cu")
		(net "XM_ADDR_23")
	)
	(segment
		(start 136.525 -39.3065)
		(end 136.4615 -39.3065)
		(width 0.1143)
		(layer "F.Cu")
		(net "XM_ADDR_23")
	)
	(segment
		(start 115.564666 -48.9331)
		(end 115.602766 -48.9712)
		(width 0.1143)
		(layer "F.Cu")
		(net "XM_ADDR_23")
	)
	(segment
		(start 133.223 -43.688)
		(end 134.239 -43.688)
		(width 0.1143)
		(layer "F.Cu")
		(net "XM_ADDR_23")
	)
	(segment
		(start 114.71783 -48.9331)
		(end 115.564666 -48.9331)
		(width 0.1143)
		(layer "F.Cu")
		(net "XM_ADDR_23")
	)
	(segment
		(start 136.099296 -39.668704)
		(end 136.099296 -42.7101)
		(width 0.1143)
		(layer "F.Cu")
		(net "XM_ADDR_23")
	)
	(segment
		(start 113.464848 -49.399952)
		(end 113.807748 -49.057052)
		(width 0.1143)
		(layer "F.Cu")
		(net "XM_ADDR_23")
	)
	(segment
		(start 114.593878 -49.057052)
		(end 114.71783 -48.9331)
		(width 0.1143)
		(layer "F.Cu")
		(net "XM_ADDR_23")
	)
	(segment
		(start 113.150142 -49.399952)
		(end 113.464848 -49.399952)
		(width 0.1143)
		(layer "F.Cu")
		(net "XM_ADDR_23")
	)
	(segment
		(start 135.972296 -44.45)
		(end 133.223 -44.45)
		(width 0.1143)
		(layer "F.Cu")
		(net "XM_ADDR_23")
	)
	(segment
		(start 133.223 -44.45)
		(end 133.096 -44.323)
		(width 0.1143)
		(layer "F.Cu")
		(net "XM_ADDR_23")
	)
	(segment
		(start 115.602766 -48.9712)
		(end 115.805966 -48.9712)
		(width 0.1143)
		(layer "F.Cu")
		(net "XM_ADDR_23")
	)
	(segment
		(start 133.096 -43.815)
		(end 133.223 -43.688)
		(width 0.1143)
		(layer "F.Cu")
		(net "XM_ADDR_23")
	)
	(segment
		(start 113.807748 -49.057052)
		(end 114.593878 -49.057052)
		(width 0.1143)
		(layer "F.Cu")
		(net "XM_ADDR_23")
	)
	(segment
		(start 136.099296 -44.323)
		(end 135.972296 -44.45)
		(width 0.1143)
		(layer "F.Cu")
		(net "XM_ADDR_23")
	)
	(via
		(at 115.805966 -48.9712)
		(size 0.508)
		(drill 0.254)
		(layers "F.Cu" "B.Cu")
		(net "XM_ADDR_23")
	)
	(via
		(at 136.525 -39.3065)
		(size 0.7112)
		(drill 0.3556)
		(layers "F.Cu" "B.Cu")
		(net "XM_ADDR_23")
	)
	(via
		(at 134.239 -43.688)
		(size 0.5588)
		(drill 0.3048)
		(layers "F.Cu" "B.Cu")
		(net "XM_ADDR_23")
	)
	(segment
		(start 120.959372 -45.842682)
		(end 120.595136 -45.842682)
		(width 0.127)
		(layer "In5.Cu")
		(net "XM_ADDR_23")
	)
	(segment
		(start 126.62408 -44.704)
		(end 124.003816 -44.704)
		(width 0.127)
		(layer "In5.Cu")
		(net "XM_ADDR_23")
	)
	(segment
		(start 127.628142 -44.196)
		(end 131.517136 -44.196)
		(width 0.127)
		(layer "In5.Cu")
		(net "XM_ADDR_23")
	)
	(segment
		(start 124.003816 -44.704)
		(end 123.876816 -44.577)
		(width 0.127)
		(layer "In5.Cu")
		(net "XM_ADDR_23")
	)
	(segment
		(start 124.511816 -44.196)
		(end 126.62408 -44.196)
		(width 0.127)
		(layer "In5.Cu")
		(net "XM_ADDR_23")
	)
	(segment
		(start 132.152136 -43.234864)
		(end 132.152136 -44.577)
		(width 0.127)
		(layer "In5.Cu")
		(net "XM_ADDR_23")
	)
	(segment
		(start 115.289076 -47.830994)
		(end 115.162076 -47.957994)
		(width 0.127)
		(layer "In5.Cu")
		(net "XM_ADDR_23")
	)
	(segment
		(start 131.517136 -43.688)
		(end 124.511816 -43.688)
		(width 0.127)
		(layer "In5.Cu")
		(net "XM_ADDR_23")
	)
	(segment
		(start 121.275602 -45.347128)
		(end 121.275602 -45.526452)
		(width 0.127)
		(layer "In5.Cu")
		(net "XM_ADDR_23")
	)
	(segment
		(start 134.239 -42.926)
		(end 134.112 -42.799)
		(width 0.127)
		(layer "In5.Cu")
		(net "XM_ADDR_23")
	)
	(segment
		(start 124.384816 -44.069)
		(end 124.511816 -44.196)
		(width 0.127)
		(layer "In5.Cu")
		(net "XM_ADDR_23")
	)
	(segment
		(start 124.511816 -43.688)
		(end 124.384816 -43.815)
		(width 0.127)
		(layer "In5.Cu")
		(net "XM_ADDR_23")
	)
	(segment
		(start 134.112 -42.799)
		(end 132.588 -42.799)
		(width 0.127)
		(layer "In5.Cu")
		(net "XM_ADDR_23")
	)
	(segment
		(start 122.307858 -45.660818)
		(end 121.53011 -44.882816)
		(width 0.127)
		(layer "In5.Cu")
		(net "XM_ADDR_23")
	)
	(segment
		(start 113.792 -46.541944)
		(end 113.665 -46.668944)
		(width 0.127)
		(layer "In5.Cu")
		(net "XM_ADDR_23")
	)
	(segment
		(start 116.865908 -46.389036)
		(end 116.713 -46.541944)
		(width 0.127)
		(layer "In5.Cu")
		(net "XM_ADDR_23")
	)
	(segment
		(start 121.350786 -44.882816)
		(end 121.170954 -45.062648)
		(width 0.127)
		(layer "In5.Cu")
		(net "XM_ADDR_23")
	)
	(segment
		(start 113.665 -46.668944)
		(end 113.665 -46.947074)
		(width 0.127)
		(layer "In5.Cu")
		(net "XM_ADDR_23")
	)
	(segment
		(start 122.659648 -44.142406)
		(end 122.301 -44.142406)
		(width 0.127)
		(layer "In5.Cu")
		(net "XM_ADDR_23")
	)
	(segment
		(start 115.805966 -48.465994)
		(end 115.805966 -48.9712)
		(width 0.127)
		(layer "In5.Cu")
		(net "XM_ADDR_23")
	)
	(segment
		(start 113.665 -46.947074)
		(end 113.792 -47.074074)
		(width 0.127)
		(layer "In5.Cu")
		(net "XM_ADDR_23")
	)
	(segment
		(start 122.793506 -45.17517)
		(end 122.793506 -45.354494)
		(width 0.127)
		(layer "In5.Cu")
		(net "XM_ADDR_23")
	)
	(segment
		(start 120.048782 -46.389036)
		(end 116.865908 -46.389036)
		(width 0.127)
		(layer "In5.Cu")
		(net "XM_ADDR_23")
	)
	(segment
		(start 126.75108 -44.577)
		(end 126.62408 -44.704)
		(width 0.127)
		(layer "In5.Cu")
		(net "XM_ADDR_23")
	)
	(segment
		(start 120.595136 -45.842682)
		(end 120.048782 -46.389036)
		(width 0.127)
		(layer "In5.Cu")
		(net "XM_ADDR_23")
	)
	(segment
		(start 123.114054 -43.688)
		(end 122.659648 -44.142406)
		(width 0.127)
		(layer "In5.Cu")
		(net "XM_ADDR_23")
	)
	(segment
		(start 115.678966 -47.830994)
		(end 115.289076 -47.830994)
		(width 0.127)
		(layer "In5.Cu")
		(net "XM_ADDR_23")
	)
	(segment
		(start 127.501142 -44.323)
		(end 127.628142 -44.196)
		(width 0.127)
		(layer "In5.Cu")
		(net "XM_ADDR_23")
	)
	(segment
		(start 134.239 -43.688)
		(end 134.239 -42.926)
		(width 0.127)
		(layer "In5.Cu")
		(net "XM_ADDR_23")
	)
	(segment
		(start 127.628142 -44.704)
		(end 127.501142 -44.577)
		(width 0.127)
		(layer "In5.Cu")
		(net "XM_ADDR_23")
	)
	(segment
		(start 115.678966 -48.338994)
		(end 115.805966 -48.465994)
		(width 0.127)
		(layer "In5.Cu")
		(net "XM_ADDR_23")
	)
	(segment
		(start 115.805966 -47.201074)
		(end 115.805966 -47.703994)
		(width 0.127)
		(layer "In5.Cu")
		(net "XM_ADDR_23")
	)
	(segment
		(start 127.501142 -44.577)
		(end 127.501142 -44.323)
		(width 0.127)
		(layer "In5.Cu")
		(net "XM_ADDR_23")
	)
	(segment
		(start 132.025136 -44.704)
		(end 127.628142 -44.704)
		(width 0.127)
		(layer "In5.Cu")
		(net "XM_ADDR_23")
	)
	(segment
		(start 123.876816 -44.577)
		(end 123.876816 -43.815)
		(width 0.127)
		(layer "In5.Cu")
		(net "XM_ADDR_23")
	)
	(segment
		(start 126.62408 -44.196)
		(end 126.75108 -44.323)
		(width 0.127)
		(layer "In5.Cu")
		(net "XM_ADDR_23")
	)
	(segment
		(start 131.644136 -43.815)
		(end 131.517136 -43.688)
		(width 0.127)
		(layer "In5.Cu")
		(net "XM_ADDR_23")
	)
	(segment
		(start 132.588 -42.799)
		(end 132.152136 -43.234864)
		(width 0.127)
		(layer "In5.Cu")
		(net "XM_ADDR_23")
	)
	(segment
		(start 121.53011 -44.882816)
		(end 121.350786 -44.882816)
		(width 0.127)
		(layer "In5.Cu")
		(net "XM_ADDR_23")
	)
	(segment
		(start 115.162076 -47.957994)
		(end 115.162076 -48.211994)
		(width 0.127)
		(layer "In5.Cu")
		(net "XM_ADDR_23")
	)
	(segment
		(start 122.487182 -45.660818)
		(end 122.307858 -45.660818)
		(width 0.127)
		(layer "In5.Cu")
		(net "XM_ADDR_23")
	)
	(segment
		(start 115.805966 -47.703994)
		(end 115.678966 -47.830994)
		(width 0.127)
		(layer "In5.Cu")
		(net "XM_ADDR_23")
	)
	(segment
		(start 122.301 -44.142406)
		(end 122.12066 -44.322746)
		(width 0.127)
		(layer "In5.Cu")
		(net "XM_ADDR_23")
	)
	(segment
		(start 115.162076 -48.211994)
		(end 115.289076 -48.338994)
		(width 0.127)
		(layer "In5.Cu")
		(net "XM_ADDR_23")
	)
	(segment
		(start 121.275602 -45.526452)
		(end 120.959372 -45.842682)
		(width 0.127)
		(layer "In5.Cu")
		(net "XM_ADDR_23")
	)
	(segment
		(start 126.75108 -44.323)
		(end 126.75108 -44.577)
		(width 0.127)
		(layer "In5.Cu")
		(net "XM_ADDR_23")
	)
	(segment
		(start 113.792 -47.074074)
		(end 115.678966 -47.074074)
		(width 0.127)
		(layer "In5.Cu")
		(net "XM_ADDR_23")
	)
	(segment
		(start 115.289076 -48.338994)
		(end 115.678966 -48.338994)
		(width 0.127)
		(layer "In5.Cu")
		(net "XM_ADDR_23")
	)
	(segment
		(start 131.517136 -44.196)
		(end 131.644136 -44.069)
		(width 0.127)
		(layer "In5.Cu")
		(net "XM_ADDR_23")
	)
	(segment
		(start 122.12066 -44.322746)
		(end 122.12066 -44.50207)
		(width 0.127)
		(layer "In5.Cu")
		(net "XM_ADDR_23")
	)
	(segment
		(start 122.12066 -44.50207)
		(end 122.793506 -45.17517)
		(width 0.127)
		(layer "In5.Cu")
		(net "XM_ADDR_23")
	)
	(segment
		(start 132.152136 -44.577)
		(end 132.025136 -44.704)
		(width 0.127)
		(layer "In5.Cu")
		(net "XM_ADDR_23")
	)
	(segment
		(start 122.793506 -45.354494)
		(end 122.487182 -45.660818)
		(width 0.127)
		(layer "In5.Cu")
		(net "XM_ADDR_23")
	)
	(segment
		(start 121.170954 -45.062648)
		(end 121.170954 -45.24248)
		(width 0.127)
		(layer "In5.Cu")
		(net "XM_ADDR_23")
	)
	(segment
		(start 116.713 -46.541944)
		(end 113.792 -46.541944)
		(width 0.127)
		(layer "In5.Cu")
		(net "XM_ADDR_23")
	)
	(segment
		(start 131.644136 -44.069)
		(end 131.644136 -43.815)
		(width 0.127)
		(layer "In5.Cu")
		(net "XM_ADDR_23")
	)
	(segment
		(start 124.384816 -43.815)
		(end 124.384816 -44.069)
		(width 0.127)
		(layer "In5.Cu")
		(net "XM_ADDR_23")
	)
	(segment
		(start 115.678966 -47.074074)
		(end 115.805966 -47.201074)
		(width 0.127)
		(layer "In5.Cu")
		(net "XM_ADDR_23")
	)
	(segment
		(start 123.876816 -43.815)
		(end 123.749816 -43.688)
		(width 0.127)
		(layer "In5.Cu")
		(net "XM_ADDR_23")
	)
	(segment
		(start 123.749816 -43.688)
		(end 123.114054 -43.688)
		(width 0.127)
		(layer "In5.Cu")
		(net "XM_ADDR_23")
	)
	(segment
		(start 121.170954 -45.24248)
		(end 121.275602 -45.347128)
		(width 0.127)
		(layer "In5.Cu")
		(net "XM_ADDR_23")
	)
	(segment
		(start 87.76843 -30.722316)
		(end 87.89543 -30.849316)
		(width 0.1397)
		(layer "F.Cu")
		(net "CLK_100M_PCIE_N")
	)
	(segment
		(start 93.563186 -32.688784)
		(end 93.563186 -32.704532)
		(width 0.1397)
		(layer "F.Cu")
		(net "CLK_100M_PCIE_N")
	)
	(segment
		(start 87.63 -29.25445)
		(end 87.63 -30.388052)
		(width 0.1397)
		(layer "F.Cu")
		(net "CLK_100M_PCIE_N")
	)
	(segment
		(start 88.138254 -30.9499)
		(end 91.951048 -30.9499)
		(width 0.1397)
		(layer "F.Cu")
		(net "CLK_100M_PCIE_N")
	)
	(segment
		(start 93.127576 -31.93161)
		(end 93.335856 -32.13989)
		(width 0.1397)
		(layer "F.Cu")
		(net "CLK_100M_PCIE_N")
	)
	(segment
		(start 88.138 -28.620466)
		(end 87.719154 -29.039566)
		(width 0.1397)
		(layer "F.Cu")
		(net "CLK_100M_PCIE_N")
	)
	(segment
		(start 92.28328 -31.08706)
		(end 93.127576 -31.93161)
		(width 0.1397)
		(layer "F.Cu")
		(net "CLK_100M_PCIE_N")
	)
	(segment
		(start 88.138 -27.604466)
		(end 88.138 -28.620466)
		(width 0.1397)
		(layer "F.Cu")
		(net "CLK_100M_PCIE_N")
	)
	(segment
		(start 93.781372 -33.231328)
		(end 93.950028 -33.399984)
		(width 0.1397)
		(layer "F.Cu")
		(net "CLK_100M_PCIE_N")
	)
	(arc
		(start 87.89543 -30.849316)
		(mid 88.006839 -30.923757)
		(end 88.138254 -30.9499)
		(width 0.1397)
		(layer "F.Cu")
		(net "CLK_100M_PCIE_N")
	)
	(arc
		(start 87.63 -30.388052)
		(mid 87.665982 -30.568944)
		(end 87.76843 -30.722316)
		(width 0.1397)
		(layer "F.Cu")
		(net "CLK_100M_PCIE_N")
	)
	(arc
		(start 87.719154 -29.039566)
		(mid 87.653196 -29.138141)
		(end 87.63 -29.25445)
		(width 0.1397)
		(layer "F.Cu")
		(net "CLK_100M_PCIE_N")
	)
	(arc
		(start 93.563186 -32.704532)
		(mid 93.619894 -32.989624)
		(end 93.781372 -33.231328)
		(width 0.1397)
		(layer "F.Cu")
		(net "CLK_100M_PCIE_N")
	)
	(arc
		(start 93.335856 -32.13989)
		(mid 93.504073 -32.391739)
		(end 93.563186 -32.688784)
		(width 0.1397)
		(layer "F.Cu")
		(net "CLK_100M_PCIE_N")
	)
	(arc
		(start 91.951048 -30.9499)
		(mid 92.130812 -30.985434)
		(end 92.28328 -31.08706)
		(width 0.1397)
		(layer "F.Cu")
		(net "CLK_100M_PCIE_N")
	)
	(segment
		(start 80.648556 -19.369532)
		(end 80.071468 -19.369532)
		(width 0.3048)
		(layer "F.Cu")
		(net "VT235_AVDD")
	)
	(segment
		(start 84.91982 -19.869658)
		(end 84.385658 -19.869658)
		(width 0.3048)
		(layer "F.Cu")
		(net "VT235_AVDD")
	)
	(segment
		(start 81.915 -19.685)
		(end 81.599532 -19.369532)
		(width 0.3048)
		(layer "F.Cu")
		(net "VT235_AVDD")
	)
	(segment
		(start 79.882492 -19.558)
		(end 79.552292 -19.8882)
		(width 0.3048)
		(layer "F.Cu")
		(net "VT235_AVDD")
	)
	(segment
		(start 79.552292 -19.8882)
		(end 78.6638 -19.8882)
		(width 0.3048)
		(layer "F.Cu")
		(net "VT235_AVDD")
	)
	(segment
		(start 81.599532 -19.369532)
		(end 80.648556 -19.369532)
		(width 0.3048)
		(layer "F.Cu")
		(net "VT235_AVDD")
	)
	(segment
		(start 84.201 -19.685)
		(end 81.915 -19.685)
		(width 0.3048)
		(layer "F.Cu")
		(net "VT235_AVDD")
	)
	(segment
		(start 79.883 -19.558)
		(end 79.882492 -19.558)
		(width 0.3048)
		(layer "F.Cu")
		(net "VT235_AVDD")
	)
	(segment
		(start 78.6638 -19.8882)
		(end 78.613 -19.939)
		(width 0.3048)
		(layer "F.Cu")
		(net "VT235_AVDD")
	)
	(segment
		(start 80.071468 -19.369532)
		(end 79.883 -19.558)
		(width 0.3048)
		(layer "F.Cu")
		(net "VT235_AVDD")
	)
	(segment
		(start 84.385658 -19.869658)
		(end 84.201 -19.685)
		(width 0.3048)
		(layer "F.Cu")
		(net "VT235_AVDD")
	)
	(via
		(at 78.613 -19.939)
		(size 0.5588)
		(drill 0.3048)
		(layers "F.Cu" "B.Cu")
		(net "VT235_AVDD")
	)
	(via
		(at 78.613 -19.05)
		(size 0.7112)
		(drill 0.3556)
		(layers "F.Cu" "B.Cu")
		(net "VT235_AVDD")
	)
	(segment
		(start 81.153 -18.034)
		(end 79.883 -18.034)
		(width 0.508)
		(layer "B.Cu")
		(net "VT235_AVDD")
	)
	(segment
		(start 79.502 -18.034)
		(end 78.613 -18.923)
		(width 0.508)
		(layer "B.Cu")
		(net "VT235_AVDD")
	)
	(segment
		(start 78.613 -19.939)
		(end 78.613 -19.05)
		(width 0.508)
		(layer "B.Cu")
		(net "VT235_AVDD")
	)
	(segment
		(start 79.883 -18.034)
		(end 79.502 -18.034)
		(width 0.508)
		(layer "B.Cu")
		(net "VT235_AVDD")
	)
	(segment
		(start 78.613 -18.923)
		(end 78.613 -19.05)
		(width 0.508)
		(layer "B.Cu")
		(net "VT235_AVDD")
	)
	(segment
		(start 106.347514 -55.3974)
		(end 106.357166 -55.3974)
		(width 0.1143)
		(layer "F.Cu")
		(net "XM_DATA_6")
	)
	(segment
		(start 139.599416 -61.9379)
		(end 139.599416 -58.958226)
		(width 0.1143)
		(layer "F.Cu")
		(net "XM_DATA_6")
	)
	(segment
		(start 139.68095 -58.876692)
		(end 139.68095 -56.0451)
		(width 0.1143)
		(layer "F.Cu")
		(net "XM_DATA_6")
	)
	(segment
		(start 139.68095 -56.0451)
		(end 138.916664 -55.280814)
		(width 0.1143)
		(layer "F.Cu")
		(net "XM_DATA_6")
	)
	(segment
		(start 105.950004 -54.99989)
		(end 106.347514 -55.3974)
		(width 0.1143)
		(layer "F.Cu")
		(net "XM_DATA_6")
	)
	(segment
		(start 139.599416 -58.958226)
		(end 139.68095 -58.876692)
		(width 0.1143)
		(layer "F.Cu")
		(net "XM_DATA_6")
	)
	(via
		(at 138.916664 -55.280814)
		(size 0.5588)
		(drill 0.3048)
		(layers "F.Cu" "B.Cu")
		(net "XM_DATA_6")
	)
	(via
		(at 106.357166 -55.3974)
		(size 0.508)
		(drill 0.254)
		(layers "F.Cu" "B.Cu")
		(net "XM_DATA_6")
	)
	(via
		(at 137.287 -53.594)
		(size 0.7112)
		(drill 0.3556)
		(layers "F.Cu" "B.Cu")
		(net "XM_DATA_6")
	)
	(segment
		(start 138.916664 -55.280814)
		(end 138.916664 -54.588664)
		(width 0.1143)
		(layer "B.Cu")
		(net "XM_DATA_6")
	)
	(segment
		(start 108.957872 -54.606698)
		(end 108.327444 -54.606698)
		(width 0.1143)
		(layer "B.Cu")
		(net "XM_DATA_6")
	)
	(segment
		(start 119.295926 -53.594)
		(end 118.608602 -52.906676)
		(width 0.1143)
		(layer "B.Cu")
		(net "XM_DATA_6")
	)
	(segment
		(start 137.287 -53.594)
		(end 136.525 -53.594)
		(width 0.1143)
		(layer "B.Cu")
		(net "XM_DATA_6")
	)
	(segment
		(start 112.916208 -54.21757)
		(end 109.347 -54.21757)
		(width 0.1143)
		(layer "B.Cu")
		(net "XM_DATA_6")
	)
	(segment
		(start 108.327444 -54.606698)
		(end 107.949492 -54.98465)
		(width 0.1143)
		(layer "B.Cu")
		(net "XM_DATA_6")
	)
	(segment
		(start 132.2451 -54.61)
		(end 131.826 -54.61)
		(width 0.1143)
		(layer "B.Cu")
		(net "XM_DATA_6")
	)
	(segment
		(start 116.09197 -52.93995)
		(end 115.897914 -52.745894)
		(width 0.1143)
		(layer "B.Cu")
		(net "XM_DATA_6")
	)
	(segment
		(start 131.826 -54.61)
		(end 130.81 -53.594)
		(width 0.1143)
		(layer "B.Cu")
		(net "XM_DATA_6")
	)
	(segment
		(start 116.434362 -52.93995)
		(end 116.09197 -52.93995)
		(width 0.1143)
		(layer "B.Cu")
		(net "XM_DATA_6")
	)
	(segment
		(start 132.9309 -54.61)
		(end 132.8166 -54.4957)
		(width 0.1143)
		(layer "B.Cu")
		(net "XM_DATA_6")
	)
	(segment
		(start 115.897914 -52.745894)
		(end 114.387884 -52.745894)
		(width 0.1143)
		(layer "B.Cu")
		(net "XM_DATA_6")
	)
	(segment
		(start 135.509 -54.61)
		(end 132.9309 -54.61)
		(width 0.1143)
		(layer "B.Cu")
		(net "XM_DATA_6")
	)
	(segment
		(start 109.347 -54.21757)
		(end 108.957872 -54.606698)
		(width 0.1143)
		(layer "B.Cu")
		(net "XM_DATA_6")
	)
	(segment
		(start 114.387884 -52.745894)
		(end 112.916208 -54.21757)
		(width 0.1143)
		(layer "B.Cu")
		(net "XM_DATA_6")
	)
	(segment
		(start 138.916664 -54.588664)
		(end 137.922 -53.594)
		(width 0.1143)
		(layer "B.Cu")
		(net "XM_DATA_6")
	)
	(segment
		(start 132.3594 -53.8353)
		(end 132.3594 -54.4957)
		(width 0.1143)
		(layer "B.Cu")
		(net "XM_DATA_6")
	)
	(segment
		(start 132.7023 -53.721)
		(end 132.4737 -53.721)
		(width 0.1143)
		(layer "B.Cu")
		(net "XM_DATA_6")
	)
	(segment
		(start 132.3594 -54.4957)
		(end 132.2451 -54.61)
		(width 0.1143)
		(layer "B.Cu")
		(net "XM_DATA_6")
	)
	(segment
		(start 132.8166 -53.8353)
		(end 132.7023 -53.721)
		(width 0.1143)
		(layer "B.Cu")
		(net "XM_DATA_6")
	)
	(segment
		(start 116.467636 -52.906676)
		(end 116.434362 -52.93995)
		(width 0.1143)
		(layer "B.Cu")
		(net "XM_DATA_6")
	)
	(segment
		(start 106.769916 -54.98465)
		(end 106.357166 -55.3974)
		(width 0.1143)
		(layer "B.Cu")
		(net "XM_DATA_6")
	)
	(segment
		(start 136.525 -53.594)
		(end 135.509 -54.61)
		(width 0.1143)
		(layer "B.Cu")
		(net "XM_DATA_6")
	)
	(segment
		(start 137.922 -53.594)
		(end 137.287 -53.594)
		(width 0.1143)
		(layer "B.Cu")
		(net "XM_DATA_6")
	)
	(segment
		(start 132.8166 -54.4957)
		(end 132.8166 -53.8353)
		(width 0.1143)
		(layer "B.Cu")
		(net "XM_DATA_6")
	)
	(segment
		(start 107.949492 -54.98465)
		(end 106.769916 -54.98465)
		(width 0.1143)
		(layer "B.Cu")
		(net "XM_DATA_6")
	)
	(segment
		(start 132.4737 -53.721)
		(end 132.3594 -53.8353)
		(width 0.1143)
		(layer "B.Cu")
		(net "XM_DATA_6")
	)
	(segment
		(start 118.608602 -52.906676)
		(end 116.467636 -52.906676)
		(width 0.1143)
		(layer "B.Cu")
		(net "XM_DATA_6")
	)
	(segment
		(start 130.81 -53.594)
		(end 119.295926 -53.594)
		(width 0.1143)
		(layer "B.Cu")
		(net "XM_DATA_6")
	)
	(segment
		(start 102.750112 -35.80003)
		(end 102.350062 -35.39998)
		(width 0.1397)
		(layer "F.Cu")
		(net "PCIE_SAS_C_CPU_RX_P6")
	)
	(via
		(at 102.350062 -35.39998)
		(size 0.508)
		(drill 0.254)
		(layers "F.Cu" "B.Cu")
		(net "PCIE_SAS_C_CPU_RX_P6")
	)
	(segment
		(start 102.77475 -32.567626)
		(end 102.77475 -33.93567)
		(width 0.1397)
		(layer "B.Cu")
		(net "PCIE_SAS_C_CPU_RX_P6")
	)
	(segment
		(start 102.749858 -33.995868)
		(end 102.724712 -34.021014)
		(width 0.1397)
		(layer "B.Cu")
		(net "PCIE_SAS_C_CPU_RX_P6")
	)
	(segment
		(start 102.350062 -34.654998)
		(end 102.350062 -35.39998)
		(width 0.1397)
		(layer "B.Cu")
		(net "PCIE_SAS_C_CPU_RX_P6")
	)
	(segment
		(start 102.724712 -34.029396)
		(end 102.527608 -34.2265)
		(width 0.1397)
		(layer "B.Cu")
		(net "PCIE_SAS_C_CPU_RX_P6")
	)
	(segment
		(start 102.724712 -34.021014)
		(end 102.724712 -34.029396)
		(width 0.1397)
		(layer "B.Cu")
		(net "PCIE_SAS_C_CPU_RX_P6")
	)
	(arc
		(start 102.774496 -33.940242)
		(mid 102.767341 -33.970349)
		(end 102.749858 -33.995868)
		(width 0.1397)
		(layer "B.Cu")
		(net "PCIE_SAS_C_CPU_RX_P6")
	)
	(arc
		(start 102.77475 -33.93567)
		(mid 102.774651 -33.937958)
		(end 102.774496 -33.940242)
		(width 0.1397)
		(layer "B.Cu")
		(net "PCIE_SAS_C_CPU_RX_P6")
	)
	(arc
		(start 102.527608 -34.2265)
		(mid 102.396193 -34.423082)
		(end 102.350062 -34.654998)
		(width 0.1397)
		(layer "B.Cu")
		(net "PCIE_SAS_C_CPU_RX_P6")
	)
	(arc
		(start 102.49916 -31.9024)
		(mid 102.703094 -32.207608)
		(end 102.77475 -32.567626)
		(width 0.1397)
		(layer "B.Cu")
		(net "PCIE_SAS_C_CPU_RX_P6")
	)
	(segment
		(start 193.8147 -118.8212)
		(end 193.802 -118.8212)
		(width 0.254)
		(layer "F.Cu")
		(net "P1V8_PG_R_1")
	)
	(segment
		(start 194.818 -119.8245)
		(end 193.8147 -118.8212)
		(width 0.254)
		(layer "F.Cu")
		(net "P1V8_PG_R_1")
	)
	(segment
		(start 192.3415 -117.221)
		(end 192.405 -117.2845)
		(width 0.254)
		(layer "F.Cu")
		(net "P1V8_PG_R_1")
	)
	(segment
		(start 192.405 -117.4242)
		(end 193.802 -118.8212)
		(width 0.254)
		(layer "F.Cu")
		(net "P1V8_PG_R_1")
	)
	(segment
		(start 192.405 -117.2845)
		(end 192.405 -117.4242)
		(width 0.254)
		(layer "F.Cu")
		(net "P1V8_PG_R_1")
	)
	(segment
		(start 194.818 -118.6815)
		(end 194.818 -119.8245)
		(width 0.254)
		(layer "F.Cu")
		(net "P1V8_PG_R_1")
	)
	(via
		(at 193.802 -118.8212)
		(size 0.7112)
		(drill 0.3556)
		(layers "F.Cu" "B.Cu")
		(net "P1V8_PG_R_1")
	)
	(segment
		(start 85.52434 -18.86966)
		(end 85.8266 -18.5674)
		(width 0.3048)
		(layer "F.Cu")
		(net "VT235_BST")
	)
	(segment
		(start 85.979 -18.415)
		(end 86.868 -18.415)
		(width 0.508)
		(layer "F.Cu")
		(net "VT235_BST")
	)
	(segment
		(start 85.8266 -18.5674)
		(end 85.979 -18.415)
		(width 0.508)
		(layer "F.Cu")
		(net "VT235_BST")
	)
	(segment
		(start 87.122 -19.685)
		(end 87.122 -18.669)
		(width 0.508)
		(layer "F.Cu")
		(net "VT235_BST")
	)
	(segment
		(start 86.868 -18.415)
		(end 87.122 -18.669)
		(width 0.508)
		(layer "F.Cu")
		(net "VT235_BST")
	)
	(segment
		(start 84.91982 -18.86966)
		(end 85.52434 -18.86966)
		(width 0.3048)
		(layer "F.Cu")
		(net "VT235_BST")
	)
	(via
		(at 87.122 -19.685)
		(size 0.7112)
		(drill 0.3556)
		(layers "F.Cu" "B.Cu")
		(net "VT235_BST")
	)
	(segment
		(start 119.350028 -86.34984)
		(end 119.850154 -85.849714)
		(width 0.1143)
		(layer "F.Cu")
		(net "TEST_MUX_47")
	)
	(via
		(at 119.850154 -85.849714)
		(size 0.508)
		(drill 0.254)
		(layers "F.Cu" "B.Cu")
		(net "TEST_MUX_47")
	)
	(segment
		(start 119.850154 -85.19287)
		(end 119.850154 -85.849714)
		(width 0.1143)
		(layer "B.Cu")
		(net "TEST_MUX_47")
	)
	(segment
		(start 120.973342 -84.907882)
		(end 119.90197 -84.836)
		(width 0.1143)
		(layer "B.Cu")
		(net "TEST_MUX_47")
	)
	(segment
		(start 119.90197 -84.836)
		(end 119.850154 -85.19287)
		(width 0.1143)
		(layer "B.Cu")
		(net "TEST_MUX_47")
	)
	(segment
		(start 141.87805 -46.881542)
		(end 141.87805 -47.446692)
		(width 0.1143)
		(layer "F.Cu")
		(net "XM_ADDR_20")
	)
	(segment
		(start 117.400578 -53.350414)
		(end 117.400578 -53.67528)
		(width 0.1143)
		(layer "F.Cu")
		(net "XM_ADDR_20")
	)
	(segment
		(start 116.577364 -52.5272)
		(end 117.400578 -53.350414)
		(width 0.1143)
		(layer "F.Cu")
		(net "XM_ADDR_20")
	)
	(segment
		(start 114.665506 -52.701698)
		(end 114.563652 -52.599844)
		(width 0.1143)
		(layer "F.Cu")
		(net "XM_ADDR_20")
	)
	(segment
		(start 116.261896 -53.80228)
		(end 115.161314 -52.701698)
		(width 0.1143)
		(layer "F.Cu")
		(net "XM_ADDR_20")
	)
	(segment
		(start 140.598906 -42.7101)
		(end 140.598906 -45.602398)
		(width 0.1143)
		(layer "F.Cu")
		(net "XM_ADDR_20")
	)
	(segment
		(start 117.273578 -53.80228)
		(end 116.261896 -53.80228)
		(width 0.1143)
		(layer "F.Cu")
		(net "XM_ADDR_20")
	)
	(segment
		(start 116.263166 -52.5272)
		(end 116.577364 -52.5272)
		(width 0.1143)
		(layer "F.Cu")
		(net "XM_ADDR_20")
	)
	(segment
		(start 114.563652 -52.599844)
		(end 113.949988 -52.599844)
		(width 0.1143)
		(layer "F.Cu")
		(net "XM_ADDR_20")
	)
	(segment
		(start 140.598906 -45.602398)
		(end 141.87805 -46.881542)
		(width 0.1143)
		(layer "F.Cu")
		(net "XM_ADDR_20")
	)
	(segment
		(start 117.400578 -53.67528)
		(end 117.273578 -53.80228)
		(width 0.1143)
		(layer "F.Cu")
		(net "XM_ADDR_20")
	)
	(segment
		(start 141.87805 -47.446692)
		(end 143.0274 -48.596042)
		(width 0.1143)
		(layer "F.Cu")
		(net "XM_ADDR_20")
	)
	(segment
		(start 143.0274 -48.596042)
		(end 143.0274 -49.276)
		(width 0.1143)
		(layer "F.Cu")
		(net "XM_ADDR_20")
	)
	(segment
		(start 115.161314 -52.701698)
		(end 114.665506 -52.701698)
		(width 0.1143)
		(layer "F.Cu")
		(net "XM_ADDR_20")
	)
	(via
		(at 116.263166 -52.5272)
		(size 0.508)
		(drill 0.254)
		(layers "F.Cu" "B.Cu")
		(net "XM_ADDR_20")
	)
	(via
		(at 143.0274 -49.276)
		(size 0.5588)
		(drill 0.3048)
		(layers "F.Cu" "B.Cu")
		(net "XM_ADDR_20")
	)
	(segment
		(start 143.9926 -49.7586)
		(end 143.51 -49.276)
		(width 0.1143)
		(layer "B.Cu")
		(net "XM_ADDR_20")
	)
	(segment
		(start 143.51 -49.276)
		(end 143.0274 -49.276)
		(width 0.1143)
		(layer "B.Cu")
		(net "XM_ADDR_20")
	)
	(segment
		(start 123.439428 -50.12309)
		(end 123.439428 -50.302414)
		(width 0.127)
		(layer "In5.Cu")
		(net "XM_ADDR_20")
	)
	(segment
		(start 127.122936 -47.968154)
		(end 126.868936 -47.968154)
		(width 0.127)
		(layer "In5.Cu")
		(net "XM_ADDR_20")
	)
	(segment
		(start 141.548104 -47.796704)
		(end 141.36878 -47.796704)
		(width 0.127)
		(layer "In5.Cu")
		(net "XM_ADDR_20")
	)
	(segment
		(start 128.646936 -48.796194)
		(end 128.392936 -48.796194)
		(width 0.127)
		(layer "In5.Cu")
		(net "XM_ADDR_20")
	)
	(segment
		(start 132.202936 -47.968154)
		(end 131.948936 -47.968154)
		(width 0.127)
		(layer "In5.Cu")
		(net "XM_ADDR_20")
	)
	(segment
		(start 122.181874 -51.380644)
		(end 121.875804 -51.686714)
		(width 0.127)
		(layer "In5.Cu")
		(net "XM_ADDR_20")
	)
	(segment
		(start 128.900936 -47.968154)
		(end 128.773936 -48.095154)
		(width 0.127)
		(layer "In5.Cu")
		(net "XM_ADDR_20")
	)
	(segment
		(start 124.877068 -48.864774)
		(end 125.038866 -49.026826)
		(width 0.127)
		(layer "In5.Cu")
		(net "XM_ADDR_20")
	)
	(segment
		(start 125.038866 -49.20615)
		(end 124.85878 -49.386236)
		(width 0.127)
		(layer "In5.Cu")
		(net "XM_ADDR_20")
	)
	(segment
		(start 123.601226 -50.64379)
		(end 123.42114 -50.823876)
		(width 0.127)
		(layer "In5.Cu")
		(net "XM_ADDR_20")
	)
	(segment
		(start 123.601226 -50.464466)
		(end 123.601226 -50.64379)
		(width 0.127)
		(layer "In5.Cu")
		(net "XM_ADDR_20")
	)
	(segment
		(start 122.522996 -51.542696)
		(end 122.361198 -51.380644)
		(width 0.127)
		(layer "In5.Cu")
		(net "XM_ADDR_20")
	)
	(segment
		(start 140.622274 -48.00473)
		(end 140.622274 -47.825406)
		(width 0.127)
		(layer "In5.Cu")
		(net "XM_ADDR_20")
	)
	(segment
		(start 128.773936 -48.095154)
		(end 128.773936 -48.669194)
		(width 0.127)
		(layer "In5.Cu")
		(net "XM_ADDR_20")
	)
	(segment
		(start 131.440936 -48.796194)
		(end 131.313936 -48.669194)
		(width 0.127)
		(layer "In5.Cu")
		(net "XM_ADDR_20")
	)
	(segment
		(start 124.517658 -49.224184)
		(end 124.338334 -49.224184)
		(width 0.127)
		(layer "In5.Cu")
		(net "XM_ADDR_20")
	)
	(segment
		(start 140.7033 -46.9519)
		(end 134.80923 -46.9519)
		(width 0.127)
		(layer "In5.Cu")
		(net "XM_ADDR_20")
	)
	(segment
		(start 126.614936 -48.796194)
		(end 126.360936 -48.796194)
		(width 0.127)
		(layer "In5.Cu")
		(net "XM_ADDR_20")
	)
	(segment
		(start 131.948936 -47.968154)
		(end 131.821936 -48.095154)
		(width 0.127)
		(layer "In5.Cu")
		(net "XM_ADDR_20")
	)
	(segment
		(start 123.619514 -49.943004)
		(end 123.439428 -50.12309)
		(width 0.127)
		(layer "In5.Cu")
		(net "XM_ADDR_20")
	)
	(segment
		(start 124.320046 -49.92497)
		(end 124.13996 -50.105056)
		(width 0.127)
		(layer "In5.Cu")
		(net "XM_ADDR_20")
	)
	(segment
		(start 124.85878 -49.386236)
		(end 124.679456 -49.386236)
		(width 0.127)
		(layer "In5.Cu")
		(net "XM_ADDR_20")
	)
	(segment
		(start 140.9954 -48.1711)
		(end 140.789152 -48.1711)
		(width 0.127)
		(layer "In5.Cu")
		(net "XM_ADDR_20")
	)
	(segment
		(start 126.741936 -48.669194)
		(end 126.614936 -48.796194)
		(width 0.127)
		(layer "In5.Cu")
		(net "XM_ADDR_20")
	)
	(segment
		(start 133.792976 -47.968154)
		(end 132.964936 -47.968154)
		(width 0.127)
		(layer "In5.Cu")
		(net "XM_ADDR_20")
	)
	(segment
		(start 124.877068 -48.68545)
		(end 124.877068 -48.864774)
		(width 0.127)
		(layer "In5.Cu")
		(net "XM_ADDR_20")
	)
	(segment
		(start 127.757936 -48.095154)
		(end 127.757936 -48.669194)
		(width 0.127)
		(layer "In5.Cu")
		(net "XM_ADDR_20")
	)
	(segment
		(start 125.594364 -47.968154)
		(end 124.877068 -48.68545)
		(width 0.127)
		(layer "In5.Cu")
		(net "XM_ADDR_20")
	)
	(segment
		(start 117.229128 -51.686714)
		(end 116.388642 -52.5272)
		(width 0.127)
		(layer "In5.Cu")
		(net "XM_ADDR_20")
	)
	(segment
		(start 122.882406 -51.183286)
		(end 122.882406 -51.36261)
		(width 0.127)
		(layer "In5.Cu")
		(net "XM_ADDR_20")
	)
	(segment
		(start 122.361198 -51.380644)
		(end 122.181874 -51.380644)
		(width 0.127)
		(layer "In5.Cu")
		(net "XM_ADDR_20")
	)
	(segment
		(start 123.080018 -50.661824)
		(end 122.900694 -50.661824)
		(width 0.127)
		(layer "In5.Cu")
		(net "XM_ADDR_20")
	)
	(segment
		(start 141.00937 -47.437294)
		(end 141.00937 -47.25797)
		(width 0.127)
		(layer "In5.Cu")
		(net "XM_ADDR_20")
	)
	(segment
		(start 127.757936 -48.669194)
		(end 127.630936 -48.796194)
		(width 0.127)
		(layer "In5.Cu")
		(net "XM_ADDR_20")
	)
	(segment
		(start 129.408936 -48.796194)
		(end 129.281936 -48.669194)
		(width 0.127)
		(layer "In5.Cu")
		(net "XM_ADDR_20")
	)
	(segment
		(start 130.678936 -48.796194)
		(end 130.424936 -48.796194)
		(width 0.127)
		(layer "In5.Cu")
		(net "XM_ADDR_20")
	)
	(segment
		(start 127.249936 -48.095154)
		(end 127.122936 -47.968154)
		(width 0.127)
		(layer "In5.Cu")
		(net "XM_ADDR_20")
	)
	(segment
		(start 130.932936 -47.968154)
		(end 130.805936 -48.095154)
		(width 0.127)
		(layer "In5.Cu")
		(net "XM_ADDR_20")
	)
	(segment
		(start 130.297936 -48.095154)
		(end 130.170936 -47.968154)
		(width 0.127)
		(layer "In5.Cu")
		(net "XM_ADDR_20")
	)
	(segment
		(start 124.320046 -49.745646)
		(end 124.320046 -49.92497)
		(width 0.127)
		(layer "In5.Cu")
		(net "XM_ADDR_20")
	)
	(segment
		(start 122.720608 -51.021234)
		(end 122.882406 -51.183286)
		(width 0.127)
		(layer "In5.Cu")
		(net "XM_ADDR_20")
	)
	(segment
		(start 116.388642 -52.5272)
		(end 116.263166 -52.5272)
		(width 0.127)
		(layer "In5.Cu")
		(net "XM_ADDR_20")
	)
	(segment
		(start 130.805936 -48.669194)
		(end 130.678936 -48.796194)
		(width 0.127)
		(layer "In5.Cu")
		(net "XM_ADDR_20")
	)
	(segment
		(start 124.679456 -49.386236)
		(end 124.517658 -49.224184)
		(width 0.127)
		(layer "In5.Cu")
		(net "XM_ADDR_20")
	)
	(segment
		(start 122.720608 -50.84191)
		(end 122.720608 -51.021234)
		(width 0.127)
		(layer "In5.Cu")
		(net "XM_ADDR_20")
	)
	(segment
		(start 128.138936 -47.968154)
		(end 127.884936 -47.968154)
		(width 0.127)
		(layer "In5.Cu")
		(net "XM_ADDR_20")
	)
	(segment
		(start 140.622274 -47.825406)
		(end 141.00937 -47.437294)
		(width 0.127)
		(layer "In5.Cu")
		(net "XM_ADDR_20")
	)
	(segment
		(start 127.249936 -48.669194)
		(end 127.249936 -48.095154)
		(width 0.127)
		(layer "In5.Cu")
		(net "XM_ADDR_20")
	)
	(segment
		(start 128.392936 -48.796194)
		(end 128.265936 -48.669194)
		(width 0.127)
		(layer "In5.Cu")
		(net "XM_ADDR_20")
	)
	(segment
		(start 129.916936 -47.968154)
		(end 129.789936 -48.095154)
		(width 0.127)
		(layer "In5.Cu")
		(net "XM_ADDR_20")
	)
	(segment
		(start 132.329936 -48.669194)
		(end 132.329936 -48.095154)
		(width 0.127)
		(layer "In5.Cu")
		(net "XM_ADDR_20")
	)
	(segment
		(start 123.439428 -50.302414)
		(end 123.601226 -50.464466)
		(width 0.127)
		(layer "In5.Cu")
		(net "XM_ADDR_20")
	)
	(segment
		(start 125.038866 -49.026826)
		(end 125.038866 -49.20615)
		(width 0.127)
		(layer "In5.Cu")
		(net "XM_ADDR_20")
	)
	(segment
		(start 129.154936 -47.968154)
		(end 128.900936 -47.968154)
		(width 0.127)
		(layer "In5.Cu")
		(net "XM_ADDR_20")
	)
	(segment
		(start 128.265936 -48.669194)
		(end 128.265936 -48.095154)
		(width 0.127)
		(layer "In5.Cu")
		(net "XM_ADDR_20")
	)
	(segment
		(start 126.106936 -47.968154)
		(end 125.594364 -47.968154)
		(width 0.127)
		(layer "In5.Cu")
		(net "XM_ADDR_20")
	)
	(segment
		(start 128.773936 -48.669194)
		(end 128.646936 -48.796194)
		(width 0.127)
		(layer "In5.Cu")
		(net "XM_ADDR_20")
	)
	(segment
		(start 121.875804 -51.686714)
		(end 117.229128 -51.686714)
		(width 0.127)
		(layer "In5.Cu")
		(net "XM_ADDR_20")
	)
	(segment
		(start 124.13996 -50.105056)
		(end 123.960636 -50.105056)
		(width 0.127)
		(layer "In5.Cu")
		(net "XM_ADDR_20")
	)
	(segment
		(start 134.80923 -46.9519)
		(end 133.792976 -47.968154)
		(width 0.127)
		(layer "In5.Cu")
		(net "XM_ADDR_20")
	)
	(segment
		(start 129.789936 -48.669194)
		(end 129.662936 -48.796194)
		(width 0.127)
		(layer "In5.Cu")
		(net "XM_ADDR_20")
	)
	(segment
		(start 129.662936 -48.796194)
		(end 129.408936 -48.796194)
		(width 0.127)
		(layer "In5.Cu")
		(net "XM_ADDR_20")
	)
	(segment
		(start 143.0274 -49.276)
		(end 141.548104 -47.796704)
		(width 0.127)
		(layer "In5.Cu")
		(net "XM_ADDR_20")
	)
	(segment
		(start 131.821936 -48.669194)
		(end 131.694936 -48.796194)
		(width 0.127)
		(layer "In5.Cu")
		(net "XM_ADDR_20")
	)
	(segment
		(start 141.00937 -47.25797)
		(end 140.7033 -46.9519)
		(width 0.127)
		(layer "In5.Cu")
		(net "XM_ADDR_20")
	)
	(segment
		(start 131.186936 -47.968154)
		(end 130.932936 -47.968154)
		(width 0.127)
		(layer "In5.Cu")
		(net "XM_ADDR_20")
	)
	(segment
		(start 126.233936 -48.669194)
		(end 126.233936 -48.095154)
		(width 0.127)
		(layer "In5.Cu")
		(net "XM_ADDR_20")
	)
	(segment
		(start 129.789936 -48.095154)
		(end 129.789936 -48.669194)
		(width 0.127)
		(layer "In5.Cu")
		(net "XM_ADDR_20")
	)
	(segment
		(start 132.837936 -48.669194)
		(end 132.710936 -48.796194)
		(width 0.127)
		(layer "In5.Cu")
		(net "XM_ADDR_20")
	)
	(segment
		(start 130.805936 -48.095154)
		(end 130.805936 -48.669194)
		(width 0.127)
		(layer "In5.Cu")
		(net "XM_ADDR_20")
	)
	(segment
		(start 129.281936 -48.095154)
		(end 129.154936 -47.968154)
		(width 0.127)
		(layer "In5.Cu")
		(net "XM_ADDR_20")
	)
	(segment
		(start 124.158248 -49.583594)
		(end 124.320046 -49.745646)
		(width 0.127)
		(layer "In5.Cu")
		(net "XM_ADDR_20")
	)
	(segment
		(start 132.837936 -48.095154)
		(end 132.837936 -48.669194)
		(width 0.127)
		(layer "In5.Cu")
		(net "XM_ADDR_20")
	)
	(segment
		(start 140.789152 -48.1711)
		(end 140.622274 -48.00473)
		(width 0.127)
		(layer "In5.Cu")
		(net "XM_ADDR_20")
	)
	(segment
		(start 129.281936 -48.669194)
		(end 129.281936 -48.095154)
		(width 0.127)
		(layer "In5.Cu")
		(net "XM_ADDR_20")
	)
	(segment
		(start 132.329936 -48.095154)
		(end 132.202936 -47.968154)
		(width 0.127)
		(layer "In5.Cu")
		(net "XM_ADDR_20")
	)
	(segment
		(start 128.265936 -48.095154)
		(end 128.138936 -47.968154)
		(width 0.127)
		(layer "In5.Cu")
		(net "XM_ADDR_20")
	)
	(segment
		(start 123.960636 -50.105056)
		(end 123.798838 -49.943004)
		(width 0.127)
		(layer "In5.Cu")
		(net "XM_ADDR_20")
	)
	(segment
		(start 131.313936 -48.095154)
		(end 131.186936 -47.968154)
		(width 0.127)
		(layer "In5.Cu")
		(net "XM_ADDR_20")
	)
	(segment
		(start 127.630936 -48.796194)
		(end 127.376936 -48.796194)
		(width 0.127)
		(layer "In5.Cu")
		(net "XM_ADDR_20")
	)
	(segment
		(start 130.170936 -47.968154)
		(end 129.916936 -47.968154)
		(width 0.127)
		(layer "In5.Cu")
		(net "XM_ADDR_20")
	)
	(segment
		(start 124.338334 -49.224184)
		(end 124.158248 -49.40427)
		(width 0.127)
		(layer "In5.Cu")
		(net "XM_ADDR_20")
	)
	(segment
		(start 132.710936 -48.796194)
		(end 132.456936 -48.796194)
		(width 0.127)
		(layer "In5.Cu")
		(net "XM_ADDR_20")
	)
	(segment
		(start 130.424936 -48.796194)
		(end 130.297936 -48.669194)
		(width 0.127)
		(layer "In5.Cu")
		(net "XM_ADDR_20")
	)
	(segment
		(start 122.900694 -50.661824)
		(end 122.720608 -50.84191)
		(width 0.127)
		(layer "In5.Cu")
		(net "XM_ADDR_20")
	)
	(segment
		(start 123.241816 -50.823876)
		(end 123.080018 -50.661824)
		(width 0.127)
		(layer "In5.Cu")
		(net "XM_ADDR_20")
	)
	(segment
		(start 132.456936 -48.796194)
		(end 132.329936 -48.669194)
		(width 0.127)
		(layer "In5.Cu")
		(net "XM_ADDR_20")
	)
	(segment
		(start 127.376936 -48.796194)
		(end 127.249936 -48.669194)
		(width 0.127)
		(layer "In5.Cu")
		(net "XM_ADDR_20")
	)
	(segment
		(start 127.884936 -47.968154)
		(end 127.757936 -48.095154)
		(width 0.127)
		(layer "In5.Cu")
		(net "XM_ADDR_20")
	)
	(segment
		(start 131.694936 -48.796194)
		(end 131.440936 -48.796194)
		(width 0.127)
		(layer "In5.Cu")
		(net "XM_ADDR_20")
	)
	(segment
		(start 122.882406 -51.36261)
		(end 122.70232 -51.542696)
		(width 0.127)
		(layer "In5.Cu")
		(net "XM_ADDR_20")
	)
	(segment
		(start 141.36878 -47.796704)
		(end 140.9954 -48.1711)
		(width 0.127)
		(layer "In5.Cu")
		(net "XM_ADDR_20")
	)
	(segment
		(start 126.868936 -47.968154)
		(end 126.741936 -48.095154)
		(width 0.127)
		(layer "In5.Cu")
		(net "XM_ADDR_20")
	)
	(segment
		(start 123.798838 -49.943004)
		(end 123.619514 -49.943004)
		(width 0.127)
		(layer "In5.Cu")
		(net "XM_ADDR_20")
	)
	(segment
		(start 130.297936 -48.669194)
		(end 130.297936 -48.095154)
		(width 0.127)
		(layer "In5.Cu")
		(net "XM_ADDR_20")
	)
	(segment
		(start 132.964936 -47.968154)
		(end 132.837936 -48.095154)
		(width 0.127)
		(layer "In5.Cu")
		(net "XM_ADDR_20")
	)
	(segment
		(start 131.313936 -48.669194)
		(end 131.313936 -48.095154)
		(width 0.127)
		(layer "In5.Cu")
		(net "XM_ADDR_20")
	)
	(segment
		(start 131.821936 -48.095154)
		(end 131.821936 -48.669194)
		(width 0.127)
		(layer "In5.Cu")
		(net "XM_ADDR_20")
	)
	(segment
		(start 124.158248 -49.40427)
		(end 124.158248 -49.583594)
		(width 0.127)
		(layer "In5.Cu")
		(net "XM_ADDR_20")
	)
	(segment
		(start 123.42114 -50.823876)
		(end 123.241816 -50.823876)
		(width 0.127)
		(layer "In5.Cu")
		(net "XM_ADDR_20")
	)
	(segment
		(start 126.741936 -48.095154)
		(end 126.741936 -48.669194)
		(width 0.127)
		(layer "In5.Cu")
		(net "XM_ADDR_20")
	)
	(segment
		(start 126.233936 -48.095154)
		(end 126.106936 -47.968154)
		(width 0.127)
		(layer "In5.Cu")
		(net "XM_ADDR_20")
	)
	(segment
		(start 126.360936 -48.796194)
		(end 126.233936 -48.669194)
		(width 0.127)
		(layer "In5.Cu")
		(net "XM_ADDR_20")
	)
	(segment
		(start 122.70232 -51.542696)
		(end 122.522996 -51.542696)
		(width 0.127)
		(layer "In5.Cu")
		(net "XM_ADDR_20")
	)
	(segment
		(start 102.750112 -36.599876)
		(end 102.350316 -36.20008)
		(width 0.1397)
		(layer "F.Cu")
		(net "PCIE_SAS_C_CPU_RX_N6")
	)
	(via
		(at 102.350316 -36.20008)
		(size 0.508)
		(drill 0.254)
		(layers "F.Cu" "B.Cu")
		(net "PCIE_SAS_C_CPU_RX_N6")
	)
	(segment
		(start 103.067612 -34.171636)
		(end 102.902766 -34.336482)
		(width 0.1397)
		(layer "B.Cu")
		(net "PCIE_SAS_C_CPU_RX_N6")
	)
	(segment
		(start 102.55631 -35.994086)
		(end 102.350316 -36.20008)
		(width 0.0889)
		(layer "B.Cu")
		(net "PCIE_SAS_C_CPU_RX_N6")
	)
	(segment
		(start 103.11765 -31.942278)
		(end 103.11765 -34.050732)
		(width 0.1397)
		(layer "B.Cu")
		(net "PCIE_SAS_C_CPU_RX_N6")
	)
	(segment
		(start 102.750112 -34.704782)
		(end 102.750112 -35.526472)
		(width 0.0889)
		(layer "B.Cu")
		(net "PCIE_SAS_C_CPU_RX_N6")
	)
	(arc
		(start 103.13416 -31.9024)
		(mid 103.121935 -31.920696)
		(end 103.11765 -31.942278)
		(width 0.1397)
		(layer "B.Cu")
		(net "PCIE_SAS_C_CPU_RX_N6")
	)
	(arc
		(start 102.902766 -34.336482)
		(mid 102.789805 -34.505445)
		(end 102.750112 -34.704782)
		(width 0.0889)
		(layer "B.Cu")
		(net "PCIE_SAS_C_CPU_RX_N6")
	)
	(arc
		(start 102.750112 -35.526472)
		(mid 102.699682 -35.779531)
		(end 102.55631 -35.994086)
		(width 0.0889)
		(layer "B.Cu")
		(net "PCIE_SAS_C_CPU_RX_N6")
	)
	(arc
		(start 103.11765 -34.050732)
		(mid 103.104638 -34.116149)
		(end 103.067612 -34.171636)
		(width 0.1397)
		(layer "B.Cu")
		(net "PCIE_SAS_C_CPU_RX_N6")
	)
	(segment
		(start 222.123 -112.9665)
		(end 222.25 -112.8395)
		(width 0.254)
		(layer "F.Cu")
		(net "P1V8_PG_R_2")
	)
	(segment
		(start 222.25 -112.8395)
		(end 223.393 -112.8395)
		(width 0.254)
		(layer "F.Cu")
		(net "P1V8_PG_R_2")
	)
	(segment
		(start 222.123 -114.046)
		(end 222.123 -115.3795)
		(width 0.254)
		(layer "F.Cu")
		(net "P1V8_PG_R_2")
	)
	(segment
		(start 222.123 -114.046)
		(end 222.123 -112.9665)
		(width 0.254)
		(layer "F.Cu")
		(net "P1V8_PG_R_2")
	)
	(via
		(at 222.123 -114.046)
		(size 0.7112)
		(drill 0.3556)
		(layers "F.Cu" "B.Cu")
		(net "P1V8_PG_R_2")
	)
	(segment
		(start 86.02853 -20.36953)
		(end 86.36 -20.701)
		(width 0.254)
		(layer "F.Cu")
		(net "VT235_VFB")
	)
	(segment
		(start 89.662 -20.6375)
		(end 88.4555 -20.6375)
		(width 0.254)
		(layer "F.Cu")
		(net "VT235_VFB")
	)
	(segment
		(start 90.3605 -20.6375)
		(end 89.662 -20.6375)
		(width 0.254)
		(layer "F.Cu")
		(net "VT235_VFB")
	)
	(segment
		(start 88.4555 -20.6375)
		(end 88.392 -20.701)
		(width 0.254)
		(layer "F.Cu")
		(net "VT235_VFB")
	)
	(segment
		(start 86.36 -20.701)
		(end 88.392 -20.701)
		(width 0.254)
		(layer "F.Cu")
		(net "VT235_VFB")
	)
	(segment
		(start 90.805 -20.193)
		(end 90.3605 -20.6375)
		(width 0.254)
		(layer "F.Cu")
		(net "VT235_VFB")
	)
	(segment
		(start 84.91982 -20.36953)
		(end 86.02853 -20.36953)
		(width 0.254)
		(layer "F.Cu")
		(net "VT235_VFB")
	)
	(via
		(at 90.805 -20.193)
		(size 0.5588)
		(drill 0.3048)
		(layers "F.Cu" "B.Cu")
		(net "VT235_VFB")
	)
	(via
		(at 115.824 -61.849)
		(size 0.5588)
		(drill 0.3048)
		(layers "F.Cu" "B.Cu")
		(net "VT235_VFB")
	)
	(via
		(at 126.84506 -38.989)
		(size 0.5588)
		(drill 0.3048)
		(layers "F.Cu" "B.Cu")
		(net "VT235_VFB")
	)
	(via
		(at 111.252 -62.23)
		(size 0.7112)
		(drill 0.3556)
		(layers "F.Cu" "B.Cu")
		(net "VT235_VFB")
	)
	(segment
		(start 109.2835 -61.214)
		(end 109.855 -61.214)
		(width 0.254)
		(layer "B.Cu")
		(net "VT235_VFB")
	)
	(segment
		(start 110.871 -62.23)
		(end 111.252 -62.23)
		(width 0.254)
		(layer "B.Cu")
		(net "VT235_VFB")
	)
	(segment
		(start 111.252 -62.23)
		(end 115.443 -62.23)
		(width 0.254)
		(layer "B.Cu")
		(net "VT235_VFB")
	)
	(segment
		(start 115.443 -62.23)
		(end 115.824 -61.849)
		(width 0.254)
		(layer "B.Cu")
		(net "VT235_VFB")
	)
	(segment
		(start 109.855 -61.214)
		(end 110.871 -62.23)
		(width 0.254)
		(layer "B.Cu")
		(net "VT235_VFB")
	)
	(segment
		(start 116.078 -61.595)
		(end 115.824 -61.849)
		(width 0.254)
		(layer "In2.Cu")
		(net "VT235_VFB")
	)
	(segment
		(start 126.84506 -39.72306)
		(end 128.016 -40.894)
		(width 0.254)
		(layer "In2.Cu")
		(net "VT235_VFB")
	)
	(segment
		(start 116.078 -58.068718)
		(end 116.078 -61.595)
		(width 0.254)
		(layer "In2.Cu")
		(net "VT235_VFB")
	)
	(segment
		(start 128.016 -40.894)
		(end 128.016 -46.130718)
		(width 0.254)
		(layer "In2.Cu")
		(net "VT235_VFB")
	)
	(segment
		(start 128.016 -46.130718)
		(end 116.078 -58.068718)
		(width 0.254)
		(layer "In2.Cu")
		(net "VT235_VFB")
	)
	(segment
		(start 126.84506 -38.989)
		(end 126.84506 -39.72306)
		(width 0.254)
		(layer "In2.Cu")
		(net "VT235_VFB")
	)
	(segment
		(start 125.95606 -29.806138)
		(end 125.95606 -37.065204)
		(width 0.254)
		(layer "In5.Cu")
		(net "VT235_VFB")
	)
	(segment
		(start 90.805 -20.193)
		(end 92.80144 -22.18944)
		(width 0.254)
		(layer "In5.Cu")
		(net "VT235_VFB")
	)
	(segment
		(start 126.84506 -37.954204)
		(end 126.84506 -38.989)
		(width 0.254)
		(layer "In5.Cu")
		(net "VT235_VFB")
	)
	(segment
		(start 118.339362 -22.18944)
		(end 125.95606 -29.806138)
		(width 0.254)
		(layer "In5.Cu")
		(net "VT235_VFB")
	)
	(segment
		(start 92.80144 -22.18944)
		(end 118.339362 -22.18944)
		(width 0.254)
		(layer "In5.Cu")
		(net "VT235_VFB")
	)
	(segment
		(start 125.95606 -37.065204)
		(end 126.84506 -37.954204)
		(width 0.254)
		(layer "In5.Cu")
		(net "VT235_VFB")
	)
	(segment
		(start 54.991 -180.5305)
		(end 54.991 -180.975)
		(width 0.1143)
		(layer "F.Cu")
		(net "ICE_TMS")
	)
	(segment
		(start 54.991 -180.975)
		(end 53.975 -181.991)
		(width 0.1143)
		(layer "F.Cu")
		(net "ICE_TMS")
	)
	(segment
		(start 103.349806 -102.350062)
		(end 102.84968 -102.850188)
		(width 0.1143)
		(layer "F.Cu")
		(net "ICE_TMS")
	)
	(segment
		(start 53.369972 -182.596028)
		(end 53.975 -181.991)
		(width 0.1143)
		(layer "F.Cu")
		(net "ICE_TMS")
	)
	(segment
		(start 53.369972 -185.269886)
		(end 53.369972 -182.596028)
		(width 0.1143)
		(layer "F.Cu")
		(net "ICE_TMS")
	)
	(via
		(at 102.84968 -102.850188)
		(size 0.508)
		(drill 0.254)
		(layers "F.Cu" "B.Cu")
		(net "ICE_TMS")
	)
	(via
		(at 53.975 -181.991)
		(size 0.5588)
		(drill 0.3048)
		(layers "F.Cu" "B.Cu")
		(net "ICE_TMS")
	)
	(via
		(at 92.94876 -117.9068)
		(size 0.7112)
		(drill 0.3556)
		(layers "F.Cu" "B.Cu")
		(net "ICE_TMS")
	)
	(segment
		(start 96.85147 -113.47069)
		(end 92.94876 -117.3734)
		(width 0.1143)
		(layer "B.Cu")
		(net "ICE_TMS")
	)
	(segment
		(start 83.763866 -150.011892)
		(end 67.0814 -166.694358)
		(width 0.1143)
		(layer "B.Cu")
		(net "ICE_TMS")
	)
	(segment
		(start 92.94876 -117.3734)
		(end 92.94876 -117.9068)
		(width 0.1143)
		(layer "B.Cu")
		(net "ICE_TMS")
	)
	(segment
		(start 100.41382 -105.760774)
		(end 100.234242 -105.760774)
		(width 0.1143)
		(layer "B.Cu")
		(net "ICE_TMS")
	)
	(segment
		(start 83.763866 -149.255734)
		(end 83.763866 -150.011892)
		(width 0.1143)
		(layer "B.Cu")
		(net "ICE_TMS")
	)
	(segment
		(start 91.254072 -143.891)
		(end 89.1286 -143.891)
		(width 0.1143)
		(layer "B.Cu")
		(net "ICE_TMS")
	)
	(segment
		(start 92.94876 -119.750586)
		(end 95.37192 -122.173746)
		(width 0.1143)
		(layer "B.Cu")
		(net "ICE_TMS")
	)
	(segment
		(start 96.85147 -109.143546)
		(end 96.85147 -113.47069)
		(width 0.1143)
		(layer "B.Cu")
		(net "ICE_TMS")
	)
	(segment
		(start 102.84968 -102.850188)
		(end 102.84968 -103.324914)
		(width 0.1143)
		(layer "B.Cu")
		(net "ICE_TMS")
	)
	(segment
		(start 92.94876 -117.9068)
		(end 92.94876 -119.750586)
		(width 0.1143)
		(layer "B.Cu")
		(net "ICE_TMS")
	)
	(segment
		(start 89.1286 -143.891)
		(end 83.763866 -149.255734)
		(width 0.1143)
		(layer "B.Cu")
		(net "ICE_TMS")
	)
	(segment
		(start 56.261 -181.991)
		(end 53.975 -181.991)
		(width 0.1143)
		(layer "B.Cu")
		(net "ICE_TMS")
	)
	(segment
		(start 67.0814 -166.694358)
		(end 67.0814 -171.1706)
		(width 0.1143)
		(layer "B.Cu")
		(net "ICE_TMS")
	)
	(segment
		(start 67.0814 -171.1706)
		(end 56.261 -181.991)
		(width 0.1143)
		(layer "B.Cu")
		(net "ICE_TMS")
	)
	(segment
		(start 102.84968 -103.324914)
		(end 100.41382 -105.760774)
		(width 0.1143)
		(layer "B.Cu")
		(net "ICE_TMS")
	)
	(segment
		(start 95.37192 -122.173746)
		(end 95.37192 -139.773152)
		(width 0.1143)
		(layer "B.Cu")
		(net "ICE_TMS")
	)
	(segment
		(start 95.37192 -139.773152)
		(end 91.254072 -143.891)
		(width 0.1143)
		(layer "B.Cu")
		(net "ICE_TMS")
	)
	(segment
		(start 100.234242 -105.760774)
		(end 96.85147 -109.143546)
		(width 0.1143)
		(layer "B.Cu")
		(net "ICE_TMS")
	)
	(segment
		(start 113.150142 -57.296304)
		(end 113.150142 -56.599836)
		(width 0.1143)
		(layer "F.Cu")
		(net "XM_DATA_11")
	)
	(segment
		(start 142.232634 -60.571634)
		(end 142.232634 -60.389262)
		(width 0.1143)
		(layer "F.Cu")
		(net "XM_DATA_11")
	)
	(segment
		(start 142.599156 -61.9379)
		(end 142.599156 -60.938156)
		(width 0.1143)
		(layer "F.Cu")
		(net "XM_DATA_11")
	)
	(segment
		(start 142.599156 -60.938156)
		(end 142.232634 -60.571634)
		(width 0.1143)
		(layer "F.Cu")
		(net "XM_DATA_11")
	)
	(segment
		(start 113.256568 -57.40273)
		(end 113.150142 -57.296304)
		(width 0.1143)
		(layer "F.Cu")
		(net "XM_DATA_11")
	)
	(via
		(at 142.232634 -60.389262)
		(size 0.5588)
		(drill 0.3048)
		(layers "F.Cu" "B.Cu")
		(net "XM_DATA_11")
	)
	(via
		(at 113.256568 -57.40273)
		(size 0.508)
		(drill 0.254)
		(layers "F.Cu" "B.Cu")
		(net "XM_DATA_11")
	)
	(via
		(at 114.937286 -57.647332)
		(size 0.7112)
		(drill 0.3556)
		(layers "F.Cu" "B.Cu")
		(net "XM_DATA_11")
	)
	(segment
		(start 117.752622 -58.989468)
		(end 117.524022 -58.989468)
		(width 0.1143)
		(layer "B.Cu")
		(net "XM_DATA_11")
	)
	(segment
		(start 121.790968 -58.875168)
		(end 121.676668 -58.989468)
		(width 0.1143)
		(layer "B.Cu")
		(net "XM_DATA_11")
	)
	(segment
		(start 114.937286 -57.932574)
		(end 114.937286 -57.647332)
		(width 0.1143)
		(layer "B.Cu")
		(net "XM_DATA_11")
	)
	(segment
		(start 115.202716 -58.198004)
		(end 114.937286 -57.932574)
		(width 0.1143)
		(layer "B.Cu")
		(net "XM_DATA_11")
	)
	(segment
		(start 116.609622 -58.989468)
		(end 116.495322 -58.875168)
		(width 0.1143)
		(layer "B.Cu")
		(net "XM_DATA_11")
	)
	(segment
		(start 119.238522 -58.875168)
		(end 119.238522 -58.231786)
		(width 0.1143)
		(layer "B.Cu")
		(net "XM_DATA_11")
	)
	(segment
		(start 119.581422 -58.989468)
		(end 119.352822 -58.989468)
		(width 0.1143)
		(layer "B.Cu")
		(net "XM_DATA_11")
	)
	(segment
		(start 117.524022 -58.989468)
		(end 117.409722 -58.875168)
		(width 0.1143)
		(layer "B.Cu")
		(net "XM_DATA_11")
	)
	(segment
		(start 142.232634 -60.389262)
		(end 142.133574 -60.389262)
		(width 0.1143)
		(layer "B.Cu")
		(net "XM_DATA_11")
	)
	(segment
		(start 123.619768 -58.875168)
		(end 123.505468 -58.989468)
		(width 0.1143)
		(layer "B.Cu")
		(net "XM_DATA_11")
	)
	(segment
		(start 115.202716 -58.560716)
		(end 115.202716 -58.198004)
		(width 0.1143)
		(layer "B.Cu")
		(net "XM_DATA_11")
	)
	(segment
		(start 116.495322 -58.875168)
		(end 116.495322 -58.231786)
		(width 0.1143)
		(layer "B.Cu")
		(net "XM_DATA_11")
	)
	(segment
		(start 118.324122 -58.231786)
		(end 118.209822 -58.117486)
		(width 0.1143)
		(layer "B.Cu")
		(net "XM_DATA_11")
	)
	(segment
		(start 116.152422 -58.117486)
		(end 116.038122 -58.231786)
		(width 0.1143)
		(layer "B.Cu")
		(net "XM_DATA_11")
	)
	(segment
		(start 116.952522 -58.231786)
		(end 116.952522 -58.875168)
		(width 0.1143)
		(layer "B.Cu")
		(net "XM_DATA_11")
	)
	(segment
		(start 120.267222 -58.989468)
		(end 120.152922 -58.875168)
		(width 0.1143)
		(layer "B.Cu")
		(net "XM_DATA_11")
	)
	(segment
		(start 117.866922 -58.875168)
		(end 117.752622 -58.989468)
		(width 0.1143)
		(layer "B.Cu")
		(net "XM_DATA_11")
	)
	(segment
		(start 124.076968 -58.225944)
		(end 123.962668 -58.111644)
		(width 0.1143)
		(layer "B.Cu")
		(net "XM_DATA_11")
	)
	(segment
		(start 116.381022 -58.117486)
		(end 116.152422 -58.117486)
		(width 0.1143)
		(layer "B.Cu")
		(net "XM_DATA_11")
	)
	(segment
		(start 119.352822 -58.989468)
		(end 119.238522 -58.875168)
		(width 0.1143)
		(layer "B.Cu")
		(net "XM_DATA_11")
	)
	(segment
		(start 120.152922 -58.875168)
		(end 120.152922 -58.231786)
		(width 0.1143)
		(layer "B.Cu")
		(net "XM_DATA_11")
	)
	(segment
		(start 117.295422 -58.117486)
		(end 117.066822 -58.117486)
		(width 0.1143)
		(layer "B.Cu")
		(net "XM_DATA_11")
	)
	(segment
		(start 116.038122 -58.231786)
		(end 116.038122 -58.875168)
		(width 0.1143)
		(layer "B.Cu")
		(net "XM_DATA_11")
	)
	(segment
		(start 121.905268 -58.111644)
		(end 121.790968 -58.225944)
		(width 0.1143)
		(layer "B.Cu")
		(net "XM_DATA_11")
	)
	(segment
		(start 120.038622 -58.117486)
		(end 119.810022 -58.117486)
		(width 0.1143)
		(layer "B.Cu")
		(net "XM_DATA_11")
	)
	(segment
		(start 117.409722 -58.231786)
		(end 117.295422 -58.117486)
		(width 0.1143)
		(layer "B.Cu")
		(net "XM_DATA_11")
	)
	(segment
		(start 119.238522 -58.231786)
		(end 119.124222 -58.117486)
		(width 0.1143)
		(layer "B.Cu")
		(net "XM_DATA_11")
	)
	(segment
		(start 122.248168 -58.225944)
		(end 122.133868 -58.111644)
		(width 0.1143)
		(layer "B.Cu")
		(net "XM_DATA_11")
	)
	(segment
		(start 118.209822 -58.117486)
		(end 117.981222 -58.117486)
		(width 0.1143)
		(layer "B.Cu")
		(net "XM_DATA_11")
	)
	(segment
		(start 121.676668 -58.989468)
		(end 120.267222 -58.989468)
		(width 0.1143)
		(layer "B.Cu")
		(net "XM_DATA_11")
	)
	(segment
		(start 116.952522 -58.875168)
		(end 116.838222 -58.989468)
		(width 0.1143)
		(layer "B.Cu")
		(net "XM_DATA_11")
	)
	(segment
		(start 123.162568 -58.875168)
		(end 123.162568 -58.225944)
		(width 0.1143)
		(layer "B.Cu")
		(net "XM_DATA_11")
	)
	(segment
		(start 121.790968 -58.225944)
		(end 121.790968 -58.875168)
		(width 0.1143)
		(layer "B.Cu")
		(net "XM_DATA_11")
	)
	(segment
		(start 119.810022 -58.117486)
		(end 119.695722 -58.231786)
		(width 0.1143)
		(layer "B.Cu")
		(net "XM_DATA_11")
	)
	(segment
		(start 123.505468 -58.989468)
		(end 123.276868 -58.989468)
		(width 0.1143)
		(layer "B.Cu")
		(net "XM_DATA_11")
	)
	(segment
		(start 118.781322 -58.875168)
		(end 118.667022 -58.989468)
		(width 0.1143)
		(layer "B.Cu")
		(net "XM_DATA_11")
	)
	(segment
		(start 113.613438 -57.7596)
		(end 114.176556 -57.7596)
		(width 0.1143)
		(layer "B.Cu")
		(net "XM_DATA_11")
	)
	(segment
		(start 123.734068 -58.111644)
		(end 123.619768 -58.225944)
		(width 0.1143)
		(layer "B.Cu")
		(net "XM_DATA_11")
	)
	(segment
		(start 116.838222 -58.989468)
		(end 116.609622 -58.989468)
		(width 0.1143)
		(layer "B.Cu")
		(net "XM_DATA_11")
	)
	(segment
		(start 123.048268 -58.111644)
		(end 122.819668 -58.111644)
		(width 0.1143)
		(layer "B.Cu")
		(net "XM_DATA_11")
	)
	(segment
		(start 122.362468 -58.989468)
		(end 122.248168 -58.875168)
		(width 0.1143)
		(layer "B.Cu")
		(net "XM_DATA_11")
	)
	(segment
		(start 119.695722 -58.231786)
		(end 119.695722 -58.875168)
		(width 0.1143)
		(layer "B.Cu")
		(net "XM_DATA_11")
	)
	(segment
		(start 117.066822 -58.117486)
		(end 116.952522 -58.231786)
		(width 0.1143)
		(layer "B.Cu")
		(net "XM_DATA_11")
	)
	(segment
		(start 123.162568 -58.225944)
		(end 123.048268 -58.111644)
		(width 0.1143)
		(layer "B.Cu")
		(net "XM_DATA_11")
	)
	(segment
		(start 113.256568 -57.40273)
		(end 113.613438 -57.7596)
		(width 0.1143)
		(layer "B.Cu")
		(net "XM_DATA_11")
	)
	(segment
		(start 116.038122 -58.875168)
		(end 115.923822 -58.989468)
		(width 0.1143)
		(layer "B.Cu")
		(net "XM_DATA_11")
	)
	(segment
		(start 122.705368 -58.225944)
		(end 122.705368 -58.875168)
		(width 0.1143)
		(layer "B.Cu")
		(net "XM_DATA_11")
	)
	(segment
		(start 118.895622 -58.117486)
		(end 118.781322 -58.231786)
		(width 0.1143)
		(layer "B.Cu")
		(net "XM_DATA_11")
	)
	(segment
		(start 124.191268 -58.989468)
		(end 124.076968 -58.875168)
		(width 0.1143)
		(layer "B.Cu")
		(net "XM_DATA_11")
	)
	(segment
		(start 122.591068 -58.989468)
		(end 122.362468 -58.989468)
		(width 0.1143)
		(layer "B.Cu")
		(net "XM_DATA_11")
	)
	(segment
		(start 142.133574 -60.389262)
		(end 142.102586 -60.42025)
		(width 0.1143)
		(layer "B.Cu")
		(net "XM_DATA_11")
	)
	(segment
		(start 118.324122 -58.875168)
		(end 118.324122 -58.231786)
		(width 0.1143)
		(layer "B.Cu")
		(net "XM_DATA_11")
	)
	(segment
		(start 122.819668 -58.111644)
		(end 122.705368 -58.225944)
		(width 0.1143)
		(layer "B.Cu")
		(net "XM_DATA_11")
	)
	(segment
		(start 123.962668 -58.111644)
		(end 123.734068 -58.111644)
		(width 0.1143)
		(layer "B.Cu")
		(net "XM_DATA_11")
	)
	(segment
		(start 120.152922 -58.231786)
		(end 120.038622 -58.117486)
		(width 0.1143)
		(layer "B.Cu")
		(net "XM_DATA_11")
	)
	(segment
		(start 118.781322 -58.231786)
		(end 118.781322 -58.875168)
		(width 0.1143)
		(layer "B.Cu")
		(net "XM_DATA_11")
	)
	(segment
		(start 123.619768 -58.225944)
		(end 123.619768 -58.875168)
		(width 0.1143)
		(layer "B.Cu")
		(net "XM_DATA_11")
	)
	(segment
		(start 114.288824 -57.647332)
		(end 114.937286 -57.647332)
		(width 0.1143)
		(layer "B.Cu")
		(net "XM_DATA_11")
	)
	(segment
		(start 117.409722 -58.875168)
		(end 117.409722 -58.231786)
		(width 0.1143)
		(layer "B.Cu")
		(net "XM_DATA_11")
	)
	(segment
		(start 136.954768 -58.989468)
		(end 124.191268 -58.989468)
		(width 0.1143)
		(layer "B.Cu")
		(net "XM_DATA_11")
	)
	(segment
		(start 122.705368 -58.875168)
		(end 122.591068 -58.989468)
		(width 0.1143)
		(layer "B.Cu")
		(net "XM_DATA_11")
	)
	(segment
		(start 118.438422 -58.989468)
		(end 118.324122 -58.875168)
		(width 0.1143)
		(layer "B.Cu")
		(net "XM_DATA_11")
	)
	(segment
		(start 122.133868 -58.111644)
		(end 121.905268 -58.111644)
		(width 0.1143)
		(layer "B.Cu")
		(net "XM_DATA_11")
	)
	(segment
		(start 117.981222 -58.117486)
		(end 117.866922 -58.231786)
		(width 0.1143)
		(layer "B.Cu")
		(net "XM_DATA_11")
	)
	(segment
		(start 119.695722 -58.875168)
		(end 119.581422 -58.989468)
		(width 0.1143)
		(layer "B.Cu")
		(net "XM_DATA_11")
	)
	(segment
		(start 123.276868 -58.989468)
		(end 123.162568 -58.875168)
		(width 0.1143)
		(layer "B.Cu")
		(net "XM_DATA_11")
	)
	(segment
		(start 115.631468 -58.989468)
		(end 115.202716 -58.560716)
		(width 0.1143)
		(layer "B.Cu")
		(net "XM_DATA_11")
	)
	(segment
		(start 117.866922 -58.231786)
		(end 117.866922 -58.875168)
		(width 0.1143)
		(layer "B.Cu")
		(net "XM_DATA_11")
	)
	(segment
		(start 116.495322 -58.231786)
		(end 116.381022 -58.117486)
		(width 0.1143)
		(layer "B.Cu")
		(net "XM_DATA_11")
	)
	(segment
		(start 124.076968 -58.875168)
		(end 124.076968 -58.225944)
		(width 0.1143)
		(layer "B.Cu")
		(net "XM_DATA_11")
	)
	(segment
		(start 122.248168 -58.875168)
		(end 122.248168 -58.225944)
		(width 0.1143)
		(layer "B.Cu")
		(net "XM_DATA_11")
	)
	(segment
		(start 138.38555 -60.42025)
		(end 136.954768 -58.989468)
		(width 0.1143)
		(layer "B.Cu")
		(net "XM_DATA_11")
	)
	(segment
		(start 115.923822 -58.989468)
		(end 115.631468 -58.989468)
		(width 0.1143)
		(layer "B.Cu")
		(net "XM_DATA_11")
	)
	(segment
		(start 142.102586 -60.42025)
		(end 138.38555 -60.42025)
		(width 0.1143)
		(layer "B.Cu")
		(net "XM_DATA_11")
	)
	(segment
		(start 119.124222 -58.117486)
		(end 118.895622 -58.117486)
		(width 0.1143)
		(layer "B.Cu")
		(net "XM_DATA_11")
	)
	(segment
		(start 114.176556 -57.7596)
		(end 114.288824 -57.647332)
		(width 0.1143)
		(layer "B.Cu")
		(net "XM_DATA_11")
	)
	(segment
		(start 118.667022 -58.989468)
		(end 118.438422 -58.989468)
		(width 0.1143)
		(layer "B.Cu")
		(net "XM_DATA_11")
	)
	(segment
		(start 84.538566 -66.7004)
		(end 84.690966 -66.548)
		(width 0.1143)
		(layer "F.Cu")
		(net "IOC_REF_CLK_P")
	)
	(segment
		(start 85.040216 -60.86475)
		(end 85.040216 -59.993784)
		(width 0.1143)
		(layer "F.Cu")
		(net "IOC_REF_CLK_P")
	)
	(segment
		(start 84.690966 -66.548)
		(end 84.690966 -64.77)
		(width 0.1143)
		(layer "F.Cu")
		(net "IOC_REF_CLK_P")
	)
	(segment
		(start 85.579966 -63.881)
		(end 85.579966 -61.4045)
		(width 0.1143)
		(layer "F.Cu")
		(net "IOC_REF_CLK_P")
	)
	(segment
		(start 87.611966 -48.767492)
		(end 90.179652 -46.199806)
		(width 0.1143)
		(layer "F.Cu")
		(net "IOC_REF_CLK_P")
	)
	(segment
		(start 85.579966 -61.4045)
		(end 85.516466 -61.341)
		(width 0.1143)
		(layer "F.Cu")
		(net "IOC_REF_CLK_P")
	)
	(segment
		(start 84.690966 -64.77)
		(end 85.579966 -63.881)
		(width 0.1143)
		(layer "F.Cu")
		(net "IOC_REF_CLK_P")
	)
	(segment
		(start 90.179652 -46.199806)
		(end 90.750136 -46.199806)
		(width 0.1143)
		(layer "F.Cu")
		(net "IOC_REF_CLK_P")
	)
	(segment
		(start 87.611966 -57.422034)
		(end 87.611966 -48.767492)
		(width 0.1143)
		(layer "F.Cu")
		(net "IOC_REF_CLK_P")
	)
	(segment
		(start 85.040216 -59.993784)
		(end 87.611966 -57.422034)
		(width 0.1143)
		(layer "F.Cu")
		(net "IOC_REF_CLK_P")
	)
	(segment
		(start 85.516466 -61.341)
		(end 85.040216 -60.86475)
		(width 0.1143)
		(layer "F.Cu")
		(net "IOC_REF_CLK_P")
	)
	(segment
		(start 190.427356 -119.770652)
		(end 190.427356 -120.913652)
		(width 0.127)
		(layer "F.Cu")
		(net "P3V3_STBY_R2")
	)
	(segment
		(start 190.427356 -120.913652)
		(end 190.427356 -122.678444)
		(width 0.127)
		(layer "F.Cu")
		(net "P3V3_STBY_R2")
	)
	(segment
		(start 188.985652 -119.770652)
		(end 188.976 -119.761)
		(width 0.127)
		(layer "F.Cu")
		(net "P3V3_STBY_R2")
	)
	(segment
		(start 190.427356 -122.678444)
		(end 190.4238 -122.682)
		(width 0.127)
		(layer "F.Cu")
		(net "P3V3_STBY_R2")
	)
	(segment
		(start 190.427356 -119.770652)
		(end 188.985652 -119.770652)
		(width 0.127)
		(layer "F.Cu")
		(net "P3V3_STBY_R2")
	)
	(via
		(at 188.976 -119.761)
		(size 0.7112)
		(drill 0.3556)
		(layers "F.Cu" "B.Cu")
		(net "P3V3_STBY_R2")
	)
	(segment
		(start 109.15015 -54.99989)
		(end 109.550454 -55.400194)
		(width 0.1143)
		(layer "F.Cu")
		(net "XM_DATA_7")
	)
	(segment
		(start 138.598656 -57.75579)
		(end 139.127484 -57.226962)
		(width 0.1143)
		(layer "F.Cu")
		(net "XM_DATA_7")
	)
	(segment
		(start 138.598656 -61.9379)
		(end 138.598656 -57.75579)
		(width 0.1143)
		(layer "F.Cu")
		(net "XM_DATA_7")
	)
	(segment
		(start 109.550454 -55.400194)
		(end 109.559344 -55.400194)
		(width 0.1143)
		(layer "F.Cu")
		(net "XM_DATA_7")
	)
	(via
		(at 138.303 -57.023)
		(size 0.7112)
		(drill 0.3556)
		(layers "F.Cu" "B.Cu")
		(net "XM_DATA_7")
	)
	(via
		(at 139.127484 -57.226962)
		(size 0.5588)
		(drill 0.3048)
		(layers "F.Cu" "B.Cu")
		(net "XM_DATA_7")
	)
	(via
		(at 109.559344 -55.400194)
		(size 0.508)
		(drill 0.254)
		(layers "F.Cu" "B.Cu")
		(net "XM_DATA_7")
	)
	(segment
		(start 129.196846 -54.991)
		(end 129.082546 -55.1053)
		(width 0.1143)
		(layer "B.Cu")
		(net "XM_DATA_7")
	)
	(segment
		(start 129.082546 -55.1053)
		(end 129.082546 -55.848504)
		(width 0.1143)
		(layer "B.Cu")
		(net "XM_DATA_7")
	)
	(segment
		(start 129.996946 -55.848504)
		(end 129.882646 -55.962804)
		(width 0.1143)
		(layer "B.Cu")
		(net "XM_DATA_7")
	)
	(segment
		(start 129.539746 -55.1053)
		(end 129.425446 -54.991)
		(width 0.1143)
		(layer "B.Cu")
		(net "XM_DATA_7")
	)
	(segment
		(start 123.81357 -55.848504)
		(end 123.81357 -55.1053)
		(width 0.1143)
		(layer "B.Cu")
		(net "XM_DATA_7")
	)
	(segment
		(start 124.61367 -54.991)
		(end 124.38507 -54.991)
		(width 0.1143)
		(layer "B.Cu")
		(net "XM_DATA_7")
	)
	(segment
		(start 124.15647 -55.962804)
		(end 123.92787 -55.962804)
		(width 0.1143)
		(layer "B.Cu")
		(net "XM_DATA_7")
	)
	(segment
		(start 128.625346 -55.848504)
		(end 128.625346 -55.1053)
		(width 0.1143)
		(layer "B.Cu")
		(net "XM_DATA_7")
	)
	(segment
		(start 129.425446 -54.991)
		(end 129.196846 -54.991)
		(width 0.1143)
		(layer "B.Cu")
		(net "XM_DATA_7")
	)
	(segment
		(start 124.27077 -55.848504)
		(end 124.15647 -55.962804)
		(width 0.1143)
		(layer "B.Cu")
		(net "XM_DATA_7")
	)
	(segment
		(start 128.968246 -55.962804)
		(end 128.739646 -55.962804)
		(width 0.1143)
		(layer "B.Cu")
		(net "XM_DATA_7")
	)
	(segment
		(start 136.94664 -55.962804)
		(end 130.568446 -55.962804)
		(width 0.1143)
		(layer "B.Cu")
		(net "XM_DATA_7")
	)
	(segment
		(start 128.739646 -55.962804)
		(end 128.625346 -55.848504)
		(width 0.1143)
		(layer "B.Cu")
		(net "XM_DATA_7")
	)
	(segment
		(start 114.246152 -54.986936)
		(end 109.972602 -54.986936)
		(width 0.1143)
		(layer "B.Cu")
		(net "XM_DATA_7")
	)
	(segment
		(start 115.424712 -53.808376)
		(end 114.246152 -54.986936)
		(width 0.1143)
		(layer "B.Cu")
		(net "XM_DATA_7")
	)
	(segment
		(start 129.539746 -55.848504)
		(end 129.539746 -55.1053)
		(width 0.1143)
		(layer "B.Cu")
		(net "XM_DATA_7")
	)
	(segment
		(start 125.07087 -55.962804)
		(end 124.84227 -55.962804)
		(width 0.1143)
		(layer "B.Cu")
		(net "XM_DATA_7")
	)
	(segment
		(start 130.454146 -55.1053)
		(end 130.339846 -54.991)
		(width 0.1143)
		(layer "B.Cu")
		(net "XM_DATA_7")
	)
	(segment
		(start 128.625346 -55.1053)
		(end 128.511046 -54.991)
		(width 0.1143)
		(layer "B.Cu")
		(net "XM_DATA_7")
	)
	(segment
		(start 123.69927 -54.991)
		(end 118.914418 -54.991)
		(width 0.1143)
		(layer "B.Cu")
		(net "XM_DATA_7")
	)
	(segment
		(start 129.654046 -55.962804)
		(end 129.539746 -55.848504)
		(width 0.1143)
		(layer "B.Cu")
		(net "XM_DATA_7")
	)
	(segment
		(start 130.568446 -55.962804)
		(end 130.454146 -55.848504)
		(width 0.1143)
		(layer "B.Cu")
		(net "XM_DATA_7")
	)
	(segment
		(start 116.888768 -54.186582)
		(end 116.510562 -53.808376)
		(width 0.1143)
		(layer "B.Cu")
		(net "XM_DATA_7")
	)
	(segment
		(start 138.303 -57.023)
		(end 138.506962 -57.226962)
		(width 0.1143)
		(layer "B.Cu")
		(net "XM_DATA_7")
	)
	(segment
		(start 118.914418 -54.991)
		(end 118.11 -54.186582)
		(width 0.1143)
		(layer "B.Cu")
		(net "XM_DATA_7")
	)
	(segment
		(start 118.11 -54.186582)
		(end 116.888768 -54.186582)
		(width 0.1143)
		(layer "B.Cu")
		(net "XM_DATA_7")
	)
	(segment
		(start 124.27077 -55.1053)
		(end 124.27077 -55.848504)
		(width 0.1143)
		(layer "B.Cu")
		(net "XM_DATA_7")
	)
	(segment
		(start 125.18517 -55.1053)
		(end 125.18517 -55.848504)
		(width 0.1143)
		(layer "B.Cu")
		(net "XM_DATA_7")
	)
	(segment
		(start 124.72797 -55.848504)
		(end 124.72797 -55.1053)
		(width 0.1143)
		(layer "B.Cu")
		(net "XM_DATA_7")
	)
	(segment
		(start 138.303 -57.023)
		(end 138.006836 -57.023)
		(width 0.1143)
		(layer "B.Cu")
		(net "XM_DATA_7")
	)
	(segment
		(start 128.511046 -54.991)
		(end 125.29947 -54.991)
		(width 0.1143)
		(layer "B.Cu")
		(net "XM_DATA_7")
	)
	(segment
		(start 129.996946 -55.1053)
		(end 129.996946 -55.848504)
		(width 0.1143)
		(layer "B.Cu")
		(net "XM_DATA_7")
	)
	(segment
		(start 130.454146 -55.848504)
		(end 130.454146 -55.1053)
		(width 0.1143)
		(layer "B.Cu")
		(net "XM_DATA_7")
	)
	(segment
		(start 129.882646 -55.962804)
		(end 129.654046 -55.962804)
		(width 0.1143)
		(layer "B.Cu")
		(net "XM_DATA_7")
	)
	(segment
		(start 123.92787 -55.962804)
		(end 123.81357 -55.848504)
		(width 0.1143)
		(layer "B.Cu")
		(net "XM_DATA_7")
	)
	(segment
		(start 109.972602 -54.986936)
		(end 109.559344 -55.400194)
		(width 0.1143)
		(layer "B.Cu")
		(net "XM_DATA_7")
	)
	(segment
		(start 130.339846 -54.991)
		(end 130.111246 -54.991)
		(width 0.1143)
		(layer "B.Cu")
		(net "XM_DATA_7")
	)
	(segment
		(start 125.18517 -55.848504)
		(end 125.07087 -55.962804)
		(width 0.1143)
		(layer "B.Cu")
		(net "XM_DATA_7")
	)
	(segment
		(start 130.111246 -54.991)
		(end 129.996946 -55.1053)
		(width 0.1143)
		(layer "B.Cu")
		(net "XM_DATA_7")
	)
	(segment
		(start 125.29947 -54.991)
		(end 125.18517 -55.1053)
		(width 0.1143)
		(layer "B.Cu")
		(net "XM_DATA_7")
	)
	(segment
		(start 116.510562 -53.808376)
		(end 115.424712 -53.808376)
		(width 0.1143)
		(layer "B.Cu")
		(net "XM_DATA_7")
	)
	(segment
		(start 124.72797 -55.1053)
		(end 124.61367 -54.991)
		(width 0.1143)
		(layer "B.Cu")
		(net "XM_DATA_7")
	)
	(segment
		(start 124.38507 -54.991)
		(end 124.27077 -55.1053)
		(width 0.1143)
		(layer "B.Cu")
		(net "XM_DATA_7")
	)
	(segment
		(start 138.506962 -57.226962)
		(end 139.127484 -57.226962)
		(width 0.1143)
		(layer "B.Cu")
		(net "XM_DATA_7")
	)
	(segment
		(start 123.81357 -55.1053)
		(end 123.69927 -54.991)
		(width 0.1143)
		(layer "B.Cu")
		(net "XM_DATA_7")
	)
	(segment
		(start 138.006836 -57.023)
		(end 136.94664 -55.962804)
		(width 0.1143)
		(layer "B.Cu")
		(net "XM_DATA_7")
	)
	(segment
		(start 129.082546 -55.848504)
		(end 128.968246 -55.962804)
		(width 0.1143)
		(layer "B.Cu")
		(net "XM_DATA_7")
	)
	(segment
		(start 124.84227 -55.962804)
		(end 124.72797 -55.848504)
		(width 0.1143)
		(layer "B.Cu")
		(net "XM_DATA_7")
	)
	(segment
		(start 96.473518 -72.5932)
		(end 98.375216 -70.691502)
		(width 0.1143)
		(layer "F.Cu")
		(net "AVSO_VREF")
	)
	(segment
		(start 100.6221 -57.592722)
		(end 100.686616 -57.528206)
		(width 0.1143)
		(layer "F.Cu")
		(net "AVSO_VREF")
	)
	(segment
		(start 98.375216 -67.664584)
		(end 99.0854 -66.9544)
		(width 0.1143)
		(layer "F.Cu")
		(net "AVSO_VREF")
	)
	(segment
		(start 98.375216 -70.691502)
		(end 98.375216 -67.664584)
		(width 0.1143)
		(layer "F.Cu")
		(net "AVSO_VREF")
	)
	(segment
		(start 100.686616 -56.46039)
		(end 100.350066 -56.12384)
		(width 0.1143)
		(layer "F.Cu")
		(net "AVSO_VREF")
	)
	(segment
		(start 101.6 -60.071)
		(end 100.6221 -59.0931)
		(width 0.1143)
		(layer "F.Cu")
		(net "AVSO_VREF")
	)
	(segment
		(start 100.6221 -59.0931)
		(end 100.6221 -57.592722)
		(width 0.1143)
		(layer "F.Cu")
		(net "AVSO_VREF")
	)
	(segment
		(start 93.1164 -72.5932)
		(end 96.473518 -72.5932)
		(width 0.1143)
		(layer "F.Cu")
		(net "AVSO_VREF")
	)
	(segment
		(start 100.350066 -56.12384)
		(end 100.350066 -55.79999)
		(width 0.1143)
		(layer "F.Cu")
		(net "AVSO_VREF")
	)
	(segment
		(start 101.6 -60.325)
		(end 101.6 -60.071)
		(width 0.1143)
		(layer "F.Cu")
		(net "AVSO_VREF")
	)
	(segment
		(start 100.686616 -57.528206)
		(end 100.686616 -56.46039)
		(width 0.1143)
		(layer "F.Cu")
		(net "AVSO_VREF")
	)
	(via
		(at 101.6 -60.325)
		(size 0.508)
		(drill 0.254)
		(layers "F.Cu" "B.Cu")
		(net "AVSO_VREF")
	)
	(via
		(at 99.187 -65.405)
		(size 0.7112)
		(drill 0.3556)
		(layers "F.Cu" "B.Cu")
		(net "AVSO_VREF")
	)
	(via
		(at 99.0854 -66.9544)
		(size 0.5588)
		(drill 0.3048)
		(layers "F.Cu" "B.Cu")
		(net "AVSO_VREF")
	)
	(via
		(at 93.1164 -72.5932)
		(size 0.5588)
		(drill 0.3048)
		(layers "F.Cu" "B.Cu")
		(net "AVSO_VREF")
	)
	(via
		(at 85.725 -21.3995)
		(size 0.5588)
		(drill 0.3048)
		(layers "F.Cu" "B.Cu")
		(net "AVSO_VREF")
	)
	(segment
		(start 101.6 -60.325)
		(end 101.981 -60.706)
		(width 0.1143)
		(layer "B.Cu")
		(net "AVSO_VREF")
	)
	(segment
		(start 101.981 -60.706)
		(end 101.981 -61.849)
		(width 0.1143)
		(layer "B.Cu")
		(net "AVSO_VREF")
	)
	(segment
		(start 99.0854 -66.9036)
		(end 99.187 -66.802)
		(width 0.1143)
		(layer "B.Cu")
		(net "AVSO_VREF")
	)
	(segment
		(start 84.836 -21.3995)
		(end 85.725 -21.3995)
		(width 0.1143)
		(layer "B.Cu")
		(net "AVSO_VREF")
	)
	(segment
		(start 101.981 -61.849)
		(end 99.187 -64.643)
		(width 0.1143)
		(layer "B.Cu")
		(net "AVSO_VREF")
	)
	(segment
		(start 83.82 -21.3995)
		(end 84.836 -21.3995)
		(width 0.1143)
		(layer "B.Cu")
		(net "AVSO_VREF")
	)
	(segment
		(start 99.187 -64.643)
		(end 99.187 -65.405)
		(width 0.1143)
		(layer "B.Cu")
		(net "AVSO_VREF")
	)
	(segment
		(start 99.0854 -66.9544)
		(end 99.0854 -66.9036)
		(width 0.1143)
		(layer "B.Cu")
		(net "AVSO_VREF")
	)
	(segment
		(start 99.187 -66.802)
		(end 99.187 -65.405)
		(width 0.1143)
		(layer "B.Cu")
		(net "AVSO_VREF")
	)
	(segment
		(start 91.9607 -71.4375)
		(end 91.9607 -70.596506)
		(width 0.127)
		(layer "In2.Cu")
		(net "AVSO_VREF")
	)
	(segment
		(start 90.071194 -68.707)
		(end 84.201 -68.707)
		(width 0.127)
		(layer "In2.Cu")
		(net "AVSO_VREF")
	)
	(segment
		(start 80.482948 -63.6905)
		(end 80.008984 -63.6905)
		(width 0.127)
		(layer "In2.Cu")
		(net "AVSO_VREF")
	)
	(segment
		(start 75.692 -25.146)
		(end 81.534 -25.146)
		(width 0.127)
		(layer "In2.Cu")
		(net "AVSO_VREF")
	)
	(segment
		(start 80.817466 -65.323466)
		(end 80.817466 -64.025018)
		(width 0.127)
		(layer "In2.Cu")
		(net "AVSO_VREF")
	)
	(segment
		(start 70.62978 -43.92422)
		(end 71.628 -42.926)
		(width 0.127)
		(layer "In2.Cu")
		(net "AVSO_VREF")
	)
	(segment
		(start 84.201 -68.707)
		(end 80.817466 -65.323466)
		(width 0.127)
		(layer "In2.Cu")
		(net "AVSO_VREF")
	)
	(segment
		(start 71.628 -42.926)
		(end 71.628 -29.21)
		(width 0.127)
		(layer "In2.Cu")
		(net "AVSO_VREF")
	)
	(segment
		(start 79.754984 -63.9445)
		(end 79.4385 -63.9445)
		(width 0.127)
		(layer "In2.Cu")
		(net "AVSO_VREF")
	)
	(segment
		(start 81.534 -25.146)
		(end 85.2805 -21.3995)
		(width 0.127)
		(layer "In2.Cu")
		(net "AVSO_VREF")
	)
	(segment
		(start 93.1164 -72.5932)
		(end 91.9607 -71.4375)
		(width 0.127)
		(layer "In2.Cu")
		(net "AVSO_VREF")
	)
	(segment
		(start 70.62978 -55.13578)
		(end 70.62978 -43.92422)
		(width 0.127)
		(layer "In2.Cu")
		(net "AVSO_VREF")
	)
	(segment
		(start 71.628 -29.21)
		(end 75.692 -25.146)
		(width 0.127)
		(layer "In2.Cu")
		(net "AVSO_VREF")
	)
	(segment
		(start 91.9607 -70.596506)
		(end 90.071194 -68.707)
		(width 0.127)
		(layer "In2.Cu")
		(net "AVSO_VREF")
	)
	(segment
		(start 80.817466 -64.025018)
		(end 80.482948 -63.6905)
		(width 0.127)
		(layer "In2.Cu")
		(net "AVSO_VREF")
	)
	(segment
		(start 85.2805 -21.3995)
		(end 85.725 -21.3995)
		(width 0.127)
		(layer "In2.Cu")
		(net "AVSO_VREF")
	)
	(segment
		(start 79.4385 -63.9445)
		(end 70.62978 -55.13578)
		(width 0.127)
		(layer "In2.Cu")
		(net "AVSO_VREF")
	)
	(segment
		(start 80.008984 -63.6905)
		(end 79.754984 -63.9445)
		(width 0.127)
		(layer "In2.Cu")
		(net "AVSO_VREF")
	)
	(segment
		(start 87.655654 -33.538414)
		(end 88.758776 -34.641536)
		(width 0.1016)
		(layer "F.Cu")
		(net "SAS3008_RAID_TX_C_P0")
	)
	(segment
		(start 90.712036 -34.96183)
		(end 90.750136 -34.99993)
		(width 0.1016)
		(layer "F.Cu")
		(net "SAS3008_RAID_TX_C_P0")
	)
	(segment
		(start 87.175086 -33.4899)
		(end 87.53856 -33.4899)
		(width 0.1016)
		(layer "F.Cu")
		(net "SAS3008_RAID_TX_C_P0")
	)
	(segment
		(start 89.53246 -34.96183)
		(end 90.712036 -34.96183)
		(width 0.1016)
		(layer "F.Cu")
		(net "SAS3008_RAID_TX_C_P0")
	)
	(arc
		(start 86.77656 -33.655)
		(mid 86.959405 -33.532827)
		(end 87.175086 -33.4899)
		(width 0.1016)
		(layer "F.Cu")
		(net "SAS3008_RAID_TX_C_P0")
	)
	(arc
		(start 87.53856 -33.4899)
		(mid 87.601935 -33.502506)
		(end 87.655654 -33.538414)
		(width 0.1016)
		(layer "F.Cu")
		(net "SAS3008_RAID_TX_C_P0")
	)
	(arc
		(start 88.758776 -34.641536)
		(mid 89.11376 -34.878636)
		(end 89.53246 -34.96183)
		(width 0.1016)
		(layer "F.Cu")
		(net "SAS3008_RAID_TX_C_P0")
	)
	(segment
		(start 279.019 -114.173)
		(end 279.019 -114.554)
		(width 0.254)
		(layer "F.Cu")
		(net "P1V8_C_EN_G")
	)
	(segment
		(start 279.24125 -112.8395)
		(end 279.24125 -113.95075)
		(width 0.254)
		(layer "F.Cu")
		(net "P1V8_C_EN_G")
	)
	(segment
		(start 279.781 -115.316)
		(end 279.781 -115.3795)
		(width 0.254)
		(layer "F.Cu")
		(net "P1V8_C_EN_G")
	)
	(segment
		(start 279.019 -114.554)
		(end 279.781 -115.316)
		(width 0.254)
		(layer "F.Cu")
		(net "P1V8_C_EN_G")
	)
	(segment
		(start 279.24125 -113.95075)
		(end 279.019 -114.173)
		(width 0.254)
		(layer "F.Cu")
		(net "P1V8_C_EN_G")
	)
	(via
		(at 279.019 -114.173)
		(size 0.7112)
		(drill 0.3556)
		(layers "F.Cu" "B.Cu")
		(net "P1V8_C_EN_G")
	)
	(segment
		(start 84.91982 -19.369532)
		(end 85.979 -19.369532)
		(width 0.254)
		(layer "F.Cu")
		(net "VT235_VDDL")
	)
	(segment
		(start 85.979 -19.369532)
		(end 86.171532 -19.177)
		(width 0.254)
		(layer "F.Cu")
		(net "VT235_VDDL")
	)
	(segment
		(start 86.171532 -19.177)
		(end 86.233 -19.177)
		(width 0.254)
		(layer "F.Cu")
		(net "VT235_VDDL")
	)
	(via
		(at 86.233 -19.177)
		(size 0.5588)
		(drill 0.3048)
		(layers "F.Cu" "B.Cu")
		(net "VT235_VDDL")
	)
	(via
		(at 85.725 -17.399)
		(size 0.7112)
		(drill 0.3556)
		(layers "F.Cu" "B.Cu")
		(net "VT235_VDDL")
	)
	(segment
		(start 84.2518 -17.4498)
		(end 82.804 -17.1958)
		(width 0.254)
		(layer "B.Cu")
		(net "VT235_VDDL")
	)
	(segment
		(start 85.725 -17.399)
		(end 84.455 -17.399)
		(width 0.254)
		(layer "B.Cu")
		(net "VT235_VDDL")
	)
	(segment
		(start 85.725 -17.399)
		(end 86.233 -17.907)
		(width 0.254)
		(layer "B.Cu")
		(net "VT235_VDDL")
	)
	(segment
		(start 84.455 -17.399)
		(end 84.2518 -17.4498)
		(width 0.254)
		(layer "B.Cu")
		(net "VT235_VDDL")
	)
	(segment
		(start 86.233 -17.907)
		(end 86.233 -19.177)
		(width 0.254)
		(layer "B.Cu")
		(net "VT235_VDDL")
	)
	(segment
		(start 112.350042 -50.199798)
		(end 112.749838 -49.800002)
		(width 0.1143)
		(layer "F.Cu")
		(net "XM_DATA_12")
	)
	(segment
		(start 142.230094 -58.538618)
		(end 142.230094 -53.192426)
		(width 0.1143)
		(layer "F.Cu")
		(net "XM_DATA_12")
	)
	(segment
		(start 141.099286 -59.669426)
		(end 142.230094 -58.538618)
		(width 0.1143)
		(layer "F.Cu")
		(net "XM_DATA_12")
	)
	(segment
		(start 141.099286 -61.9379)
		(end 141.099286 -59.669426)
		(width 0.1143)
		(layer "F.Cu")
		(net "XM_DATA_12")
	)
	(via
		(at 116.967 -49.784)
		(size 0.7112)
		(drill 0.3556)
		(layers "F.Cu" "B.Cu")
		(net "XM_DATA_12")
	)
	(via
		(at 142.230094 -53.192426)
		(size 0.5588)
		(drill 0.3048)
		(layers "F.Cu" "B.Cu")
		(net "XM_DATA_12")
	)
	(via
		(at 112.749838 -49.800002)
		(size 0.508)
		(drill 0.254)
		(layers "F.Cu" "B.Cu")
		(net "XM_DATA_12")
	)
	(segment
		(start 123.6599 -51.7779)
		(end 123.1011 -51.2191)
		(width 0.1143)
		(layer "B.Cu")
		(net "XM_DATA_12")
	)
	(segment
		(start 125.271022 -51.3334)
		(end 125.271022 -51.6636)
		(width 0.1143)
		(layer "B.Cu")
		(net "XM_DATA_12")
	)
	(segment
		(start 124.470922 -51.2191)
		(end 124.356622 -51.3334)
		(width 0.1143)
		(layer "B.Cu")
		(net "XM_DATA_12")
	)
	(segment
		(start 125.728222 -51.6636)
		(end 125.728222 -51.3334)
		(width 0.1143)
		(layer "B.Cu")
		(net "XM_DATA_12")
	)
	(segment
		(start 124.928122 -51.7779)
		(end 124.813822 -51.6636)
		(width 0.1143)
		(layer "B.Cu")
		(net "XM_DATA_12")
	)
	(segment
		(start 125.842522 -51.7779)
		(end 125.728222 -51.6636)
		(width 0.1143)
		(layer "B.Cu")
		(net "XM_DATA_12")
	)
	(segment
		(start 142.230094 -53.0352)
		(end 141.137894 -51.943)
		(width 0.1143)
		(layer "B.Cu")
		(net "XM_DATA_12")
	)
	(segment
		(start 124.356622 -51.3334)
		(end 124.356622 -51.6636)
		(width 0.1143)
		(layer "B.Cu")
		(net "XM_DATA_12")
	)
	(segment
		(start 125.271022 -51.6636)
		(end 125.156722 -51.7779)
		(width 0.1143)
		(layer "B.Cu")
		(net "XM_DATA_12")
	)
	(segment
		(start 123.1011 -51.2191)
		(end 120.095264 -51.2191)
		(width 0.1143)
		(layer "B.Cu")
		(net "XM_DATA_12")
	)
	(segment
		(start 120.095264 -51.2191)
		(end 120.019064 -51.1429)
		(width 0.1143)
		(layer "B.Cu")
		(net "XM_DATA_12")
	)
	(segment
		(start 125.613922 -51.2191)
		(end 125.385322 -51.2191)
		(width 0.1143)
		(layer "B.Cu")
		(net "XM_DATA_12")
	)
	(segment
		(start 116.967 -50.715164)
		(end 116.967 -49.784)
		(width 0.1143)
		(layer "B.Cu")
		(net "XM_DATA_12")
	)
	(segment
		(start 124.242322 -51.7779)
		(end 123.6599 -51.7779)
		(width 0.1143)
		(layer "B.Cu")
		(net "XM_DATA_12")
	)
	(segment
		(start 138.637264 -51.5239)
		(end 136.478264 -51.5239)
		(width 0.1143)
		(layer "B.Cu")
		(net "XM_DATA_12")
	)
	(segment
		(start 141.092682 -51.943)
		(end 140.057632 -50.90795)
		(width 0.1143)
		(layer "B.Cu")
		(net "XM_DATA_12")
	)
	(segment
		(start 125.728222 -51.3334)
		(end 125.613922 -51.2191)
		(width 0.1143)
		(layer "B.Cu")
		(net "XM_DATA_12")
	)
	(segment
		(start 136.478264 -51.5239)
		(end 136.224264 -51.7779)
		(width 0.1143)
		(layer "B.Cu")
		(net "XM_DATA_12")
	)
	(segment
		(start 115.066064 -48.899064)
		(end 115.560856 -49.393856)
		(width 0.1143)
		(layer "B.Cu")
		(net "XM_DATA_12")
	)
	(segment
		(start 120.019064 -51.1429)
		(end 117.394736 -51.1429)
		(width 0.1143)
		(layer "B.Cu")
		(net "XM_DATA_12")
	)
	(segment
		(start 141.137894 -51.943)
		(end 141.092682 -51.943)
		(width 0.1143)
		(layer "B.Cu")
		(net "XM_DATA_12")
	)
	(segment
		(start 124.813822 -51.3334)
		(end 124.699522 -51.2191)
		(width 0.1143)
		(layer "B.Cu")
		(net "XM_DATA_12")
	)
	(segment
		(start 125.385322 -51.2191)
		(end 125.271022 -51.3334)
		(width 0.1143)
		(layer "B.Cu")
		(net "XM_DATA_12")
	)
	(segment
		(start 139.253214 -50.90795)
		(end 138.637264 -51.5239)
		(width 0.1143)
		(layer "B.Cu")
		(net "XM_DATA_12")
	)
	(segment
		(start 115.560856 -49.393856)
		(end 116.576856 -49.393856)
		(width 0.1143)
		(layer "B.Cu")
		(net "XM_DATA_12")
	)
	(segment
		(start 117.394736 -51.1429)
		(end 116.967 -50.715164)
		(width 0.1143)
		(layer "B.Cu")
		(net "XM_DATA_12")
	)
	(segment
		(start 136.224264 -51.7779)
		(end 125.842522 -51.7779)
		(width 0.1143)
		(layer "B.Cu")
		(net "XM_DATA_12")
	)
	(segment
		(start 116.576856 -49.393856)
		(end 116.967 -49.784)
		(width 0.1143)
		(layer "B.Cu")
		(net "XM_DATA_12")
	)
	(segment
		(start 125.156722 -51.7779)
		(end 124.928122 -51.7779)
		(width 0.1143)
		(layer "B.Cu")
		(net "XM_DATA_12")
	)
	(segment
		(start 124.813822 -51.6636)
		(end 124.813822 -51.3334)
		(width 0.1143)
		(layer "B.Cu")
		(net "XM_DATA_12")
	)
	(segment
		(start 113.650776 -48.899064)
		(end 115.066064 -48.899064)
		(width 0.1143)
		(layer "B.Cu")
		(net "XM_DATA_12")
	)
	(segment
		(start 112.749838 -49.800002)
		(end 113.650776 -48.899064)
		(width 0.1143)
		(layer "B.Cu")
		(net "XM_DATA_12")
	)
	(segment
		(start 140.057632 -50.90795)
		(end 139.253214 -50.90795)
		(width 0.1143)
		(layer "B.Cu")
		(net "XM_DATA_12")
	)
	(segment
		(start 124.356622 -51.6636)
		(end 124.242322 -51.7779)
		(width 0.1143)
		(layer "B.Cu")
		(net "XM_DATA_12")
	)
	(segment
		(start 124.699522 -51.2191)
		(end 124.470922 -51.2191)
		(width 0.1143)
		(layer "B.Cu")
		(net "XM_DATA_12")
	)
	(segment
		(start 142.230094 -53.192426)
		(end 142.230094 -53.0352)
		(width 0.1143)
		(layer "B.Cu")
		(net "XM_DATA_12")
	)
	(segment
		(start 90.861896 -46.609)
		(end 91.27109 -46.199806)
		(width 0.1143)
		(layer "F.Cu")
		(net "IOC_REF_CLK_N")
	)
	(segment
		(start 88.519 -48.201834)
		(end 90.111834 -46.609)
		(width 0.1143)
		(layer "F.Cu")
		(net "IOC_REF_CLK_N")
	)
	(segment
		(start 87.548466 -60.325)
		(end 88.519 -59.354466)
		(width 0.1143)
		(layer "F.Cu")
		(net "IOC_REF_CLK_N")
	)
	(segment
		(start 88.519 -59.354466)
		(end 88.519 -48.201834)
		(width 0.1143)
		(layer "F.Cu")
		(net "IOC_REF_CLK_N")
	)
	(segment
		(start 91.27109 -46.199806)
		(end 91.549982 -46.199806)
		(width 0.1143)
		(layer "F.Cu")
		(net "IOC_REF_CLK_N")
	)
	(segment
		(start 90.111834 -46.609)
		(end 90.861896 -46.609)
		(width 0.1143)
		(layer "F.Cu")
		(net "IOC_REF_CLK_N")
	)
	(segment
		(start 133.223 -82.544412)
		(end 133.223 -81.451958)
		(width 0.1016)
		(layer "F.Cu")
		(net "3008_SAS_RX_N1")
	)
	(segment
		(start 132.847842 -82.5246)
		(end 132.934456 -82.611214)
		(width 0.1016)
		(layer "F.Cu")
		(net "3008_SAS_RX_N1")
	)
	(segment
		(start 93.54947 -35.407854)
		(end 93.54947 -35.43427)
		(width 0.1016)
		(layer "F.Cu")
		(net "3008_SAS_RX_N1")
	)
	(segment
		(start 93.91523 -35.80003)
		(end 93.950028 -35.80003)
		(width 0.1016)
		(layer "F.Cu")
		(net "3008_SAS_RX_N1")
	)
	(segment
		(start 133.006338 -82.640932)
		(end 133.12648 -82.640932)
		(width 0.1016)
		(layer "F.Cu")
		(net "3008_SAS_RX_N1")
	)
	(segment
		(start 93.54947 -35.43427)
		(end 93.91523 -35.80003)
		(width 0.1016)
		(layer "F.Cu")
		(net "3008_SAS_RX_N1")
	)
	(segment
		(start 132.492242 -82.494882)
		(end 132.77596 -82.494882)
		(width 0.1016)
		(layer "F.Cu")
		(net "3008_SAS_RX_N1")
	)
	(segment
		(start 133.193282 -81.380076)
		(end 132.930392 -81.117186)
		(width 0.1016)
		(layer "F.Cu")
		(net "3008_SAS_RX_N1")
	)
	(via
		(at 93.54947 -35.407854)
		(size 0.508)
		(drill 0.254)
		(layers "F.Cu" "B.Cu")
		(net "3008_SAS_RX_N1")
	)
	(via
		(at 132.930392 -81.117186)
		(size 0.5588)
		(drill 0.3048)
		(layers "F.Cu" "B.Cu")
		(net "3008_SAS_RX_N1")
	)
	(arc
		(start 133.12648 -82.640932)
		(mid 133.19473 -82.612662)
		(end 133.223 -82.544412)
		(width 0.1016)
		(layer "F.Cu")
		(net "3008_SAS_RX_N1")
	)
	(arc
		(start 133.223 -81.451958)
		(mid 133.215281 -81.413063)
		(end 133.193282 -81.380076)
		(width 0.1016)
		(layer "F.Cu")
		(net "3008_SAS_RX_N1")
	)
	(arc
		(start 132.934456 -82.611214)
		(mid 132.96745 -82.633197)
		(end 133.006338 -82.640932)
		(width 0.1016)
		(layer "F.Cu")
		(net "3008_SAS_RX_N1")
	)
	(arc
		(start 132.77596 -82.494882)
		(mid 132.814855 -82.502601)
		(end 132.847842 -82.5246)
		(width 0.1016)
		(layer "F.Cu")
		(net "3008_SAS_RX_N1")
	)
	(segment
		(start 95.631 -64.75349)
		(end 95.58782 -64.710056)
		(width 0.1016)
		(layer "In5.Cu")
		(net "3008_SAS_RX_N1")
	)
	(segment
		(start 85.410802 -41.05529)
		(end 90.853768 -35.612324)
		(width 0.1016)
		(layer "In5.Cu")
		(net "3008_SAS_RX_N1")
	)
	(segment
		(start 85.071966 -53.492654)
		(end 85.071966 -41.873678)
		(width 0.1016)
		(layer "In5.Cu")
		(net "3008_SAS_RX_N1")
	)
	(segment
		(start 105.516934 -66.060066)
		(end 105.499154 -66.04254)
		(width 0.1016)
		(layer "In5.Cu")
		(net "3008_SAS_RX_N1")
	)
	(segment
		(start 132.930392 -81.117186)
		(end 133.124702 -80.922622)
		(width 0.1016)
		(layer "In5.Cu")
		(net "3008_SAS_RX_N1")
	)
	(segment
		(start 95.58782 -64.710056)
		(end 85.568028 -54.690264)
		(width 0.1016)
		(layer "In5.Cu")
		(net "3008_SAS_RX_N1")
	)
	(segment
		(start 132.665978 -77.507338)
		(end 132.54482 -77.38618)
		(width 0.1016)
		(layer "In5.Cu")
		(net "3008_SAS_RX_N1")
	)
	(segment
		(start 132.54482 -77.385926)
		(end 128.22682 -73.067926)
		(width 0.1016)
		(layer "In5.Cu")
		(net "3008_SAS_RX_N1")
	)
	(segment
		(start 110.21568 -70.758812)
		(end 105.516934 -66.060066)
		(width 0.1016)
		(layer "In5.Cu")
		(net "3008_SAS_RX_N1")
	)
	(segment
		(start 126.651512 -72.4154)
		(end 121.959878 -72.4154)
		(width 0.1016)
		(layer "In5.Cu")
		(net "3008_SAS_RX_N1")
	)
	(segment
		(start 132.54482 -77.38618)
		(end 132.54482 -77.385926)
		(width 0.1016)
		(layer "In5.Cu")
		(net "3008_SAS_RX_N1")
	)
	(segment
		(start 133.22935 -80.6704)
		(end 133.22935 -78.866746)
		(width 0.1016)
		(layer "In5.Cu")
		(net "3008_SAS_RX_N1")
	)
	(segment
		(start 97.5106 -65.532)
		(end 97.5106 -65.532254)
		(width 0.1016)
		(layer "In5.Cu")
		(net "3008_SAS_RX_N1")
	)
	(segment
		(start 104.267 -65.532)
		(end 97.5106 -65.532)
		(width 0.1016)
		(layer "In5.Cu")
		(net "3008_SAS_RX_N1")
	)
	(segment
		(start 85.410802 -41.055544)
		(end 85.410802 -41.05529)
		(width 0.1016)
		(layer "In5.Cu")
		(net "3008_SAS_RX_N1")
	)
	(segment
		(start 120.309386 -71.4502)
		(end 111.885222 -71.4502)
		(width 0.1016)
		(layer "In5.Cu")
		(net "3008_SAS_RX_N1")
	)
	(segment
		(start 121.605548 -72.268588)
		(end 121.12498 -71.78802)
		(width 0.1016)
		(layer "In5.Cu")
		(net "3008_SAS_RX_N1")
	)
	(segment
		(start 91.213178 -35.46348)
		(end 93.415104 -35.46348)
		(width 0.1016)
		(layer "In5.Cu")
		(net "3008_SAS_RX_N1")
	)
	(arc
		(start 97.5106 -65.532254)
		(mid 96.493331 -65.329853)
		(end 95.631 -64.75349)
		(width 0.1016)
		(layer "In5.Cu")
		(net "3008_SAS_RX_N1")
	)
	(arc
		(start 133.22935 -78.866746)
		(mid 133.082836 -78.131023)
		(end 132.665978 -77.507338)
		(width 0.1016)
		(layer "In5.Cu")
		(net "3008_SAS_RX_N1")
	)
	(arc
		(start 105.499154 -66.04254)
		(mid 104.933852 -65.664724)
		(end 104.267 -65.532)
		(width 0.1016)
		(layer "In5.Cu")
		(net "3008_SAS_RX_N1")
	)
	(arc
		(start 85.071966 -41.873678)
		(mid 85.160088 -41.43095)
		(end 85.410802 -41.055544)
		(width 0.1016)
		(layer "In5.Cu")
		(net "3008_SAS_RX_N1")
	)
	(arc
		(start 85.568028 -54.690264)
		(mid 85.200939 -54.140782)
		(end 85.071966 -53.492654)
		(width 0.1016)
		(layer "In5.Cu")
		(net "3008_SAS_RX_N1")
	)
	(arc
		(start 90.853768 -35.612324)
		(mid 91.018667 -35.502142)
		(end 91.213178 -35.46348)
		(width 0.1016)
		(layer "In5.Cu")
		(net "3008_SAS_RX_N1")
	)
	(arc
		(start 93.415104 -35.46348)
		(mid 93.487811 -35.449018)
		(end 93.54947 -35.407854)
		(width 0.1016)
		(layer "In5.Cu")
		(net "3008_SAS_RX_N1")
	)
	(arc
		(start 121.12498 -71.78802)
		(mid 120.750782 -71.537989)
		(end 120.309386 -71.4502)
		(width 0.1016)
		(layer "In5.Cu")
		(net "3008_SAS_RX_N1")
	)
	(arc
		(start 111.885222 -71.4502)
		(mid 110.981654 -71.270621)
		(end 110.21568 -70.758812)
		(width 0.1016)
		(layer "In5.Cu")
		(net "3008_SAS_RX_N1")
	)
	(arc
		(start 133.124702 -80.922622)
		(mid 133.202107 -80.806917)
		(end 133.22935 -80.6704)
		(width 0.1016)
		(layer "In5.Cu")
		(net "3008_SAS_RX_N1")
	)
	(arc
		(start 121.959878 -72.4154)
		(mid 121.768114 -72.377238)
		(end 121.605548 -72.268588)
		(width 0.1016)
		(layer "In5.Cu")
		(net "3008_SAS_RX_N1")
	)
	(arc
		(start 128.22682 -73.067926)
		(mid 127.504063 -72.584995)
		(end 126.651512 -72.4154)
		(width 0.1016)
		(layer "In5.Cu")
		(net "3008_SAS_RX_N1")
	)
	(segment
		(start 278.4348 -107.2642)
		(end 278.638 -107.4674)
		(width 0.254)
		(layer "F.Cu")
		(net "P1V8_C_EN_LV")
	)
	(segment
		(start 275.2598 -106.2228)
		(end 276.3012 -107.2642)
		(width 0.254)
		(layer "F.Cu")
		(net "P1V8_C_EN_LV")
	)
	(segment
		(start 278.257 -110.9345)
		(end 278.257 -109.6645)
		(width 0.254)
		(layer "F.Cu")
		(net "P1V8_C_EN_LV")
	)
	(segment
		(start 279.2095 -108.0389)
		(end 278.638 -107.4674)
		(width 0.254)
		(layer "F.Cu")
		(net "P1V8_C_EN_LV")
	)
	(segment
		(start 276.3012 -107.2642)
		(end 278.4348 -107.2642)
		(width 0.254)
		(layer "F.Cu")
		(net "P1V8_C_EN_LV")
	)
	(segment
		(start 274.066 -104.648)
		(end 274.64004 -105.22204)
		(width 0.254)
		(layer "F.Cu")
		(net "P1V8_C_EN_LV")
	)
	(segment
		(start 274.64004 -106.2228)
		(end 275.2598 -106.2228)
		(width 0.254)
		(layer "F.Cu")
		(net "P1V8_C_EN_LV")
	)
	(segment
		(start 278.257 -109.6645)
		(end 279.2095 -108.712)
		(width 0.254)
		(layer "F.Cu")
		(net "P1V8_C_EN_LV")
	)
	(segment
		(start 274.64004 -105.22204)
		(end 274.64004 -106.2228)
		(width 0.254)
		(layer "F.Cu")
		(net "P1V8_C_EN_LV")
	)
	(segment
		(start 279.2095 -108.712)
		(end 279.2095 -108.0389)
		(width 0.254)
		(layer "F.Cu")
		(net "P1V8_C_EN_LV")
	)
	(via
		(at 278.638 -107.4674)
		(size 0.7112)
		(drill 0.3556)
		(layers "F.Cu" "B.Cu")
		(net "P1V8_C_EN_LV")
	)
	(segment
		(start 82.534252 -21.255228)
		(end 82.534252 -22.240748)
		(width 0.254)
		(layer "F.Cu")
		(net "VT235_IMAX")
	)
	(segment
		(start 82.534252 -22.240748)
		(end 82.042 -22.733)
		(width 0.254)
		(layer "F.Cu")
		(net "VT235_IMAX")
	)
	(via
		(at 82.042 -23.622)
		(size 0.7112)
		(drill 0.3556)
		(layers "F.Cu" "B.Cu")
		(net "VT235_IMAX")
	)
	(via
		(at 82.042 -22.733)
		(size 0.5588)
		(drill 0.3048)
		(layers "F.Cu" "B.Cu")
		(net "VT235_IMAX")
	)
	(segment
		(start 81.661 -22.352)
		(end 82.042 -22.733)
		(width 0.254)
		(layer "B.Cu")
		(net "VT235_IMAX")
	)
	(segment
		(start 81.661 -21.6535)
		(end 81.661 -22.352)
		(width 0.254)
		(layer "B.Cu")
		(net "VT235_IMAX")
	)
	(segment
		(start 82.042 -23.622)
		(end 82.042 -22.733)
		(width 0.254)
		(layer "B.Cu")
		(net "VT235_IMAX")
	)
	(segment
		(start 97.54997 -80.5815)
		(end 99.39655 -82.42808)
		(width 0.1143)
		(layer "F.Cu")
		(net "TMUX_EN")
	)
	(segment
		(start 96.34347 -80.518)
		(end 97.54997 -80.518)
		(width 0.1143)
		(layer "F.Cu")
		(net "TMUX_EN")
	)
	(segment
		(start 96.34347 -79.375)
		(end 96.34347 -80.518)
		(width 0.1143)
		(layer "F.Cu")
		(net "TMUX_EN")
	)
	(segment
		(start 107.349798 -87.349838)
		(end 106.849672 -86.849712)
		(width 0.1143)
		(layer "F.Cu")
		(net "TMUX_EN")
	)
	(segment
		(start 97.54997 -80.518)
		(end 97.54997 -80.5815)
		(width 0.1143)
		(layer "F.Cu")
		(net "TMUX_EN")
	)
	(via
		(at 99.39655 -82.42808)
		(size 0.508)
		(drill 0.254)
		(layers "F.Cu" "B.Cu")
		(net "TMUX_EN")
	)
	(via
		(at 106.849672 -86.849712)
		(size 0.508)
		(drill 0.254)
		(layers "F.Cu" "B.Cu")
		(net "TMUX_EN")
	)
	(segment
		(start 103.405178 -83.701382)
		(end 103.405178 -83.998054)
		(width 0.127)
		(layer "In2.Cu")
		(net "TMUX_EN")
	)
	(segment
		(start 103.887016 -84.294218)
		(end 104.405176 -84.812378)
		(width 0.127)
		(layer "In2.Cu")
		(net "TMUX_EN")
	)
	(segment
		(start 104.405176 -84.812378)
		(end 104.405176 -84.998052)
		(width 0.127)
		(layer "In2.Cu")
		(net "TMUX_EN")
	)
	(segment
		(start 99.39655 -82.42808)
		(end 100.71989 -82.42808)
		(width 0.127)
		(layer "In2.Cu")
		(net "TMUX_EN")
	)
	(segment
		(start 105.294176 -85.887052)
		(end 105.812336 -86.405212)
		(width 0.127)
		(layer "In2.Cu")
		(net "TMUX_EN")
	)
	(segment
		(start 104.70134 -85.294216)
		(end 104.887014 -85.294216)
		(width 0.127)
		(layer "In2.Cu")
		(net "TMUX_EN")
	)
	(segment
		(start 101.906578 -82.202782)
		(end 103.405178 -83.701382)
		(width 0.127)
		(layer "In2.Cu")
		(net "TMUX_EN")
	)
	(segment
		(start 104.887014 -85.294216)
		(end 105.294176 -85.701378)
		(width 0.127)
		(layer "In2.Cu")
		(net "TMUX_EN")
	)
	(segment
		(start 106.478324 -86.849712)
		(end 106.849672 -86.849712)
		(width 0.127)
		(layer "In2.Cu")
		(net "TMUX_EN")
	)
	(segment
		(start 103.405178 -83.998054)
		(end 103.701342 -84.294218)
		(width 0.127)
		(layer "In2.Cu")
		(net "TMUX_EN")
	)
	(segment
		(start 100.71989 -82.42808)
		(end 100.945188 -82.202782)
		(width 0.127)
		(layer "In2.Cu")
		(net "TMUX_EN")
	)
	(segment
		(start 100.945188 -82.202782)
		(end 101.906578 -82.202782)
		(width 0.127)
		(layer "In2.Cu")
		(net "TMUX_EN")
	)
	(segment
		(start 105.812336 -86.405212)
		(end 106.033824 -86.405212)
		(width 0.127)
		(layer "In2.Cu")
		(net "TMUX_EN")
	)
	(segment
		(start 105.294176 -85.701378)
		(end 105.294176 -85.887052)
		(width 0.127)
		(layer "In2.Cu")
		(net "TMUX_EN")
	)
	(segment
		(start 106.033824 -86.405212)
		(end 106.478324 -86.849712)
		(width 0.127)
		(layer "In2.Cu")
		(net "TMUX_EN")
	)
	(segment
		(start 103.701342 -84.294218)
		(end 103.887016 -84.294218)
		(width 0.127)
		(layer "In2.Cu")
		(net "TMUX_EN")
	)
	(segment
		(start 104.405176 -84.998052)
		(end 104.70134 -85.294216)
		(width 0.127)
		(layer "In2.Cu")
		(net "TMUX_EN")
	)
	(segment
		(start 111.549942 -55.818024)
		(end 111.549942 -55.79999)
		(width 0.1143)
		(layer "F.Cu")
		(net "XM_ADDR_1")
	)
	(segment
		(start 148.099526 -60.29325)
		(end 148.133816 -60.25896)
		(width 0.1143)
		(layer "F.Cu")
		(net "XM_ADDR_1")
	)
	(segment
		(start 111.213392 -57.29859)
		(end 111.213392 -56.154574)
		(width 0.1143)
		(layer "F.Cu")
		(net "XM_ADDR_1")
	)
	(segment
		(start 111.026448 -58.988706)
		(end 111.291116 -58.724038)
		(width 0.1143)
		(layer "F.Cu")
		(net "XM_ADDR_1")
	)
	(segment
		(start 148.099526 -61.9379)
		(end 148.099526 -60.29325)
		(width 0.1143)
		(layer "F.Cu")
		(net "XM_ADDR_1")
	)
	(segment
		(start 111.291116 -58.724038)
		(end 111.291116 -57.376314)
		(width 0.1143)
		(layer "F.Cu")
		(net "XM_ADDR_1")
	)
	(segment
		(start 148.59 -64.1985)
		(end 148.099526 -63.708026)
		(width 0.1143)
		(layer "F.Cu")
		(net "XM_ADDR_1")
	)
	(segment
		(start 111.291116 -57.376314)
		(end 111.213392 -57.29859)
		(width 0.1143)
		(layer "F.Cu")
		(net "XM_ADDR_1")
	)
	(segment
		(start 148.133816 -60.25896)
		(end 148.133816 -60.14847)
		(width 0.1143)
		(layer "F.Cu")
		(net "XM_ADDR_1")
	)
	(segment
		(start 111.213392 -56.154574)
		(end 111.549942 -55.818024)
		(width 0.1143)
		(layer "F.Cu")
		(net "XM_ADDR_1")
	)
	(segment
		(start 148.099526 -63.708026)
		(end 148.099526 -61.9379)
		(width 0.1143)
		(layer "F.Cu")
		(net "XM_ADDR_1")
	)
	(via
		(at 148.133816 -60.14847)
		(size 0.5588)
		(drill 0.3048)
		(layers "F.Cu" "B.Cu")
		(net "XM_ADDR_1")
	)
	(via
		(at 148.463 -61.087)
		(size 0.7112)
		(drill 0.3556)
		(layers "F.Cu" "B.Cu")
		(net "XM_ADDR_1")
	)
	(via
		(at 111.026448 -58.988706)
		(size 0.508)
		(drill 0.254)
		(layers "F.Cu" "B.Cu")
		(net "XM_ADDR_1")
	)
	(segment
		(start 148.463 -61.087)
		(end 148.463 -60.477654)
		(width 0.1143)
		(layer "B.Cu")
		(net "XM_ADDR_1")
	)
	(segment
		(start 148.463 -60.477654)
		(end 148.133816 -60.14847)
		(width 0.1143)
		(layer "B.Cu")
		(net "XM_ADDR_1")
	)
	(segment
		(start 130.486404 -58.125106)
		(end 130.232404 -58.125106)
		(width 0.127)
		(layer "In5.Cu")
		(net "XM_ADDR_1")
	)
	(segment
		(start 129.470404 -58.125106)
		(end 129.216404 -58.125106)
		(width 0.127)
		(layer "In5.Cu")
		(net "XM_ADDR_1")
	)
	(segment
		(start 134.642606 -58.252106)
		(end 134.642606 -59.098688)
		(width 0.127)
		(layer "In5.Cu")
		(net "XM_ADDR_1")
	)
	(segment
		(start 129.597404 -58.252106)
		(end 129.470404 -58.125106)
		(width 0.127)
		(layer "In5.Cu")
		(net "XM_ADDR_1")
	)
	(segment
		(start 129.724404 -59.225688)
		(end 129.597404 -59.098688)
		(width 0.127)
		(layer "In5.Cu")
		(net "XM_ADDR_1")
	)
	(segment
		(start 134.007606 -58.125106)
		(end 133.753606 -58.125106)
		(width 0.127)
		(layer "In5.Cu")
		(net "XM_ADDR_1")
	)
	(segment
		(start 134.134606 -59.098688)
		(end 134.134606 -58.252106)
		(width 0.127)
		(layer "In5.Cu")
		(net "XM_ADDR_1")
	)
	(segment
		(start 128.581404 -58.252106)
		(end 128.454404 -58.125106)
		(width 0.127)
		(layer "In5.Cu")
		(net "XM_ADDR_1")
	)
	(segment
		(start 130.613404 -58.252106)
		(end 130.486404 -58.125106)
		(width 0.127)
		(layer "In5.Cu")
		(net "XM_ADDR_1")
	)
	(segment
		(start 134.134606 -58.252106)
		(end 134.007606 -58.125106)
		(width 0.127)
		(layer "In5.Cu")
		(net "XM_ADDR_1")
	)
	(segment
		(start 129.978404 -59.225688)
		(end 129.724404 -59.225688)
		(width 0.127)
		(layer "In5.Cu")
		(net "XM_ADDR_1")
	)
	(segment
		(start 131.121404 -58.252106)
		(end 131.121404 -59.098688)
		(width 0.127)
		(layer "In5.Cu")
		(net "XM_ADDR_1")
	)
	(segment
		(start 128.073404 -58.252106)
		(end 128.073404 -59.098688)
		(width 0.127)
		(layer "In5.Cu")
		(net "XM_ADDR_1")
	)
	(segment
		(start 133.753606 -58.125106)
		(end 133.626606 -58.252106)
		(width 0.127)
		(layer "In5.Cu")
		(net "XM_ADDR_1")
	)
	(segment
		(start 130.740404 -59.225688)
		(end 130.613404 -59.098688)
		(width 0.127)
		(layer "In5.Cu")
		(net "XM_ADDR_1")
	)
	(segment
		(start 135.023606 -58.125106)
		(end 134.769606 -58.125106)
		(width 0.127)
		(layer "In5.Cu")
		(net "XM_ADDR_1")
	)
	(segment
		(start 135.150606 -58.252106)
		(end 135.023606 -58.125106)
		(width 0.127)
		(layer "In5.Cu")
		(net "XM_ADDR_1")
	)
	(segment
		(start 134.261606 -59.225688)
		(end 134.134606 -59.098688)
		(width 0.127)
		(layer "In5.Cu")
		(net "XM_ADDR_1")
	)
	(segment
		(start 130.994404 -59.225688)
		(end 130.740404 -59.225688)
		(width 0.127)
		(layer "In5.Cu")
		(net "XM_ADDR_1")
	)
	(segment
		(start 118.206012 -59.530488)
		(end 117.576346 -60.1599)
		(width 0.127)
		(layer "In5.Cu")
		(net "XM_ADDR_1")
	)
	(segment
		(start 128.200404 -58.125106)
		(end 128.073404 -58.252106)
		(width 0.127)
		(layer "In5.Cu")
		(net "XM_ADDR_1")
	)
	(segment
		(start 135.277606 -59.225688)
		(end 135.150606 -59.098688)
		(width 0.127)
		(layer "In5.Cu")
		(net "XM_ADDR_1")
	)
	(segment
		(start 130.105404 -58.252106)
		(end 130.105404 -59.098688)
		(width 0.127)
		(layer "In5.Cu")
		(net "XM_ADDR_1")
	)
	(segment
		(start 148.133816 -60.14847)
		(end 147.776946 -59.7916)
		(width 0.127)
		(layer "In5.Cu")
		(net "XM_ADDR_1")
	)
	(segment
		(start 131.248404 -58.125106)
		(end 131.121404 -58.252106)
		(width 0.127)
		(layer "In5.Cu")
		(net "XM_ADDR_1")
	)
	(segment
		(start 146.927316 -59.7916)
		(end 146.697192 -60.021724)
		(width 0.127)
		(layer "In5.Cu")
		(net "XM_ADDR_1")
	)
	(segment
		(start 130.232404 -58.125106)
		(end 130.105404 -58.252106)
		(width 0.127)
		(layer "In5.Cu")
		(net "XM_ADDR_1")
	)
	(segment
		(start 146.697192 -60.021724)
		(end 143.211042 -60.021724)
		(width 0.127)
		(layer "In5.Cu")
		(net "XM_ADDR_1")
	)
	(segment
		(start 131.629404 -59.098688)
		(end 131.629404 -58.252106)
		(width 0.127)
		(layer "In5.Cu")
		(net "XM_ADDR_1")
	)
	(segment
		(start 131.502404 -58.125106)
		(end 131.248404 -58.125106)
		(width 0.127)
		(layer "In5.Cu")
		(net "XM_ADDR_1")
	)
	(segment
		(start 134.642606 -59.098688)
		(end 134.515606 -59.225688)
		(width 0.127)
		(layer "In5.Cu")
		(net "XM_ADDR_1")
	)
	(segment
		(start 114.080036 -60.1599)
		(end 113.29924 -59.379104)
		(width 0.127)
		(layer "In5.Cu")
		(net "XM_ADDR_1")
	)
	(segment
		(start 129.597404 -59.098688)
		(end 129.597404 -58.252106)
		(width 0.127)
		(layer "In5.Cu")
		(net "XM_ADDR_1")
	)
	(segment
		(start 143.211042 -60.021724)
		(end 142.415006 -59.225688)
		(width 0.127)
		(layer "In5.Cu")
		(net "XM_ADDR_1")
	)
	(segment
		(start 111.416846 -59.379104)
		(end 111.026448 -58.988706)
		(width 0.127)
		(layer "In5.Cu")
		(net "XM_ADDR_1")
	)
	(segment
		(start 117.576346 -60.1599)
		(end 114.080036 -60.1599)
		(width 0.127)
		(layer "In5.Cu")
		(net "XM_ADDR_1")
	)
	(segment
		(start 133.626606 -58.252106)
		(end 133.626606 -59.098688)
		(width 0.127)
		(layer "In5.Cu")
		(net "XM_ADDR_1")
	)
	(segment
		(start 128.454404 -58.125106)
		(end 128.200404 -58.125106)
		(width 0.127)
		(layer "In5.Cu")
		(net "XM_ADDR_1")
	)
	(segment
		(start 131.629404 -58.252106)
		(end 131.502404 -58.125106)
		(width 0.127)
		(layer "In5.Cu")
		(net "XM_ADDR_1")
	)
	(segment
		(start 131.756404 -59.225688)
		(end 131.629404 -59.098688)
		(width 0.127)
		(layer "In5.Cu")
		(net "XM_ADDR_1")
	)
	(segment
		(start 128.708404 -59.225688)
		(end 128.581404 -59.098688)
		(width 0.127)
		(layer "In5.Cu")
		(net "XM_ADDR_1")
	)
	(segment
		(start 135.150606 -59.098688)
		(end 135.150606 -58.252106)
		(width 0.127)
		(layer "In5.Cu")
		(net "XM_ADDR_1")
	)
	(segment
		(start 128.581404 -59.098688)
		(end 128.581404 -58.252106)
		(width 0.127)
		(layer "In5.Cu")
		(net "XM_ADDR_1")
	)
	(segment
		(start 133.499606 -59.225688)
		(end 131.756404 -59.225688)
		(width 0.127)
		(layer "In5.Cu")
		(net "XM_ADDR_1")
	)
	(segment
		(start 113.29924 -59.379104)
		(end 111.416846 -59.379104)
		(width 0.127)
		(layer "In5.Cu")
		(net "XM_ADDR_1")
	)
	(segment
		(start 129.089404 -59.098688)
		(end 128.962404 -59.225688)
		(width 0.127)
		(layer "In5.Cu")
		(net "XM_ADDR_1")
	)
	(segment
		(start 128.962404 -59.225688)
		(end 128.708404 -59.225688)
		(width 0.127)
		(layer "In5.Cu")
		(net "XM_ADDR_1")
	)
	(segment
		(start 134.769606 -58.125106)
		(end 134.642606 -58.252106)
		(width 0.127)
		(layer "In5.Cu")
		(net "XM_ADDR_1")
	)
	(segment
		(start 128.073404 -59.098688)
		(end 127.946404 -59.225688)
		(width 0.127)
		(layer "In5.Cu")
		(net "XM_ADDR_1")
	)
	(segment
		(start 133.626606 -59.098688)
		(end 133.499606 -59.225688)
		(width 0.127)
		(layer "In5.Cu")
		(net "XM_ADDR_1")
	)
	(segment
		(start 147.776946 -59.7916)
		(end 146.927316 -59.7916)
		(width 0.127)
		(layer "In5.Cu")
		(net "XM_ADDR_1")
	)
	(segment
		(start 129.089404 -58.252106)
		(end 129.089404 -59.098688)
		(width 0.127)
		(layer "In5.Cu")
		(net "XM_ADDR_1")
	)
	(segment
		(start 130.613404 -59.098688)
		(end 130.613404 -58.252106)
		(width 0.127)
		(layer "In5.Cu")
		(net "XM_ADDR_1")
	)
	(segment
		(start 142.415006 -59.225688)
		(end 135.277606 -59.225688)
		(width 0.127)
		(layer "In5.Cu")
		(net "XM_ADDR_1")
	)
	(segment
		(start 131.121404 -59.098688)
		(end 130.994404 -59.225688)
		(width 0.127)
		(layer "In5.Cu")
		(net "XM_ADDR_1")
	)
	(segment
		(start 127.946404 -59.225688)
		(end 118.510558 -59.225688)
		(width 0.127)
		(layer "In5.Cu")
		(net "XM_ADDR_1")
	)
	(segment
		(start 129.216404 -58.125106)
		(end 129.089404 -58.252106)
		(width 0.127)
		(layer "In5.Cu")
		(net "XM_ADDR_1")
	)
	(segment
		(start 118.510558 -59.225688)
		(end 118.206012 -59.530488)
		(width 0.127)
		(layer "In5.Cu")
		(net "XM_ADDR_1")
	)
	(segment
		(start 130.105404 -59.098688)
		(end 129.978404 -59.225688)
		(width 0.127)
		(layer "In5.Cu")
		(net "XM_ADDR_1")
	)
	(segment
		(start 134.515606 -59.225688)
		(end 134.261606 -59.225688)
		(width 0.127)
		(layer "In5.Cu")
		(net "XM_ADDR_1")
	)
	(segment
		(start 93.164406 -37.4142)
		(end 93.27769 -37.4142)
		(width 0.1016)
		(layer "F.Cu")
		(net "3008_SAS_RX_P2")
	)
	(segment
		(start 93.363288 -37.391848)
		(end 93.378782 -37.391848)
		(width 0.1016)
		(layer "F.Cu")
		(net "3008_SAS_RX_P2")
	)
	(segment
		(start 134.371842 -84.497164)
		(end 134.458456 -84.41055)
		(width 0.1016)
		(layer "F.Cu")
		(net "3008_SAS_RX_P2")
	)
	(segment
		(start 93.150182 -37.399976)
		(end 93.164406 -37.4142)
		(width 0.1016)
		(layer "F.Cu")
		(net "3008_SAS_RX_P2")
	)
	(segment
		(start 93.296994 -37.41039)
		(end 93.327982 -37.398198)
		(width 0.1016)
		(layer "F.Cu")
		(net "3008_SAS_RX_P2")
	)
	(segment
		(start 135.2169 -83.814412)
		(end 135.2169 -83.011772)
		(width 0.1016)
		(layer "F.Cu")
		(net "3008_SAS_RX_P2")
	)
	(segment
		(start 93.378782 -37.391848)
		(end 93.526102 -37.244528)
		(width 0.1016)
		(layer "F.Cu")
		(net "3008_SAS_RX_P2")
	)
	(segment
		(start 93.52788 -37.228526)
		(end 93.547946 -37.141912)
		(width 0.1016)
		(layer "F.Cu")
		(net "3008_SAS_RX_P2")
	)
	(segment
		(start 135.246618 -82.93989)
		(end 135.509508 -82.677)
		(width 0.1016)
		(layer "F.Cu")
		(net "3008_SAS_RX_P2")
	)
	(segment
		(start 134.016242 -84.526882)
		(end 134.29996 -84.526882)
		(width 0.1016)
		(layer "F.Cu")
		(net "3008_SAS_RX_P2")
	)
	(segment
		(start 93.551756 -37.108384)
		(end 93.551756 -37.00272)
		(width 0.1016)
		(layer "F.Cu")
		(net "3008_SAS_RX_P2")
	)
	(segment
		(start 134.530338 -84.380832)
		(end 134.65048 -84.380832)
		(width 0.1016)
		(layer "F.Cu")
		(net "3008_SAS_RX_P2")
	)
	(via
		(at 135.509508 -82.677)
		(size 0.5588)
		(drill 0.3048)
		(layers "F.Cu" "B.Cu")
		(net "3008_SAS_RX_P2")
	)
	(via
		(at 93.551756 -37.00272)
		(size 0.508)
		(drill 0.254)
		(layers "F.Cu" "B.Cu")
		(net "3008_SAS_RX_P2")
	)
	(arc
		(start 93.526102 -37.244528)
		(mid 93.526533 -37.236476)
		(end 93.52788 -37.228526)
		(width 0.1016)
		(layer "F.Cu")
		(net "3008_SAS_RX_P2")
	)
	(arc
		(start 93.547946 -37.141912)
		(mid 93.550798 -37.125256)
		(end 93.551756 -37.108384)
		(width 0.1016)
		(layer "F.Cu")
		(net "3008_SAS_RX_P2")
	)
	(arc
		(start 134.29996 -84.526882)
		(mid 134.338855 -84.519163)
		(end 134.371842 -84.497164)
		(width 0.1016)
		(layer "F.Cu")
		(net "3008_SAS_RX_P2")
	)
	(arc
		(start 134.65048 -84.380832)
		(mid 135.050999 -84.214931)
		(end 135.2169 -83.814412)
		(width 0.1016)
		(layer "F.Cu")
		(net "3008_SAS_RX_P2")
	)
	(arc
		(start 93.27769 -37.4142)
		(mid 93.287525 -37.413219)
		(end 93.296994 -37.41039)
		(width 0.1016)
		(layer "F.Cu")
		(net "3008_SAS_RX_P2")
	)
	(arc
		(start 134.458456 -84.41055)
		(mid 134.49145 -84.388567)
		(end 134.530338 -84.380832)
		(width 0.1016)
		(layer "F.Cu")
		(net "3008_SAS_RX_P2")
	)
	(arc
		(start 135.2169 -83.011772)
		(mid 135.224619 -82.972877)
		(end 135.246618 -82.93989)
		(width 0.1016)
		(layer "F.Cu")
		(net "3008_SAS_RX_P2")
	)
	(arc
		(start 93.327982 -37.398198)
		(mid 93.345352 -37.393449)
		(end 93.363288 -37.391848)
		(width 0.1016)
		(layer "F.Cu")
		(net "3008_SAS_RX_P2")
	)
	(segment
		(start 87.179404 -42.497756)
		(end 89.603834 -40.073326)
		(width 0.1016)
		(layer "In5.Cu")
		(net "3008_SAS_RX_P2")
	)
	(segment
		(start 98.967544 -63.27394)
		(end 98.662744 -63.27394)
		(width 0.1016)
		(layer "In5.Cu")
		(net "3008_SAS_RX_P2")
	)
	(segment
		(start 108.288582 -65.637918)
		(end 108.07319 -65.422272)
		(width 0.1016)
		(layer "In5.Cu")
		(net "3008_SAS_RX_P2")
	)
	(segment
		(start 96.019112 -61.551566)
		(end 95.803466 -61.336174)
		(width 0.1016)
		(layer "In5.Cu")
		(net "3008_SAS_RX_P2")
	)
	(segment
		(start 91.19616 -37.378386)
		(end 91.19616 -37.378894)
		(width 0.1016)
		(layer "In5.Cu")
		(net "3008_SAS_RX_P2")
	)
	(segment
		(start 91.064334 -55.402734)
		(end 90.848688 -55.187088)
		(width 0.1016)
		(layer "In5.Cu")
		(net "3008_SAS_RX_P2")
	)
	(segment
		(start 93.878146 -59.4106)
		(end 93.6625 -59.195208)
		(width 0.1016)
		(layer "In5.Cu")
		(net "3008_SAS_RX_P2")
	)
	(segment
		(start 134.25932 -76.007468)
		(end 134.219188 -75.967082)
		(width 0.1016)
		(layer "In5.Cu")
		(net "3008_SAS_RX_P2")
	)
	(segment
		(start 91.059 -37.5158)
		(end 91.19616 -37.378386)
		(width 0.1016)
		(layer "In5.Cu")
		(net "3008_SAS_RX_P2")
	)
	(segment
		(start 92.630244 -58.162698)
		(end 92.414598 -57.947306)
		(width 0.1016)
		(layer "In5.Cu")
		(net "3008_SAS_RX_P2")
	)
	(segment
		(start 131.919726 -73.66762)
		(end 131.70408 -73.451974)
		(width 0.1016)
		(layer "In5.Cu")
		(net "3008_SAS_RX_P2")
	)
	(segment
		(start 135.29183 -82.58683)
		(end 135.255 -82.55)
		(width 0.1016)
		(layer "In5.Cu")
		(net "3008_SAS_RX_P2")
	)
	(segment
		(start 97.46488 -63.31712)
		(end 96.178878 -62.031118)
		(width 0.1016)
		(layer "In5.Cu")
		(net "3008_SAS_RX_P2")
	)
	(segment
		(start 95.323914 -61.176154)
		(end 95.108268 -60.960508)
		(width 0.1016)
		(layer "In5.Cu")
		(net "3008_SAS_RX_P2")
	)
	(segment
		(start 132.61467 -74.042778)
		(end 132.399278 -73.827386)
		(width 0.1016)
		(layer "In5.Cu")
		(net "3008_SAS_RX_P2")
	)
	(segment
		(start 122.542046 -70.331076)
		(end 122.053858 -69.842888)
		(width 0.1016)
		(layer "In5.Cu")
		(net "3008_SAS_RX_P2")
	)
	(segment
		(start 89.922858 -39.303198)
		(end 89.922858 -38.975792)
		(width 0.1016)
		(layer "In5.Cu")
		(net "3008_SAS_RX_P2")
	)
	(segment
		(start 107.593638 -65.262506)
		(end 107.377992 -65.04686)
		(width 0.1016)
		(layer "In5.Cu")
		(net "3008_SAS_RX_P2")
	)
	(segment
		(start 89.993978 -54.332378)
		(end 88.29802 -52.63642)
		(width 0.1016)
		(layer "In5.Cu")
		(net "3008_SAS_RX_P2")
	)
	(segment
		(start 127.74422 -70.3834)
		(end 122.66803 -70.3834)
		(width 0.1016)
		(layer "In5.Cu")
		(net "3008_SAS_RX_P2")
	)
	(segment
		(start 102.945438 -63.5)
		(end 99.419664 -63.5)
		(width 0.1016)
		(layer "In5.Cu")
		(net "3008_SAS_RX_P2")
	)
	(segment
		(start 105.156254 -63.5)
		(end 104.154478 -63.5)
		(width 0.1016)
		(layer "In5.Cu")
		(net "3008_SAS_RX_P2")
	)
	(segment
		(start 103.702358 -63.27394)
		(end 103.397558 -63.27394)
		(width 0.1016)
		(layer "In5.Cu")
		(net "3008_SAS_RX_P2")
	)
	(segment
		(start 111.335566 -69.004434)
		(end 111.11992 -68.788788)
		(width 0.1016)
		(layer "In5.Cu")
		(net "3008_SAS_RX_P2")
	)
	(segment
		(start 134.219188 -75.967082)
		(end 133.845046 -75.59294)
		(width 0.1016)
		(layer "In5.Cu")
		(net "3008_SAS_RX_P2")
	)
	(segment
		(start 93.182948 -59.035188)
		(end 92.79001 -58.64225)
		(width 0.1016)
		(layer "In5.Cu")
		(net "3008_SAS_RX_P2")
	)
	(segment
		(start 110.26521 -67.934078)
		(end 108.448602 -66.11747)
		(width 0.1016)
		(layer "In5.Cu")
		(net "3008_SAS_RX_P2")
	)
	(segment
		(start 90.688922 -54.707536)
		(end 90.47353 -54.492144)
		(width 0.1016)
		(layer "In5.Cu")
		(net "3008_SAS_RX_P2")
	)
	(segment
		(start 91.935046 -57.787286)
		(end 91.678506 -57.530746)
		(width 0.1016)
		(layer "In5.Cu")
		(net "3008_SAS_RX_P2")
	)
	(segment
		(start 106.523282 -64.19215)
		(end 106.307636 -63.976504)
		(width 0.1016)
		(layer "In5.Cu")
		(net "3008_SAS_RX_P2")
	)
	(segment
		(start 91.541854 -57.2008)
		(end 91.5416 -57.201054)
		(width 0.1016)
		(layer "In5.Cu")
		(net "3008_SAS_RX_P2")
	)
	(segment
		(start 135.128 -82.243422)
		(end 135.128 -78.104746)
		(width 0.1016)
		(layer "In5.Cu")
		(net "3008_SAS_RX_P2")
	)
	(segment
		(start 90.151966 -38.423088)
		(end 91.059 -37.5158)
		(width 0.1016)
		(layer "In5.Cu")
		(net "3008_SAS_RX_P2")
	)
	(segment
		(start 133.685026 -75.113388)
		(end 133.469634 -74.897742)
		(width 0.1016)
		(layer "In5.Cu")
		(net "3008_SAS_RX_P2")
	)
	(segment
		(start 91.647518 -37.1348)
		(end 92.5449 -37.1348)
		(width 0.1016)
		(layer "In5.Cu")
		(net "3008_SAS_RX_P2")
	)
	(segment
		(start 91.5416 -57.201054)
		(end 91.5416 -56.55564)
		(width 0.1016)
		(layer "In5.Cu")
		(net "3008_SAS_RX_P2")
	)
	(segment
		(start 107.218226 -64.567308)
		(end 107.002834 -64.351916)
		(width 0.1016)
		(layer "In5.Cu")
		(net "3008_SAS_RX_P2")
	)
	(segment
		(start 132.990082 -74.737976)
		(end 132.774436 -74.52233)
		(width 0.1016)
		(layer "In5.Cu")
		(net "3008_SAS_RX_P2")
	)
	(segment
		(start 130.849116 -72.59701)
		(end 129.26568 -71.013574)
		(width 0.1016)
		(layer "In5.Cu")
		(net "3008_SAS_RX_P2")
	)
	(segment
		(start 110.960154 -68.309236)
		(end 110.744762 -68.093844)
		(width 0.1016)
		(layer "In5.Cu")
		(net "3008_SAS_RX_P2")
	)
	(segment
		(start 120.905778 -69.3674)
		(end 112.211358 -69.3674)
		(width 0.1016)
		(layer "In5.Cu")
		(net "3008_SAS_RX_P2")
	)
	(segment
		(start 91.19616 -37.378894)
		(end 91.292934 -37.281866)
		(width 0.1016)
		(layer "In5.Cu")
		(net "3008_SAS_RX_P2")
	)
	(segment
		(start 98.210624 -63.5)
		(end 97.905824 -63.5)
		(width 0.1016)
		(layer "In5.Cu")
		(net "3008_SAS_RX_P2")
	)
	(segment
		(start 94.948502 -60.480956)
		(end 94.73311 -60.265564)
		(width 0.1016)
		(layer "In5.Cu")
		(net "3008_SAS_RX_P2")
	)
	(segment
		(start 94.253558 -60.105798)
		(end 94.037912 -59.890152)
		(width 0.1016)
		(layer "In5.Cu")
		(net "3008_SAS_RX_P2")
	)
	(segment
		(start 93.048582 -36.953444)
		(end 93.432884 -36.953444)
		(width 0.1016)
		(layer "In5.Cu")
		(net "3008_SAS_RX_P2")
	)
	(segment
		(start 131.544314 -72.972422)
		(end 131.328668 -72.75703)
		(width 0.1016)
		(layer "In5.Cu")
		(net "3008_SAS_RX_P2")
	)
	(segment
		(start 87.12708 -49.8094)
		(end 87.12708 -42.62374)
		(width 0.1016)
		(layer "In5.Cu")
		(net "3008_SAS_RX_P2")
	)
	(arc
		(start 93.432884 -36.953444)
		(mid 93.497231 -36.966244)
		(end 93.551756 -37.00272)
		(width 0.1016)
		(layer "In5.Cu")
		(net "3008_SAS_RX_P2")
	)
	(arc
		(start 108.368592 -65.877694)
		(mid 108.357542 -65.748149)
		(end 108.288582 -65.637918)
		(width 0.1016)
		(layer "In5.Cu")
		(net "3008_SAS_RX_P2")
	)
	(arc
		(start 122.66803 -70.3834)
		(mid 122.599848 -70.369744)
		(end 122.542046 -70.331076)
		(width 0.1016)
		(layer "In5.Cu")
		(net "3008_SAS_RX_P2")
	)
	(arc
		(start 106.763058 -64.271906)
		(mid 106.633536 -64.260989)
		(end 106.523282 -64.19215)
		(width 0.1016)
		(layer "In5.Cu")
		(net "3008_SAS_RX_P2")
	)
	(arc
		(start 92.710254 -58.402474)
		(mid 92.699211 -58.272917)
		(end 92.630244 -58.162698)
		(width 0.1016)
		(layer "In5.Cu")
		(net "3008_SAS_RX_P2")
	)
	(arc
		(start 104.154478 -63.5)
		(mid 104.027817 -63.470761)
		(end 103.928418 -63.38697)
		(width 0.1016)
		(layer "In5.Cu")
		(net "3008_SAS_RX_P2")
	)
	(arc
		(start 90.768932 -54.947312)
		(mid 90.757889 -54.817755)
		(end 90.688922 -54.707536)
		(width 0.1016)
		(layer "In5.Cu")
		(net "3008_SAS_RX_P2")
	)
	(arc
		(start 89.922858 -38.975792)
		(mid 89.982453 -38.676659)
		(end 90.151966 -38.423088)
		(width 0.1016)
		(layer "In5.Cu")
		(net "3008_SAS_RX_P2")
	)
	(arc
		(start 107.002834 -64.351916)
		(mid 106.892604 -64.282982)
		(end 106.763058 -64.271906)
		(width 0.1016)
		(layer "In5.Cu")
		(net "3008_SAS_RX_P2")
	)
	(arc
		(start 95.803466 -61.336174)
		(mid 95.693247 -61.267177)
		(end 95.56369 -61.256164)
		(width 0.1016)
		(layer "In5.Cu")
		(net "3008_SAS_RX_P2")
	)
	(arc
		(start 107.833414 -65.342516)
		(mid 107.703857 -65.331473)
		(end 107.593638 -65.262506)
		(width 0.1016)
		(layer "In5.Cu")
		(net "3008_SAS_RX_P2")
	)
	(arc
		(start 96.098868 -61.791342)
		(mid 96.087951 -61.66182)
		(end 96.019112 -61.551566)
		(width 0.1016)
		(layer "In5.Cu")
		(net "3008_SAS_RX_P2")
	)
	(arc
		(start 111.040164 -68.549012)
		(mid 111.029121 -68.419455)
		(end 110.960154 -68.309236)
		(width 0.1016)
		(layer "In5.Cu")
		(net "3008_SAS_RX_P2")
	)
	(arc
		(start 111.11992 -68.788788)
		(mid 111.051084 -68.678533)
		(end 111.040164 -68.549012)
		(width 0.1016)
		(layer "In5.Cu")
		(net "3008_SAS_RX_P2")
	)
	(arc
		(start 108.448602 -66.11747)
		(mid 108.379605 -66.007251)
		(end 108.368592 -65.877694)
		(width 0.1016)
		(layer "In5.Cu")
		(net "3008_SAS_RX_P2")
	)
	(arc
		(start 94.493334 -60.185554)
		(mid 94.363812 -60.174637)
		(end 94.253558 -60.105798)
		(width 0.1016)
		(layer "In5.Cu")
		(net "3008_SAS_RX_P2")
	)
	(arc
		(start 135.255 -82.55)
		(mid 135.161015 -82.409341)
		(end 135.128 -82.243422)
		(width 0.1016)
		(layer "In5.Cu")
		(net "3008_SAS_RX_P2")
	)
	(arc
		(start 93.957902 -59.650376)
		(mid 93.946985 -59.520854)
		(end 93.878146 -59.4106)
		(width 0.1016)
		(layer "In5.Cu")
		(net "3008_SAS_RX_P2")
	)
	(arc
		(start 131.70408 -73.451974)
		(mid 131.635146 -73.341744)
		(end 131.62407 -73.212198)
		(width 0.1016)
		(layer "In5.Cu")
		(net "3008_SAS_RX_P2")
	)
	(arc
		(start 95.56369 -61.256164)
		(mid 95.434145 -61.245114)
		(end 95.323914 -61.176154)
		(width 0.1016)
		(layer "In5.Cu")
		(net "3008_SAS_RX_P2")
	)
	(arc
		(start 89.603834 -40.073326)
		(mid 89.839927 -39.719988)
		(end 89.922858 -39.303198)
		(width 0.1016)
		(layer "In5.Cu")
		(net "3008_SAS_RX_P2")
	)
	(arc
		(start 90.848688 -55.187088)
		(mid 90.779852 -55.076833)
		(end 90.768932 -54.947312)
		(width 0.1016)
		(layer "In5.Cu")
		(net "3008_SAS_RX_P2")
	)
	(arc
		(start 110.744762 -68.093844)
		(mid 110.634532 -68.02491)
		(end 110.504986 -68.013834)
		(width 0.1016)
		(layer "In5.Cu")
		(net "3008_SAS_RX_P2")
	)
	(arc
		(start 88.29802 -52.63642)
		(mid 87.431414 -51.339358)
		(end 87.12708 -49.8094)
		(width 0.1016)
		(layer "In5.Cu")
		(net "3008_SAS_RX_P2")
	)
	(arc
		(start 131.088892 -72.67702)
		(mid 130.959347 -72.66597)
		(end 130.849116 -72.59701)
		(width 0.1016)
		(layer "In5.Cu")
		(net "3008_SAS_RX_P2")
	)
	(arc
		(start 94.73311 -60.265564)
		(mid 94.62288 -60.19663)
		(end 94.493334 -60.185554)
		(width 0.1016)
		(layer "In5.Cu")
		(net "3008_SAS_RX_P2")
	)
	(arc
		(start 106.307636 -63.976504)
		(mid 105.779332 -63.623782)
		(end 105.156254 -63.5)
		(width 0.1016)
		(layer "In5.Cu")
		(net "3008_SAS_RX_P2")
	)
	(arc
		(start 98.662744 -63.27394)
		(mid 98.536083 -63.303179)
		(end 98.436684 -63.38697)
		(width 0.1016)
		(layer "In5.Cu")
		(net "3008_SAS_RX_P2")
	)
	(arc
		(start 131.328668 -72.75703)
		(mid 131.218449 -72.688033)
		(end 131.088892 -72.67702)
		(width 0.1016)
		(layer "In5.Cu")
		(net "3008_SAS_RX_P2")
	)
	(arc
		(start 112.211358 -69.3674)
		(mid 111.737334 -69.273075)
		(end 111.335566 -69.004434)
		(width 0.1016)
		(layer "In5.Cu")
		(net "3008_SAS_RX_P2")
	)
	(arc
		(start 110.504986 -68.013834)
		(mid 110.375464 -68.002917)
		(end 110.26521 -67.934078)
		(width 0.1016)
		(layer "In5.Cu")
		(net "3008_SAS_RX_P2")
	)
	(arc
		(start 93.422724 -59.115198)
		(mid 93.293179 -59.104148)
		(end 93.182948 -59.035188)
		(width 0.1016)
		(layer "In5.Cu")
		(net "3008_SAS_RX_P2")
	)
	(arc
		(start 91.5416 -56.55564)
		(mid 91.417609 -55.931732)
		(end 91.064334 -55.402734)
		(width 0.1016)
		(layer "In5.Cu")
		(net "3008_SAS_RX_P2")
	)
	(arc
		(start 103.928418 -63.38697)
		(mid 103.829042 -63.303133)
		(end 103.702358 -63.27394)
		(width 0.1016)
		(layer "In5.Cu")
		(net "3008_SAS_RX_P2")
	)
	(arc
		(start 95.028512 -60.720732)
		(mid 95.017469 -60.591175)
		(end 94.948502 -60.480956)
		(width 0.1016)
		(layer "In5.Cu")
		(net "3008_SAS_RX_P2")
	)
	(arc
		(start 91.292934 -37.281866)
		(mid 91.45559 -37.173056)
		(end 91.647518 -37.1348)
		(width 0.1016)
		(layer "In5.Cu")
		(net "3008_SAS_RX_P2")
	)
	(arc
		(start 90.233754 -54.412134)
		(mid 90.104232 -54.401217)
		(end 89.993978 -54.332378)
		(width 0.1016)
		(layer "In5.Cu")
		(net "3008_SAS_RX_P2")
	)
	(arc
		(start 96.178878 -62.031118)
		(mid 96.109944 -61.920888)
		(end 96.098868 -61.791342)
		(width 0.1016)
		(layer "In5.Cu")
		(net "3008_SAS_RX_P2")
	)
	(arc
		(start 133.229858 -74.817986)
		(mid 133.100301 -74.806943)
		(end 132.990082 -74.737976)
		(width 0.1016)
		(layer "In5.Cu")
		(net "3008_SAS_RX_P2")
	)
	(arc
		(start 87.12708 -42.62374)
		(mid 87.140736 -42.555558)
		(end 87.179404 -42.497756)
		(width 0.1016)
		(layer "In5.Cu")
		(net "3008_SAS_RX_P2")
	)
	(arc
		(start 92.174822 -57.867296)
		(mid 92.045277 -57.856246)
		(end 91.935046 -57.787286)
		(width 0.1016)
		(layer "In5.Cu")
		(net "3008_SAS_RX_P2")
	)
	(arc
		(start 103.171498 -63.38697)
		(mid 103.072122 -63.470807)
		(end 102.945438 -63.5)
		(width 0.1016)
		(layer "In5.Cu")
		(net "3008_SAS_RX_P2")
	)
	(arc
		(start 132.399278 -73.827386)
		(mid 132.289048 -73.758452)
		(end 132.159502 -73.747376)
		(width 0.1016)
		(layer "In5.Cu")
		(net "3008_SAS_RX_P2")
	)
	(arc
		(start 107.377992 -65.04686)
		(mid 107.309156 -64.936605)
		(end 107.298236 -64.807084)
		(width 0.1016)
		(layer "In5.Cu")
		(net "3008_SAS_RX_P2")
	)
	(arc
		(start 92.414598 -57.947306)
		(mid 92.304379 -57.878309)
		(end 92.174822 -57.867296)
		(width 0.1016)
		(layer "In5.Cu")
		(net "3008_SAS_RX_P2")
	)
	(arc
		(start 99.419664 -63.5)
		(mid 99.293003 -63.470761)
		(end 99.193604 -63.38697)
		(width 0.1016)
		(layer "In5.Cu")
		(net "3008_SAS_RX_P2")
	)
	(arc
		(start 135.509508 -82.677)
		(mid 135.3917 -82.653566)
		(end 135.29183 -82.58683)
		(width 0.1016)
		(layer "In5.Cu")
		(net "3008_SAS_RX_P2")
	)
	(arc
		(start 97.905824 -63.5)
		(mid 97.667165 -63.452416)
		(end 97.46488 -63.31712)
		(width 0.1016)
		(layer "In5.Cu")
		(net "3008_SAS_RX_P2")
	)
	(arc
		(start 132.774436 -74.52233)
		(mid 132.7056 -74.412075)
		(end 132.69468 -74.282554)
		(width 0.1016)
		(layer "In5.Cu")
		(net "3008_SAS_RX_P2")
	)
	(arc
		(start 107.298236 -64.807084)
		(mid 107.287193 -64.677527)
		(end 107.218226 -64.567308)
		(width 0.1016)
		(layer "In5.Cu")
		(net "3008_SAS_RX_P2")
	)
	(arc
		(start 131.62407 -73.212198)
		(mid 131.613153 -73.082676)
		(end 131.544314 -72.972422)
		(width 0.1016)
		(layer "In5.Cu")
		(net "3008_SAS_RX_P2")
	)
	(arc
		(start 133.765036 -75.353164)
		(mid 133.753986 -75.223619)
		(end 133.685026 -75.113388)
		(width 0.1016)
		(layer "In5.Cu")
		(net "3008_SAS_RX_P2")
	)
	(arc
		(start 99.193604 -63.38697)
		(mid 99.094228 -63.303133)
		(end 98.967544 -63.27394)
		(width 0.1016)
		(layer "In5.Cu")
		(net "3008_SAS_RX_P2")
	)
	(arc
		(start 135.128 -78.104746)
		(mid 134.902207 -76.96972)
		(end 134.25932 -76.007468)
		(width 0.1016)
		(layer "In5.Cu")
		(net "3008_SAS_RX_P2")
	)
	(arc
		(start 108.07319 -65.422272)
		(mid 107.962935 -65.353436)
		(end 107.833414 -65.342516)
		(width 0.1016)
		(layer "In5.Cu")
		(net "3008_SAS_RX_P2")
	)
	(arc
		(start 95.108268 -60.960508)
		(mid 95.039432 -60.850253)
		(end 95.028512 -60.720732)
		(width 0.1016)
		(layer "In5.Cu")
		(net "3008_SAS_RX_P2")
	)
	(arc
		(start 90.47353 -54.492144)
		(mid 90.3633 -54.42321)
		(end 90.233754 -54.412134)
		(width 0.1016)
		(layer "In5.Cu")
		(net "3008_SAS_RX_P2")
	)
	(arc
		(start 94.037912 -59.890152)
		(mid 93.968978 -59.779922)
		(end 93.957902 -59.650376)
		(width 0.1016)
		(layer "In5.Cu")
		(net "3008_SAS_RX_P2")
	)
	(arc
		(start 103.397558 -63.27394)
		(mid 103.270897 -63.303179)
		(end 103.171498 -63.38697)
		(width 0.1016)
		(layer "In5.Cu")
		(net "3008_SAS_RX_P2")
	)
	(arc
		(start 92.79001 -58.64225)
		(mid 92.721174 -58.531995)
		(end 92.710254 -58.402474)
		(width 0.1016)
		(layer "In5.Cu")
		(net "3008_SAS_RX_P2")
	)
	(arc
		(start 132.69468 -74.282554)
		(mid 132.683637 -74.152997)
		(end 132.61467 -74.042778)
		(width 0.1016)
		(layer "In5.Cu")
		(net "3008_SAS_RX_P2")
	)
	(arc
		(start 92.5449 -37.1348)
		(mid 92.812549 -37.088032)
		(end 93.048582 -36.953444)
		(width 0.1016)
		(layer "In5.Cu")
		(net "3008_SAS_RX_P2")
	)
	(arc
		(start 129.26568 -71.013574)
		(mid 128.567627 -70.54718)
		(end 127.74422 -70.3834)
		(width 0.1016)
		(layer "In5.Cu")
		(net "3008_SAS_RX_P2")
	)
	(arc
		(start 132.159502 -73.747376)
		(mid 132.02998 -73.736459)
		(end 131.919726 -73.66762)
		(width 0.1016)
		(layer "In5.Cu")
		(net "3008_SAS_RX_P2")
	)
	(arc
		(start 91.678506 -57.530746)
		(mid 91.577357 -57.379365)
		(end 91.541854 -57.2008)
		(width 0.1016)
		(layer "In5.Cu")
		(net "3008_SAS_RX_P2")
	)
	(arc
		(start 133.845046 -75.59294)
		(mid 133.776049 -75.482721)
		(end 133.765036 -75.353164)
		(width 0.1016)
		(layer "In5.Cu")
		(net "3008_SAS_RX_P2")
	)
	(arc
		(start 122.053858 -69.842888)
		(mid 121.527101 -69.490954)
		(end 120.905778 -69.3674)
		(width 0.1016)
		(layer "In5.Cu")
		(net "3008_SAS_RX_P2")
	)
	(arc
		(start 98.436684 -63.38697)
		(mid 98.337308 -63.470807)
		(end 98.210624 -63.5)
		(width 0.1016)
		(layer "In5.Cu")
		(net "3008_SAS_RX_P2")
	)
	(arc
		(start 133.469634 -74.897742)
		(mid 133.359379 -74.828906)
		(end 133.229858 -74.817986)
		(width 0.1016)
		(layer "In5.Cu")
		(net "3008_SAS_RX_P2")
	)
	(arc
		(start 93.6625 -59.195208)
		(mid 93.552281 -59.126211)
		(end 93.422724 -59.115198)
		(width 0.1016)
		(layer "In5.Cu")
		(net "3008_SAS_RX_P2")
	)
	(segment
		(start 219.8878 -120.5992)
		(end 220.7895 -119.6975)
		(width 0.127)
		(layer "F.Cu")
		(net "P3V3_STBY_R3")
	)
	(segment
		(start 220.7895 -118.745)
		(end 220.7895 -119.6975)
		(width 0.127)
		(layer "F.Cu")
		(net "P3V3_STBY_R3")
	)
	(segment
		(start 221.9325 -118.745)
		(end 220.7895 -118.745)
		(width 0.127)
		(layer "F.Cu")
		(net "P3V3_STBY_R3")
	)
	(segment
		(start 219.8878 -121.158)
		(end 219.8878 -120.5992)
		(width 0.127)
		(layer "F.Cu")
		(net "P3V3_STBY_R3")
	)
	(via
		(at 220.7895 -119.6975)
		(size 0.7112)
		(drill 0.3556)
		(layers "F.Cu" "B.Cu")
		(net "P3V3_STBY_R3")
	)
	(segment
		(start 83.693 -22.25675)
		(end 83.693 -22.86)
		(width 0.254)
		(layer "F.Cu")
		(net "VT235_VREF")
	)
	(segment
		(start 83.82 -23.5585)
		(end 83.82 -22.987)
		(width 0.254)
		(layer "F.Cu")
		(net "VT235_VREF")
	)
	(segment
		(start 83.439 -23.9395)
		(end 83.82 -23.5585)
		(width 0.254)
		(layer "F.Cu")
		(net "VT235_VREF")
	)
	(segment
		(start 83.53425 -21.255228)
		(end 83.53425 -22.098)
		(width 0.254)
		(layer "F.Cu")
		(net "VT235_VREF")
	)
	(segment
		(start 85.598 -24.8285)
		(end 84.582 -24.8285)
		(width 0.254)
		(layer "F.Cu")
		(net "VT235_VREF")
	)
	(segment
		(start 82.3595 -23.749)
		(end 83.2485 -23.749)
		(width 0.254)
		(layer "F.Cu")
		(net "VT235_VREF")
	)
	(segment
		(start 84.3915 -24.8285)
		(end 84.582 -24.8285)
		(width 0.254)
		(layer "F.Cu")
		(net "VT235_VREF")
	)
	(segment
		(start 83.53425 -22.098)
		(end 83.693 -22.25675)
		(width 0.254)
		(layer "F.Cu")
		(net "VT235_VREF")
	)
	(segment
		(start 83.2485 -23.749)
		(end 83.439 -23.9395)
		(width 0.254)
		(layer "F.Cu")
		(net "VT235_VREF")
	)
	(segment
		(start 83.5025 -23.9395)
		(end 84.3915 -24.8285)
		(width 0.254)
		(layer "F.Cu")
		(net "VT235_VREF")
	)
	(segment
		(start 83.439 -23.9395)
		(end 83.5025 -23.9395)
		(width 0.254)
		(layer "F.Cu")
		(net "VT235_VREF")
	)
	(segment
		(start 83.693 -22.86)
		(end 83.82 -22.987)
		(width 0.254)
		(layer "F.Cu")
		(net "VT235_VREF")
	)
	(via
		(at 83.82 -22.987)
		(size 0.7112)
		(drill 0.3556)
		(layers "F.Cu" "B.Cu")
		(net "VT235_VREF")
	)
	(segment
		(start 93.551756 -36.19627)
		(end 93.541342 -36.19627)
		(width 0.1016)
		(layer "F.Cu")
		(net "3008_SAS_RX_P1")
	)
	(segment
		(start 132.847842 -83.100164)
		(end 132.934456 -83.01355)
		(width 0.1016)
		(layer "F.Cu")
		(net "3008_SAS_RX_P1")
	)
	(segment
		(start 133.595618 -81.380076)
		(end 133.858508 -81.117186)
		(width 0.1016)
		(layer "F.Cu")
		(net "3008_SAS_RX_P1")
	)
	(segment
		(start 133.5659 -82.544412)
		(end 133.5659 -81.451958)
		(width 0.1016)
		(layer "F.Cu")
		(net "3008_SAS_RX_P1")
	)
	(segment
		(start 132.492242 -83.129882)
		(end 132.77596 -83.129882)
		(width 0.1016)
		(layer "F.Cu")
		(net "3008_SAS_RX_P1")
	)
	(segment
		(start 93.150182 -35.80511)
		(end 93.150182 -35.80003)
		(width 0.1016)
		(layer "F.Cu")
		(net "3008_SAS_RX_P1")
	)
	(segment
		(start 93.541342 -36.19627)
		(end 93.150182 -35.80511)
		(width 0.1016)
		(layer "F.Cu")
		(net "3008_SAS_RX_P1")
	)
	(segment
		(start 133.006338 -82.983832)
		(end 133.12648 -82.983832)
		(width 0.1016)
		(layer "F.Cu")
		(net "3008_SAS_RX_P1")
	)
	(via
		(at 93.551756 -36.19627)
		(size 0.508)
		(drill 0.254)
		(layers "F.Cu" "B.Cu")
		(net "3008_SAS_RX_P1")
	)
	(via
		(at 133.858508 -81.117186)
		(size 0.5588)
		(drill 0.3048)
		(layers "F.Cu" "B.Cu")
		(net "3008_SAS_RX_P1")
	)
	(arc
		(start 133.12648 -82.983832)
		(mid 133.437197 -82.855129)
		(end 133.5659 -82.544412)
		(width 0.1016)
		(layer "F.Cu")
		(net "3008_SAS_RX_P1")
	)
	(arc
		(start 132.77596 -83.129882)
		(mid 132.814855 -83.122163)
		(end 132.847842 -83.100164)
		(width 0.1016)
		(layer "F.Cu")
		(net "3008_SAS_RX_P1")
	)
	(arc
		(start 133.5659 -81.451958)
		(mid 133.573619 -81.413063)
		(end 133.595618 -81.380076)
		(width 0.1016)
		(layer "F.Cu")
		(net "3008_SAS_RX_P1")
	)
	(arc
		(start 132.934456 -83.01355)
		(mid 132.96745 -82.991567)
		(end 133.006338 -82.983832)
		(width 0.1016)
		(layer "F.Cu")
		(net "3008_SAS_RX_P1")
	)
	(segment
		(start 121.358406 -71.55434)
		(end 121.839228 -72.035162)
		(width 0.1016)
		(layer "In5.Cu")
		(net "3008_SAS_RX_P1")
	)
	(segment
		(start 85.628226 -47.953676)
		(end 85.628226 -48.258476)
		(width 0.1016)
		(layer "In5.Cu")
		(net "3008_SAS_RX_P1")
	)
	(segment
		(start 93.551756 -36.16579)
		(end 93.219016 -35.833304)
		(width 0.1016)
		(layer "In5.Cu")
		(net "3008_SAS_RX_P1")
	)
	(segment
		(start 91.087448 -35.846004)
		(end 90.222832 -36.71062)
		(width 0.1016)
		(layer "In5.Cu")
		(net "3008_SAS_RX_P1")
	)
	(segment
		(start 85.402166 -45.682916)
		(end 85.402166 -45.987716)
		(width 0.1016)
		(layer "In5.Cu")
		(net "3008_SAS_RX_P1")
	)
	(segment
		(start 105.731818 -65.808098)
		(end 105.748836 -65.824862)
		(width 0.1016)
		(layer "In5.Cu")
		(net "3008_SAS_RX_P1")
	)
	(segment
		(start 111.884968 -71.12)
		(end 120.309132 -71.12)
		(width 0.1016)
		(layer "In5.Cu")
		(net "3008_SAS_RX_P1")
	)
	(segment
		(start 93.194886 -61.530484)
		(end 93.410532 -61.745876)
		(width 0.1016)
		(layer "In5.Cu")
		(net "3008_SAS_RX_P1")
	)
	(segment
		(start 85.628226 -44.925996)
		(end 85.628226 -45.230796)
		(width 0.1016)
		(layer "In5.Cu")
		(net "3008_SAS_RX_P1")
	)
	(segment
		(start 85.402166 -41.873932)
		(end 85.402166 -44.473876)
		(width 0.1016)
		(layer "In5.Cu")
		(net "3008_SAS_RX_P1")
	)
	(segment
		(start 133.664198 -80.922622)
		(end 133.858508 -81.117186)
		(width 0.1016)
		(layer "In5.Cu")
		(net "3008_SAS_RX_P1")
	)
	(segment
		(start 85.801708 -54.456584)
		(end 87.630508 -56.285638)
		(width 0.1016)
		(layer "In5.Cu")
		(net "3008_SAS_RX_P1")
	)
	(segment
		(start 105.748836 -65.824862)
		(end 110.44936 -70.525386)
		(width 0.1016)
		(layer "In5.Cu")
		(net "3008_SAS_RX_P1")
	)
	(segment
		(start 93.570298 -62.225428)
		(end 93.785944 -62.441074)
		(width 0.1016)
		(layer "In5.Cu")
		(net "3008_SAS_RX_P1")
	)
	(segment
		(start 87.9221 -39.331138)
		(end 87.706708 -39.54653)
		(width 0.1016)
		(layer "In5.Cu")
		(net "3008_SAS_RX_P1")
	)
	(segment
		(start 89.367868 -37.565584)
		(end 88.081866 -38.851586)
		(width 0.1016)
		(layer "In5.Cu")
		(net "3008_SAS_RX_P1")
	)
	(segment
		(start 85.402166 -48.710596)
		(end 85.402166 -53.4924)
		(width 0.1016)
		(layer "In5.Cu")
		(net "3008_SAS_RX_P1")
	)
	(segment
		(start 90.063066 -37.190172)
		(end 89.84742 -37.405564)
		(width 0.1016)
		(layer "In5.Cu")
		(net "3008_SAS_RX_P1")
	)
	(segment
		(start 97.5106 -65.2018)
		(end 104.267254 -65.2018)
		(width 0.1016)
		(layer "In5.Cu")
		(net "3008_SAS_RX_P1")
	)
	(segment
		(start 121.959878 -72.0852)
		(end 126.651766 -72.0852)
		(width 0.1016)
		(layer "In5.Cu")
		(net "3008_SAS_RX_P1")
	)
	(segment
		(start 133.55955 -78.867)
		(end 133.55955 -80.6704)
		(width 0.1016)
		(layer "In5.Cu")
		(net "3008_SAS_RX_P1")
	)
	(segment
		(start 87.630508 -56.285638)
		(end 92.715334 -61.370464)
		(width 0.1016)
		(layer "In5.Cu")
		(net "3008_SAS_RX_P1")
	)
	(segment
		(start 93.123766 -35.79368)
		(end 91.213178 -35.79368)
		(width 0.1016)
		(layer "In5.Cu")
		(net "3008_SAS_RX_P1")
	)
	(segment
		(start 94.265496 -62.60084)
		(end 94.480888 -62.816486)
		(width 0.1016)
		(layer "In5.Cu")
		(net "3008_SAS_RX_P1")
	)
	(segment
		(start 85.402166 -47.196756)
		(end 85.402166 -47.501556)
		(width 0.1016)
		(layer "In5.Cu")
		(net "3008_SAS_RX_P1")
	)
	(segment
		(start 128.460246 -72.834246)
		(end 132.899658 -77.273658)
		(width 0.1016)
		(layer "In5.Cu")
		(net "3008_SAS_RX_P1")
	)
	(segment
		(start 93.551756 -36.19627)
		(end 93.551756 -36.16579)
		(width 0.1016)
		(layer "In5.Cu")
		(net "3008_SAS_RX_P1")
	)
	(segment
		(start 85.628226 -46.439836)
		(end 85.628226 -46.744636)
		(width 0.1016)
		(layer "In5.Cu")
		(net "3008_SAS_RX_P1")
	)
	(segment
		(start 87.227156 -39.706296)
		(end 85.644482 -41.28897)
		(width 0.1016)
		(layer "In5.Cu")
		(net "3008_SAS_RX_P1")
	)
	(segment
		(start 94.640908 -63.296038)
		(end 95.822008 -64.477138)
		(width 0.1016)
		(layer "In5.Cu")
		(net "3008_SAS_RX_P1")
	)
	(segment
		(start 95.822008 -64.477138)
		(end 95.864934 -64.520318)
		(width 0.1016)
		(layer "In5.Cu")
		(net "3008_SAS_RX_P1")
	)
	(arc
		(start 94.480888 -62.816486)
		(mid 94.549885 -62.926705)
		(end 94.560898 -63.056262)
		(width 0.1016)
		(layer "In5.Cu")
		(net "3008_SAS_RX_P1")
	)
	(arc
		(start 85.402166 -44.473876)
		(mid 85.431405 -44.600537)
		(end 85.515196 -44.699936)
		(width 0.1016)
		(layer "In5.Cu")
		(net "3008_SAS_RX_P1")
	)
	(arc
		(start 85.628226 -48.258476)
		(mid 85.598987 -48.385137)
		(end 85.515196 -48.484536)
		(width 0.1016)
		(layer "In5.Cu")
		(net "3008_SAS_RX_P1")
	)
	(arc
		(start 104.267254 -65.2018)
		(mid 105.059799 -65.359398)
		(end 105.731818 -65.808098)
		(width 0.1016)
		(layer "In5.Cu")
		(net "3008_SAS_RX_P1")
	)
	(arc
		(start 126.651766 -72.0852)
		(mid 127.630464 -72.279933)
		(end 128.460246 -72.834246)
		(width 0.1016)
		(layer "In5.Cu")
		(net "3008_SAS_RX_P1")
	)
	(arc
		(start 120.309132 -71.12)
		(mid 120.876994 -71.232767)
		(end 121.358406 -71.55434)
		(width 0.1016)
		(layer "In5.Cu")
		(net "3008_SAS_RX_P1")
	)
	(arc
		(start 93.219016 -35.833304)
		(mid 93.17533 -35.804021)
		(end 93.123766 -35.79368)
		(width 0.1016)
		(layer "In5.Cu")
		(net "3008_SAS_RX_P1")
	)
	(arc
		(start 93.490542 -61.985652)
		(mid 93.501459 -62.115174)
		(end 93.570298 -62.225428)
		(width 0.1016)
		(layer "In5.Cu")
		(net "3008_SAS_RX_P1")
	)
	(arc
		(start 89.84742 -37.405564)
		(mid 89.737201 -37.474561)
		(end 89.607644 -37.485574)
		(width 0.1016)
		(layer "In5.Cu")
		(net "3008_SAS_RX_P1")
	)
	(arc
		(start 93.785944 -62.441074)
		(mid 93.896199 -62.50991)
		(end 94.02572 -62.52083)
		(width 0.1016)
		(layer "In5.Cu")
		(net "3008_SAS_RX_P1")
	)
	(arc
		(start 91.213178 -35.79368)
		(mid 91.145093 -35.807316)
		(end 91.087448 -35.846004)
		(width 0.1016)
		(layer "In5.Cu")
		(net "3008_SAS_RX_P1")
	)
	(arc
		(start 110.44936 -70.525386)
		(mid 111.108023 -70.96549)
		(end 111.884968 -71.12)
		(width 0.1016)
		(layer "In5.Cu")
		(net "3008_SAS_RX_P1")
	)
	(arc
		(start 88.081866 -38.851586)
		(mid 88.01303 -38.961841)
		(end 88.00211 -39.091362)
		(width 0.1016)
		(layer "In5.Cu")
		(net "3008_SAS_RX_P1")
	)
	(arc
		(start 85.402166 -45.987716)
		(mid 85.431405 -46.114377)
		(end 85.515196 -46.213776)
		(width 0.1016)
		(layer "In5.Cu")
		(net "3008_SAS_RX_P1")
	)
	(arc
		(start 132.899658 -77.273658)
		(mid 133.388064 -78.004704)
		(end 133.55955 -78.867)
		(width 0.1016)
		(layer "In5.Cu")
		(net "3008_SAS_RX_P1")
	)
	(arc
		(start 90.222832 -36.71062)
		(mid 90.153996 -36.820875)
		(end 90.143076 -36.950396)
		(width 0.1016)
		(layer "In5.Cu")
		(net "3008_SAS_RX_P1")
	)
	(arc
		(start 87.466932 -39.62654)
		(mid 87.33741 -39.637457)
		(end 87.227156 -39.706296)
		(width 0.1016)
		(layer "In5.Cu")
		(net "3008_SAS_RX_P1")
	)
	(arc
		(start 85.515196 -44.699936)
		(mid 85.599033 -44.799312)
		(end 85.628226 -44.925996)
		(width 0.1016)
		(layer "In5.Cu")
		(net "3008_SAS_RX_P1")
	)
	(arc
		(start 85.515196 -48.484536)
		(mid 85.431359 -48.583912)
		(end 85.402166 -48.710596)
		(width 0.1016)
		(layer "In5.Cu")
		(net "3008_SAS_RX_P1")
	)
	(arc
		(start 133.55955 -80.6704)
		(mid 133.586798 -80.806915)
		(end 133.664198 -80.922622)
		(width 0.1016)
		(layer "In5.Cu")
		(net "3008_SAS_RX_P1")
	)
	(arc
		(start 95.864934 -64.520318)
		(mid 96.619987 -65.024735)
		(end 97.5106 -65.2018)
		(width 0.1016)
		(layer "In5.Cu")
		(net "3008_SAS_RX_P1")
	)
	(arc
		(start 93.410532 -61.745876)
		(mid 93.479466 -61.856106)
		(end 93.490542 -61.985652)
		(width 0.1016)
		(layer "In5.Cu")
		(net "3008_SAS_RX_P1")
	)
	(arc
		(start 89.607644 -37.485574)
		(mid 89.478099 -37.496624)
		(end 89.367868 -37.565584)
		(width 0.1016)
		(layer "In5.Cu")
		(net "3008_SAS_RX_P1")
	)
	(arc
		(start 87.706708 -39.54653)
		(mid 87.596478 -39.615464)
		(end 87.466932 -39.62654)
		(width 0.1016)
		(layer "In5.Cu")
		(net "3008_SAS_RX_P1")
	)
	(arc
		(start 94.560898 -63.056262)
		(mid 94.571948 -63.185807)
		(end 94.640908 -63.296038)
		(width 0.1016)
		(layer "In5.Cu")
		(net "3008_SAS_RX_P1")
	)
	(arc
		(start 85.515196 -47.727616)
		(mid 85.599033 -47.826992)
		(end 85.628226 -47.953676)
		(width 0.1016)
		(layer "In5.Cu")
		(net "3008_SAS_RX_P1")
	)
	(arc
		(start 85.402166 -47.501556)
		(mid 85.431405 -47.628217)
		(end 85.515196 -47.727616)
		(width 0.1016)
		(layer "In5.Cu")
		(net "3008_SAS_RX_P1")
	)
	(arc
		(start 85.628226 -46.744636)
		(mid 85.598987 -46.871297)
		(end 85.515196 -46.970696)
		(width 0.1016)
		(layer "In5.Cu")
		(net "3008_SAS_RX_P1")
	)
	(arc
		(start 94.02572 -62.52083)
		(mid 94.155277 -62.531873)
		(end 94.265496 -62.60084)
		(width 0.1016)
		(layer "In5.Cu")
		(net "3008_SAS_RX_P1")
	)
	(arc
		(start 121.839228 -72.035162)
		(mid 121.894568 -72.072203)
		(end 121.959878 -72.0852)
		(width 0.1016)
		(layer "In5.Cu")
		(net "3008_SAS_RX_P1")
	)
	(arc
		(start 85.644482 -41.28897)
		(mid 85.465154 -41.557353)
		(end 85.402166 -41.873932)
		(width 0.1016)
		(layer "In5.Cu")
		(net "3008_SAS_RX_P1")
	)
	(arc
		(start 85.515196 -46.213776)
		(mid 85.599033 -46.313152)
		(end 85.628226 -46.439836)
		(width 0.1016)
		(layer "In5.Cu")
		(net "3008_SAS_RX_P1")
	)
	(arc
		(start 92.715334 -61.370464)
		(mid 92.825553 -61.439461)
		(end 92.95511 -61.450474)
		(width 0.1016)
		(layer "In5.Cu")
		(net "3008_SAS_RX_P1")
	)
	(arc
		(start 88.00211 -39.091362)
		(mid 87.991067 -39.220919)
		(end 87.9221 -39.331138)
		(width 0.1016)
		(layer "In5.Cu")
		(net "3008_SAS_RX_P1")
	)
	(arc
		(start 85.515196 -45.456856)
		(mid 85.431359 -45.556232)
		(end 85.402166 -45.682916)
		(width 0.1016)
		(layer "In5.Cu")
		(net "3008_SAS_RX_P1")
	)
	(arc
		(start 90.143076 -36.950396)
		(mid 90.132033 -37.079953)
		(end 90.063066 -37.190172)
		(width 0.1016)
		(layer "In5.Cu")
		(net "3008_SAS_RX_P1")
	)
	(arc
		(start 92.95511 -61.450474)
		(mid 93.084655 -61.461524)
		(end 93.194886 -61.530484)
		(width 0.1016)
		(layer "In5.Cu")
		(net "3008_SAS_RX_P1")
	)
	(arc
		(start 85.402166 -53.4924)
		(mid 85.506056 -54.014222)
		(end 85.801708 -54.456584)
		(width 0.1016)
		(layer "In5.Cu")
		(net "3008_SAS_RX_P1")
	)
	(arc
		(start 85.515196 -46.970696)
		(mid 85.431359 -47.070072)
		(end 85.402166 -47.196756)
		(width 0.1016)
		(layer "In5.Cu")
		(net "3008_SAS_RX_P1")
	)
	(arc
		(start 85.628226 -45.230796)
		(mid 85.598987 -45.357457)
		(end 85.515196 -45.456856)
		(width 0.1016)
		(layer "In5.Cu")
		(net "3008_SAS_RX_P1")
	)
	(segment
		(start 277.27275 -112.8395)
		(end 276.352 -113.76025)
		(width 0.254)
		(layer "F.Cu")
		(net "P1V8_C_EN_B")
	)
	(segment
		(start 278.638 -115.3795)
		(end 277.495 -115.3795)
		(width 0.254)
		(layer "F.Cu")
		(net "P1V8_C_EN_B")
	)
	(segment
		(start 276.352 -113.76025)
		(end 276.352 -114.3)
		(width 0.254)
		(layer "F.Cu")
		(net "P1V8_C_EN_B")
	)
	(segment
		(start 277.495 -115.3795)
		(end 276.352 -115.3795)
		(width 0.254)
		(layer "F.Cu")
		(net "P1V8_C_EN_B")
	)
	(segment
		(start 276.352 -114.3)
		(end 276.352 -115.3795)
		(width 0.254)
		(layer "F.Cu")
		(net "P1V8_C_EN_B")
	)
	(via
		(at 276.352 -114.3)
		(size 0.7112)
		(drill 0.3556)
		(layers "F.Cu" "B.Cu")
		(net "P1V8_C_EN_B")
	)
	(segment
		(start 83.034124 -22.709124)
		(end 83.058 -22.733)
		(width 0.3556)
		(layer "F.Cu")
		(net "VT235_BIAS")
	)
	(segment
		(start 83.034124 -21.255228)
		(end 83.034124 -22.709124)
		(width 0.3556)
		(layer "F.Cu")
		(net "VT235_BIAS")
	)
	(via
		(at 83.312 -23.622)
		(size 0.7112)
		(drill 0.3556)
		(layers "F.Cu" "B.Cu")
		(net "VT235_BIAS")
	)
	(via
		(at 83.058 -22.733)
		(size 0.5588)
		(drill 0.3048)
		(layers "F.Cu" "B.Cu")
		(net "VT235_BIAS")
	)
	(segment
		(start 83.312 -22.987)
		(end 83.058 -22.733)
		(width 0.508)
		(layer "B.Cu")
		(net "VT235_BIAS")
	)
	(segment
		(start 82.804 -22.479)
		(end 83.058 -22.733)
		(width 0.508)
		(layer "B.Cu")
		(net "VT235_BIAS")
	)
	(segment
		(start 82.804 -21.6535)
		(end 82.804 -22.479)
		(width 0.508)
		(layer "B.Cu")
		(net "VT235_BIAS")
	)
	(segment
		(start 83.312 -23.622)
		(end 83.312 -22.987)
		(width 0.508)
		(layer "B.Cu")
		(net "VT235_BIAS")
	)
	(segment
		(start 110.349792 -85.349842)
		(end 110.349792 -85.353398)
		(width 0.1143)
		(layer "F.Cu")
		(net "TESTIBIAS")
	)
	(segment
		(start 110.349792 -85.353398)
		(end 109.88167 -85.82152)
		(width 0.1143)
		(layer "F.Cu")
		(net "TESTIBIAS")
	)
	(via
		(at 109.88167 -85.82152)
		(size 0.508)
		(drill 0.254)
		(layers "F.Cu" "B.Cu")
		(net "TESTIBIAS")
	)
	(segment
		(start 109.86897 -84.709)
		(end 109.88167 -84.718906)
		(width 0.1143)
		(layer "B.Cu")
		(net "TESTIBIAS")
	)
	(segment
		(start 109.88167 -84.718906)
		(end 109.88167 -85.82152)
		(width 0.1143)
		(layer "B.Cu")
		(net "TESTIBIAS")
	)
	(segment
		(start 142.334996 -49.774348)
		(end 140.44295 -49.774348)
		(width 0.1143)
		(layer "F.Cu")
		(net "XM_ADDR_11")
	)
	(segment
		(start 140.44295 -51.145948)
		(end 141.505178 -51.145948)
		(width 0.1143)
		(layer "F.Cu")
		(net "XM_ADDR_11")
	)
	(segment
		(start 141.505178 -50.688748)
		(end 140.44295 -50.688748)
		(width 0.1143)
		(layer "F.Cu")
		(net "XM_ADDR_11")
	)
	(segment
		(start 140.31595 -51.272948)
		(end 140.44295 -51.145948)
		(width 0.1143)
		(layer "F.Cu")
		(net "XM_ADDR_11")
	)
	(segment
		(start 113.408206 -55.17769)
		(end 113.649506 -55.41899)
		(width 0.1143)
		(layer "F.Cu")
		(net "XM_ADDR_11")
	)
	(segment
		(start 139.681204 -52.051712)
		(end 139.808204 -52.178712)
		(width 0.1143)
		(layer "F.Cu")
		(net "XM_ADDR_11")
	)
	(segment
		(start 141.00175 -52.178712)
		(end 141.12875 -52.051712)
		(width 0.1143)
		(layer "F.Cu")
		(net "XM_ADDR_11")
	)
	(segment
		(start 139.898374 -46.897036)
		(end 139.782042 -47.013368)
		(width 0.1143)
		(layer "F.Cu")
		(net "XM_ADDR_11")
	)
	(segment
		(start 140.31595 -51.485546)
		(end 140.31595 -51.272948)
		(width 0.1143)
		(layer "F.Cu")
		(net "XM_ADDR_11")
	)
	(segment
		(start 142.461996 -49.901348)
		(end 142.334996 -49.774348)
		(width 0.1143)
		(layer "F.Cu")
		(net "XM_ADDR_11")
	)
	(segment
		(start 141.12875 -51.739546)
		(end 141.00175 -51.612546)
		(width 0.1143)
		(layer "F.Cu")
		(net "XM_ADDR_11")
	)
	(segment
		(start 139.782042 -47.013368)
		(end 139.46378 -47.013368)
		(width 0.1143)
		(layer "F.Cu")
		(net "XM_ADDR_11")
	)
	(segment
		(start 113.649506 -55.41899)
		(end 114.089942 -55.41899)
		(width 0.1143)
		(layer "F.Cu")
		(net "XM_ADDR_11")
	)
	(segment
		(start 140.31595 -49.647348)
		(end 140.31595 -47.132748)
		(width 0.1143)
		(layer "F.Cu")
		(net "XM_ADDR_11")
	)
	(segment
		(start 115.69573 -57.024778)
		(end 116.059966 -57.024778)
		(width 0.1143)
		(layer "F.Cu")
		(net "XM_ADDR_11")
	)
	(segment
		(start 140.44295 -50.231548)
		(end 142.334996 -50.231548)
		(width 0.1143)
		(layer "F.Cu")
		(net "XM_ADDR_11")
	)
	(segment
		(start 140.31595 -47.132748)
		(end 140.080238 -46.897036)
		(width 0.1143)
		(layer "F.Cu")
		(net "XM_ADDR_11")
	)
	(segment
		(start 117.221 -57.023)
		(end 116.061744 -57.023)
		(width 0.1143)
		(layer "F.Cu")
		(net "XM_ADDR_11")
	)
	(segment
		(start 139.46378 -47.013368)
		(end 139.3571 -46.906688)
		(width 0.1143)
		(layer "F.Cu")
		(net "XM_ADDR_11")
	)
	(segment
		(start 139.3571 -46.906688)
		(end 139.3571 -46.173898)
		(width 0.1143)
		(layer "F.Cu")
		(net "XM_ADDR_11")
	)
	(segment
		(start 139.446 -40.894)
		(end 139.099036 -41.240964)
		(width 0.1143)
		(layer "F.Cu")
		(net "XM_ADDR_11")
	)
	(segment
		(start 140.44295 -49.774348)
		(end 140.31595 -49.647348)
		(width 0.1143)
		(layer "F.Cu")
		(net "XM_ADDR_11")
	)
	(segment
		(start 140.31595 -50.358548)
		(end 140.44295 -50.231548)
		(width 0.1143)
		(layer "F.Cu")
		(net "XM_ADDR_11")
	)
	(segment
		(start 141.505178 -51.145948)
		(end 141.632178 -51.018948)
		(width 0.1143)
		(layer "F.Cu")
		(net "XM_ADDR_11")
	)
	(segment
		(start 139.681204 -51.816)
		(end 139.681204 -52.051712)
		(width 0.1143)
		(layer "F.Cu")
		(net "XM_ADDR_11")
	)
	(segment
		(start 141.632178 -50.815748)
		(end 141.505178 -50.688748)
		(width 0.1143)
		(layer "F.Cu")
		(net "XM_ADDR_11")
	)
	(segment
		(start 141.12875 -52.051712)
		(end 141.12875 -51.739546)
		(width 0.1143)
		(layer "F.Cu")
		(net "XM_ADDR_11")
	)
	(segment
		(start 139.808204 -52.178712)
		(end 141.00175 -52.178712)
		(width 0.1143)
		(layer "F.Cu")
		(net "XM_ADDR_11")
	)
	(segment
		(start 140.080238 -46.897036)
		(end 139.898374 -46.897036)
		(width 0.1143)
		(layer "F.Cu")
		(net "XM_ADDR_11")
	)
	(segment
		(start 141.00175 -51.612546)
		(end 140.44295 -51.612546)
		(width 0.1143)
		(layer "F.Cu")
		(net "XM_ADDR_11")
	)
	(segment
		(start 142.461996 -50.104548)
		(end 142.461996 -49.901348)
		(width 0.1143)
		(layer "F.Cu")
		(net "XM_ADDR_11")
	)
	(segment
		(start 114.089942 -55.41899)
		(end 115.69573 -57.024778)
		(width 0.1143)
		(layer "F.Cu")
		(net "XM_ADDR_11")
	)
	(segment
		(start 116.061744 -57.023)
		(end 116.059966 -57.024778)
		(width 0.1143)
		(layer "F.Cu")
		(net "XM_ADDR_11")
	)
	(segment
		(start 113.327942 -55.17769)
		(end 113.408206 -55.17769)
		(width 0.1143)
		(layer "F.Cu")
		(net "XM_ADDR_11")
	)
	(segment
		(start 113.150142 -54.99989)
		(end 113.327942 -55.17769)
		(width 0.1143)
		(layer "F.Cu")
		(net "XM_ADDR_11")
	)
	(segment
		(start 139.099036 -45.915834)
		(end 139.099036 -42.7101)
		(width 0.1143)
		(layer "F.Cu")
		(net "XM_ADDR_11")
	)
	(segment
		(start 140.44295 -51.612546)
		(end 140.31595 -51.485546)
		(width 0.1143)
		(layer "F.Cu")
		(net "XM_ADDR_11")
	)
	(segment
		(start 140.31595 -50.561748)
		(end 140.31595 -50.358548)
		(width 0.1143)
		(layer "F.Cu")
		(net "XM_ADDR_11")
	)
	(segment
		(start 139.099036 -41.240964)
		(end 139.099036 -42.7101)
		(width 0.1143)
		(layer "F.Cu")
		(net "XM_ADDR_11")
	)
	(segment
		(start 139.446 -39.3065)
		(end 139.446 -40.894)
		(width 0.1143)
		(layer "F.Cu")
		(net "XM_ADDR_11")
	)
	(segment
		(start 142.334996 -50.231548)
		(end 142.461996 -50.104548)
		(width 0.1143)
		(layer "F.Cu")
		(net "XM_ADDR_11")
	)
	(segment
		(start 140.44295 -50.688748)
		(end 140.31595 -50.561748)
		(width 0.1143)
		(layer "F.Cu")
		(net "XM_ADDR_11")
	)
	(segment
		(start 139.3571 -46.173898)
		(end 139.099036 -45.915834)
		(width 0.1143)
		(layer "F.Cu")
		(net "XM_ADDR_11")
	)
	(segment
		(start 141.632178 -51.018948)
		(end 141.632178 -50.815748)
		(width 0.1143)
		(layer "F.Cu")
		(net "XM_ADDR_11")
	)
	(via
		(at 117.221 -57.023)
		(size 0.7112)
		(drill 0.3556)
		(layers "F.Cu" "B.Cu")
		(net "XM_ADDR_11")
	)
	(via
		(at 139.681204 -51.816)
		(size 0.5588)
		(drill 0.3048)
		(layers "F.Cu" "B.Cu")
		(net "XM_ADDR_11")
	)
	(via
		(at 116.059966 -57.024778)
		(size 0.508)
		(drill 0.254)
		(layers "F.Cu" "B.Cu")
		(net "XM_ADDR_11")
	)
	(segment
		(start 127.7874 -54.462934)
		(end 127.5334 -54.462934)
		(width 0.127)
		(layer "In5.Cu")
		(net "XM_ADDR_11")
	)
	(segment
		(start 126.8984 -54.939438)
		(end 126.8984 -54.589934)
		(width 0.127)
		(layer "In5.Cu")
		(net "XM_ADDR_11")
	)
	(segment
		(start 123.952508 -56.058054)
		(end 123.952254 -56.0578)
		(width 0.127)
		(layer "In5.Cu")
		(net "XM_ADDR_11")
	)
	(segment
		(start 126.3904 -54.939438)
		(end 126.2634 -55.066438)
		(width 0.127)
		(layer "In5.Cu")
		(net "XM_ADDR_11")
	)
	(segment
		(start 130.9624 -54.589934)
		(end 130.8354 -54.462934)
		(width 0.127)
		(layer "In5.Cu")
		(net "XM_ADDR_11")
	)
	(segment
		(start 139.678156 -51.819048)
		(end 139.678156 -52.535328)
		(width 0.127)
		(layer "In5.Cu")
		(net "XM_ADDR_11")
	)
	(segment
		(start 130.9624 -54.939438)
		(end 130.9624 -54.589934)
		(width 0.127)
		(layer "In5.Cu")
		(net "XM_ADDR_11")
	)
	(segment
		(start 116.895118 -56.189626)
		(end 116.059966 -57.024778)
		(width 0.127)
		(layer "In5.Cu")
		(net "XM_ADDR_11")
	)
	(segment
		(start 132.1054 -55.066438)
		(end 131.9784 -54.939438)
		(width 0.127)
		(layer "In5.Cu")
		(net "XM_ADDR_11")
	)
	(segment
		(start 133.1214 -55.066438)
		(end 132.9944 -54.939438)
		(width 0.127)
		(layer "In5.Cu")
		(net "XM_ADDR_11")
	)
	(segment
		(start 126.8984 -54.589934)
		(end 126.7714 -54.462934)
		(width 0.127)
		(layer "In5.Cu")
		(net "XM_ADDR_11")
	)
	(segment
		(start 129.9464 -54.589934)
		(end 129.8194 -54.462934)
		(width 0.127)
		(layer "In5.Cu")
		(net "XM_ADDR_11")
	)
	(segment
		(start 131.4704 -54.589934)
		(end 131.4704 -54.939438)
		(width 0.127)
		(layer "In5.Cu")
		(net "XM_ADDR_11")
	)
	(segment
		(start 127.0254 -55.066438)
		(end 126.8984 -54.939438)
		(width 0.127)
		(layer "In5.Cu")
		(net "XM_ADDR_11")
	)
	(segment
		(start 128.4224 -54.589934)
		(end 128.4224 -54.939438)
		(width 0.127)
		(layer "In5.Cu")
		(net "XM_ADDR_11")
	)
	(segment
		(start 127.5334 -54.462934)
		(end 127.4064 -54.589934)
		(width 0.127)
		(layer "In5.Cu")
		(net "XM_ADDR_11")
	)
	(segment
		(start 132.4864 -54.939438)
		(end 132.3594 -55.066438)
		(width 0.127)
		(layer "In5.Cu")
		(net "XM_ADDR_11")
	)
	(segment
		(start 118.548404 -56.189626)
		(end 116.895118 -56.189626)
		(width 0.127)
		(layer "In5.Cu")
		(net "XM_ADDR_11")
	)
	(segment
		(start 128.0414 -55.066438)
		(end 127.9144 -54.939438)
		(width 0.127)
		(layer "In5.Cu")
		(net "XM_ADDR_11")
	)
	(segment
		(start 118.68023 -56.0578)
		(end 118.548404 -56.189626)
		(width 0.127)
		(layer "In5.Cu")
		(net "XM_ADDR_11")
	)
	(segment
		(start 131.8514 -54.462934)
		(end 131.5974 -54.462934)
		(width 0.127)
		(layer "In5.Cu")
		(net "XM_ADDR_11")
	)
	(segment
		(start 129.8194 -54.462934)
		(end 129.5654 -54.462934)
		(width 0.127)
		(layer "In5.Cu")
		(net "XM_ADDR_11")
	)
	(segment
		(start 128.5494 -54.462934)
		(end 128.4224 -54.589934)
		(width 0.127)
		(layer "In5.Cu")
		(net "XM_ADDR_11")
	)
	(segment
		(start 132.6134 -54.462934)
		(end 132.4864 -54.589934)
		(width 0.127)
		(layer "In5.Cu")
		(net "XM_ADDR_11")
	)
	(segment
		(start 129.4384 -54.939438)
		(end 129.3114 -55.066438)
		(width 0.127)
		(layer "In5.Cu")
		(net "XM_ADDR_11")
	)
	(segment
		(start 129.5654 -54.462934)
		(end 129.4384 -54.589934)
		(width 0.127)
		(layer "In5.Cu")
		(net "XM_ADDR_11")
	)
	(segment
		(start 127.9144 -54.589934)
		(end 127.7874 -54.462934)
		(width 0.127)
		(layer "In5.Cu")
		(net "XM_ADDR_11")
	)
	(segment
		(start 126.3904 -54.589934)
		(end 126.3904 -54.939438)
		(width 0.127)
		(layer "In5.Cu")
		(net "XM_ADDR_11")
	)
	(segment
		(start 128.8034 -54.462934)
		(end 128.5494 -54.462934)
		(width 0.127)
		(layer "In5.Cu")
		(net "XM_ADDR_11")
	)
	(segment
		(start 132.8674 -54.462934)
		(end 132.6134 -54.462934)
		(width 0.127)
		(layer "In5.Cu")
		(net "XM_ADDR_11")
	)
	(segment
		(start 130.8354 -54.462934)
		(end 130.5814 -54.462934)
		(width 0.127)
		(layer "In5.Cu")
		(net "XM_ADDR_11")
	)
	(segment
		(start 123.952254 -56.0578)
		(end 118.68023 -56.0578)
		(width 0.127)
		(layer "In5.Cu")
		(net "XM_ADDR_11")
	)
	(segment
		(start 129.9464 -54.939438)
		(end 129.9464 -54.589934)
		(width 0.127)
		(layer "In5.Cu")
		(net "XM_ADDR_11")
	)
	(segment
		(start 131.9784 -54.589934)
		(end 131.8514 -54.462934)
		(width 0.127)
		(layer "In5.Cu")
		(net "XM_ADDR_11")
	)
	(segment
		(start 126.5174 -54.462934)
		(end 126.3904 -54.589934)
		(width 0.127)
		(layer "In5.Cu")
		(net "XM_ADDR_11")
	)
	(segment
		(start 139.681204 -51.816)
		(end 139.678156 -51.819048)
		(width 0.127)
		(layer "In5.Cu")
		(net "XM_ADDR_11")
	)
	(segment
		(start 130.3274 -55.066438)
		(end 130.0734 -55.066438)
		(width 0.127)
		(layer "In5.Cu")
		(net "XM_ADDR_11")
	)
	(segment
		(start 131.9784 -54.939438)
		(end 131.9784 -54.589934)
		(width 0.127)
		(layer "In5.Cu")
		(net "XM_ADDR_11")
	)
	(segment
		(start 130.0734 -55.066438)
		(end 129.9464 -54.939438)
		(width 0.127)
		(layer "In5.Cu")
		(net "XM_ADDR_11")
	)
	(segment
		(start 129.0574 -55.066438)
		(end 128.9304 -54.939438)
		(width 0.127)
		(layer "In5.Cu")
		(net "XM_ADDR_11")
	)
	(segment
		(start 127.2794 -55.066438)
		(end 127.0254 -55.066438)
		(width 0.127)
		(layer "In5.Cu")
		(net "XM_ADDR_11")
	)
	(segment
		(start 128.2954 -55.066438)
		(end 128.0414 -55.066438)
		(width 0.127)
		(layer "In5.Cu")
		(net "XM_ADDR_11")
	)
	(segment
		(start 129.4384 -54.589934)
		(end 129.4384 -54.939438)
		(width 0.127)
		(layer "In5.Cu")
		(net "XM_ADDR_11")
	)
	(segment
		(start 139.678156 -52.535328)
		(end 137.147046 -55.066438)
		(width 0.127)
		(layer "In5.Cu")
		(net "XM_ADDR_11")
	)
	(segment
		(start 128.9304 -54.939438)
		(end 128.9304 -54.589934)
		(width 0.127)
		(layer "In5.Cu")
		(net "XM_ADDR_11")
	)
	(segment
		(start 132.3594 -55.066438)
		(end 132.1054 -55.066438)
		(width 0.127)
		(layer "In5.Cu")
		(net "XM_ADDR_11")
	)
	(segment
		(start 132.9944 -54.589934)
		(end 132.8674 -54.462934)
		(width 0.127)
		(layer "In5.Cu")
		(net "XM_ADDR_11")
	)
	(segment
		(start 132.9944 -54.939438)
		(end 132.9944 -54.589934)
		(width 0.127)
		(layer "In5.Cu")
		(net "XM_ADDR_11")
	)
	(segment
		(start 128.9304 -54.589934)
		(end 128.8034 -54.462934)
		(width 0.127)
		(layer "In5.Cu")
		(net "XM_ADDR_11")
	)
	(segment
		(start 129.3114 -55.066438)
		(end 129.0574 -55.066438)
		(width 0.127)
		(layer "In5.Cu")
		(net "XM_ADDR_11")
	)
	(segment
		(start 127.4064 -54.589934)
		(end 127.4064 -54.939438)
		(width 0.127)
		(layer "In5.Cu")
		(net "XM_ADDR_11")
	)
	(segment
		(start 128.4224 -54.939438)
		(end 128.2954 -55.066438)
		(width 0.127)
		(layer "In5.Cu")
		(net "XM_ADDR_11")
	)
	(segment
		(start 131.5974 -54.462934)
		(end 131.4704 -54.589934)
		(width 0.127)
		(layer "In5.Cu")
		(net "XM_ADDR_11")
	)
	(segment
		(start 137.147046 -55.066438)
		(end 133.1214 -55.066438)
		(width 0.127)
		(layer "In5.Cu")
		(net "XM_ADDR_11")
	)
	(segment
		(start 125.659896 -55.066438)
		(end 124.66828 -56.058054)
		(width 0.127)
		(layer "In5.Cu")
		(net "XM_ADDR_11")
	)
	(segment
		(start 131.4704 -54.939438)
		(end 131.3434 -55.066438)
		(width 0.127)
		(layer "In5.Cu")
		(net "XM_ADDR_11")
	)
	(segment
		(start 124.66828 -56.058054)
		(end 123.952508 -56.058054)
		(width 0.127)
		(layer "In5.Cu")
		(net "XM_ADDR_11")
	)
	(segment
		(start 131.3434 -55.066438)
		(end 131.0894 -55.066438)
		(width 0.127)
		(layer "In5.Cu")
		(net "XM_ADDR_11")
	)
	(segment
		(start 126.7714 -54.462934)
		(end 126.5174 -54.462934)
		(width 0.127)
		(layer "In5.Cu")
		(net "XM_ADDR_11")
	)
	(segment
		(start 127.9144 -54.939438)
		(end 127.9144 -54.589934)
		(width 0.127)
		(layer "In5.Cu")
		(net "XM_ADDR_11")
	)
	(segment
		(start 132.4864 -54.589934)
		(end 132.4864 -54.939438)
		(width 0.127)
		(layer "In5.Cu")
		(net "XM_ADDR_11")
	)
	(segment
		(start 130.4544 -54.589934)
		(end 130.4544 -54.939438)
		(width 0.127)
		(layer "In5.Cu")
		(net "XM_ADDR_11")
	)
	(segment
		(start 127.4064 -54.939438)
		(end 127.2794 -55.066438)
		(width 0.127)
		(layer "In5.Cu")
		(net "XM_ADDR_11")
	)
	(segment
		(start 130.4544 -54.939438)
		(end 130.3274 -55.066438)
		(width 0.127)
		(layer "In5.Cu")
		(net "XM_ADDR_11")
	)
	(segment
		(start 130.5814 -54.462934)
		(end 130.4544 -54.589934)
		(width 0.127)
		(layer "In5.Cu")
		(net "XM_ADDR_11")
	)
	(segment
		(start 131.0894 -55.066438)
		(end 130.9624 -54.939438)
		(width 0.127)
		(layer "In5.Cu")
		(net "XM_ADDR_11")
	)
	(segment
		(start 126.2634 -55.066438)
		(end 125.659896 -55.066438)
		(width 0.127)
		(layer "In5.Cu")
		(net "XM_ADDR_11")
	)
	(segment
		(start 88.392 -17.78)
		(end 89.408 -16.764)
		(width 0.254)
		(layer "F.Cu")
		(net "VT235_VDES")
	)
	(segment
		(start 84.034122 -21.931122)
		(end 84.582 -22.479)
		(width 0.254)
		(layer "F.Cu")
		(net "VT235_VDES")
	)
	(segment
		(start 84.582 -22.479)
		(end 84.582 -22.987)
		(width 0.254)
		(layer "F.Cu")
		(net "VT235_VDES")
	)
	(segment
		(start 88.392 -22.225)
		(end 87.503 -22.225)
		(width 0.254)
		(layer "F.Cu")
		(net "VT235_VDES")
	)
	(segment
		(start 84.582 -23.9395)
		(end 84.582 -22.987)
		(width 0.254)
		(layer "F.Cu")
		(net "VT235_VDES")
	)
	(segment
		(start 88.392 -17.907)
		(end 88.392 -17.78)
		(width 0.254)
		(layer "F.Cu")
		(net "VT235_VDES")
	)
	(segment
		(start 87.503 -22.225)
		(end 87.122 -22.606)
		(width 0.254)
		(layer "F.Cu")
		(net "VT235_VDES")
	)
	(segment
		(start 84.034122 -21.255228)
		(end 84.034122 -21.931122)
		(width 0.254)
		(layer "F.Cu")
		(net "VT235_VDES")
	)
	(via
		(at 84.582 -22.987)
		(size 0.5588)
		(drill 0.3048)
		(layers "F.Cu" "B.Cu")
		(net "VT235_VDES")
	)
	(via
		(at 89.408 -16.764)
		(size 0.5588)
		(drill 0.3048)
		(layers "F.Cu" "B.Cu")
		(net "VT235_VDES")
	)
	(via
		(at 87.122 -22.606)
		(size 0.5588)
		(drill 0.3048)
		(layers "F.Cu" "B.Cu")
		(net "VT235_VDES")
	)
	(via
		(at 88.646 -19.812)
		(size 0.7112)
		(drill 0.3556)
		(layers "F.Cu" "B.Cu")
		(net "VT235_VDES")
	)
	(segment
		(start 87.122 -21.336)
		(end 87.122 -22.606)
		(width 0.254)
		(layer "B.Cu")
		(net "VT235_VDES")
	)
	(segment
		(start 89.408 -16.764)
		(end 89.408 -19.05)
		(width 0.254)
		(layer "B.Cu")
		(net "VT235_VDES")
	)
	(segment
		(start 89.408 -19.05)
		(end 88.646 -19.812)
		(width 0.254)
		(layer "B.Cu")
		(net "VT235_VDES")
	)
	(segment
		(start 83.8835 -22.2885)
		(end 84.582 -22.987)
		(width 0.254)
		(layer "B.Cu")
		(net "VT235_VDES")
	)
	(segment
		(start 83.82 -22.2885)
		(end 83.8835 -22.2885)
		(width 0.254)
		(layer "B.Cu")
		(net "VT235_VDES")
	)
	(segment
		(start 88.646 -19.812)
		(end 87.122 -21.336)
		(width 0.254)
		(layer "B.Cu")
		(net "VT235_VDES")
	)
	(segment
		(start 87.122 -22.606)
		(end 85.725 -22.606)
		(width 0.254)
		(layer "In2.Cu")
		(net "VT235_VDES")
	)
	(segment
		(start 85.344 -22.987)
		(end 84.582 -22.987)
		(width 0.254)
		(layer "In2.Cu")
		(net "VT235_VDES")
	)
	(segment
		(start 85.725 -22.606)
		(end 85.344 -22.987)
		(width 0.254)
		(layer "In2.Cu")
		(net "VT235_VDES")
	)
	(segment
		(start 88.56726 -117.506242)
		(end 90.166952 -115.90655)
		(width 0.1143)
		(layer "F.Cu")
		(net "EXP_I2C_SDA_2")
	)
	(segment
		(start 96.15297 -113.03)
		(end 96.15297 -110.617)
		(width 0.1143)
		(layer "F.Cu")
		(net "EXP_I2C_SDA_2")
	)
	(segment
		(start 103.70312 -109.16285)
		(end 103.70312 -108.32338)
		(width 0.1143)
		(layer "F.Cu")
		(net "EXP_I2C_SDA_2")
	)
	(segment
		(start 103.411528 -108.031788)
		(end 103.411528 -107.411774)
		(width 0.1143)
		(layer "F.Cu")
		(net "EXP_I2C_SDA_2")
	)
	(segment
		(start 87.483442 -117.506242)
		(end 88.56726 -117.506242)
		(width 0.1143)
		(layer "F.Cu")
		(net "EXP_I2C_SDA_2")
	)
	(segment
		(start 103.70312 -108.32338)
		(end 103.411528 -108.031788)
		(width 0.1143)
		(layer "F.Cu")
		(net "EXP_I2C_SDA_2")
	)
	(segment
		(start 90.166952 -115.90655)
		(end 91.773502 -114.3)
		(width 0.1143)
		(layer "F.Cu")
		(net "EXP_I2C_SDA_2")
	)
	(segment
		(start 91.773502 -114.3)
		(end 94.88297 -114.3)
		(width 0.1143)
		(layer "F.Cu")
		(net "EXP_I2C_SDA_2")
	)
	(segment
		(start 94.88297 -114.3)
		(end 96.15297 -113.03)
		(width 0.1143)
		(layer "F.Cu")
		(net "EXP_I2C_SDA_2")
	)
	(segment
		(start 102.88397 -109.982)
		(end 103.70312 -109.16285)
		(width 0.1143)
		(layer "F.Cu")
		(net "EXP_I2C_SDA_2")
	)
	(segment
		(start 96.15297 -110.617)
		(end 96.78797 -109.982)
		(width 0.1143)
		(layer "F.Cu")
		(net "EXP_I2C_SDA_2")
	)
	(segment
		(start 103.411528 -107.411774)
		(end 103.349806 -107.350052)
		(width 0.1143)
		(layer "F.Cu")
		(net "EXP_I2C_SDA_2")
	)
	(segment
		(start 96.78797 -109.982)
		(end 102.88397 -109.982)
		(width 0.1143)
		(layer "F.Cu")
		(net "EXP_I2C_SDA_2")
	)
	(via
		(at 90.166952 -115.90655)
		(size 0.7112)
		(drill 0.3556)
		(layers "F.Cu" "B.Cu")
		(net "EXP_I2C_SDA_2")
	)
	(segment
		(start 223.901 -117.602)
		(end 223.901 -118.745)
		(width 0.127)
		(layer "F.Cu")
		(net "P3V3_STBY_B3")
	)
	(segment
		(start 223.10725 -117.2845)
		(end 223.5835 -117.2845)
		(width 0.127)
		(layer "F.Cu")
		(net "P3V3_STBY_B3")
	)
	(segment
		(start 222.8215 -118.745)
		(end 223.901 -118.745)
		(width 0.127)
		(layer "F.Cu")
		(net "P3V3_STBY_B3")
	)
	(segment
		(start 223.5835 -117.2845)
		(end 223.901 -117.602)
		(width 0.127)
		(layer "F.Cu")
		(net "P3V3_STBY_B3")
	)
	(via
		(at 223.901 -118.745)
		(size 0.7112)
		(drill 0.3556)
		(layers "F.Cu" "B.Cu")
		(net "P3V3_STBY_B3")
	)
	(segment
		(start 56.134 -180.5305)
		(end 56.134 -183.642)
		(width 0.1143)
		(layer "F.Cu")
		(net "ICE_TCK")
	)
	(segment
		(start 107.349798 -98.35007)
		(end 106.849672 -98.850196)
		(width 0.1143)
		(layer "F.Cu")
		(net "ICE_TCK")
	)
	(via
		(at 56.134 -183.642)
		(size 0.5588)
		(drill 0.3048)
		(layers "F.Cu" "B.Cu")
		(net "ICE_TCK")
	)
	(via
		(at 106.849672 -98.850196)
		(size 0.508)
		(drill 0.254)
		(layers "F.Cu" "B.Cu")
		(net "ICE_TCK")
	)
	(via
		(at 97.547684 -136.282684)
		(size 0.5588)
		(drill 0.3048)
		(layers "F.Cu" "B.Cu")
		(net "ICE_TCK")
	)
	(segment
		(start 97.536 -139.692888)
		(end 97.536 -136.294368)
		(width 0.1143)
		(layer "B.Cu")
		(net "ICE_TCK")
	)
	(segment
		(start 68.67525 -167.186864)
		(end 85.875114 -149.987)
		(width 0.1143)
		(layer "B.Cu")
		(net "ICE_TCK")
	)
	(segment
		(start 97.536 -136.294368)
		(end 97.547684 -136.282684)
		(width 0.1143)
		(layer "B.Cu")
		(net "ICE_TCK")
	)
	(segment
		(start 68.67525 -172.150278)
		(end 68.67525 -167.186864)
		(width 0.1143)
		(layer "B.Cu")
		(net "ICE_TCK")
	)
	(segment
		(start 85.875114 -149.987)
		(end 87.241888 -149.987)
		(width 0.1143)
		(layer "B.Cu")
		(net "ICE_TCK")
	)
	(segment
		(start 87.241888 -149.987)
		(end 97.536 -139.692888)
		(width 0.1143)
		(layer "B.Cu")
		(net "ICE_TCK")
	)
	(segment
		(start 55.909972 -185.269886)
		(end 55.909972 -184.182766)
		(width 0.1143)
		(layer "B.Cu")
		(net "ICE_TCK")
	)
	(segment
		(start 57.183528 -183.642)
		(end 68.67525 -172.150278)
		(width 0.1143)
		(layer "B.Cu")
		(net "ICE_TCK")
	)
	(segment
		(start 56.134 -183.642)
		(end 57.183528 -183.642)
		(width 0.1143)
		(layer "B.Cu")
		(net "ICE_TCK")
	)
	(arc
		(start 55.909972 -184.182766)
		(mid 55.968188 -183.890092)
		(end 56.134 -183.642)
		(width 0.1143)
		(layer "B.Cu")
		(net "ICE_TCK")
	)
	(segment
		(start 95.77197 -103.449374)
		(end 98.764344 -100.457)
		(width 0.127)
		(layer "In2.Cu")
		(net "ICE_TCK")
	)
	(segment
		(start 98.764344 -100.457)
		(end 100.65004 -100.457)
		(width 0.127)
		(layer "In2.Cu")
		(net "ICE_TCK")
	)
	(segment
		(start 84.98205 -125.86716)
		(end 82.576924 -125.86716)
		(width 0.127)
		(layer "In2.Cu")
		(net "ICE_TCK")
	)
	(segment
		(start 106.478324 -98.850196)
		(end 106.849672 -98.850196)
		(width 0.127)
		(layer "In2.Cu")
		(net "ICE_TCK")
	)
	(segment
		(start 79.93507 -120.762522)
		(end 83.222846 -117.474746)
		(width 0.127)
		(layer "In2.Cu")
		(net "ICE_TCK")
	)
	(segment
		(start 79.93507 -123.225306)
		(end 79.93507 -120.762522)
		(width 0.127)
		(layer "In2.Cu")
		(net "ICE_TCK")
	)
	(segment
		(start 91.517724 -132.206746)
		(end 90.727022 -132.206746)
		(width 0.127)
		(layer "In2.Cu")
		(net "ICE_TCK")
	)
	(segment
		(start 96.138238 -136.042146)
		(end 95.353124 -136.042146)
		(width 0.127)
		(layer "In2.Cu")
		(net "ICE_TCK")
	)
	(segment
		(start 82.576924 -125.86716)
		(end 79.93507 -123.225306)
		(width 0.127)
		(layer "In2.Cu")
		(net "ICE_TCK")
	)
	(segment
		(start 95.77197 -106.884216)
		(end 95.77197 -103.449374)
		(width 0.127)
		(layer "In2.Cu")
		(net "ICE_TCK")
	)
	(segment
		(start 83.222846 -117.474746)
		(end 85.18144 -117.474746)
		(width 0.127)
		(layer "In2.Cu")
		(net "ICE_TCK")
	)
	(segment
		(start 96.378776 -136.282684)
		(end 96.138238 -136.042146)
		(width 0.127)
		(layer "In2.Cu")
		(net "ICE_TCK")
	)
	(segment
		(start 100.65004 -100.457)
		(end 102.675944 -98.431096)
		(width 0.127)
		(layer "In2.Cu")
		(net "ICE_TCK")
	)
	(segment
		(start 95.353124 -136.042146)
		(end 91.517724 -132.206746)
		(width 0.127)
		(layer "In2.Cu")
		(net "ICE_TCK")
	)
	(segment
		(start 102.675944 -98.431096)
		(end 106.059224 -98.431096)
		(width 0.127)
		(layer "In2.Cu")
		(net "ICE_TCK")
	)
	(segment
		(start 90.727022 -132.206746)
		(end 89.33307 -130.812794)
		(width 0.127)
		(layer "In2.Cu")
		(net "ICE_TCK")
	)
	(segment
		(start 85.18144 -117.474746)
		(end 95.77197 -106.884216)
		(width 0.127)
		(layer "In2.Cu")
		(net "ICE_TCK")
	)
	(segment
		(start 89.33307 -130.21818)
		(end 84.98205 -125.86716)
		(width 0.127)
		(layer "In2.Cu")
		(net "ICE_TCK")
	)
	(segment
		(start 97.547684 -136.282684)
		(end 96.378776 -136.282684)
		(width 0.127)
		(layer "In2.Cu")
		(net "ICE_TCK")
	)
	(segment
		(start 106.059224 -98.431096)
		(end 106.478324 -98.850196)
		(width 0.127)
		(layer "In2.Cu")
		(net "ICE_TCK")
	)
	(segment
		(start 89.33307 -130.812794)
		(end 89.33307 -130.21818)
		(width 0.127)
		(layer "In2.Cu")
		(net "ICE_TCK")
	)
	(segment
		(start 95.532194 -109.97184)
		(end 95.59798 -109.97184)
		(width 0.1143)
		(layer "F.Cu")
		(net "EXP_I2C_SCL_2")
	)
	(segment
		(start 95.74022 -109.8296)
		(end 96.096074 -109.474)
		(width 0.1143)
		(layer "F.Cu")
		(net "EXP_I2C_SCL_2")
	)
	(segment
		(start 94.81185 -110.08995)
		(end 95.044006 -110.08995)
		(width 0.1143)
		(layer "F.Cu")
		(net "EXP_I2C_SCL_2")
	)
	(segment
		(start 95.522796 -109.981238)
		(end 95.532194 -109.97184)
		(width 0.1143)
		(layer "F.Cu")
		(net "EXP_I2C_SCL_2")
	)
	(segment
		(start 94.57182 -110.32998)
		(end 94.81185 -110.08995)
		(width 0.1143)
		(layer "F.Cu")
		(net "EXP_I2C_SCL_2")
	)
	(segment
		(start 87.483442 -116.856002)
		(end 88.400128 -116.856002)
		(width 0.1143)
		(layer "F.Cu")
		(net "EXP_I2C_SCL_2")
	)
	(segment
		(start 94.57182 -112.57915)
		(end 94.57182 -110.32998)
		(width 0.1143)
		(layer "F.Cu")
		(net "EXP_I2C_SCL_2")
	)
	(segment
		(start 96.27997 -109.347)
		(end 102.75697 -109.347)
		(width 0.1143)
		(layer "F.Cu")
		(net "EXP_I2C_SCL_2")
	)
	(segment
		(start 95.152464 -109.981238)
		(end 95.522796 -109.981238)
		(width 0.1143)
		(layer "F.Cu")
		(net "EXP_I2C_SCL_2")
	)
	(segment
		(start 96.15297 -109.474)
		(end 96.27997 -109.347)
		(width 0.1143)
		(layer "F.Cu")
		(net "EXP_I2C_SCL_2")
	)
	(segment
		(start 95.632524 -109.93755)
		(end 95.74022 -109.829854)
		(width 0.1143)
		(layer "F.Cu")
		(net "EXP_I2C_SCL_2")
	)
	(segment
		(start 91.46413 -113.792)
		(end 93.35897 -113.792)
		(width 0.1143)
		(layer "F.Cu")
		(net "EXP_I2C_SCL_2")
	)
	(segment
		(start 95.74022 -109.829854)
		(end 95.74022 -109.8296)
		(width 0.1143)
		(layer "F.Cu")
		(net "EXP_I2C_SCL_2")
	)
	(segment
		(start 93.35897 -113.792)
		(end 94.57182 -112.57915)
		(width 0.1143)
		(layer "F.Cu")
		(net "EXP_I2C_SCL_2")
	)
	(segment
		(start 109.324902 -99.350068)
		(end 108.85297 -99.822)
		(width 0.1143)
		(layer "F.Cu")
		(net "EXP_I2C_SCL_2")
	)
	(segment
		(start 96.096074 -109.474)
		(end 96.15297 -109.474)
		(width 0.1143)
		(layer "F.Cu")
		(net "EXP_I2C_SCL_2")
	)
	(segment
		(start 109.349794 -99.350068)
		(end 109.324902 -99.350068)
		(width 0.1143)
		(layer "F.Cu")
		(net "EXP_I2C_SCL_2")
	)
	(segment
		(start 95.63227 -109.93755)
		(end 95.632524 -109.93755)
		(width 0.1143)
		(layer "F.Cu")
		(net "EXP_I2C_SCL_2")
	)
	(segment
		(start 88.400128 -116.856002)
		(end 91.46413 -113.792)
		(width 0.1143)
		(layer "F.Cu")
		(net "EXP_I2C_SCL_2")
	)
	(segment
		(start 95.59798 -109.97184)
		(end 95.63227 -109.93755)
		(width 0.1143)
		(layer "F.Cu")
		(net "EXP_I2C_SCL_2")
	)
	(segment
		(start 95.044006 -110.08995)
		(end 95.152464 -109.981238)
		(width 0.1143)
		(layer "F.Cu")
		(net "EXP_I2C_SCL_2")
	)
	(via
		(at 102.75697 -109.347)
		(size 0.508)
		(drill 0.254)
		(layers "F.Cu" "B.Cu")
		(net "EXP_I2C_SCL_2")
	)
	(via
		(at 103.13797 -107.6198)
		(size 0.7112)
		(drill 0.3556)
		(layers "F.Cu" "B.Cu")
		(net "EXP_I2C_SCL_2")
	)
	(via
		(at 108.85297 -99.822)
		(size 0.508)
		(drill 0.254)
		(layers "F.Cu" "B.Cu")
		(net "EXP_I2C_SCL_2")
	)
	(segment
		(start 106.411522 -100.704396)
		(end 106.827574 -100.288344)
		(width 0.1143)
		(layer "B.Cu")
		(net "EXP_I2C_SCL_2")
	)
	(segment
		(start 104.287828 -106.995976)
		(end 104.287828 -103.828088)
		(width 0.1143)
		(layer "B.Cu")
		(net "EXP_I2C_SCL_2")
	)
	(segment
		(start 105.411524 -102.872286)
		(end 105.411524 -101.704394)
		(width 0.1143)
		(layer "B.Cu")
		(net "EXP_I2C_SCL_2")
	)
	(segment
		(start 103.13797 -107.6198)
		(end 103.13797 -107.62615)
		(width 0.1143)
		(layer "B.Cu")
		(net "EXP_I2C_SCL_2")
	)
	(segment
		(start 104.287828 -103.828088)
		(end 104.827578 -103.288338)
		(width 0.1143)
		(layer "B.Cu")
		(net "EXP_I2C_SCL_2")
	)
	(segment
		(start 104.995472 -103.288338)
		(end 105.411524 -102.872286)
		(width 0.1143)
		(layer "B.Cu")
		(net "EXP_I2C_SCL_2")
	)
	(segment
		(start 103.13797 -107.6198)
		(end 103.39197 -107.3658)
		(width 0.1143)
		(layer "B.Cu")
		(net "EXP_I2C_SCL_2")
	)
	(segment
		(start 103.39197 -107.3658)
		(end 103.918004 -107.3658)
		(width 0.1143)
		(layer "B.Cu")
		(net "EXP_I2C_SCL_2")
	)
	(segment
		(start 102.86492 -108.37291)
		(end 102.83317 -108.40466)
		(width 0.1143)
		(layer "B.Cu")
		(net "EXP_I2C_SCL_2")
	)
	(segment
		(start 102.83317 -108.40466)
		(end 102.83317 -109.2708)
		(width 0.1143)
		(layer "B.Cu")
		(net "EXP_I2C_SCL_2")
	)
	(segment
		(start 105.411524 -101.704394)
		(end 105.703878 -101.41204)
		(width 0.1143)
		(layer "B.Cu")
		(net "EXP_I2C_SCL_2")
	)
	(segment
		(start 103.13797 -107.62615)
		(end 102.86492 -107.8992)
		(width 0.1143)
		(layer "B.Cu")
		(net "EXP_I2C_SCL_2")
	)
	(segment
		(start 102.83317 -109.2708)
		(end 102.75697 -109.347)
		(width 0.1143)
		(layer "B.Cu")
		(net "EXP_I2C_SCL_2")
	)
	(segment
		(start 105.871772 -101.41204)
		(end 106.411522 -100.87229)
		(width 0.1143)
		(layer "B.Cu")
		(net "EXP_I2C_SCL_2")
	)
	(segment
		(start 108.03128 -100.288344)
		(end 108.497624 -99.822)
		(width 0.1143)
		(layer "B.Cu")
		(net "EXP_I2C_SCL_2")
	)
	(segment
		(start 103.918004 -107.3658)
		(end 104.287828 -106.995976)
		(width 0.1143)
		(layer "B.Cu")
		(net "EXP_I2C_SCL_2")
	)
	(segment
		(start 106.827574 -100.288344)
		(end 108.03128 -100.288344)
		(width 0.1143)
		(layer "B.Cu")
		(net "EXP_I2C_SCL_2")
	)
	(segment
		(start 102.86492 -107.8992)
		(end 102.86492 -108.37291)
		(width 0.1143)
		(layer "B.Cu")
		(net "EXP_I2C_SCL_2")
	)
	(segment
		(start 106.411522 -100.87229)
		(end 106.411522 -100.704396)
		(width 0.1143)
		(layer "B.Cu")
		(net "EXP_I2C_SCL_2")
	)
	(segment
		(start 104.827578 -103.288338)
		(end 104.995472 -103.288338)
		(width 0.1143)
		(layer "B.Cu")
		(net "EXP_I2C_SCL_2")
	)
	(segment
		(start 105.703878 -101.41204)
		(end 105.871772 -101.41204)
		(width 0.1143)
		(layer "B.Cu")
		(net "EXP_I2C_SCL_2")
	)
	(segment
		(start 108.497624 -99.822)
		(end 108.85297 -99.822)
		(width 0.1143)
		(layer "B.Cu")
		(net "EXP_I2C_SCL_2")
	)
	(segment
		(start 137.6172 -60.2742)
		(end 136.924542 -60.2742)
		(width 0.1143)
		(layer "F.Cu")
		(net "XM_DATA_15")
	)
	(segment
		(start 138.099546 -61.9379)
		(end 138.099546 -60.756546)
		(width 0.1143)
		(layer "F.Cu")
		(net "XM_DATA_15")
	)
	(segment
		(start 138.099546 -60.756546)
		(end 137.6172 -60.2742)
		(width 0.1143)
		(layer "F.Cu")
		(net "XM_DATA_15")
	)
	(segment
		(start 105.150158 -54.99989)
		(end 105.549954 -55.399686)
		(width 0.1143)
		(layer "F.Cu")
		(net "XM_DATA_15")
	)
	(via
		(at 105.549954 -55.399686)
		(size 0.508)
		(drill 0.254)
		(layers "F.Cu" "B.Cu")
		(net "XM_DATA_15")
	)
	(via
		(at 136.924542 -60.2742)
		(size 0.5588)
		(drill 0.3048)
		(layers "F.Cu" "B.Cu")
		(net "XM_DATA_15")
	)
	(via
		(at 129.667 -60.2742)
		(size 0.7112)
		(drill 0.3556)
		(layers "F.Cu" "B.Cu")
		(net "XM_DATA_15")
	)
	(segment
		(start 133.490716 -59.827668)
		(end 133.605016 -59.941968)
		(width 0.1143)
		(layer "B.Cu")
		(net "XM_DATA_15")
	)
	(segment
		(start 132.347716 -59.827668)
		(end 132.576316 -59.827668)
		(width 0.1143)
		(layer "B.Cu")
		(net "XM_DATA_15")
	)
	(segment
		(start 134.519416 -60.1599)
		(end 134.633716 -60.2742)
		(width 0.1143)
		(layer "B.Cu")
		(net "XM_DATA_15")
	)
	(segment
		(start 134.862316 -60.2742)
		(end 134.976616 -60.1599)
		(width 0.1143)
		(layer "B.Cu")
		(net "XM_DATA_15")
	)
	(segment
		(start 130.404616 -60.1599)
		(end 130.404616 -59.941968)
		(width 0.1143)
		(layer "B.Cu")
		(net "XM_DATA_15")
	)
	(segment
		(start 130.290316 -60.2742)
		(end 130.404616 -60.1599)
		(width 0.1143)
		(layer "B.Cu")
		(net "XM_DATA_15")
	)
	(segment
		(start 106.897424 -56.650382)
		(end 106.22153 -56.650382)
		(width 0.1143)
		(layer "B.Cu")
		(net "XM_DATA_15")
	)
	(segment
		(start 129.667 -60.2742)
		(end 130.290316 -60.2742)
		(width 0.1143)
		(layer "B.Cu")
		(net "XM_DATA_15")
	)
	(segment
		(start 131.319016 -60.1599)
		(end 131.319016 -59.941968)
		(width 0.1143)
		(layer "B.Cu")
		(net "XM_DATA_15")
	)
	(segment
		(start 134.062216 -60.1599)
		(end 134.062216 -59.941968)
		(width 0.1143)
		(layer "B.Cu")
		(net "XM_DATA_15")
	)
	(segment
		(start 106.22153 -56.650382)
		(end 105.944416 -56.373268)
		(width 0.1143)
		(layer "B.Cu")
		(net "XM_DATA_15")
	)
	(segment
		(start 134.633716 -60.2742)
		(end 134.862316 -60.2742)
		(width 0.1143)
		(layer "B.Cu")
		(net "XM_DATA_15")
	)
	(segment
		(start 135.433816 -59.941968)
		(end 135.433816 -60.1599)
		(width 0.1143)
		(layer "B.Cu")
		(net "XM_DATA_15")
	)
	(segment
		(start 130.747516 -59.827668)
		(end 130.861816 -59.941968)
		(width 0.1143)
		(layer "B.Cu")
		(net "XM_DATA_15")
	)
	(segment
		(start 131.776216 -60.1599)
		(end 131.890516 -60.2742)
		(width 0.1143)
		(layer "B.Cu")
		(net "XM_DATA_15")
	)
	(segment
		(start 112.451642 -59.713368)
		(end 112.337342 -59.827668)
		(width 0.1143)
		(layer "B.Cu")
		(net "XM_DATA_15")
	)
	(segment
		(start 133.605016 -59.941968)
		(end 133.605016 -60.1599)
		(width 0.1143)
		(layer "B.Cu")
		(net "XM_DATA_15")
	)
	(segment
		(start 113.023142 -59.827668)
		(end 112.908842 -59.713368)
		(width 0.1143)
		(layer "B.Cu")
		(net "XM_DATA_15")
	)
	(segment
		(start 112.108742 -59.827668)
		(end 111.994442 -59.713368)
		(width 0.1143)
		(layer "B.Cu")
		(net "XM_DATA_15")
	)
	(segment
		(start 113.251742 -59.827668)
		(end 113.023142 -59.827668)
		(width 0.1143)
		(layer "B.Cu")
		(net "XM_DATA_15")
	)
	(segment
		(start 112.451642 -58.674)
		(end 112.451642 -59.713368)
		(width 0.1143)
		(layer "B.Cu")
		(net "XM_DATA_15")
	)
	(segment
		(start 113.696242 -58.674)
		(end 113.493042 -58.674)
		(width 0.1143)
		(layer "B.Cu")
		(net "XM_DATA_15")
	)
	(segment
		(start 132.576316 -59.827668)
		(end 132.690616 -59.941968)
		(width 0.1143)
		(layer "B.Cu")
		(net "XM_DATA_15")
	)
	(segment
		(start 135.548116 -60.2742)
		(end 136.924542 -60.2742)
		(width 0.1143)
		(layer "B.Cu")
		(net "XM_DATA_15")
	)
	(segment
		(start 130.861816 -60.1599)
		(end 130.976116 -60.2742)
		(width 0.1143)
		(layer "B.Cu")
		(net "XM_DATA_15")
	)
	(segment
		(start 134.405116 -59.827668)
		(end 134.519416 -59.941968)
		(width 0.1143)
		(layer "B.Cu")
		(net "XM_DATA_15")
	)
	(segment
		(start 111.537242 -59.510676)
		(end 111.537242 -59.713368)
		(width 0.1143)
		(layer "B.Cu")
		(net "XM_DATA_15")
	)
	(segment
		(start 133.147816 -59.941968)
		(end 133.262116 -59.827668)
		(width 0.1143)
		(layer "B.Cu")
		(net "XM_DATA_15")
	)
	(segment
		(start 133.147816 -60.1599)
		(end 133.147816 -59.941968)
		(width 0.1143)
		(layer "B.Cu")
		(net "XM_DATA_15")
	)
	(segment
		(start 112.578642 -58.547)
		(end 112.451642 -58.674)
		(width 0.1143)
		(layer "B.Cu")
		(net "XM_DATA_15")
	)
	(segment
		(start 111.036608 -59.827668)
		(end 108.591858 -57.382918)
		(width 0.1143)
		(layer "B.Cu")
		(net "XM_DATA_15")
	)
	(segment
		(start 131.433316 -59.827668)
		(end 131.661916 -59.827668)
		(width 0.1143)
		(layer "B.Cu")
		(net "XM_DATA_15")
	)
	(segment
		(start 130.861816 -59.941968)
		(end 130.861816 -60.1599)
		(width 0.1143)
		(layer "B.Cu")
		(net "XM_DATA_15")
	)
	(segment
		(start 130.404616 -59.941968)
		(end 130.518916 -59.827668)
		(width 0.1143)
		(layer "B.Cu")
		(net "XM_DATA_15")
	)
	(segment
		(start 131.776216 -59.941968)
		(end 131.776216 -60.1599)
		(width 0.1143)
		(layer "B.Cu")
		(net "XM_DATA_15")
	)
	(segment
		(start 112.908842 -58.674)
		(end 112.781842 -58.547)
		(width 0.1143)
		(layer "B.Cu")
		(net "XM_DATA_15")
	)
	(segment
		(start 133.719316 -60.2742)
		(end 133.947916 -60.2742)
		(width 0.1143)
		(layer "B.Cu")
		(net "XM_DATA_15")
	)
	(segment
		(start 111.422942 -59.827668)
		(end 111.036608 -59.827668)
		(width 0.1143)
		(layer "B.Cu")
		(net "XM_DATA_15")
	)
	(segment
		(start 131.319016 -59.941968)
		(end 131.433316 -59.827668)
		(width 0.1143)
		(layer "B.Cu")
		(net "XM_DATA_15")
	)
	(segment
		(start 132.233416 -59.941968)
		(end 132.347716 -59.827668)
		(width 0.1143)
		(layer "B.Cu")
		(net "XM_DATA_15")
	)
	(segment
		(start 111.994442 -59.713368)
		(end 111.994442 -59.510676)
		(width 0.1143)
		(layer "B.Cu")
		(net "XM_DATA_15")
	)
	(segment
		(start 135.090916 -59.827668)
		(end 135.319516 -59.827668)
		(width 0.1143)
		(layer "B.Cu")
		(net "XM_DATA_15")
	)
	(segment
		(start 134.519416 -59.941968)
		(end 134.519416 -60.1599)
		(width 0.1143)
		(layer "B.Cu")
		(net "XM_DATA_15")
	)
	(segment
		(start 134.062216 -59.941968)
		(end 134.176516 -59.827668)
		(width 0.1143)
		(layer "B.Cu")
		(net "XM_DATA_15")
	)
	(segment
		(start 132.690616 -59.941968)
		(end 132.690616 -60.1599)
		(width 0.1143)
		(layer "B.Cu")
		(net "XM_DATA_15")
	)
	(segment
		(start 105.944416 -55.794148)
		(end 105.549954 -55.399686)
		(width 0.1143)
		(layer "B.Cu")
		(net "XM_DATA_15")
	)
	(segment
		(start 133.605016 -60.1599)
		(end 133.719316 -60.2742)
		(width 0.1143)
		(layer "B.Cu")
		(net "XM_DATA_15")
	)
	(segment
		(start 131.204716 -60.2742)
		(end 131.319016 -60.1599)
		(width 0.1143)
		(layer "B.Cu")
		(net "XM_DATA_15")
	)
	(segment
		(start 111.537242 -59.713368)
		(end 111.422942 -59.827668)
		(width 0.1143)
		(layer "B.Cu")
		(net "XM_DATA_15")
	)
	(segment
		(start 132.233416 -60.1599)
		(end 132.233416 -59.941968)
		(width 0.1143)
		(layer "B.Cu")
		(net "XM_DATA_15")
	)
	(segment
		(start 113.493042 -58.674)
		(end 113.366042 -58.801)
		(width 0.1143)
		(layer "B.Cu")
		(net "XM_DATA_15")
	)
	(segment
		(start 113.823242 -58.801)
		(end 113.696242 -58.674)
		(width 0.1143)
		(layer "B.Cu")
		(net "XM_DATA_15")
	)
	(segment
		(start 113.823242 -59.713368)
		(end 113.823242 -58.801)
		(width 0.1143)
		(layer "B.Cu")
		(net "XM_DATA_15")
	)
	(segment
		(start 112.337342 -59.827668)
		(end 112.108742 -59.827668)
		(width 0.1143)
		(layer "B.Cu")
		(net "XM_DATA_15")
	)
	(segment
		(start 130.518916 -59.827668)
		(end 130.747516 -59.827668)
		(width 0.1143)
		(layer "B.Cu")
		(net "XM_DATA_15")
	)
	(segment
		(start 134.976616 -60.1599)
		(end 134.976616 -59.941968)
		(width 0.1143)
		(layer "B.Cu")
		(net "XM_DATA_15")
	)
	(segment
		(start 133.033516 -60.2742)
		(end 133.147816 -60.1599)
		(width 0.1143)
		(layer "B.Cu")
		(net "XM_DATA_15")
	)
	(segment
		(start 129.667 -60.2742)
		(end 129.6162 -60.2742)
		(width 0.1143)
		(layer "B.Cu")
		(net "XM_DATA_15")
	)
	(segment
		(start 105.944416 -56.373268)
		(end 105.944416 -55.794148)
		(width 0.1143)
		(layer "B.Cu")
		(net "XM_DATA_15")
	)
	(segment
		(start 111.994442 -59.510676)
		(end 111.880142 -59.396376)
		(width 0.1143)
		(layer "B.Cu")
		(net "XM_DATA_15")
	)
	(segment
		(start 135.319516 -59.827668)
		(end 135.433816 -59.941968)
		(width 0.1143)
		(layer "B.Cu")
		(net "XM_DATA_15")
	)
	(segment
		(start 129.169668 -59.827668)
		(end 113.937542 -59.827668)
		(width 0.1143)
		(layer "B.Cu")
		(net "XM_DATA_15")
	)
	(segment
		(start 108.591858 -57.382918)
		(end 107.62996 -57.382918)
		(width 0.1143)
		(layer "B.Cu")
		(net "XM_DATA_15")
	)
	(segment
		(start 135.433816 -60.1599)
		(end 135.548116 -60.2742)
		(width 0.1143)
		(layer "B.Cu")
		(net "XM_DATA_15")
	)
	(segment
		(start 113.366042 -58.801)
		(end 113.366042 -59.713368)
		(width 0.1143)
		(layer "B.Cu")
		(net "XM_DATA_15")
	)
	(segment
		(start 134.176516 -59.827668)
		(end 134.405116 -59.827668)
		(width 0.1143)
		(layer "B.Cu")
		(net "XM_DATA_15")
	)
	(segment
		(start 132.690616 -60.1599)
		(end 132.804916 -60.2742)
		(width 0.1143)
		(layer "B.Cu")
		(net "XM_DATA_15")
	)
	(segment
		(start 131.890516 -60.2742)
		(end 132.119116 -60.2742)
		(width 0.1143)
		(layer "B.Cu")
		(net "XM_DATA_15")
	)
	(segment
		(start 131.661916 -59.827668)
		(end 131.776216 -59.941968)
		(width 0.1143)
		(layer "B.Cu")
		(net "XM_DATA_15")
	)
	(segment
		(start 130.976116 -60.2742)
		(end 131.204716 -60.2742)
		(width 0.1143)
		(layer "B.Cu")
		(net "XM_DATA_15")
	)
	(segment
		(start 112.908842 -59.713368)
		(end 112.908842 -58.674)
		(width 0.1143)
		(layer "B.Cu")
		(net "XM_DATA_15")
	)
	(segment
		(start 129.6162 -60.2742)
		(end 129.169668 -59.827668)
		(width 0.1143)
		(layer "B.Cu")
		(net "XM_DATA_15")
	)
	(segment
		(start 111.880142 -59.396376)
		(end 111.651542 -59.396376)
		(width 0.1143)
		(layer "B.Cu")
		(net "XM_DATA_15")
	)
	(segment
		(start 132.804916 -60.2742)
		(end 133.033516 -60.2742)
		(width 0.1143)
		(layer "B.Cu")
		(net "XM_DATA_15")
	)
	(segment
		(start 133.262116 -59.827668)
		(end 133.490716 -59.827668)
		(width 0.1143)
		(layer "B.Cu")
		(net "XM_DATA_15")
	)
	(segment
		(start 113.366042 -59.713368)
		(end 113.251742 -59.827668)
		(width 0.1143)
		(layer "B.Cu")
		(net "XM_DATA_15")
	)
	(segment
		(start 111.651542 -59.396376)
		(end 111.537242 -59.510676)
		(width 0.1143)
		(layer "B.Cu")
		(net "XM_DATA_15")
	)
	(segment
		(start 132.119116 -60.2742)
		(end 132.233416 -60.1599)
		(width 0.1143)
		(layer "B.Cu")
		(net "XM_DATA_15")
	)
	(segment
		(start 134.976616 -59.941968)
		(end 135.090916 -59.827668)
		(width 0.1143)
		(layer "B.Cu")
		(net "XM_DATA_15")
	)
	(segment
		(start 133.947916 -60.2742)
		(end 134.062216 -60.1599)
		(width 0.1143)
		(layer "B.Cu")
		(net "XM_DATA_15")
	)
	(segment
		(start 113.937542 -59.827668)
		(end 113.823242 -59.713368)
		(width 0.1143)
		(layer "B.Cu")
		(net "XM_DATA_15")
	)
	(segment
		(start 112.781842 -58.547)
		(end 112.578642 -58.547)
		(width 0.1143)
		(layer "B.Cu")
		(net "XM_DATA_15")
	)
	(segment
		(start 107.62996 -57.382918)
		(end 106.897424 -56.650382)
		(width 0.1143)
		(layer "B.Cu")
		(net "XM_DATA_15")
	)
	(segment
		(start 134.530338 -84.037932)
		(end 134.65048 -84.037932)
		(width 0.1016)
		(layer "F.Cu")
		(net "3008_SAS_RX_N2")
	)
	(segment
		(start 134.371842 -83.9216)
		(end 134.458456 -84.008214)
		(width 0.1016)
		(layer "F.Cu")
		(net "3008_SAS_RX_N2")
	)
	(segment
		(start 93.950028 -37.399976)
		(end 94.350586 -36.999418)
		(width 0.1016)
		(layer "F.Cu")
		(net "3008_SAS_RX_N2")
	)
	(segment
		(start 134.016242 -83.891882)
		(end 134.29996 -83.891882)
		(width 0.1016)
		(layer "F.Cu")
		(net "3008_SAS_RX_N2")
	)
	(segment
		(start 94.350586 -36.999418)
		(end 94.359222 -36.999418)
		(width 0.1016)
		(layer "F.Cu")
		(net "3008_SAS_RX_N2")
	)
	(segment
		(start 134.844282 -82.93989)
		(end 134.581392 -82.677)
		(width 0.1016)
		(layer "F.Cu")
		(net "3008_SAS_RX_N2")
	)
	(segment
		(start 134.874 -83.814412)
		(end 134.874 -83.011772)
		(width 0.1016)
		(layer "F.Cu")
		(net "3008_SAS_RX_N2")
	)
	(via
		(at 134.581392 -82.677)
		(size 0.5588)
		(drill 0.3048)
		(layers "F.Cu" "B.Cu")
		(net "3008_SAS_RX_N2")
	)
	(via
		(at 94.359222 -36.999418)
		(size 0.508)
		(drill 0.254)
		(layers "F.Cu" "B.Cu")
		(net "3008_SAS_RX_N2")
	)
	(arc
		(start 134.29996 -83.891882)
		(mid 134.338855 -83.899601)
		(end 134.371842 -83.9216)
		(width 0.1016)
		(layer "F.Cu")
		(net "3008_SAS_RX_N2")
	)
	(arc
		(start 134.458456 -84.008214)
		(mid 134.49145 -84.030197)
		(end 134.530338 -84.037932)
		(width 0.1016)
		(layer "F.Cu")
		(net "3008_SAS_RX_N2")
	)
	(arc
		(start 134.874 -83.011772)
		(mid 134.866281 -82.972877)
		(end 134.844282 -82.93989)
		(width 0.1016)
		(layer "F.Cu")
		(net "3008_SAS_RX_N2")
	)
	(arc
		(start 134.65048 -84.037932)
		(mid 134.808533 -83.972465)
		(end 134.874 -83.814412)
		(width 0.1016)
		(layer "F.Cu")
		(net "3008_SAS_RX_N2")
	)
	(segment
		(start 121.820432 -70.076568)
		(end 122.308366 -70.564502)
		(width 0.1016)
		(layer "In5.Cu")
		(net "3008_SAS_RX_N2")
	)
	(segment
		(start 122.667776 -70.7136)
		(end 127.74422 -70.7136)
		(width 0.1016)
		(layer "In5.Cu")
		(net "3008_SAS_RX_N2")
	)
	(segment
		(start 89.592658 -38.975538)
		(end 89.592658 -39.30269)
		(width 0.1016)
		(layer "In5.Cu")
		(net "3008_SAS_RX_N2")
	)
	(segment
		(start 90.825574 -37.28212)
		(end 89.918286 -38.189408)
		(width 0.1016)
		(layer "In5.Cu")
		(net "3008_SAS_RX_N2")
	)
	(segment
		(start 93.2434 -36.60267)
		(end 93.070426 -36.60267)
		(width 0.1016)
		(layer "In5.Cu")
		(net "3008_SAS_RX_N2")
	)
	(segment
		(start 97.905824 -63.8302)
		(end 105.156508 -63.8302)
		(width 0.1016)
		(layer "In5.Cu")
		(net "3008_SAS_RX_N2")
	)
	(segment
		(start 94.017084 -36.60267)
		(end 93.6752 -36.60267)
		(width 0.1016)
		(layer "In5.Cu")
		(net "3008_SAS_RX_N2")
	)
	(segment
		(start 91.444826 -57.764426)
		(end 97.2312 -63.5508)
		(width 0.1016)
		(layer "In5.Cu")
		(net "3008_SAS_RX_N2")
	)
	(segment
		(start 93.6752 -36.60267)
		(end 93.2434 -36.60267)
		(width 0.0889)
		(layer "In5.Cu")
		(net "3008_SAS_RX_N2")
	)
	(segment
		(start 86.79688 -42.623486)
		(end 86.79688 -49.809654)
		(width 0.1016)
		(layer "In5.Cu")
		(net "3008_SAS_RX_N2")
	)
	(segment
		(start 106.073956 -64.210184)
		(end 111.101886 -69.238114)
		(width 0.1016)
		(layer "In5.Cu")
		(net "3008_SAS_RX_N2")
	)
	(segment
		(start 91.2114 -56.55564)
		(end 91.2114 -57.2008)
		(width 0.1016)
		(layer "In5.Cu")
		(net "3008_SAS_RX_N2")
	)
	(segment
		(start 133.985 -76.2)
		(end 134.025386 -76.24064)
		(width 0.1016)
		(layer "In5.Cu")
		(net "3008_SAS_RX_N2")
	)
	(segment
		(start 87.0204 -42.1894)
		(end 86.945978 -42.264076)
		(width 0.1016)
		(layer "In5.Cu")
		(net "3008_SAS_RX_N2")
	)
	(segment
		(start 88.06434 -52.8701)
		(end 90.830654 -55.636414)
		(width 0.1016)
		(layer "In5.Cu")
		(net "3008_SAS_RX_N2")
	)
	(segment
		(start 112.211104 -69.6976)
		(end 120.905524 -69.6976)
		(width 0.1016)
		(layer "In5.Cu")
		(net "3008_SAS_RX_N2")
	)
	(segment
		(start 91.059254 -37.048186)
		(end 90.825574 -37.28212)
		(width 0.1016)
		(layer "In5.Cu")
		(net "3008_SAS_RX_N2")
	)
	(segment
		(start 129.032 -71.247)
		(end 133.985 -76.2)
		(width 0.1016)
		(layer "In5.Cu")
		(net "3008_SAS_RX_N2")
	)
	(segment
		(start 94.359222 -36.999418)
		(end 94.359222 -36.944046)
		(width 0.1016)
		(layer "In5.Cu")
		(net "3008_SAS_RX_N2")
	)
	(segment
		(start 92.544646 -36.8046)
		(end 91.647264 -36.8046)
		(width 0.1016)
		(layer "In5.Cu")
		(net "3008_SAS_RX_N2")
	)
	(segment
		(start 134.7978 -78.105)
		(end 134.7978 -82.154522)
		(width 0.1016)
		(layer "In5.Cu")
		(net "3008_SAS_RX_N2")
	)
	(segment
		(start 89.370408 -39.839646)
		(end 89.281 -39.9288)
		(width 0.1016)
		(layer "In5.Cu")
		(net "3008_SAS_RX_N2")
	)
	(segment
		(start 89.281 -39.9288)
		(end 87.0204 -42.1894)
		(width 0.1016)
		(layer "In5.Cu")
		(net "3008_SAS_RX_N2")
	)
	(arc
		(start 94.359222 -36.944046)
		(mid 94.333275 -36.813601)
		(end 94.2594 -36.703)
		(width 0.1016)
		(layer "In5.Cu")
		(net "3008_SAS_RX_N2")
	)
	(arc
		(start 105.156508 -63.8302)
		(mid 105.653014 -63.928961)
		(end 106.073956 -64.210184)
		(width 0.1016)
		(layer "In5.Cu")
		(net "3008_SAS_RX_N2")
	)
	(arc
		(start 86.945978 -42.264076)
		(mid 86.835713 -42.42896)
		(end 86.79688 -42.623486)
		(width 0.1016)
		(layer "In5.Cu")
		(net "3008_SAS_RX_N2")
	)
	(arc
		(start 111.101886 -69.238114)
		(mid 111.6108 -69.578159)
		(end 112.211104 -69.6976)
		(width 0.1016)
		(layer "In5.Cu")
		(net "3008_SAS_RX_N2")
	)
	(arc
		(start 134.797546 -82.164428)
		(mid 134.739568 -82.441847)
		(end 134.581392 -82.677)
		(width 0.1016)
		(layer "In5.Cu")
		(net "3008_SAS_RX_N2")
	)
	(arc
		(start 90.830654 -55.636414)
		(mid 91.112455 -56.058158)
		(end 91.2114 -56.55564)
		(width 0.1016)
		(layer "In5.Cu")
		(net "3008_SAS_RX_N2")
	)
	(arc
		(start 120.905524 -69.6976)
		(mid 121.400669 -69.79609)
		(end 121.820432 -70.076568)
		(width 0.1016)
		(layer "In5.Cu")
		(net "3008_SAS_RX_N2")
	)
	(arc
		(start 93.070426 -36.60267)
		(mid 92.944647 -36.627689)
		(end 92.838016 -36.698936)
		(width 0.1016)
		(layer "In5.Cu")
		(net "3008_SAS_RX_N2")
	)
	(arc
		(start 97.2312 -63.5508)
		(mid 97.54072 -63.757615)
		(end 97.905824 -63.8302)
		(width 0.1016)
		(layer "In5.Cu")
		(net "3008_SAS_RX_N2")
	)
	(arc
		(start 122.308366 -70.564502)
		(mid 122.47325 -70.674767)
		(end 122.667776 -70.7136)
		(width 0.1016)
		(layer "In5.Cu")
		(net "3008_SAS_RX_N2")
	)
	(arc
		(start 91.2114 -57.2008)
		(mid 91.272072 -57.505819)
		(end 91.444826 -57.764426)
		(width 0.1016)
		(layer "In5.Cu")
		(net "3008_SAS_RX_N2")
	)
	(arc
		(start 134.025386 -76.24064)
		(mid 134.597013 -77.096001)
		(end 134.7978 -78.105)
		(width 0.1016)
		(layer "In5.Cu")
		(net "3008_SAS_RX_N2")
	)
	(arc
		(start 134.7978 -82.154522)
		(mid 134.79769 -82.159475)
		(end 134.797546 -82.164428)
		(width 0.1016)
		(layer "In5.Cu")
		(net "3008_SAS_RX_N2")
	)
	(arc
		(start 89.592658 -39.30269)
		(mid 89.53495 -39.593279)
		(end 89.370408 -39.839646)
		(width 0.1016)
		(layer "In5.Cu")
		(net "3008_SAS_RX_N2")
	)
	(arc
		(start 89.918286 -38.189408)
		(mid 89.677258 -38.550087)
		(end 89.592658 -38.975538)
		(width 0.1016)
		(layer "In5.Cu")
		(net "3008_SAS_RX_N2")
	)
	(arc
		(start 127.74422 -70.7136)
		(mid 128.441155 -70.852229)
		(end 129.032 -71.247)
		(width 0.1016)
		(layer "In5.Cu")
		(net "3008_SAS_RX_N2")
	)
	(arc
		(start 94.2594 -36.703)
		(mid 94.148224 -36.628715)
		(end 94.017084 -36.60267)
		(width 0.1016)
		(layer "In5.Cu")
		(net "3008_SAS_RX_N2")
	)
	(arc
		(start 86.79688 -49.809654)
		(mid 87.126277 -51.465915)
		(end 88.06434 -52.8701)
		(width 0.1016)
		(layer "In5.Cu")
		(net "3008_SAS_RX_N2")
	)
	(arc
		(start 91.647264 -36.8046)
		(mid 91.329026 -36.867901)
		(end 91.059254 -37.048186)
		(width 0.1016)
		(layer "In5.Cu")
		(net "3008_SAS_RX_N2")
	)
	(arc
		(start 92.838016 -36.698936)
		(mid 92.700552 -36.777387)
		(end 92.544646 -36.8046)
		(width 0.1016)
		(layer "In5.Cu")
		(net "3008_SAS_RX_N2")
	)
	(segment
		(start 191.316356 -119.085106)
		(end 190.4365 -118.20525)
		(width 0.127)
		(layer "F.Cu")
		(net "P3V3_STBY_B2")
	)
	(segment
		(start 189.00775 -118.20525)
		(end 190.4365 -118.20525)
		(width 0.127)
		(layer "F.Cu")
		(net "P3V3_STBY_B2")
	)
	(segment
		(start 188.976 -118.237)
		(end 189.00775 -118.20525)
		(width 0.127)
		(layer "F.Cu")
		(net "P3V3_STBY_B2")
	)
	(segment
		(start 191.316356 -119.770652)
		(end 191.316356 -119.085106)
		(width 0.127)
		(layer "F.Cu")
		(net "P3V3_STBY_B2")
	)
	(via
		(at 188.976 -118.237)
		(size 0.7112)
		(drill 0.3556)
		(layers "F.Cu" "B.Cu")
		(net "P3V3_STBY_B2")
	)
	(segment
		(start 120.91797 -82.781902)
		(end 120.91797 -82.141314)
		(width 0.1016)
		(layer "F.Cu")
		(net "EXP_REF_CLK_P")
	)
	(segment
		(start 119.845328 -77.844142)
		(end 120.09247 -77.597)
		(width 0.1016)
		(layer "F.Cu")
		(net "EXP_REF_CLK_P")
	)
	(segment
		(start 120.93067 -76.7588)
		(end 122.4788 -76.7588)
		(width 0.1016)
		(layer "F.Cu")
		(net "EXP_REF_CLK_P")
	)
	(segment
		(start 120.909842 -82.133186)
		(end 120.909842 -81.015332)
		(width 0.1016)
		(layer "F.Cu")
		(net "EXP_REF_CLK_P")
	)
	(segment
		(start 124.92736 -77.3684)
		(end 125.507242 -77.948282)
		(width 0.1016)
		(layer "F.Cu")
		(net "EXP_REF_CLK_P")
	)
	(segment
		(start 122.4788 -76.7588)
		(end 123.0884 -77.3684)
		(width 0.1016)
		(layer "F.Cu")
		(net "EXP_REF_CLK_P")
	)
	(segment
		(start 120.909842 -81.015332)
		(end 119.845328 -79.950818)
		(width 0.1016)
		(layer "F.Cu")
		(net "EXP_REF_CLK_P")
	)
	(segment
		(start 119.845328 -79.950818)
		(end 119.845328 -77.844142)
		(width 0.1016)
		(layer "F.Cu")
		(net "EXP_REF_CLK_P")
	)
	(segment
		(start 123.0884 -77.3684)
		(end 124.92736 -77.3684)
		(width 0.1016)
		(layer "F.Cu")
		(net "EXP_REF_CLK_P")
	)
	(segment
		(start 120.09247 -77.597)
		(end 120.93067 -76.7588)
		(width 0.1016)
		(layer "F.Cu")
		(net "EXP_REF_CLK_P")
	)
	(segment
		(start 120.91797 -82.141314)
		(end 120.909842 -82.133186)
		(width 0.1016)
		(layer "F.Cu")
		(net "EXP_REF_CLK_P")
	)
	(segment
		(start 120.350026 -83.349846)
		(end 120.91797 -82.781902)
		(width 0.1016)
		(layer "F.Cu")
		(net "EXP_REF_CLK_P")
	)
	(segment
		(start 105.349802 -104.350058)
		(end 105.349802 -104.468168)
		(width 0.1143)
		(layer "F.Cu")
		(net "EXP_I2C_SDA_1")
	)
	(segment
		(start 83.96097 -119.870728)
		(end 84.105242 -120.015)
		(width 0.1143)
		(layer "F.Cu")
		(net "EXP_I2C_SDA_1")
	)
	(segment
		(start 105.349802 -104.468168)
		(end 104.967786 -104.850184)
		(width 0.1143)
		(layer "F.Cu")
		(net "EXP_I2C_SDA_1")
	)
	(segment
		(start 84.47405 -118.23192)
		(end 83.96097 -118.745)
		(width 0.1143)
		(layer "F.Cu")
		(net "EXP_I2C_SDA_1")
	)
	(segment
		(start 90.493342 -117.800882)
		(end 89.992708 -117.800882)
		(width 0.1143)
		(layer "F.Cu")
		(net "EXP_I2C_SDA_1")
	)
	(segment
		(start 104.967786 -104.850184)
		(end 104.849676 -104.850184)
		(width 0.1143)
		(layer "F.Cu")
		(net "EXP_I2C_SDA_1")
	)
	(segment
		(start 83.96097 -118.745)
		(end 83.96097 -119.870728)
		(width 0.1143)
		(layer "F.Cu")
		(net "EXP_I2C_SDA_1")
	)
	(segment
		(start 84.105242 -120.015)
		(end 84.105242 -121.143522)
		(width 0.1143)
		(layer "F.Cu")
		(net "EXP_I2C_SDA_1")
	)
	(segment
		(start 89.992708 -117.800882)
		(end 89.56167 -118.23192)
		(width 0.1143)
		(layer "F.Cu")
		(net "EXP_I2C_SDA_1")
	)
	(segment
		(start 89.56167 -118.23192)
		(end 89.29497 -118.23192)
		(width 0.1143)
		(layer "F.Cu")
		(net "EXP_I2C_SDA_1")
	)
	(segment
		(start 89.29497 -118.23192)
		(end 84.47405 -118.23192)
		(width 0.1143)
		(layer "F.Cu")
		(net "EXP_I2C_SDA_1")
	)
	(via
		(at 83.96097 -118.745)
		(size 0.5588)
		(drill 0.3048)
		(layers "F.Cu" "B.Cu")
		(net "EXP_I2C_SDA_1")
	)
	(via
		(at 89.29497 -118.23192)
		(size 0.7112)
		(drill 0.3556)
		(layers "F.Cu" "B.Cu")
		(net "EXP_I2C_SDA_1")
	)
	(via
		(at 104.849676 -104.850184)
		(size 0.508)
		(drill 0.254)
		(layers "F.Cu" "B.Cu")
		(net "EXP_I2C_SDA_1")
	)
	(segment
		(start 83.96097 -118.745)
		(end 84.44484 -119.22887)
		(width 0.127)
		(layer "In2.Cu")
		(net "EXP_I2C_SDA_1")
	)
	(segment
		(start 84.44484 -119.22887)
		(end 86.6521 -119.22887)
		(width 0.127)
		(layer "In2.Cu")
		(net "EXP_I2C_SDA_1")
	)
	(segment
		(start 104.713786 -104.850184)
		(end 104.849676 -104.850184)
		(width 0.127)
		(layer "In2.Cu")
		(net "EXP_I2C_SDA_1")
	)
	(segment
		(start 104.294686 -104.431084)
		(end 104.713786 -104.850184)
		(width 0.127)
		(layer "In2.Cu")
		(net "EXP_I2C_SDA_1")
	)
	(segment
		(start 86.6521 -119.22887)
		(end 101.449886 -104.431084)
		(width 0.127)
		(layer "In2.Cu")
		(net "EXP_I2C_SDA_1")
	)
	(segment
		(start 101.449886 -104.431084)
		(end 104.294686 -104.431084)
		(width 0.127)
		(layer "In2.Cu")
		(net "EXP_I2C_SDA_1")
	)
	(segment
		(start 115.726464 -51.380898)
		(end 115.755166 -51.4096)
		(width 0.1143)
		(layer "F.Cu")
		(net "XM_ADDR_21")
	)
	(segment
		(start 115.217702 -51.3715)
		(end 115.2271 -51.380898)
		(width 0.1143)
		(layer "F.Cu")
		(net "XM_ADDR_21")
	)
	(segment
		(start 141.39672 -45.342556)
		(end 141.39672 -45.5041)
		(width 0.1143)
		(layer "F.Cu")
		(net "XM_ADDR_21")
	)
	(segment
		(start 143.086582 -47.556674)
		(end 142.959582 -47.683674)
		(width 0.1143)
		(layer "F.Cu")
		(net "XM_ADDR_21")
	)
	(segment
		(start 143.086582 -46.791372)
		(end 143.086582 -47.556674)
		(width 0.1143)
		(layer "F.Cu")
		(net "XM_ADDR_21")
	)
	(segment
		(start 142.769336 -46.474126)
		(end 143.086582 -46.791372)
		(width 0.1143)
		(layer "F.Cu")
		(net "XM_ADDR_21")
	)
	(segment
		(start 141.881606 -45.827442)
		(end 142.043404 -45.98924)
		(width 0.1143)
		(layer "F.Cu")
		(net "XM_ADDR_21")
	)
	(segment
		(start 142.959582 -47.683674)
		(end 142.707868 -47.683674)
		(width 0.1143)
		(layer "F.Cu")
		(net "XM_ADDR_21")
	)
	(segment
		(start 141.972792 -46.38294)
		(end 142.13459 -46.544738)
		(width 0.1143)
		(layer "F.Cu")
		(net "XM_ADDR_21")
	)
	(segment
		(start 142.043404 -46.150784)
		(end 141.972792 -46.221396)
		(width 0.1143)
		(layer "F.Cu")
		(net "XM_ADDR_21")
	)
	(segment
		(start 114.87023 -51.3715)
		(end 115.217702 -51.3715)
		(width 0.1143)
		(layer "F.Cu")
		(net "XM_ADDR_21")
	)
	(segment
		(start 141.64945 -45.898054)
		(end 141.720062 -45.827442)
		(width 0.1143)
		(layer "F.Cu")
		(net "XM_ADDR_21")
	)
	(segment
		(start 141.487906 -45.898054)
		(end 141.64945 -45.898054)
		(width 0.1143)
		(layer "F.Cu")
		(net "XM_ADDR_21")
	)
	(segment
		(start 115.755166 -51.4096)
		(end 115.945666 -51.4096)
		(width 0.1143)
		(layer "F.Cu")
		(net "XM_ADDR_21")
	)
	(segment
		(start 141.326108 -45.736256)
		(end 141.487906 -45.898054)
		(width 0.1143)
		(layer "F.Cu")
		(net "XM_ADDR_21")
	)
	(segment
		(start 142.707868 -47.683674)
		(end 142.367 -47.342806)
		(width 0.1143)
		(layer "F.Cu")
		(net "XM_ADDR_21")
	)
	(segment
		(start 142.296134 -46.544738)
		(end 142.366746 -46.474126)
		(width 0.1143)
		(layer "F.Cu")
		(net "XM_ADDR_21")
	)
	(segment
		(start 142.367 -47.342806)
		(end 142.367 -47.244)
		(width 0.1143)
		(layer "F.Cu")
		(net "XM_ADDR_21")
	)
	(segment
		(start 115.2271 -51.380898)
		(end 115.726464 -51.380898)
		(width 0.1143)
		(layer "F.Cu")
		(net "XM_ADDR_21")
	)
	(segment
		(start 142.366746 -46.474126)
		(end 142.769336 -46.474126)
		(width 0.1143)
		(layer "F.Cu")
		(net "XM_ADDR_21")
	)
	(segment
		(start 141.326108 -45.574712)
		(end 141.326108 -45.736256)
		(width 0.1143)
		(layer "F.Cu")
		(net "XM_ADDR_21")
	)
	(segment
		(start 141.972792 -46.221396)
		(end 141.972792 -46.38294)
		(width 0.1143)
		(layer "F.Cu")
		(net "XM_ADDR_21")
	)
	(segment
		(start 113.150142 -51.799998)
		(end 113.464848 -51.799998)
		(width 0.1143)
		(layer "F.Cu")
		(net "XM_ADDR_21")
	)
	(segment
		(start 113.464848 -51.799998)
		(end 113.883948 -51.380898)
		(width 0.1143)
		(layer "F.Cu")
		(net "XM_ADDR_21")
	)
	(segment
		(start 141.720062 -45.827442)
		(end 141.881606 -45.827442)
		(width 0.1143)
		(layer "F.Cu")
		(net "XM_ADDR_21")
	)
	(segment
		(start 142.043404 -45.98924)
		(end 142.043404 -46.150784)
		(width 0.1143)
		(layer "F.Cu")
		(net "XM_ADDR_21")
	)
	(segment
		(start 141.099286 -42.7101)
		(end 141.099286 -45.045122)
		(width 0.1143)
		(layer "F.Cu")
		(net "XM_ADDR_21")
	)
	(segment
		(start 141.099286 -45.045122)
		(end 141.39672 -45.342556)
		(width 0.1143)
		(layer "F.Cu")
		(net "XM_ADDR_21")
	)
	(segment
		(start 113.883948 -51.380898)
		(end 114.860832 -51.380898)
		(width 0.1143)
		(layer "F.Cu")
		(net "XM_ADDR_21")
	)
	(segment
		(start 142.13459 -46.544738)
		(end 142.296134 -46.544738)
		(width 0.1143)
		(layer "F.Cu")
		(net "XM_ADDR_21")
	)
	(segment
		(start 141.39672 -45.5041)
		(end 141.326108 -45.574712)
		(width 0.1143)
		(layer "F.Cu")
		(net "XM_ADDR_21")
	)
	(segment
		(start 114.860832 -51.380898)
		(end 114.87023 -51.3715)
		(width 0.1143)
		(layer "F.Cu")
		(net "XM_ADDR_21")
	)
	(via
		(at 115.945666 -51.4096)
		(size 0.508)
		(drill 0.254)
		(layers "F.Cu" "B.Cu")
		(net "XM_ADDR_21")
	)
	(via
		(at 142.367 -47.244)
		(size 0.5588)
		(drill 0.3048)
		(layers "F.Cu" "B.Cu")
		(net "XM_ADDR_21")
	)
	(segment
		(start 141.732 -47.244)
		(end 142.367 -47.244)
		(width 0.1143)
		(layer "B.Cu")
		(net "XM_ADDR_21")
	)
	(segment
		(start 141.351 -46.863)
		(end 141.732 -47.244)
		(width 0.1143)
		(layer "B.Cu")
		(net "XM_ADDR_21")
	)
	(segment
		(start 139.507214 -45.4406)
		(end 139.253214 -45.4406)
		(width 0.127)
		(layer "In5.Cu")
		(net "XM_ADDR_21")
	)
	(segment
		(start 142.240762 -46.0883)
		(end 141.793214 -46.0883)
		(width 0.127)
		(layer "In5.Cu")
		(net "XM_ADDR_21")
	)
	(segment
		(start 123.491498 -47.944786)
		(end 123.85421 -48.307244)
		(width 0.127)
		(layer "In5.Cu")
		(net "XM_ADDR_21")
	)
	(segment
		(start 140.269214 -45.4406)
		(end 140.142214 -45.5676)
		(width 0.127)
		(layer "In5.Cu")
		(net "XM_ADDR_21")
	)
	(segment
		(start 141.793214 -46.0883)
		(end 141.666214 -45.9613)
		(width 0.127)
		(layer "In5.Cu")
		(net "XM_ADDR_21")
	)
	(segment
		(start 139.253214 -45.4406)
		(end 139.126214 -45.5676)
		(width 0.127)
		(layer "In5.Cu")
		(net "XM_ADDR_21")
	)
	(segment
		(start 138.491214 -45.4406)
		(end 138.237214 -45.4406)
		(width 0.127)
		(layer "In5.Cu")
		(net "XM_ADDR_21")
	)
	(segment
		(start 142.494762 -46.632114)
		(end 142.367762 -46.505114)
		(width 0.127)
		(layer "In5.Cu")
		(net "XM_ADDR_21")
	)
	(segment
		(start 138.618214 -45.5676)
		(end 138.491214 -45.4406)
		(width 0.127)
		(layer "In5.Cu")
		(net "XM_ADDR_21")
	)
	(segment
		(start 142.748762 -46.632114)
		(end 142.494762 -46.632114)
		(width 0.127)
		(layer "In5.Cu")
		(net "XM_ADDR_21")
	)
	(segment
		(start 139.634214 -45.9613)
		(end 139.634214 -45.5676)
		(width 0.127)
		(layer "In5.Cu")
		(net "XM_ADDR_21")
	)
	(segment
		(start 140.142214 -45.5676)
		(end 140.142214 -45.9613)
		(width 0.127)
		(layer "In5.Cu")
		(net "XM_ADDR_21")
	)
	(segment
		(start 143.383762 -46.780196)
		(end 143.383762 -46.2153)
		(width 0.127)
		(layer "In5.Cu")
		(net "XM_ADDR_21")
	)
	(segment
		(start 140.650214 -45.9613)
		(end 140.650214 -45.5676)
		(width 0.127)
		(layer "In5.Cu")
		(net "XM_ADDR_21")
	)
	(segment
		(start 123.85421 -48.307244)
		(end 123.85421 -48.486568)
		(width 0.127)
		(layer "In5.Cu")
		(net "XM_ADDR_21")
	)
	(segment
		(start 122.236484 -50.104294)
		(end 122.05716 -50.104294)
		(width 0.127)
		(layer "In5.Cu")
		(net "XM_ADDR_21")
	)
	(segment
		(start 142.875762 -46.2153)
		(end 142.875762 -46.505114)
		(width 0.127)
		(layer "In5.Cu")
		(net "XM_ADDR_21")
	)
	(segment
		(start 139.126214 -45.9613)
		(end 138.999214 -46.0883)
		(width 0.127)
		(layer "In5.Cu")
		(net "XM_ADDR_21")
	)
	(segment
		(start 121.694448 -49.741836)
		(end 121.515124 -49.741836)
		(width 0.127)
		(layer "In5.Cu")
		(net "XM_ADDR_21")
	)
	(segment
		(start 144.450562 -47.516034)
		(end 144.577562 -47.389034)
		(width 0.127)
		(layer "In5.Cu")
		(net "XM_ADDR_21")
	)
	(segment
		(start 143.891762 -46.780196)
		(end 143.764762 -46.907196)
		(width 0.127)
		(layer "In5.Cu")
		(net "XM_ADDR_21")
	)
	(segment
		(start 116.97208 -50.79492)
		(end 116.3574 -51.4096)
		(width 0.127)
		(layer "In5.Cu")
		(net "XM_ADDR_21")
	)
	(segment
		(start 122.053858 -49.382426)
		(end 122.41657 -49.744884)
		(width 0.127)
		(layer "In5.Cu")
		(net "XM_ADDR_21")
	)
	(segment
		(start 143.002762 -46.0883)
		(end 142.875762 -46.2153)
		(width 0.127)
		(layer "In5.Cu")
		(net "XM_ADDR_21")
	)
	(segment
		(start 121.335038 -49.921922)
		(end 121.335038 -50.101246)
		(width 0.127)
		(layer "In5.Cu")
		(net "XM_ADDR_21")
	)
	(segment
		(start 141.158214 -45.5676)
		(end 141.158214 -45.9613)
		(width 0.127)
		(layer "In5.Cu")
		(net "XM_ADDR_21")
	)
	(segment
		(start 139.634214 -45.5676)
		(end 139.507214 -45.4406)
		(width 0.127)
		(layer "In5.Cu")
		(net "XM_ADDR_21")
	)
	(segment
		(start 123.674124 -48.666654)
		(end 123.4948 -48.666654)
		(width 0.127)
		(layer "In5.Cu")
		(net "XM_ADDR_21")
	)
	(segment
		(start 141.285214 -45.4406)
		(end 141.158214 -45.5676)
		(width 0.127)
		(layer "In5.Cu")
		(net "XM_ADDR_21")
	)
	(segment
		(start 138.110214 -45.9613)
		(end 137.983214 -46.0883)
		(width 0.127)
		(layer "In5.Cu")
		(net "XM_ADDR_21")
	)
	(segment
		(start 139.761214 -46.0883)
		(end 139.634214 -45.9613)
		(width 0.127)
		(layer "In5.Cu")
		(net "XM_ADDR_21")
	)
	(segment
		(start 141.158214 -45.9613)
		(end 141.031214 -46.0883)
		(width 0.127)
		(layer "In5.Cu")
		(net "XM_ADDR_21")
	)
	(segment
		(start 123.85421 -48.486568)
		(end 123.674124 -48.666654)
		(width 0.127)
		(layer "In5.Cu")
		(net "XM_ADDR_21")
	)
	(segment
		(start 143.510762 -46.907196)
		(end 143.383762 -46.780196)
		(width 0.127)
		(layer "In5.Cu")
		(net "XM_ADDR_21")
	)
	(segment
		(start 144.577562 -46.2153)
		(end 144.450562 -46.0883)
		(width 0.127)
		(layer "In5.Cu")
		(net "XM_ADDR_21")
	)
	(segment
		(start 144.450562 -46.0883)
		(end 144.018762 -46.0883)
		(width 0.127)
		(layer "In5.Cu")
		(net "XM_ADDR_21")
	)
	(segment
		(start 143.764762 -46.907196)
		(end 143.510762 -46.907196)
		(width 0.127)
		(layer "In5.Cu")
		(net "XM_ADDR_21")
	)
	(segment
		(start 141.031214 -46.0883)
		(end 140.777214 -46.0883)
		(width 0.127)
		(layer "In5.Cu")
		(net "XM_ADDR_21")
	)
	(segment
		(start 123.4948 -48.666654)
		(end 123.132088 -48.304196)
		(width 0.127)
		(layer "In5.Cu")
		(net "XM_ADDR_21")
	)
	(segment
		(start 122.77598 -49.385474)
		(end 122.413268 -49.023016)
		(width 0.127)
		(layer "In5.Cu")
		(net "XM_ADDR_21")
	)
	(segment
		(start 122.955304 -49.385474)
		(end 122.77598 -49.385474)
		(width 0.127)
		(layer "In5.Cu")
		(net "XM_ADDR_21")
	)
	(segment
		(start 141.666214 -45.5676)
		(end 141.539214 -45.4406)
		(width 0.127)
		(layer "In5.Cu")
		(net "XM_ADDR_21")
	)
	(segment
		(start 134.375906 -46.0883)
		(end 133.359652 -47.104554)
		(width 0.127)
		(layer "In5.Cu")
		(net "XM_ADDR_21")
	)
	(segment
		(start 142.367762 -46.505114)
		(end 142.367762 -46.2153)
		(width 0.127)
		(layer "In5.Cu")
		(net "XM_ADDR_21")
	)
	(segment
		(start 142.367 -47.389034)
		(end 142.494 -47.516034)
		(width 0.127)
		(layer "In5.Cu")
		(net "XM_ADDR_21")
	)
	(segment
		(start 122.772678 -48.484282)
		(end 122.772678 -48.663606)
		(width 0.127)
		(layer "In5.Cu")
		(net "XM_ADDR_21")
	)
	(segment
		(start 123.13539 -49.205388)
		(end 122.955304 -49.385474)
		(width 0.127)
		(layer "In5.Cu")
		(net "XM_ADDR_21")
	)
	(segment
		(start 138.110214 -45.5676)
		(end 138.110214 -45.9613)
		(width 0.127)
		(layer "In5.Cu")
		(net "XM_ADDR_21")
	)
	(segment
		(start 143.383762 -46.2153)
		(end 143.256762 -46.0883)
		(width 0.127)
		(layer "In5.Cu")
		(net "XM_ADDR_21")
	)
	(segment
		(start 122.952764 -48.304196)
		(end 122.772678 -48.484282)
		(width 0.127)
		(layer "In5.Cu")
		(net "XM_ADDR_21")
	)
	(segment
		(start 123.132088 -48.304196)
		(end 122.952764 -48.304196)
		(width 0.127)
		(layer "In5.Cu")
		(net "XM_ADDR_21")
	)
	(segment
		(start 140.523214 -45.4406)
		(end 140.269214 -45.4406)
		(width 0.127)
		(layer "In5.Cu")
		(net "XM_ADDR_21")
	)
	(segment
		(start 144.018762 -46.0883)
		(end 143.891762 -46.2153)
		(width 0.127)
		(layer "In5.Cu")
		(net "XM_ADDR_21")
	)
	(segment
		(start 122.053858 -49.203102)
		(end 122.053858 -49.382426)
		(width 0.127)
		(layer "In5.Cu")
		(net "XM_ADDR_21")
	)
	(segment
		(start 138.618214 -45.9613)
		(end 138.618214 -45.5676)
		(width 0.127)
		(layer "In5.Cu")
		(net "XM_ADDR_21")
	)
	(segment
		(start 120.46204 -50.79492)
		(end 116.97208 -50.79492)
		(width 0.127)
		(layer "In5.Cu")
		(net "XM_ADDR_21")
	)
	(segment
		(start 140.650214 -45.5676)
		(end 140.523214 -45.4406)
		(width 0.127)
		(layer "In5.Cu")
		(net "XM_ADDR_21")
	)
	(segment
		(start 121.33834 -50.823114)
		(end 120.975628 -50.460656)
		(width 0.127)
		(layer "In5.Cu")
		(net "XM_ADDR_21")
	)
	(segment
		(start 140.015214 -46.0883)
		(end 139.761214 -46.0883)
		(width 0.127)
		(layer "In5.Cu")
		(net "XM_ADDR_21")
	)
	(segment
		(start 116.3574 -51.4096)
		(end 115.945666 -51.4096)
		(width 0.127)
		(layer "In5.Cu")
		(net "XM_ADDR_21")
	)
	(segment
		(start 122.41657 -49.924208)
		(end 122.236484 -50.104294)
		(width 0.127)
		(layer "In5.Cu")
		(net "XM_ADDR_21")
	)
	(segment
		(start 142.875762 -46.505114)
		(end 142.748762 -46.632114)
		(width 0.127)
		(layer "In5.Cu")
		(net "XM_ADDR_21")
	)
	(segment
		(start 133.359652 -47.104554)
		(end 124.152406 -47.104554)
		(width 0.127)
		(layer "In5.Cu")
		(net "XM_ADDR_21")
	)
	(segment
		(start 140.777214 -46.0883)
		(end 140.650214 -45.9613)
		(width 0.127)
		(layer "In5.Cu")
		(net "XM_ADDR_21")
	)
	(segment
		(start 121.69775 -50.643028)
		(end 121.517664 -50.823114)
		(width 0.127)
		(layer "In5.Cu")
		(net "XM_ADDR_21")
	)
	(segment
		(start 143.891762 -46.2153)
		(end 143.891762 -46.780196)
		(width 0.127)
		(layer "In5.Cu")
		(net "XM_ADDR_21")
	)
	(segment
		(start 140.142214 -45.9613)
		(end 140.015214 -46.0883)
		(width 0.127)
		(layer "In5.Cu")
		(net "XM_ADDR_21")
	)
	(segment
		(start 138.999214 -46.0883)
		(end 138.745214 -46.0883)
		(width 0.127)
		(layer "In5.Cu")
		(net "XM_ADDR_21")
	)
	(segment
		(start 142.367762 -46.2153)
		(end 142.240762 -46.0883)
		(width 0.127)
		(layer "In5.Cu")
		(net "XM_ADDR_21")
	)
	(segment
		(start 123.491498 -47.765462)
		(end 123.491498 -47.944786)
		(width 0.127)
		(layer "In5.Cu")
		(net "XM_ADDR_21")
	)
	(segment
		(start 120.796304 -50.460656)
		(end 120.46204 -50.79492)
		(width 0.127)
		(layer "In5.Cu")
		(net "XM_ADDR_21")
	)
	(segment
		(start 142.367 -47.244)
		(end 142.367 -47.389034)
		(width 0.127)
		(layer "In5.Cu")
		(net "XM_ADDR_21")
	)
	(segment
		(start 122.413268 -49.023016)
		(end 122.233944 -49.023016)
		(width 0.127)
		(layer "In5.Cu")
		(net "XM_ADDR_21")
	)
	(segment
		(start 121.515124 -49.741836)
		(end 121.335038 -49.921922)
		(width 0.127)
		(layer "In5.Cu")
		(net "XM_ADDR_21")
	)
	(segment
		(start 141.539214 -45.4406)
		(end 141.285214 -45.4406)
		(width 0.127)
		(layer "In5.Cu")
		(net "XM_ADDR_21")
	)
	(segment
		(start 122.233944 -49.023016)
		(end 122.053858 -49.203102)
		(width 0.127)
		(layer "In5.Cu")
		(net "XM_ADDR_21")
	)
	(segment
		(start 138.745214 -46.0883)
		(end 138.618214 -45.9613)
		(width 0.127)
		(layer "In5.Cu")
		(net "XM_ADDR_21")
	)
	(segment
		(start 144.577562 -47.389034)
		(end 144.577562 -46.2153)
		(width 0.127)
		(layer "In5.Cu")
		(net "XM_ADDR_21")
	)
	(segment
		(start 122.41657 -49.744884)
		(end 122.41657 -49.924208)
		(width 0.127)
		(layer "In5.Cu")
		(net "XM_ADDR_21")
	)
	(segment
		(start 124.152406 -47.104554)
		(end 123.491498 -47.765462)
		(width 0.127)
		(layer "In5.Cu")
		(net "XM_ADDR_21")
	)
	(segment
		(start 121.69775 -50.463704)
		(end 121.69775 -50.643028)
		(width 0.127)
		(layer "In5.Cu")
		(net "XM_ADDR_21")
	)
	(segment
		(start 142.494 -47.516034)
		(end 144.450562 -47.516034)
		(width 0.127)
		(layer "In5.Cu")
		(net "XM_ADDR_21")
	)
	(segment
		(start 122.05716 -50.104294)
		(end 121.694448 -49.741836)
		(width 0.127)
		(layer "In5.Cu")
		(net "XM_ADDR_21")
	)
	(segment
		(start 139.126214 -45.5676)
		(end 139.126214 -45.9613)
		(width 0.127)
		(layer "In5.Cu")
		(net "XM_ADDR_21")
	)
	(segment
		(start 121.335038 -50.101246)
		(end 121.69775 -50.463704)
		(width 0.127)
		(layer "In5.Cu")
		(net "XM_ADDR_21")
	)
	(segment
		(start 123.13539 -49.026064)
		(end 123.13539 -49.205388)
		(width 0.127)
		(layer "In5.Cu")
		(net "XM_ADDR_21")
	)
	(segment
		(start 122.772678 -48.663606)
		(end 123.13539 -49.026064)
		(width 0.127)
		(layer "In5.Cu")
		(net "XM_ADDR_21")
	)
	(segment
		(start 141.666214 -45.9613)
		(end 141.666214 -45.5676)
		(width 0.127)
		(layer "In5.Cu")
		(net "XM_ADDR_21")
	)
	(segment
		(start 143.256762 -46.0883)
		(end 143.002762 -46.0883)
		(width 0.127)
		(layer "In5.Cu")
		(net "XM_ADDR_21")
	)
	(segment
		(start 120.975628 -50.460656)
		(end 120.796304 -50.460656)
		(width 0.127)
		(layer "In5.Cu")
		(net "XM_ADDR_21")
	)
	(segment
		(start 138.237214 -45.4406)
		(end 138.110214 -45.5676)
		(width 0.127)
		(layer "In5.Cu")
		(net "XM_ADDR_21")
	)
	(segment
		(start 121.517664 -50.823114)
		(end 121.33834 -50.823114)
		(width 0.127)
		(layer "In5.Cu")
		(net "XM_ADDR_21")
	)
	(segment
		(start 137.983214 -46.0883)
		(end 134.375906 -46.0883)
		(width 0.127)
		(layer "In5.Cu")
		(net "XM_ADDR_21")
	)
	(segment
		(start 93.555566 -38.596824)
		(end 93.52026 -38.561518)
		(width 0.1016)
		(layer "F.Cu")
		(net "3008_SAS_RX_P3")
	)
	(segment
		(start 131.704842 -85.005164)
		(end 131.791456 -84.91855)
		(width 0.1016)
		(layer "F.Cu")
		(net "3008_SAS_RX_P3")
	)
	(segment
		(start 131.863338 -84.888832)
		(end 131.98348 -84.888832)
		(width 0.1016)
		(layer "F.Cu")
		(net "3008_SAS_RX_P3")
	)
	(segment
		(start 93.52026 -38.551104)
		(end 93.168978 -38.199822)
		(width 0.1016)
		(layer "F.Cu")
		(net "3008_SAS_RX_P3")
	)
	(segment
		(start 93.52026 -38.561518)
		(end 93.52026 -38.551104)
		(width 0.1016)
		(layer "F.Cu")
		(net "3008_SAS_RX_P3")
	)
	(segment
		(start 132.39242 -85.05825)
		(end 132.47497 -85.1408)
		(width 0.1016)
		(layer "F.Cu")
		(net "3008_SAS_RX_P3")
	)
	(segment
		(start 131.349242 -85.034882)
		(end 131.63296 -85.034882)
		(width 0.1016)
		(layer "F.Cu")
		(net "3008_SAS_RX_P3")
	)
	(segment
		(start 93.168978 -38.199822)
		(end 93.150182 -38.199822)
		(width 0.1016)
		(layer "F.Cu")
		(net "3008_SAS_RX_P3")
	)
	(segment
		(start 132.843016 -85.2932)
		(end 135.188706 -85.2932)
		(width 0.1016)
		(layer "F.Cu")
		(net "3008_SAS_RX_P3")
	)
	(segment
		(start 136.667748 -81.674462)
		(end 136.807956 -81.534)
		(width 0.1016)
		(layer "F.Cu")
		(net "3008_SAS_RX_P3")
	)
	(segment
		(start 136.515348 -83.951064)
		(end 136.515348 -82.042)
		(width 0.1016)
		(layer "F.Cu")
		(net "3008_SAS_RX_P3")
	)
	(segment
		(start 135.828278 -85.028278)
		(end 136.239758 -84.616798)
		(width 0.1016)
		(layer "F.Cu")
		(net "3008_SAS_RX_P3")
	)
	(via
		(at 136.807956 -81.534)
		(size 0.5588)
		(drill 0.3048)
		(layers "F.Cu" "B.Cu")
		(net "3008_SAS_RX_P3")
	)
	(via
		(at 93.555566 -38.596824)
		(size 0.508)
		(drill 0.254)
		(layers "F.Cu" "B.Cu")
		(net "3008_SAS_RX_P3")
	)
	(arc
		(start 136.515348 -82.042)
		(mid 136.555009 -81.843082)
		(end 136.667748 -81.674462)
		(width 0.1016)
		(layer "F.Cu")
		(net "3008_SAS_RX_P3")
	)
	(arc
		(start 131.98348 -84.888832)
		(mid 132.204808 -84.932857)
		(end 132.39242 -85.05825)
		(width 0.1016)
		(layer "F.Cu")
		(net "3008_SAS_RX_P3")
	)
	(arc
		(start 131.63296 -85.034882)
		(mid 131.671855 -85.027163)
		(end 131.704842 -85.005164)
		(width 0.1016)
		(layer "F.Cu")
		(net "3008_SAS_RX_P3")
	)
	(arc
		(start 132.47497 -85.1408)
		(mid 132.643831 -85.253629)
		(end 132.843016 -85.2932)
		(width 0.1016)
		(layer "F.Cu")
		(net "3008_SAS_RX_P3")
	)
	(arc
		(start 135.188706 -85.2932)
		(mid 135.534855 -85.224365)
		(end 135.828278 -85.028278)
		(width 0.1016)
		(layer "F.Cu")
		(net "3008_SAS_RX_P3")
	)
	(arc
		(start 131.791456 -84.91855)
		(mid 131.82445 -84.896567)
		(end 131.863338 -84.888832)
		(width 0.1016)
		(layer "F.Cu")
		(net "3008_SAS_RX_P3")
	)
	(arc
		(start 136.239758 -84.616798)
		(mid 136.443764 -84.311342)
		(end 136.515348 -83.951064)
		(width 0.1016)
		(layer "F.Cu")
		(net "3008_SAS_RX_P3")
	)
	(segment
		(start 135.11784 -72.534018)
		(end 135.333486 -72.74941)
		(width 0.1016)
		(layer "In5.Cu")
		(net "3008_SAS_RX_P3")
	)
	(segment
		(start 101.803962 -61.590174)
		(end 101.803962 -61.590428)
		(width 0.1016)
		(layer "In5.Cu")
		(net "3008_SAS_RX_P3")
	)
	(segment
		(start 101.762814 -61.631068)
		(end 101.803962 -61.590174)
		(width 0.1016)
		(layer "In5.Cu")
		(net "3008_SAS_RX_P3")
	)
	(segment
		(start 136.508998 -79.951834)
		(end 136.508998 -81.026)
		(width 0.1016)
		(layer "In5.Cu")
		(net "3008_SAS_RX_P3")
	)
	(segment
		(start 126.217934 -68.45554)
		(end 126.522734 -68.45554)
		(width 0.1016)
		(layer "In5.Cu")
		(net "3008_SAS_RX_P3")
	)
	(segment
		(start 113.715038 -67.665346)
		(end 121.624852 -67.665346)
		(width 0.1016)
		(layer "In5.Cu")
		(net "3008_SAS_RX_P3")
	)
	(segment
		(start 136.656826 -81.38287)
		(end 136.807956 -81.534)
		(width 0.1016)
		(layer "In5.Cu")
		(net "3008_SAS_RX_P3")
	)
	(segment
		(start 99.632008 -61.550042)
		(end 99.632262 -61.550042)
		(width 0.1016)
		(layer "In5.Cu")
		(net "3008_SAS_RX_P3")
	)
	(segment
		(start 102.40645 -61.341)
		(end 106.349292 -61.341)
		(width 0.1016)
		(layer "In5.Cu")
		(net "3008_SAS_RX_P3")
	)
	(segment
		(start 93.555566 -38.596824)
		(end 93.198188 -38.239446)
		(width 0.0889)
		(layer "In5.Cu")
		(net "3008_SAS_RX_P3")
	)
	(segment
		(start 126.974854 -68.6816)
		(end 129.413 -68.6816)
		(width 0.1016)
		(layer "In5.Cu")
		(net "3008_SAS_RX_P3")
	)
	(segment
		(start 138.2903 -78.4987)
		(end 138.176 -78.613)
		(width 0.1016)
		(layer "In5.Cu")
		(net "3008_SAS_RX_P3")
	)
	(segment
		(start 122.749564 -68.131182)
		(end 123.067064 -68.448682)
		(width 0.1016)
		(layer "In5.Cu")
		(net "3008_SAS_RX_P3")
	)
	(segment
		(start 138.6078 -76.358242)
		(end 138.6078 -77.732128)
		(width 0.1016)
		(layer "In5.Cu")
		(net "3008_SAS_RX_P3")
	)
	(segment
		(start 138.176 -78.613)
		(end 138.081258 -78.707996)
		(width 0.1016)
		(layer "In5.Cu")
		(net "3008_SAS_RX_P3")
	)
	(segment
		(start 88.82888 -43.84294)
		(end 88.82888 -49.902364)
		(width 0.1016)
		(layer "In5.Cu")
		(net "3008_SAS_RX_P3")
	)
	(segment
		(start 92.288106 -38.349428)
		(end 91.721178 -38.916356)
		(width 0.0889)
		(layer "In5.Cu")
		(net "3008_SAS_RX_P3")
	)
	(segment
		(start 135.813038 -72.909176)
		(end 136.02843 -73.124822)
		(width 0.1016)
		(layer "In5.Cu")
		(net "3008_SAS_RX_P3")
	)
	(segment
		(start 91.721178 -39.01567)
		(end 91.705684 -39.031164)
		(width 0.0889)
		(layer "In5.Cu")
		(net "3008_SAS_RX_P3")
	)
	(segment
		(start 123.62942 -68.6816)
		(end 125.765814 -68.6816)
		(width 0.1016)
		(layer "In5.Cu")
		(net "3008_SAS_RX_P3")
	)
	(segment
		(start 89.426542 -51.344576)
		(end 99.632008 -61.550042)
		(width 0.1016)
		(layer "In5.Cu")
		(net "3008_SAS_RX_P3")
	)
	(segment
		(start 107.3912 -61.772546)
		(end 112.9792 -67.360546)
		(width 0.1016)
		(layer "In5.Cu")
		(net "3008_SAS_RX_P3")
	)
	(segment
		(start 134.742428 -71.83882)
		(end 134.958074 -72.054466)
		(width 0.1016)
		(layer "In5.Cu")
		(net "3008_SAS_RX_P3")
	)
	(segment
		(start 91.543886 -39.281608)
		(end 91.543886 -40.843708)
		(width 0.1016)
		(layer "In5.Cu")
		(net "3008_SAS_RX_P3")
	)
	(segment
		(start 91.721178 -38.916356)
		(end 91.721178 -39.01567)
		(width 0.0889)
		(layer "In5.Cu")
		(net "3008_SAS_RX_P3")
	)
	(segment
		(start 138.081258 -78.707996)
		(end 138.06805 -78.721458)
		(width 0.1016)
		(layer "In5.Cu")
		(net "3008_SAS_RX_P3")
	)
	(segment
		(start 91.395042 -41.203118)
		(end 88.881204 -43.716956)
		(width 0.1016)
		(layer "In5.Cu")
		(net "3008_SAS_RX_P3")
	)
	(segment
		(start 101.763068 -61.631322)
		(end 101.762814 -61.631068)
		(width 0.1016)
		(layer "In5.Cu")
		(net "3008_SAS_RX_P3")
	)
	(segment
		(start 91.705684 -39.031164)
		(end 91.606624 -39.130224)
		(width 0.1016)
		(layer "In5.Cu")
		(net "3008_SAS_RX_P3")
	)
	(segment
		(start 132.575554 -69.991732)
		(end 134.262876 -71.679054)
		(width 0.1016)
		(layer "In5.Cu")
		(net "3008_SAS_RX_P3")
	)
	(segment
		(start 136.18845 -73.604374)
		(end 138.371326 -75.78725)
		(width 0.1016)
		(layer "In5.Cu")
		(net "3008_SAS_RX_P3")
	)
	(segment
		(start 99.632262 -61.550042)
		(end 99.64547 -61.56325)
		(width 0.1016)
		(layer "In5.Cu")
		(net "3008_SAS_RX_P3")
	)
	(segment
		(start 137.0838 -79.121)
		(end 136.6901 -79.5147)
		(width 0.1016)
		(layer "In5.Cu")
		(net "3008_SAS_RX_P3")
	)
	(segment
		(start 137.287 -79.0448)
		(end 137.267696 -79.0448)
		(width 0.1016)
		(layer "In5.Cu")
		(net "3008_SAS_RX_P3")
	)
	(segment
		(start 93.0148 -38.1635)
		(end 92.737178 -38.1635)
		(width 0.0889)
		(layer "In5.Cu")
		(net "3008_SAS_RX_P3")
	)
	(segment
		(start 100.203254 -61.79439)
		(end 101.369622 -61.79439)
		(width 0.1016)
		(layer "In5.Cu")
		(net "3008_SAS_RX_P3")
	)
	(arc
		(start 125.991874 -68.56857)
		(mid 126.09125 -68.484733)
		(end 126.217934 -68.45554)
		(width 0.1016)
		(layer "In5.Cu")
		(net "3008_SAS_RX_P3")
	)
	(arc
		(start 93.198188 -38.239446)
		(mid 93.114049 -38.183226)
		(end 93.0148 -38.1635)
		(width 0.0889)
		(layer "In5.Cu")
		(net "3008_SAS_RX_P3")
	)
	(arc
		(start 135.333486 -72.74941)
		(mid 135.443716 -72.818344)
		(end 135.573262 -72.82942)
		(width 0.1016)
		(layer "In5.Cu")
		(net "3008_SAS_RX_P3")
	)
	(arc
		(start 138.06805 -78.721458)
		(mid 137.709686 -78.960816)
		(end 137.287 -79.0448)
		(width 0.1016)
		(layer "In5.Cu")
		(net "3008_SAS_RX_P3")
	)
	(arc
		(start 126.748794 -68.56857)
		(mid 126.84817 -68.652407)
		(end 126.974854 -68.6816)
		(width 0.1016)
		(layer "In5.Cu")
		(net "3008_SAS_RX_P3")
	)
	(arc
		(start 112.9792 -67.360546)
		(mid 113.316805 -67.586127)
		(end 113.715038 -67.665346)
		(width 0.1016)
		(layer "In5.Cu")
		(net "3008_SAS_RX_P3")
	)
	(arc
		(start 137.267696 -79.0448)
		(mid 137.168162 -79.064599)
		(end 137.0838 -79.121)
		(width 0.1016)
		(layer "In5.Cu")
		(net "3008_SAS_RX_P3")
	)
	(arc
		(start 136.02843 -73.124822)
		(mid 136.097427 -73.235041)
		(end 136.10844 -73.364598)
		(width 0.1016)
		(layer "In5.Cu")
		(net "3008_SAS_RX_P3")
	)
	(arc
		(start 134.958074 -72.054466)
		(mid 135.027008 -72.164696)
		(end 135.038084 -72.294242)
		(width 0.1016)
		(layer "In5.Cu")
		(net "3008_SAS_RX_P3")
	)
	(arc
		(start 101.803962 -61.590428)
		(mid 102.080387 -61.405786)
		(end 102.40645 -61.341)
		(width 0.1016)
		(layer "In5.Cu")
		(net "3008_SAS_RX_P3")
	)
	(arc
		(start 134.502652 -71.75881)
		(mid 134.632209 -71.769853)
		(end 134.742428 -71.83882)
		(width 0.1016)
		(layer "In5.Cu")
		(net "3008_SAS_RX_P3")
	)
	(arc
		(start 136.6901 -79.5147)
		(mid 136.556091 -79.715259)
		(end 136.508998 -79.951834)
		(width 0.1016)
		(layer "In5.Cu")
		(net "3008_SAS_RX_P3")
	)
	(arc
		(start 88.82888 -49.902364)
		(mid 88.984254 -50.682922)
		(end 89.426542 -51.344576)
		(width 0.1016)
		(layer "In5.Cu")
		(net "3008_SAS_RX_P3")
	)
	(arc
		(start 101.369622 -61.79439)
		(mid 101.582565 -61.751975)
		(end 101.763068 -61.631322)
		(width 0.1016)
		(layer "In5.Cu")
		(net "3008_SAS_RX_P3")
	)
	(arc
		(start 88.881204 -43.716956)
		(mid 88.842499 -43.774743)
		(end 88.82888 -43.84294)
		(width 0.1016)
		(layer "In5.Cu")
		(net "3008_SAS_RX_P3")
	)
	(arc
		(start 126.522734 -68.45554)
		(mid 126.649395 -68.484779)
		(end 126.748794 -68.56857)
		(width 0.1016)
		(layer "In5.Cu")
		(net "3008_SAS_RX_P3")
	)
	(arc
		(start 92.737178 -38.1635)
		(mid 92.494174 -38.211836)
		(end 92.288106 -38.349428)
		(width 0.0889)
		(layer "In5.Cu")
		(net "3008_SAS_RX_P3")
	)
	(arc
		(start 136.508998 -81.026)
		(mid 136.547416 -81.21914)
		(end 136.656826 -81.38287)
		(width 0.1016)
		(layer "In5.Cu")
		(net "3008_SAS_RX_P3")
	)
	(arc
		(start 106.349292 -61.341)
		(mid 106.913133 -61.453213)
		(end 107.3912 -61.772546)
		(width 0.1016)
		(layer "In5.Cu")
		(net "3008_SAS_RX_P3")
	)
	(arc
		(start 135.038084 -72.294242)
		(mid 135.049001 -72.423764)
		(end 135.11784 -72.534018)
		(width 0.1016)
		(layer "In5.Cu")
		(net "3008_SAS_RX_P3")
	)
	(arc
		(start 134.262876 -71.679054)
		(mid 134.373131 -71.74789)
		(end 134.502652 -71.75881)
		(width 0.1016)
		(layer "In5.Cu")
		(net "3008_SAS_RX_P3")
	)
	(arc
		(start 138.371326 -75.78725)
		(mid 138.546371 -76.049223)
		(end 138.6078 -76.358242)
		(width 0.1016)
		(layer "In5.Cu")
		(net "3008_SAS_RX_P3")
	)
	(arc
		(start 138.6078 -77.732128)
		(mid 138.52528 -78.146984)
		(end 138.2903 -78.4987)
		(width 0.1016)
		(layer "In5.Cu")
		(net "3008_SAS_RX_P3")
	)
	(arc
		(start 91.606624 -39.130224)
		(mid 91.560215 -39.19968)
		(end 91.543886 -39.281608)
		(width 0.1016)
		(layer "In5.Cu")
		(net "3008_SAS_RX_P3")
	)
	(arc
		(start 123.067064 -68.448682)
		(mid 123.325075 -68.62108)
		(end 123.62942 -68.6816)
		(width 0.1016)
		(layer "In5.Cu")
		(net "3008_SAS_RX_P3")
	)
	(arc
		(start 99.64547 -61.56325)
		(mid 99.901369 -61.7343)
		(end 100.203254 -61.79439)
		(width 0.1016)
		(layer "In5.Cu")
		(net "3008_SAS_RX_P3")
	)
	(arc
		(start 125.765814 -68.6816)
		(mid 125.892475 -68.652361)
		(end 125.991874 -68.56857)
		(width 0.1016)
		(layer "In5.Cu")
		(net "3008_SAS_RX_P3")
	)
	(arc
		(start 91.543886 -40.843708)
		(mid 91.505197 -41.038208)
		(end 91.395042 -41.203118)
		(width 0.1016)
		(layer "In5.Cu")
		(net "3008_SAS_RX_P3")
	)
	(arc
		(start 121.624852 -67.665346)
		(mid 122.233503 -67.786472)
		(end 122.749564 -68.131182)
		(width 0.1016)
		(layer "In5.Cu")
		(net "3008_SAS_RX_P3")
	)
	(arc
		(start 136.10844 -73.364598)
		(mid 136.11949 -73.494143)
		(end 136.18845 -73.604374)
		(width 0.1016)
		(layer "In5.Cu")
		(net "3008_SAS_RX_P3")
	)
	(arc
		(start 135.573262 -72.82942)
		(mid 135.702784 -72.840337)
		(end 135.813038 -72.909176)
		(width 0.1016)
		(layer "In5.Cu")
		(net "3008_SAS_RX_P3")
	)
	(arc
		(start 129.413 -68.6816)
		(mid 131.124569 -69.022146)
		(end 132.575554 -69.991732)
		(width 0.1016)
		(layer "In5.Cu")
		(net "3008_SAS_RX_P3")
	)
	(segment
		(start 105.349802 -100.350066)
		(end 104.849676 -100.850192)
		(width 0.1143)
		(layer "F.Cu")
		(net "PHY_CLK")
	)
	(via
		(at 104.849676 -100.850192)
		(size 0.508)
		(drill 0.254)
		(layers "F.Cu" "B.Cu")
		(net "PHY_CLK")
	)
	(segment
		(start 104.287828 -101.41204)
		(end 104.849676 -100.850192)
		(width 0.1143)
		(layer "B.Cu")
		(net "PHY_CLK")
	)
	(segment
		(start 102.75697 -104.648)
		(end 103.411528 -103.993442)
		(width 0.1143)
		(layer "B.Cu")
		(net "PHY_CLK")
	)
	(segment
		(start 103.871776 -103.412036)
		(end 104.287828 -102.995984)
		(width 0.1143)
		(layer "B.Cu")
		(net "PHY_CLK")
	)
	(segment
		(start 104.287828 -102.995984)
		(end 104.287828 -101.41204)
		(width 0.1143)
		(layer "B.Cu")
		(net "PHY_CLK")
	)
	(segment
		(start 103.703882 -103.412036)
		(end 103.871776 -103.412036)
		(width 0.1143)
		(layer "B.Cu")
		(net "PHY_CLK")
	)
	(segment
		(start 103.411528 -103.993442)
		(end 103.411528 -103.70439)
		(width 0.1143)
		(layer "B.Cu")
		(net "PHY_CLK")
	)
	(segment
		(start 103.411528 -103.70439)
		(end 103.703882 -103.412036)
		(width 0.1143)
		(layer "B.Cu")
		(net "PHY_CLK")
	)
	(segment
		(start 88.15197 -118.9863)
		(end 90.47099 -118.9863)
		(width 0.1143)
		(layer "F.Cu")
		(net "EXP_I2C_SCL_1")
	)
	(segment
		(start 84.105242 -121.793762)
		(end 85.59419 -121.793762)
		(width 0.1143)
		(layer "F.Cu")
		(net "EXP_I2C_SCL_1")
	)
	(segment
		(start 87.77097 -118.9863)
		(end 87.51189 -118.72722)
		(width 0.1143)
		(layer "F.Cu")
		(net "EXP_I2C_SCL_1")
	)
	(segment
		(start 86.10219 -118.72722)
		(end 86.10219 -118.72087)
		(width 0.1143)
		(layer "F.Cu")
		(net "EXP_I2C_SCL_1")
	)
	(segment
		(start 88.15197 -118.9863)
		(end 87.77097 -118.9863)
		(width 0.1143)
		(layer "F.Cu")
		(net "EXP_I2C_SCL_1")
	)
	(segment
		(start 87.51189 -118.72722)
		(end 86.10219 -118.72722)
		(width 0.1143)
		(layer "F.Cu")
		(net "EXP_I2C_SCL_1")
	)
	(segment
		(start 105.349802 -106.350054)
		(end 104.849676 -106.85018)
		(width 0.1143)
		(layer "F.Cu")
		(net "EXP_I2C_SCL_1")
	)
	(segment
		(start 85.59419 -121.793762)
		(end 86.10219 -121.285762)
		(width 0.1143)
		(layer "F.Cu")
		(net "EXP_I2C_SCL_1")
	)
	(segment
		(start 86.10219 -121.285762)
		(end 86.10219 -118.72722)
		(width 0.1143)
		(layer "F.Cu")
		(net "EXP_I2C_SCL_1")
	)
	(via
		(at 86.10219 -118.72087)
		(size 0.5588)
		(drill 0.3048)
		(layers "F.Cu" "B.Cu")
		(net "EXP_I2C_SCL_1")
	)
	(via
		(at 104.849676 -106.85018)
		(size 0.508)
		(drill 0.254)
		(layers "F.Cu" "B.Cu")
		(net "EXP_I2C_SCL_1")
	)
	(via
		(at 88.15197 -118.9863)
		(size 0.7112)
		(drill 0.3556)
		(layers "F.Cu" "B.Cu")
		(net "EXP_I2C_SCL_1")
	)
	(segment
		(start 86.10219 -118.72087)
		(end 86.441534 -118.72087)
		(width 0.127)
		(layer "In2.Cu")
		(net "EXP_I2C_SCL_1")
	)
	(segment
		(start 101.731318 -103.431086)
		(end 104.023414 -103.431086)
		(width 0.127)
		(layer "In2.Cu")
		(net "EXP_I2C_SCL_1")
	)
	(segment
		(start 105.268776 -104.676448)
		(end 105.268776 -105.02392)
		(width 0.127)
		(layer "In2.Cu")
		(net "EXP_I2C_SCL_1")
	)
	(segment
		(start 104.394 -104.14)
		(end 104.648 -104.394)
		(width 0.127)
		(layer "In2.Cu")
		(net "EXP_I2C_SCL_1")
	)
	(segment
		(start 104.023414 -103.431086)
		(end 104.394 -103.801672)
		(width 0.127)
		(layer "In2.Cu")
		(net "EXP_I2C_SCL_1")
	)
	(segment
		(start 104.887014 -105.405682)
		(end 104.70134 -105.405682)
		(width 0.127)
		(layer "In2.Cu")
		(net "EXP_I2C_SCL_1")
	)
	(segment
		(start 104.394 -103.801672)
		(end 104.394 -104.14)
		(width 0.127)
		(layer "In2.Cu")
		(net "EXP_I2C_SCL_1")
	)
	(segment
		(start 105.268776 -105.02392)
		(end 104.887014 -105.405682)
		(width 0.127)
		(layer "In2.Cu")
		(net "EXP_I2C_SCL_1")
	)
	(segment
		(start 104.430576 -105.676446)
		(end 104.430576 -106.059732)
		(width 0.127)
		(layer "In2.Cu")
		(net "EXP_I2C_SCL_1")
	)
	(segment
		(start 104.70134 -105.405682)
		(end 104.430576 -105.676446)
		(width 0.127)
		(layer "In2.Cu")
		(net "EXP_I2C_SCL_1")
	)
	(segment
		(start 104.430576 -106.059732)
		(end 104.849676 -106.478832)
		(width 0.127)
		(layer "In2.Cu")
		(net "EXP_I2C_SCL_1")
	)
	(segment
		(start 104.986328 -104.394)
		(end 105.268776 -104.676448)
		(width 0.127)
		(layer "In2.Cu")
		(net "EXP_I2C_SCL_1")
	)
	(segment
		(start 104.849676 -106.478832)
		(end 104.849676 -106.85018)
		(width 0.127)
		(layer "In2.Cu")
		(net "EXP_I2C_SCL_1")
	)
	(segment
		(start 86.441534 -118.72087)
		(end 101.731318 -103.431086)
		(width 0.127)
		(layer "In2.Cu")
		(net "EXP_I2C_SCL_1")
	)
	(segment
		(start 104.648 -104.394)
		(end 104.986328 -104.394)
		(width 0.127)
		(layer "In2.Cu")
		(net "EXP_I2C_SCL_1")
	)
	(segment
		(start 113.949988 -50.199798)
		(end 114.628168 -50.199798)
		(width 0.1143)
		(layer "F.Cu")
		(net "XM_ADDR_24")
	)
	(via
		(at 114.628168 -50.199798)
		(size 0.508)
		(drill 0.254)
		(layers "F.Cu" "B.Cu")
		(net "XM_ADDR_24")
	)
	(segment
		(start 114.014504 -49.59985)
		(end 114.02822 -49.59985)
		(width 0.1143)
		(layer "B.Cu")
		(net "XM_ADDR_24")
	)
	(segment
		(start 114.02822 -49.59985)
		(end 114.628168 -50.199798)
		(width 0.1143)
		(layer "B.Cu")
		(net "XM_ADDR_24")
	)
	(via
		(at 172.6946 -119.4308)
		(size 0.7112)
		(drill 0.3556)
		(layers "F.Cu" "B.Cu")
		(net "P0V9_E_VIN")
	)
	(via
		(at 172.085 -120.015)
		(size 0.5588)
		(drill 0.3048)
		(layers "F.Cu" "B.Cu")
		(net "P0V9_E_VIN")
	)
	(segment
		(start 172.6946 -118.5926)
		(end 172.6946 -119.4308)
		(width 0.508)
		(layer "B.Cu")
		(net "P0V9_E_VIN")
	)
	(segment
		(start 172.085 -120.015)
		(end 172.1104 -120.015)
		(width 0.508)
		(layer "B.Cu")
		(net "P0V9_E_VIN")
	)
	(segment
		(start 172.466 -118.364)
		(end 172.6946 -118.5926)
		(width 0.508)
		(layer "B.Cu")
		(net "P0V9_E_VIN")
	)
	(segment
		(start 172.1104 -120.015)
		(end 172.6946 -119.4308)
		(width 0.508)
		(layer "B.Cu")
		(net "P0V9_E_VIN")
	)
	(segment
		(start 100.85197 -78.105)
		(end 100.85197 -78.867)
		(width 0.1143)
		(layer "F.Cu")
		(net "LSI_PROCMON")
	)
	(segment
		(start 102.482904 -80.497934)
		(end 102.482904 -81.482946)
		(width 0.1143)
		(layer "F.Cu")
		(net "LSI_PROCMON")
	)
	(segment
		(start 100.85197 -78.867)
		(end 102.482904 -80.497934)
		(width 0.1143)
		(layer "F.Cu")
		(net "LSI_PROCMON")
	)
	(segment
		(start 102.482904 -81.482946)
		(end 103.349806 -82.349848)
		(width 0.1143)
		(layer "F.Cu")
		(net "LSI_PROCMON")
	)
	(segment
		(start 116.250466 -55.2831)
		(end 116.280692 -55.313326)
		(width 0.1143)
		(layer "F.Cu")
		(net "XM_ADDR_17")
	)
	(segment
		(start 136.598406 -61.9379)
		(end 136.598406 -61.099446)
		(width 0.1143)
		(layer "F.Cu")
		(net "XM_ADDR_17")
	)
	(segment
		(start 133.25729 -53.895752)
		(end 135.389112 -53.895752)
		(width 0.1143)
		(layer "F.Cu")
		(net "XM_ADDR_17")
	)
	(segment
		(start 113.949988 -54.402736)
		(end 114.830352 -55.2831)
		(width 0.1143)
		(layer "F.Cu")
		(net "XM_ADDR_17")
	)
	(segment
		(start 114.830352 -55.2831)
		(end 116.250466 -55.2831)
		(width 0.1143)
		(layer "F.Cu")
		(net "XM_ADDR_17")
	)
	(segment
		(start 136.598406 -61.099446)
		(end 135.701786 -60.202826)
		(width 0.1143)
		(layer "F.Cu")
		(net "XM_ADDR_17")
	)
	(segment
		(start 135.701786 -53.998622)
		(end 135.494014 -53.79085)
		(width 0.1143)
		(layer "F.Cu")
		(net "XM_ADDR_17")
	)
	(segment
		(start 135.701786 -60.202826)
		(end 135.701786 -53.998622)
		(width 0.1143)
		(layer "F.Cu")
		(net "XM_ADDR_17")
	)
	(segment
		(start 135.389112 -53.895752)
		(end 135.494014 -53.79085)
		(width 0.1143)
		(layer "F.Cu")
		(net "XM_ADDR_17")
	)
	(segment
		(start 113.949988 -54.19979)
		(end 113.949988 -54.402736)
		(width 0.1143)
		(layer "F.Cu")
		(net "XM_ADDR_17")
	)
	(via
		(at 116.280692 -55.313326)
		(size 0.508)
		(drill 0.254)
		(layers "F.Cu" "B.Cu")
		(net "XM_ADDR_17")
	)
	(via
		(at 135.494014 -53.79085)
		(size 0.508)
		(drill 0.254)
		(layers "F.Cu" "B.Cu")
		(net "XM_ADDR_17")
	)
	(segment
		(start 135.389366 -52.059332)
		(end 135.262366 -51.932332)
		(width 0.127)
		(layer "In5.Cu")
		(net "XM_ADDR_17")
	)
	(segment
		(start 135.262366 -52.948332)
		(end 135.262366 -52.694332)
		(width 0.127)
		(layer "In5.Cu")
		(net "XM_ADDR_17")
	)
	(segment
		(start 134.13105 -53.831236)
		(end 133.270498 -52.970684)
		(width 0.127)
		(layer "In5.Cu")
		(net "XM_ADDR_17")
	)
	(segment
		(start 133.629908 -52.611274)
		(end 134.49046 -53.471826)
		(width 0.127)
		(layer "In5.Cu")
		(net "XM_ADDR_17")
	)
	(segment
		(start 124.310394 -55.1942)
		(end 118.32209 -55.1942)
		(width 0.127)
		(layer "In5.Cu")
		(net "XM_ADDR_17")
	)
	(segment
		(start 134.310882 -53.831236)
		(end 134.13105 -53.831236)
		(width 0.127)
		(layer "In5.Cu")
		(net "XM_ADDR_17")
	)
	(segment
		(start 133.629908 -52.431442)
		(end 133.629908 -52.611274)
		(width 0.127)
		(layer "In5.Cu")
		(net "XM_ADDR_17")
	)
	(segment
		(start 138.088624 -51.93538)
		(end 137.964672 -52.059332)
		(width 0.127)
		(layer "In5.Cu")
		(net "XM_ADDR_17")
	)
	(segment
		(start 125.986794 -53.5178)
		(end 124.310394 -55.1942)
		(width 0.127)
		(layer "In5.Cu")
		(net "XM_ADDR_17")
	)
	(segment
		(start 138.662664 -51.425602)
		(end 138.515344 -51.278282)
		(width 0.127)
		(layer "In5.Cu")
		(net "XM_ADDR_17")
	)
	(segment
		(start 138.424412 -52.567332)
		(end 138.662664 -52.32908)
		(width 0.127)
		(layer "In5.Cu")
		(net "XM_ADDR_17")
	)
	(segment
		(start 138.662664 -52.32908)
		(end 138.662664 -51.425602)
		(width 0.127)
		(layer "In5.Cu")
		(net "XM_ADDR_17")
	)
	(segment
		(start 135.389366 -53.075332)
		(end 135.262366 -52.948332)
		(width 0.127)
		(layer "In5.Cu")
		(net "XM_ADDR_17")
	)
	(segment
		(start 137.459466 -51.062382)
		(end 137.262616 -50.865532)
		(width 0.127)
		(layer "In5.Cu")
		(net "XM_ADDR_17")
	)
	(segment
		(start 137.262616 -50.865532)
		(end 135.195818 -50.865532)
		(width 0.127)
		(layer "In5.Cu")
		(net "XM_ADDR_17")
	)
	(segment
		(start 137.332466 -51.551332)
		(end 137.459466 -51.424332)
		(width 0.127)
		(layer "In5.Cu")
		(net "XM_ADDR_17")
	)
	(segment
		(start 138.088624 -51.410108)
		(end 138.088624 -51.93538)
		(width 0.127)
		(layer "In5.Cu")
		(net "XM_ADDR_17")
	)
	(segment
		(start 134.784084 -52.32781)
		(end 134.784084 -52.507642)
		(width 0.127)
		(layer "In5.Cu")
		(net "XM_ADDR_17")
	)
	(segment
		(start 134.49046 -53.471826)
		(end 134.49046 -53.651658)
		(width 0.127)
		(layer "In5.Cu")
		(net "XM_ADDR_17")
	)
	(segment
		(start 136.789414 -54.20233)
		(end 137.459466 -53.532278)
		(width 0.127)
		(layer "In5.Cu")
		(net "XM_ADDR_17")
	)
	(segment
		(start 134.348728 -51.712622)
		(end 134.348728 -51.892454)
		(width 0.127)
		(layer "In5.Cu")
		(net "XM_ADDR_17")
	)
	(segment
		(start 133.809486 -52.251864)
		(end 133.629908 -52.431442)
		(width 0.127)
		(layer "In5.Cu")
		(net "XM_ADDR_17")
	)
	(segment
		(start 134.784084 -52.507642)
		(end 134.604506 -52.68722)
		(width 0.127)
		(layer "In5.Cu")
		(net "XM_ADDR_17")
	)
	(segment
		(start 133.090666 -52.970684)
		(end 132.54355 -53.5178)
		(width 0.127)
		(layer "In5.Cu")
		(net "XM_ADDR_17")
	)
	(segment
		(start 132.54355 -53.5178)
		(end 125.986794 -53.5178)
		(width 0.127)
		(layer "In5.Cu")
		(net "XM_ADDR_17")
	)
	(segment
		(start 137.459466 -53.532278)
		(end 137.459466 -53.202332)
		(width 0.127)
		(layer "In5.Cu")
		(net "XM_ADDR_17")
	)
	(segment
		(start 137.332466 -53.075332)
		(end 135.389366 -53.075332)
		(width 0.127)
		(layer "In5.Cu")
		(net "XM_ADDR_17")
	)
	(segment
		(start 133.270498 -52.970684)
		(end 133.090666 -52.970684)
		(width 0.127)
		(layer "In5.Cu")
		(net "XM_ADDR_17")
	)
	(segment
		(start 134.348728 -51.892454)
		(end 134.784084 -52.32781)
		(width 0.127)
		(layer "In5.Cu")
		(net "XM_ADDR_17")
	)
	(segment
		(start 135.262366 -51.678332)
		(end 135.389366 -51.551332)
		(width 0.127)
		(layer "In5.Cu")
		(net "XM_ADDR_17")
	)
	(segment
		(start 137.459466 -51.424332)
		(end 137.459466 -51.062382)
		(width 0.127)
		(layer "In5.Cu")
		(net "XM_ADDR_17")
	)
	(segment
		(start 135.262366 -51.932332)
		(end 135.262366 -51.678332)
		(width 0.127)
		(layer "In5.Cu")
		(net "XM_ADDR_17")
	)
	(segment
		(start 116.293392 -55.326026)
		(end 116.280692 -55.313326)
		(width 0.127)
		(layer "In5.Cu")
		(net "XM_ADDR_17")
	)
	(segment
		(start 134.424674 -52.68722)
		(end 133.989318 -52.251864)
		(width 0.127)
		(layer "In5.Cu")
		(net "XM_ADDR_17")
	)
	(segment
		(start 133.989318 -52.251864)
		(end 133.809486 -52.251864)
		(width 0.127)
		(layer "In5.Cu")
		(net "XM_ADDR_17")
	)
	(segment
		(start 134.604506 -52.68722)
		(end 134.424674 -52.68722)
		(width 0.127)
		(layer "In5.Cu")
		(net "XM_ADDR_17")
	)
	(segment
		(start 118.32209 -55.1942)
		(end 118.190264 -55.326026)
		(width 0.127)
		(layer "In5.Cu")
		(net "XM_ADDR_17")
	)
	(segment
		(start 135.262366 -52.694332)
		(end 135.389366 -52.567332)
		(width 0.127)
		(layer "In5.Cu")
		(net "XM_ADDR_17")
	)
	(segment
		(start 138.515344 -51.278282)
		(end 138.22045 -51.278282)
		(width 0.127)
		(layer "In5.Cu")
		(net "XM_ADDR_17")
	)
	(segment
		(start 135.494014 -54.07533)
		(end 135.621014 -54.20233)
		(width 0.127)
		(layer "In5.Cu")
		(net "XM_ADDR_17")
	)
	(segment
		(start 135.389366 -51.551332)
		(end 137.332466 -51.551332)
		(width 0.127)
		(layer "In5.Cu")
		(net "XM_ADDR_17")
	)
	(segment
		(start 118.190264 -55.326026)
		(end 116.293392 -55.326026)
		(width 0.127)
		(layer "In5.Cu")
		(net "XM_ADDR_17")
	)
	(segment
		(start 134.49046 -53.651658)
		(end 134.310882 -53.831236)
		(width 0.127)
		(layer "In5.Cu")
		(net "XM_ADDR_17")
	)
	(segment
		(start 137.459466 -53.202332)
		(end 137.332466 -53.075332)
		(width 0.127)
		(layer "In5.Cu")
		(net "XM_ADDR_17")
	)
	(segment
		(start 135.494014 -53.79085)
		(end 135.494014 -54.07533)
		(width 0.127)
		(layer "In5.Cu")
		(net "XM_ADDR_17")
	)
	(segment
		(start 135.195818 -50.865532)
		(end 134.348728 -51.712622)
		(width 0.127)
		(layer "In5.Cu")
		(net "XM_ADDR_17")
	)
	(segment
		(start 138.22045 -51.278282)
		(end 138.088624 -51.410108)
		(width 0.127)
		(layer "In5.Cu")
		(net "XM_ADDR_17")
	)
	(segment
		(start 135.389366 -52.567332)
		(end 138.424412 -52.567332)
		(width 0.127)
		(layer "In5.Cu")
		(net "XM_ADDR_17")
	)
	(segment
		(start 135.621014 -54.20233)
		(end 136.789414 -54.20233)
		(width 0.127)
		(layer "In5.Cu")
		(net "XM_ADDR_17")
	)
	(segment
		(start 137.964672 -52.059332)
		(end 135.389366 -52.059332)
		(width 0.127)
		(layer "In5.Cu")
		(net "XM_ADDR_17")
	)
	(segment
		(start 113.574322 -52.980844)
		(end 115.081558 -52.980844)
		(width 0.1143)
		(layer "F.Cu")
		(net "XM_DATA_14")
	)
	(segment
		(start 139.099036 -61.9379)
		(end 139.099036 -58.766964)
		(width 0.1143)
		(layer "F.Cu")
		(net "XM_DATA_14")
	)
	(segment
		(start 115.081558 -52.980844)
		(end 115.802156 -53.701442)
		(width 0.1143)
		(layer "F.Cu")
		(net "XM_DATA_14")
	)
	(segment
		(start 116.72824 -54.61)
		(end 116.339366 -54.221126)
		(width 0.1143)
		(layer "F.Cu")
		(net "XM_DATA_14")
	)
	(segment
		(start 115.802156 -53.701442)
		(end 115.819682 -53.701442)
		(width 0.1143)
		(layer "F.Cu")
		(net "XM_DATA_14")
	)
	(segment
		(start 139.099036 -58.766964)
		(end 139.192 -58.674)
		(width 0.1143)
		(layer "F.Cu")
		(net "XM_DATA_14")
	)
	(segment
		(start 115.819682 -53.701442)
		(end 116.339366 -54.221126)
		(width 0.1143)
		(layer "F.Cu")
		(net "XM_DATA_14")
	)
	(segment
		(start 113.150142 -53.399944)
		(end 113.155222 -53.399944)
		(width 0.1143)
		(layer "F.Cu")
		(net "XM_DATA_14")
	)
	(segment
		(start 117.094 -54.61)
		(end 116.72824 -54.61)
		(width 0.1143)
		(layer "F.Cu")
		(net "XM_DATA_14")
	)
	(segment
		(start 113.155222 -53.399944)
		(end 113.574322 -52.980844)
		(width 0.1143)
		(layer "F.Cu")
		(net "XM_DATA_14")
	)
	(via
		(at 117.094 -54.991)
		(size 0.7112)
		(drill 0.3556)
		(layers "F.Cu" "B.Cu")
		(net "XM_DATA_14")
	)
	(via
		(at 116.339366 -54.221126)
		(size 0.508)
		(drill 0.254)
		(layers "F.Cu" "B.Cu")
		(net "XM_DATA_14")
	)
	(via
		(at 117.094 -54.61)
		(size 0.7112)
		(drill 0.3556)
		(layers "F.Cu" "B.Cu")
		(net "XM_DATA_14")
	)
	(via
		(at 139.192 -58.674)
		(size 0.5588)
		(drill 0.3048)
		(layers "F.Cu" "B.Cu")
		(net "XM_DATA_14")
	)
	(segment
		(start 126.197868 -55.5244)
		(end 126.083568 -55.4101)
		(width 0.1143)
		(layer "B.Cu")
		(net "XM_DATA_14")
	)
	(segment
		(start 119.903748 -55.6133)
		(end 119.903748 -56.267604)
		(width 0.1143)
		(layer "B.Cu")
		(net "XM_DATA_14")
	)
	(segment
		(start 122.989848 -55.499)
		(end 122.761248 -55.499)
		(width 0.1143)
		(layer "B.Cu")
		(net "XM_DATA_14")
	)
	(segment
		(start 119.446548 -55.6133)
		(end 119.332248 -55.499)
		(width 0.1143)
		(layer "B.Cu")
		(net "XM_DATA_14")
	)
	(segment
		(start 127.226568 -56.381904)
		(end 127.112268 -56.267604)
		(width 0.1143)
		(layer "B.Cu")
		(net "XM_DATA_14")
	)
	(segment
		(start 120.360948 -55.6133)
		(end 120.246648 -55.499)
		(width 0.1143)
		(layer "B.Cu")
		(net "XM_DATA_14")
	)
	(segment
		(start 121.732548 -55.6133)
		(end 121.732548 -56.267604)
		(width 0.1143)
		(layer "B.Cu")
		(net "XM_DATA_14")
	)
	(segment
		(start 139.065 -58.674)
		(end 136.772904 -56.381904)
		(width 0.1143)
		(layer "B.Cu")
		(net "XM_DATA_14")
	)
	(segment
		(start 127.683768 -55.4101)
		(end 127.569468 -55.5244)
		(width 0.1143)
		(layer "B.Cu")
		(net "XM_DATA_14")
	)
	(segment
		(start 120.246648 -55.499)
		(end 120.018048 -55.499)
		(width 0.1143)
		(layer "B.Cu")
		(net "XM_DATA_14")
	)
	(segment
		(start 119.903748 -56.267604)
		(end 119.789448 -56.381904)
		(width 0.1143)
		(layer "B.Cu")
		(net "XM_DATA_14")
	)
	(segment
		(start 119.789448 -56.381904)
		(end 119.560848 -56.381904)
		(width 0.1143)
		(layer "B.Cu")
		(net "XM_DATA_14")
	)
	(segment
		(start 118.875048 -56.381904)
		(end 118.395242 -56.381904)
		(width 0.1143)
		(layer "B.Cu")
		(net "XM_DATA_14")
	)
	(segment
		(start 123.104148 -55.6133)
		(end 122.989848 -55.499)
		(width 0.1143)
		(layer "B.Cu")
		(net "XM_DATA_14")
	)
	(segment
		(start 127.912368 -55.4101)
		(end 127.683768 -55.4101)
		(width 0.1143)
		(layer "B.Cu")
		(net "XM_DATA_14")
	)
	(segment
		(start 116.339366 -54.221126)
		(end 116.339366 -54.236366)
		(width 0.1143)
		(layer "B.Cu")
		(net "XM_DATA_14")
	)
	(segment
		(start 119.332248 -55.499)
		(end 119.103648 -55.499)
		(width 0.1143)
		(layer "B.Cu")
		(net "XM_DATA_14")
	)
	(segment
		(start 126.655068 -56.267604)
		(end 126.540768 -56.381904)
		(width 0.1143)
		(layer "B.Cu")
		(net "XM_DATA_14")
	)
	(segment
		(start 125.626368 -56.381904)
		(end 123.218448 -56.381904)
		(width 0.1143)
		(layer "B.Cu")
		(net "XM_DATA_14")
	)
	(segment
		(start 127.569468 -55.5244)
		(end 127.569468 -56.267604)
		(width 0.1143)
		(layer "B.Cu")
		(net "XM_DATA_14")
	)
	(segment
		(start 122.646948 -55.6133)
		(end 122.646948 -56.267604)
		(width 0.1143)
		(layer "B.Cu")
		(net "XM_DATA_14")
	)
	(segment
		(start 126.312168 -56.381904)
		(end 126.197868 -56.267604)
		(width 0.1143)
		(layer "B.Cu")
		(net "XM_DATA_14")
	)
	(segment
		(start 128.140968 -56.381904)
		(end 128.026668 -56.267604)
		(width 0.1143)
		(layer "B.Cu")
		(net "XM_DATA_14")
	)
	(segment
		(start 121.275348 -56.267604)
		(end 121.275348 -55.6133)
		(width 0.1143)
		(layer "B.Cu")
		(net "XM_DATA_14")
	)
	(segment
		(start 126.769368 -55.4101)
		(end 126.655068 -55.5244)
		(width 0.1143)
		(layer "B.Cu")
		(net "XM_DATA_14")
	)
	(segment
		(start 123.104148 -56.267604)
		(end 123.104148 -55.6133)
		(width 0.1143)
		(layer "B.Cu")
		(net "XM_DATA_14")
	)
	(segment
		(start 120.703848 -56.381904)
		(end 120.475248 -56.381904)
		(width 0.1143)
		(layer "B.Cu")
		(net "XM_DATA_14")
	)
	(segment
		(start 121.161048 -55.499)
		(end 120.932448 -55.499)
		(width 0.1143)
		(layer "B.Cu")
		(net "XM_DATA_14")
	)
	(segment
		(start 120.018048 -55.499)
		(end 119.903748 -55.6133)
		(width 0.1143)
		(layer "B.Cu")
		(net "XM_DATA_14")
	)
	(segment
		(start 126.540768 -56.381904)
		(end 126.312168 -56.381904)
		(width 0.1143)
		(layer "B.Cu")
		(net "XM_DATA_14")
	)
	(segment
		(start 125.740668 -56.267604)
		(end 125.626368 -56.381904)
		(width 0.1143)
		(layer "B.Cu")
		(net "XM_DATA_14")
	)
	(segment
		(start 122.189748 -56.267604)
		(end 122.189748 -55.6133)
		(width 0.1143)
		(layer "B.Cu")
		(net "XM_DATA_14")
	)
	(segment
		(start 120.360948 -56.267604)
		(end 120.360948 -55.6133)
		(width 0.1143)
		(layer "B.Cu")
		(net "XM_DATA_14")
	)
	(segment
		(start 128.026668 -55.5244)
		(end 127.912368 -55.4101)
		(width 0.1143)
		(layer "B.Cu")
		(net "XM_DATA_14")
	)
	(segment
		(start 117.094 -55.080662)
		(end 117.094 -54.991)
		(width 0.1143)
		(layer "B.Cu")
		(net "XM_DATA_14")
	)
	(segment
		(start 123.218448 -56.381904)
		(end 123.104148 -56.267604)
		(width 0.1143)
		(layer "B.Cu")
		(net "XM_DATA_14")
	)
	(segment
		(start 120.818148 -56.267604)
		(end 120.703848 -56.381904)
		(width 0.1143)
		(layer "B.Cu")
		(net "XM_DATA_14")
	)
	(segment
		(start 121.275348 -55.6133)
		(end 121.161048 -55.499)
		(width 0.1143)
		(layer "B.Cu")
		(net "XM_DATA_14")
	)
	(segment
		(start 127.112268 -56.267604)
		(end 127.112268 -55.5244)
		(width 0.1143)
		(layer "B.Cu")
		(net "XM_DATA_14")
	)
	(segment
		(start 126.083568 -55.4101)
		(end 125.854968 -55.4101)
		(width 0.1143)
		(layer "B.Cu")
		(net "XM_DATA_14")
	)
	(segment
		(start 118.989348 -55.6133)
		(end 118.989348 -56.267604)
		(width 0.1143)
		(layer "B.Cu")
		(net "XM_DATA_14")
	)
	(segment
		(start 122.761248 -55.499)
		(end 122.646948 -55.6133)
		(width 0.1143)
		(layer "B.Cu")
		(net "XM_DATA_14")
	)
	(segment
		(start 121.732548 -56.267604)
		(end 121.618248 -56.381904)
		(width 0.1143)
		(layer "B.Cu")
		(net "XM_DATA_14")
	)
	(segment
		(start 122.646948 -56.267604)
		(end 122.532648 -56.381904)
		(width 0.1143)
		(layer "B.Cu")
		(net "XM_DATA_14")
	)
	(segment
		(start 121.846848 -55.499)
		(end 121.732548 -55.6133)
		(width 0.1143)
		(layer "B.Cu")
		(net "XM_DATA_14")
	)
	(segment
		(start 121.618248 -56.381904)
		(end 121.389648 -56.381904)
		(width 0.1143)
		(layer "B.Cu")
		(net "XM_DATA_14")
	)
	(segment
		(start 125.854968 -55.4101)
		(end 125.740668 -55.5244)
		(width 0.1143)
		(layer "B.Cu")
		(net "XM_DATA_14")
	)
	(segment
		(start 126.197868 -56.267604)
		(end 126.197868 -55.5244)
		(width 0.1143)
		(layer "B.Cu")
		(net "XM_DATA_14")
	)
	(segment
		(start 122.304048 -56.381904)
		(end 122.189748 -56.267604)
		(width 0.1143)
		(layer "B.Cu")
		(net "XM_DATA_14")
	)
	(segment
		(start 122.189748 -55.6133)
		(end 122.075448 -55.499)
		(width 0.1143)
		(layer "B.Cu")
		(net "XM_DATA_14")
	)
	(segment
		(start 127.569468 -56.267604)
		(end 127.455168 -56.381904)
		(width 0.1143)
		(layer "B.Cu")
		(net "XM_DATA_14")
	)
	(segment
		(start 120.818148 -55.6133)
		(end 120.818148 -56.267604)
		(width 0.1143)
		(layer "B.Cu")
		(net "XM_DATA_14")
	)
	(segment
		(start 122.075448 -55.499)
		(end 121.846848 -55.499)
		(width 0.1143)
		(layer "B.Cu")
		(net "XM_DATA_14")
	)
	(segment
		(start 119.560848 -56.381904)
		(end 119.446548 -56.267604)
		(width 0.1143)
		(layer "B.Cu")
		(net "XM_DATA_14")
	)
	(segment
		(start 128.026668 -56.267604)
		(end 128.026668 -55.5244)
		(width 0.1143)
		(layer "B.Cu")
		(net "XM_DATA_14")
	)
	(segment
		(start 127.112268 -55.5244)
		(end 126.997968 -55.4101)
		(width 0.1143)
		(layer "B.Cu")
		(net "XM_DATA_14")
	)
	(segment
		(start 126.997968 -55.4101)
		(end 126.769368 -55.4101)
		(width 0.1143)
		(layer "B.Cu")
		(net "XM_DATA_14")
	)
	(segment
		(start 120.475248 -56.381904)
		(end 120.360948 -56.267604)
		(width 0.1143)
		(layer "B.Cu")
		(net "XM_DATA_14")
	)
	(segment
		(start 119.103648 -55.499)
		(end 118.989348 -55.6133)
		(width 0.1143)
		(layer "B.Cu")
		(net "XM_DATA_14")
	)
	(segment
		(start 119.446548 -56.267604)
		(end 119.446548 -55.6133)
		(width 0.1143)
		(layer "B.Cu")
		(net "XM_DATA_14")
	)
	(segment
		(start 118.989348 -56.267604)
		(end 118.875048 -56.381904)
		(width 0.1143)
		(layer "B.Cu")
		(net "XM_DATA_14")
	)
	(segment
		(start 139.192 -58.674)
		(end 139.065 -58.674)
		(width 0.1143)
		(layer "B.Cu")
		(net "XM_DATA_14")
	)
	(segment
		(start 120.932448 -55.499)
		(end 120.818148 -55.6133)
		(width 0.1143)
		(layer "B.Cu")
		(net "XM_DATA_14")
	)
	(segment
		(start 116.339366 -54.236366)
		(end 117.094 -54.991)
		(width 0.1143)
		(layer "B.Cu")
		(net "XM_DATA_14")
	)
	(segment
		(start 122.532648 -56.381904)
		(end 122.304048 -56.381904)
		(width 0.1143)
		(layer "B.Cu")
		(net "XM_DATA_14")
	)
	(segment
		(start 127.455168 -56.381904)
		(end 127.226568 -56.381904)
		(width 0.1143)
		(layer "B.Cu")
		(net "XM_DATA_14")
	)
	(segment
		(start 125.740668 -55.5244)
		(end 125.740668 -56.267604)
		(width 0.1143)
		(layer "B.Cu")
		(net "XM_DATA_14")
	)
	(segment
		(start 118.395242 -56.381904)
		(end 117.094 -55.080662)
		(width 0.1143)
		(layer "B.Cu")
		(net "XM_DATA_14")
	)
	(segment
		(start 121.389648 -56.381904)
		(end 121.275348 -56.267604)
		(width 0.1143)
		(layer "B.Cu")
		(net "XM_DATA_14")
	)
	(segment
		(start 136.772904 -56.381904)
		(end 128.140968 -56.381904)
		(width 0.1143)
		(layer "B.Cu")
		(net "XM_DATA_14")
	)
	(segment
		(start 126.655068 -55.5244)
		(end 126.655068 -56.267604)
		(width 0.1143)
		(layer "B.Cu")
		(net "XM_DATA_14")
	)
	(segment
		(start 93.689424 -37.803836)
		(end 93.55836 -37.803836)
		(width 0.1016)
		(layer "F.Cu")
		(net "3008_SAS_RX_N3")
	)
	(segment
		(start 131.704842 -84.4296)
		(end 131.791456 -84.516214)
		(width 0.1016)
		(layer "F.Cu")
		(net "3008_SAS_RX_N3")
	)
	(segment
		(start 136.172448 -83.951064)
		(end 136.172448 -82.042)
		(width 0.1016)
		(layer "F.Cu")
		(net "3008_SAS_RX_N3")
	)
	(segment
		(start 132.63499 -84.81568)
		(end 132.71754 -84.89823)
		(width 0.1016)
		(layer "F.Cu")
		(net "3008_SAS_RX_N3")
	)
	(segment
		(start 93.55836 -37.803836)
		(end 93.556582 -37.802058)
		(width 0.1016)
		(layer "F.Cu")
		(net "3008_SAS_RX_N3")
	)
	(segment
		(start 131.349242 -84.399882)
		(end 131.63296 -84.399882)
		(width 0.1016)
		(layer "F.Cu")
		(net "3008_SAS_RX_N3")
	)
	(segment
		(start 136.020048 -81.674462)
		(end 135.87984 -81.534)
		(width 0.1016)
		(layer "F.Cu")
		(net "3008_SAS_RX_N3")
	)
	(segment
		(start 132.843016 -84.9503)
		(end 135.188452 -84.9503)
		(width 0.1016)
		(layer "F.Cu")
		(net "3008_SAS_RX_N3")
	)
	(segment
		(start 93.950028 -38.199822)
		(end 93.950028 -38.06444)
		(width 0.1016)
		(layer "F.Cu")
		(net "3008_SAS_RX_N3")
	)
	(segment
		(start 93.912944 -37.974778)
		(end 93.779086 -37.84092)
		(width 0.1016)
		(layer "F.Cu")
		(net "3008_SAS_RX_N3")
	)
	(segment
		(start 131.863338 -84.545932)
		(end 131.98348 -84.545932)
		(width 0.1016)
		(layer "F.Cu")
		(net "3008_SAS_RX_N3")
	)
	(segment
		(start 135.585708 -84.785708)
		(end 135.997188 -84.374228)
		(width 0.1016)
		(layer "F.Cu")
		(net "3008_SAS_RX_N3")
	)
	(via
		(at 135.87984 -81.534)
		(size 0.5588)
		(drill 0.3048)
		(layers "F.Cu" "B.Cu")
		(net "3008_SAS_RX_N3")
	)
	(via
		(at 93.556582 -37.802058)
		(size 0.508)
		(drill 0.254)
		(layers "F.Cu" "B.Cu")
		(net "3008_SAS_RX_N3")
	)
	(arc
		(start 132.71754 -84.89823)
		(mid 132.775109 -84.936696)
		(end 132.843016 -84.9503)
		(width 0.1016)
		(layer "F.Cu")
		(net "3008_SAS_RX_N3")
	)
	(arc
		(start 131.98348 -84.545932)
		(mid 132.336084 -84.615976)
		(end 132.63499 -84.81568)
		(width 0.1016)
		(layer "F.Cu")
		(net "3008_SAS_RX_N3")
	)
	(arc
		(start 136.172448 -82.042)
		(mid 136.132787 -81.843082)
		(end 136.020048 -81.674462)
		(width 0.1016)
		(layer "F.Cu")
		(net "3008_SAS_RX_N3")
	)
	(arc
		(start 135.188452 -84.9503)
		(mid 135.403462 -84.907532)
		(end 135.585708 -84.785708)
		(width 0.1016)
		(layer "F.Cu")
		(net "3008_SAS_RX_N3")
	)
	(arc
		(start 135.997188 -84.374228)
		(mid 136.126914 -84.180079)
		(end 136.172448 -83.951064)
		(width 0.1016)
		(layer "F.Cu")
		(net "3008_SAS_RX_N3")
	)
	(arc
		(start 131.63296 -84.399882)
		(mid 131.671855 -84.407601)
		(end 131.704842 -84.4296)
		(width 0.1016)
		(layer "F.Cu")
		(net "3008_SAS_RX_N3")
	)
	(arc
		(start 93.779086 -37.84092)
		(mid 93.737935 -37.813487)
		(end 93.689424 -37.803836)
		(width 0.1016)
		(layer "F.Cu")
		(net "3008_SAS_RX_N3")
	)
	(arc
		(start 131.791456 -84.516214)
		(mid 131.82445 -84.538197)
		(end 131.863338 -84.545932)
		(width 0.1016)
		(layer "F.Cu")
		(net "3008_SAS_RX_N3")
	)
	(arc
		(start 93.950028 -38.06444)
		(mid 93.940395 -38.015922)
		(end 93.912944 -37.974778)
		(width 0.1016)
		(layer "F.Cu")
		(net "3008_SAS_RX_N3")
	)
	(segment
		(start 93.143832 -37.973)
		(end 92.736924 -37.973)
		(width 0.0889)
		(layer "In5.Cu")
		(net "3008_SAS_RX_N3")
	)
	(segment
		(start 137.846308 -78.475586)
		(end 137.833354 -78.488794)
		(width 0.1016)
		(layer "In5.Cu")
		(net "3008_SAS_RX_N3")
	)
	(segment
		(start 138.2776 -76.357988)
		(end 138.2776 -77.732382)
		(width 0.1016)
		(layer "In5.Cu")
		(net "3008_SAS_RX_N3")
	)
	(segment
		(start 137.94232 -78.379574)
		(end 137.847578 -78.47457)
		(width 0.1016)
		(layer "In5.Cu")
		(net "3008_SAS_RX_N3")
	)
	(segment
		(start 101.996748 -61.864748)
		(end 102.037642 -61.823854)
		(width 0.1016)
		(layer "In5.Cu")
		(net "3008_SAS_RX_N3")
	)
	(segment
		(start 92.153232 -38.214808)
		(end 91.585796 -38.782244)
		(width 0.0889)
		(layer "In5.Cu")
		(net "3008_SAS_RX_N3")
	)
	(segment
		(start 122.516138 -68.364862)
		(end 122.833384 -68.682108)
		(width 0.1016)
		(layer "In5.Cu")
		(net "3008_SAS_RX_N3")
	)
	(segment
		(start 91.472004 -38.797738)
		(end 91.372944 -38.896544)
		(width 0.1016)
		(layer "In5.Cu")
		(net "3008_SAS_RX_N3")
	)
	(segment
		(start 137.847578 -78.47457)
		(end 137.847324 -78.47457)
		(width 0.1016)
		(layer "In5.Cu")
		(net "3008_SAS_RX_N3")
	)
	(segment
		(start 132.341874 -70.225412)
		(end 136.722358 -74.605388)
		(width 0.1016)
		(layer "In5.Cu")
		(net "3008_SAS_RX_N3")
	)
	(segment
		(start 137.287 -78.7146)
		(end 137.267442 -78.7146)
		(width 0.1016)
		(layer "In5.Cu")
		(net "3008_SAS_RX_N3")
	)
	(segment
		(start 136.178798 -79.95158)
		(end 136.178798 -81.026)
		(width 0.1016)
		(layer "In5.Cu")
		(net "3008_SAS_RX_N3")
	)
	(segment
		(start 113.714784 -67.995546)
		(end 121.624598 -67.995546)
		(width 0.1016)
		(layer "In5.Cu")
		(net "3008_SAS_RX_N3")
	)
	(segment
		(start 100.203 -62.12459)
		(end 101.369368 -62.12459)
		(width 0.1016)
		(layer "In5.Cu")
		(net "3008_SAS_RX_N3")
	)
	(segment
		(start 123.62942 -69.0118)
		(end 129.412746 -69.0118)
		(width 0.1016)
		(layer "In5.Cu")
		(net "3008_SAS_RX_N3")
	)
	(segment
		(start 91.585796 -38.782244)
		(end 91.487498 -38.782244)
		(width 0.0889)
		(layer "In5.Cu")
		(net "3008_SAS_RX_N3")
	)
	(segment
		(start 89.192862 -51.578256)
		(end 99.41179 -61.79693)
		(width 0.1016)
		(layer "In5.Cu")
		(net "3008_SAS_RX_N3")
	)
	(segment
		(start 136.456166 -79.281274)
		(end 136.45642 -79.281274)
		(width 0.1016)
		(layer "In5.Cu")
		(net "3008_SAS_RX_N3")
	)
	(segment
		(start 107.157774 -62.006226)
		(end 112.745774 -67.594226)
		(width 0.1016)
		(layer "In5.Cu")
		(net "3008_SAS_RX_N3")
	)
	(segment
		(start 91.213686 -39.281354)
		(end 91.213686 -40.843708)
		(width 0.1016)
		(layer "In5.Cu")
		(net "3008_SAS_RX_N3")
	)
	(segment
		(start 138.2776 -77.732382)
		(end 138.277346 -77.732128)
		(width 0.1016)
		(layer "In5.Cu")
		(net "3008_SAS_RX_N3")
	)
	(segment
		(start 137.847324 -78.47457)
		(end 137.846308 -78.475586)
		(width 0.1016)
		(layer "In5.Cu")
		(net "3008_SAS_RX_N3")
	)
	(segment
		(start 138.05662 -78.26502)
		(end 137.94232 -78.379574)
		(width 0.1016)
		(layer "In5.Cu")
		(net "3008_SAS_RX_N3")
	)
	(segment
		(start 88.49868 -43.842686)
		(end 88.49868 -49.902364)
		(width 0.1016)
		(layer "In5.Cu")
		(net "3008_SAS_RX_N3")
	)
	(segment
		(start 91.372944 -38.896544)
		(end 91.372944 -38.896798)
		(width 0.1016)
		(layer "In5.Cu")
		(net "3008_SAS_RX_N3")
	)
	(segment
		(start 136.722358 -74.605388)
		(end 138.1379 -76.02093)
		(width 0.1016)
		(layer "In5.Cu")
		(net "3008_SAS_RX_N3")
	)
	(segment
		(start 91.487498 -38.782244)
		(end 91.472004 -38.797738)
		(width 0.0889)
		(layer "In5.Cu")
		(net "3008_SAS_RX_N3")
	)
	(segment
		(start 138.277346 -76.358242)
		(end 138.2776 -76.357988)
		(width 0.1016)
		(layer "In5.Cu")
		(net "3008_SAS_RX_N3")
	)
	(segment
		(start 102.406196 -61.6712)
		(end 106.349038 -61.6712)
		(width 0.1016)
		(layer "In5.Cu")
		(net "3008_SAS_RX_N3")
	)
	(segment
		(start 91.161616 -40.969438)
		(end 88.647778 -43.483276)
		(width 0.1016)
		(layer "In5.Cu")
		(net "3008_SAS_RX_N3")
	)
	(segment
		(start 136.85012 -78.88732)
		(end 136.456166 -79.281274)
		(width 0.1016)
		(layer "In5.Cu")
		(net "3008_SAS_RX_N3")
	)
	(segment
		(start 136.03097 -81.38287)
		(end 135.87984 -81.534)
		(width 0.1016)
		(layer "In5.Cu")
		(net "3008_SAS_RX_N3")
	)
	(arc
		(start 136.178798 -81.026)
		(mid 136.14038 -81.21914)
		(end 136.03097 -81.38287)
		(width 0.1016)
		(layer "In5.Cu")
		(net "3008_SAS_RX_N3")
	)
	(arc
		(start 121.624598 -67.995546)
		(mid 122.107107 -68.091523)
		(end 122.516138 -68.364862)
		(width 0.1016)
		(layer "In5.Cu")
		(net "3008_SAS_RX_N3")
	)
	(arc
		(start 112.745774 -67.594226)
		(mid 113.190373 -67.891264)
		(end 113.714784 -67.995546)
		(width 0.1016)
		(layer "In5.Cu")
		(net "3008_SAS_RX_N3")
	)
	(arc
		(start 129.412746 -69.0118)
		(mid 130.998022 -69.32726)
		(end 132.341874 -70.225412)
		(width 0.1016)
		(layer "In5.Cu")
		(net "3008_SAS_RX_N3")
	)
	(arc
		(start 136.45642 -79.281274)
		(mid 136.250953 -79.588826)
		(end 136.178798 -79.95158)
		(width 0.1016)
		(layer "In5.Cu")
		(net "3008_SAS_RX_N3")
	)
	(arc
		(start 122.833384 -68.682108)
		(mid 123.198609 -68.926114)
		(end 123.62942 -69.0118)
		(width 0.1016)
		(layer "In5.Cu")
		(net "3008_SAS_RX_N3")
	)
	(arc
		(start 91.213686 -40.843708)
		(mid 91.200167 -40.911763)
		(end 91.161616 -40.969438)
		(width 0.1016)
		(layer "In5.Cu")
		(net "3008_SAS_RX_N3")
	)
	(arc
		(start 88.49868 -49.902364)
		(mid 88.679091 -50.809352)
		(end 89.192862 -51.578256)
		(width 0.1016)
		(layer "In5.Cu")
		(net "3008_SAS_RX_N3")
	)
	(arc
		(start 138.277346 -77.732128)
		(mid 138.21998 -78.020525)
		(end 138.05662 -78.26502)
		(width 0.1016)
		(layer "In5.Cu")
		(net "3008_SAS_RX_N3")
	)
	(arc
		(start 92.736924 -37.973)
		(mid 92.421019 -38.035837)
		(end 92.153232 -38.214808)
		(width 0.0889)
		(layer "In5.Cu")
		(net "3008_SAS_RX_N3")
	)
	(arc
		(start 88.647778 -43.483276)
		(mid 88.537513 -43.64816)
		(end 88.49868 -43.842686)
		(width 0.1016)
		(layer "In5.Cu")
		(net "3008_SAS_RX_N3")
	)
	(arc
		(start 106.349038 -61.6712)
		(mid 106.786737 -61.758264)
		(end 107.157774 -62.006226)
		(width 0.1016)
		(layer "In5.Cu")
		(net "3008_SAS_RX_N3")
	)
	(arc
		(start 93.556582 -37.802058)
		(mid 93.367211 -37.928592)
		(end 93.143832 -37.973)
		(width 0.0889)
		(layer "In5.Cu")
		(net "3008_SAS_RX_N3")
	)
	(arc
		(start 99.41179 -61.79693)
		(mid 99.774814 -62.039432)
		(end 100.203 -62.12459)
		(width 0.1016)
		(layer "In5.Cu")
		(net "3008_SAS_RX_N3")
	)
	(arc
		(start 137.833354 -78.488794)
		(mid 137.582586 -78.65594)
		(end 137.287 -78.7146)
		(width 0.1016)
		(layer "In5.Cu")
		(net "3008_SAS_RX_N3")
	)
	(arc
		(start 102.037642 -61.823854)
		(mid 102.206736 -61.710869)
		(end 102.406196 -61.6712)
		(width 0.1016)
		(layer "In5.Cu")
		(net "3008_SAS_RX_N3")
	)
	(arc
		(start 138.1379 -76.02093)
		(mid 138.241117 -76.175733)
		(end 138.277346 -76.358242)
		(width 0.1016)
		(layer "In5.Cu")
		(net "3008_SAS_RX_N3")
	)
	(arc
		(start 91.372944 -38.896798)
		(mid 91.255078 -39.073247)
		(end 91.213686 -39.281354)
		(width 0.1016)
		(layer "In5.Cu")
		(net "3008_SAS_RX_N3")
	)
	(arc
		(start 137.267442 -78.7146)
		(mid 137.041614 -78.759484)
		(end 136.85012 -78.88732)
		(width 0.1016)
		(layer "In5.Cu")
		(net "3008_SAS_RX_N3")
	)
	(arc
		(start 101.369368 -62.12459)
		(mid 101.708893 -62.057054)
		(end 101.996748 -61.864748)
		(width 0.1016)
		(layer "In5.Cu")
		(net "3008_SAS_RX_N3")
	)
	(segment
		(start 168.932352 -118.391178)
		(end 168.932352 -119.634)
		(width 0.254)
		(layer "F.Cu")
		(net "P0V9_E_TRIP")
	)
	(segment
		(start 168.646348 -119.920004)
		(end 168.646348 -120.269)
		(width 0.254)
		(layer "F.Cu")
		(net "P0V9_E_TRIP")
	)
	(segment
		(start 168.932352 -119.634)
		(end 168.646348 -119.920004)
		(width 0.254)
		(layer "F.Cu")
		(net "P0V9_E_TRIP")
	)
	(segment
		(start 168.646348 -122.101356)
		(end 168.646348 -120.269)
		(width 0.254)
		(layer "F.Cu")
		(net "P0V9_E_TRIP")
	)
	(via
		(at 168.646348 -120.269)
		(size 0.7112)
		(drill 0.3556)
		(layers "F.Cu" "B.Cu")
		(net "P0V9_E_TRIP")
	)
	(segment
		(start 118.63197 -77.870812)
		(end 118.637558 -77.8764)
		(width 0.1016)
		(layer "F.Cu")
		(net "EXP_REF_CLK_N")
	)
	(segment
		(start 120.566942 -81.157572)
		(end 120.566942 -82.132932)
		(width 0.1016)
		(layer "F.Cu")
		(net "EXP_REF_CLK_N")
	)
	(segment
		(start 118.63197 -75.1967)
		(end 118.63197 -77.870812)
		(width 0.1016)
		(layer "F.Cu")
		(net "EXP_REF_CLK_N")
	)
	(segment
		(start 118.637558 -77.8764)
		(end 118.637558 -77.997558)
		(width 0.1016)
		(layer "F.Cu")
		(net "EXP_REF_CLK_N")
	)
	(segment
		(start 120.566942 -82.132932)
		(end 120.350026 -82.349848)
		(width 0.1016)
		(layer "F.Cu")
		(net "EXP_REF_CLK_N")
	)
	(segment
		(start 118.637558 -77.997558)
		(end 119.502428 -78.862428)
		(width 0.1016)
		(layer "F.Cu")
		(net "EXP_REF_CLK_N")
	)
	(segment
		(start 119.502428 -80.093058)
		(end 120.566942 -81.157572)
		(width 0.1016)
		(layer "F.Cu")
		(net "EXP_REF_CLK_N")
	)
	(segment
		(start 119.502428 -78.862428)
		(end 119.502428 -80.093058)
		(width 0.1016)
		(layer "F.Cu")
		(net "EXP_REF_CLK_N")
	)
	(segment
		(start 119.20347 -74.6252)
		(end 118.63197 -75.1967)
		(width 0.1016)
		(layer "F.Cu")
		(net "EXP_REF_CLK_N")
	)
	(segment
		(start 108.719112 -55.368952)
		(end 108.719112 -55.37962)
		(width 0.1143)
		(layer "F.Cu")
		(net "XM_CLE")
	)
	(segment
		(start 108.719112 -55.37962)
		(end 108.723938 -55.384446)
		(width 0.1143)
		(layer "F.Cu")
		(net "XM_CLE")
	)
	(segment
		(start 108.35005 -54.99989)
		(end 108.719112 -55.368952)
		(width 0.1143)
		(layer "F.Cu")
		(net "XM_CLE")
	)
	(via
		(at 108.723938 -55.384446)
		(size 0.508)
		(drill 0.254)
		(layers "F.Cu" "B.Cu")
		(net "XM_CLE")
	)
	(segment
		(start 107.982004 -56.165496)
		(end 107.982004 -56.12638)
		(width 0.1143)
		(layer "B.Cu")
		(net "XM_CLE")
	)
	(segment
		(start 107.982004 -56.12638)
		(end 108.723938 -55.384446)
		(width 0.1143)
		(layer "B.Cu")
		(net "XM_CLE")
	)
	(via
		(at 171.554394 -113.284)
		(size 0.7112)
		(drill 0.3556)
		(layers "F.Cu" "B.Cu")
		(net "P0V9_E_VBST_RC")
	)
	(segment
		(start 171.554394 -113.284)
		(end 170.434 -113.284)
		(width 0.508)
		(layer "B.Cu")
		(net "P0V9_E_VBST_RC")
	)
	(segment
		(start 172.8978 -113.284)
		(end 171.554394 -113.284)
		(width 0.508)
		(layer "B.Cu")
		(net "P0V9_E_VBST_RC")
	)
	(segment
		(start 46.130972 -140.416534)
		(end 46.130972 -140.30833)
		(width 0.1143)
		(layer "F.Cu")
		(net "EXP_RESET_N")
	)
	(segment
		(start 60.99683 -125.603)
		(end 61.91377 -124.68606)
		(width 0.1143)
		(layer "F.Cu")
		(net "EXP_RESET_N")
	)
	(segment
		(start 46.607222 -140.892784)
		(end 46.607222 -143.491966)
		(width 0.1143)
		(layer "F.Cu")
		(net "EXP_RESET_N")
	)
	(segment
		(start 55.88 -125.603)
		(end 60.99683 -125.603)
		(width 0.1143)
		(layer "F.Cu")
		(net "EXP_RESET_N")
	)
	(segment
		(start 46.607222 -140.892784)
		(end 46.130972 -140.416534)
		(width 0.1143)
		(layer "F.Cu")
		(net "EXP_RESET_N")
	)
	(segment
		(start 47.44847 -143.9545)
		(end 48.14697 -143.9545)
		(width 0.1143)
		(layer "F.Cu")
		(net "EXP_RESET_N")
	)
	(segment
		(start 46.637956 -143.5227)
		(end 47.01667 -143.5227)
		(width 0.1143)
		(layer "F.Cu")
		(net "EXP_RESET_N")
	)
	(segment
		(start 51.054 -130.429)
		(end 52.832 -128.651)
		(width 0.1143)
		(layer "F.Cu")
		(net "EXP_RESET_N")
	)
	(segment
		(start 105.349802 -86.34984)
		(end 104.849676 -85.849714)
		(width 0.1143)
		(layer "F.Cu")
		(net "EXP_RESET_N")
	)
	(segment
		(start 46.130972 -140.30833)
		(end 46.023276 -140.200634)
		(width 0.1143)
		(layer "F.Cu")
		(net "EXP_RESET_N")
	)
	(segment
		(start 39.56304 -141.39545)
		(end 37.65169 -139.4841)
		(width 0.1143)
		(layer "F.Cu")
		(net "EXP_RESET_N")
	)
	(segment
		(start 42.510456 -130.429)
		(end 51.054 -130.429)
		(width 0.1143)
		(layer "F.Cu")
		(net "EXP_RESET_N")
	)
	(segment
		(start 42.1386 -141.39545)
		(end 39.56304 -141.39545)
		(width 0.1143)
		(layer "F.Cu")
		(net "EXP_RESET_N")
	)
	(segment
		(start 52.832 -128.651)
		(end 55.88 -125.603)
		(width 0.1143)
		(layer "F.Cu")
		(net "EXP_RESET_N")
	)
	(segment
		(start 46.023276 -140.200634)
		(end 43.333416 -140.200634)
		(width 0.1143)
		(layer "F.Cu")
		(net "EXP_RESET_N")
	)
	(segment
		(start 46.607222 -143.491966)
		(end 46.637956 -143.5227)
		(width 0.1143)
		(layer "F.Cu")
		(net "EXP_RESET_N")
	)
	(segment
		(start 37.65169 -135.287766)
		(end 42.510456 -130.429)
		(width 0.1143)
		(layer "F.Cu")
		(net "EXP_RESET_N")
	)
	(segment
		(start 47.01667 -143.5227)
		(end 47.44847 -143.9545)
		(width 0.1143)
		(layer "F.Cu")
		(net "EXP_RESET_N")
	)
	(segment
		(start 43.333416 -140.200634)
		(end 42.1386 -141.39545)
		(width 0.1143)
		(layer "F.Cu")
		(net "EXP_RESET_N")
	)
	(segment
		(start 37.65169 -139.4841)
		(end 37.65169 -135.287766)
		(width 0.1143)
		(layer "F.Cu")
		(net "EXP_RESET_N")
	)
	(via
		(at 61.91377 -124.68606)
		(size 0.5588)
		(drill 0.3048)
		(layers "F.Cu" "B.Cu")
		(net "EXP_RESET_N")
	)
	(via
		(at 52.832 -128.651)
		(size 0.7112)
		(drill 0.3556)
		(layers "F.Cu" "B.Cu")
		(net "EXP_RESET_N")
	)
	(via
		(at 104.849676 -85.849714)
		(size 0.508)
		(drill 0.254)
		(layers "F.Cu" "B.Cu")
		(net "EXP_RESET_N")
	)
	(segment
		(start 92.41917 -92.78112)
		(end 93.581728 -92.78112)
		(width 0.127)
		(layer "In5.Cu")
		(net "EXP_RESET_N")
	)
	(segment
		(start 103.31704 -85.849714)
		(end 104.849676 -85.849714)
		(width 0.127)
		(layer "In5.Cu")
		(net "EXP_RESET_N")
	)
	(segment
		(start 99.517454 -86.739984)
		(end 102.42677 -86.739984)
		(width 0.127)
		(layer "In5.Cu")
		(net "EXP_RESET_N")
	)
	(segment
		(start 93.581728 -92.78112)
		(end 93.85681 -92.506038)
		(width 0.127)
		(layer "In5.Cu")
		(net "EXP_RESET_N")
	)
	(segment
		(start 93.85681 -92.400628)
		(end 99.517454 -86.739984)
		(width 0.127)
		(layer "In5.Cu")
		(net "EXP_RESET_N")
	)
	(segment
		(start 102.42677 -86.739984)
		(end 103.31704 -85.849714)
		(width 0.127)
		(layer "In5.Cu")
		(net "EXP_RESET_N")
	)
	(segment
		(start 61.91377 -124.68606)
		(end 61.91377 -123.28652)
		(width 0.127)
		(layer "In5.Cu")
		(net "EXP_RESET_N")
	)
	(segment
		(start 93.85681 -92.506038)
		(end 93.85681 -92.400628)
		(width 0.127)
		(layer "In5.Cu")
		(net "EXP_RESET_N")
	)
	(segment
		(start 61.91377 -123.28652)
		(end 92.41917 -92.78112)
		(width 0.127)
		(layer "In5.Cu")
		(net "EXP_RESET_N")
	)
	(segment
		(start 138.37285 -51.21148)
		(end 138.49985 -51.08448)
		(width 0.1143)
		(layer "F.Cu")
		(net "XM_ADDR_14")
	)
	(segment
		(start 137.131806 -46.679358)
		(end 137.566146 -46.679358)
		(width 0.1143)
		(layer "F.Cu")
		(net "XM_ADDR_14")
	)
	(segment
		(start 137.680446 -46.793658)
		(end 137.680446 -47.022258)
		(width 0.1143)
		(layer "F.Cu")
		(net "XM_ADDR_14")
	)
	(segment
		(start 137.566146 -46.679358)
		(end 137.680446 -46.793658)
		(width 0.1143)
		(layer "F.Cu")
		(net "XM_ADDR_14")
	)
	(segment
		(start 137.886948 -47.879)
		(end 137.795 -47.879)
		(width 0.1143)
		(layer "F.Cu")
		(net "XM_ADDR_14")
	)
	(segment
		(start 137.680446 -47.022258)
		(end 137.566146 -47.136558)
		(width 0.1143)
		(layer "F.Cu")
		(net "XM_ADDR_14")
	)
	(segment
		(start 138.0109 -49.257458)
		(end 138.0109 -48.002952)
		(width 0.1143)
		(layer "F.Cu")
		(net "XM_ADDR_14")
	)
	(segment
		(start 138.49985 -51.08448)
		(end 138.49985 -50.14595)
		(width 0.1143)
		(layer "F.Cu")
		(net "XM_ADDR_14")
	)
	(segment
		(start 137.790428 -49.47793)
		(end 138.0109 -49.257458)
		(width 0.1143)
		(layer "F.Cu")
		(net "XM_ADDR_14")
	)
	(segment
		(start 138.49985 -50.14595)
		(end 138.37285 -50.01895)
		(width 0.1143)
		(layer "F.Cu")
		(net "XM_ADDR_14")
	)
	(segment
		(start 137.636758 -50.01895)
		(end 137.509758 -49.89195)
		(width 0.1143)
		(layer "F.Cu")
		(net "XM_ADDR_14")
	)
	(segment
		(start 137.144506 -51.21148)
		(end 138.37285 -51.21148)
		(width 0.1143)
		(layer "F.Cu")
		(net "XM_ADDR_14")
	)
	(segment
		(start 137.131806 -47.136558)
		(end 137.017506 -47.250858)
		(width 0.1143)
		(layer "F.Cu")
		(net "XM_ADDR_14")
	)
	(segment
		(start 137.566146 -47.136558)
		(end 137.131806 -47.136558)
		(width 0.1143)
		(layer "F.Cu")
		(net "XM_ADDR_14")
	)
	(segment
		(start 114.365532 -53.61559)
		(end 114.556032 -53.80609)
		(width 0.1143)
		(layer "F.Cu")
		(net "XM_ADDR_14")
	)
	(segment
		(start 137.636758 -49.47793)
		(end 137.790428 -49.47793)
		(width 0.1143)
		(layer "F.Cu")
		(net "XM_ADDR_14")
	)
	(segment
		(start 114.556032 -53.80609)
		(end 114.780822 -53.80609)
		(width 0.1143)
		(layer "F.Cu")
		(net "XM_ADDR_14")
	)
	(segment
		(start 137.017506 -46.145958)
		(end 137.017506 -46.565058)
		(width 0.1143)
		(layer "F.Cu")
		(net "XM_ADDR_14")
	)
	(segment
		(start 137.144506 -46.018958)
		(end 137.017506 -46.145958)
		(width 0.1143)
		(layer "F.Cu")
		(net "XM_ADDR_14")
	)
	(segment
		(start 137.017506 -46.565058)
		(end 137.131806 -46.679358)
		(width 0.1143)
		(layer "F.Cu")
		(net "XM_ADDR_14")
	)
	(segment
		(start 137.599166 -42.7101)
		(end 137.599166 -45.891958)
		(width 0.1143)
		(layer "F.Cu")
		(net "XM_ADDR_14")
	)
	(segment
		(start 113.949988 -53.399944)
		(end 113.949988 -53.48859)
		(width 0.1143)
		(layer "F.Cu")
		(net "XM_ADDR_14")
	)
	(segment
		(start 137.017506 -51.08448)
		(end 137.144506 -51.21148)
		(width 0.1143)
		(layer "F.Cu")
		(net "XM_ADDR_14")
	)
	(segment
		(start 113.949988 -53.48859)
		(end 114.076988 -53.61559)
		(width 0.1143)
		(layer "F.Cu")
		(net "XM_ADDR_14")
	)
	(segment
		(start 137.599166 -45.891958)
		(end 137.472166 -46.018958)
		(width 0.1143)
		(layer "F.Cu")
		(net "XM_ADDR_14")
	)
	(segment
		(start 138.0109 -48.002952)
		(end 137.886948 -47.879)
		(width 0.1143)
		(layer "F.Cu")
		(net "XM_ADDR_14")
	)
	(segment
		(start 137.472166 -46.018958)
		(end 137.144506 -46.018958)
		(width 0.1143)
		(layer "F.Cu")
		(net "XM_ADDR_14")
	)
	(segment
		(start 114.076988 -53.61559)
		(end 114.365532 -53.61559)
		(width 0.1143)
		(layer "F.Cu")
		(net "XM_ADDR_14")
	)
	(segment
		(start 138.37285 -50.01895)
		(end 137.636758 -50.01895)
		(width 0.1143)
		(layer "F.Cu")
		(net "XM_ADDR_14")
	)
	(segment
		(start 137.017506 -47.250858)
		(end 137.017506 -51.08448)
		(width 0.1143)
		(layer "F.Cu")
		(net "XM_ADDR_14")
	)
	(segment
		(start 137.509758 -49.60493)
		(end 137.636758 -49.47793)
		(width 0.1143)
		(layer "F.Cu")
		(net "XM_ADDR_14")
	)
	(segment
		(start 137.509758 -49.89195)
		(end 137.509758 -49.60493)
		(width 0.1143)
		(layer "F.Cu")
		(net "XM_ADDR_14")
	)
	(segment
		(start 114.780822 -53.80609)
		(end 114.907822 -53.67909)
		(width 0.1143)
		(layer "F.Cu")
		(net "XM_ADDR_14")
	)
	(segment
		(start 114.907822 -53.67909)
		(end 114.907822 -53.399944)
		(width 0.1143)
		(layer "F.Cu")
		(net "XM_ADDR_14")
	)
	(via
		(at 136.779 -47.879)
		(size 0.7112)
		(drill 0.3556)
		(layers "F.Cu" "B.Cu")
		(net "XM_ADDR_14")
	)
	(via
		(at 114.907822 -53.399944)
		(size 0.508)
		(drill 0.254)
		(layers "F.Cu" "B.Cu")
		(net "XM_ADDR_14")
	)
	(via
		(at 137.795 -47.879)
		(size 0.5588)
		(drill 0.3048)
		(layers "F.Cu" "B.Cu")
		(net "XM_ADDR_14")
	)
	(segment
		(start 136.779 -47.879)
		(end 137.795 -47.879)
		(width 0.1143)
		(layer "B.Cu")
		(net "XM_ADDR_14")
	)
	(segment
		(start 136.914128 -48.160686)
		(end 136.787128 -48.033686)
		(width 0.127)
		(layer "In5.Cu")
		(net "XM_ADDR_14")
	)
	(segment
		(start 123.9901 -51.66741)
		(end 124.237496 -51.914806)
		(width 0.127)
		(layer "In5.Cu")
		(net "XM_ADDR_14")
	)
	(segment
		(start 132.70865 -50.29835)
		(end 132.544058 -50.462942)
		(width 0.127)
		(layer "In5.Cu")
		(net "XM_ADDR_14")
	)
	(segment
		(start 131.161536 -50.589942)
		(end 131.161536 -51.205638)
		(width 0.127)
		(layer "In5.Cu")
		(net "XM_ADDR_14")
	)
	(segment
		(start 130.272536 -50.462942)
		(end 130.145536 -50.589942)
		(width 0.127)
		(layer "In5.Cu")
		(net "XM_ADDR_14")
	)
	(segment
		(start 136.2583 -48.0441)
		(end 136.1313 -48.1711)
		(width 0.127)
		(layer "In5.Cu")
		(net "XM_ADDR_14")
	)
	(segment
		(start 125.954536 -51.332638)
		(end 125.700536 -51.332638)
		(width 0.127)
		(layer "In5.Cu")
		(net "XM_ADDR_14")
	)
	(segment
		(start 128.494536 -50.462942)
		(end 128.240536 -50.462942)
		(width 0.127)
		(layer "In5.Cu")
		(net "XM_ADDR_14")
	)
	(segment
		(start 127.986536 -51.332638)
		(end 127.732536 -51.332638)
		(width 0.127)
		(layer "In5.Cu")
		(net "XM_ADDR_14")
	)
	(segment
		(start 132.544058 -50.462942)
		(end 131.288536 -50.462942)
		(width 0.127)
		(layer "In5.Cu")
		(net "XM_ADDR_14")
	)
	(segment
		(start 137.795 -47.879)
		(end 137.795 -48.033686)
		(width 0.127)
		(layer "In5.Cu")
		(net "XM_ADDR_14")
	)
	(segment
		(start 126.589536 -51.205638)
		(end 126.589536 -50.589942)
		(width 0.127)
		(layer "In5.Cu")
		(net "XM_ADDR_14")
	)
	(segment
		(start 130.653536 -51.205638)
		(end 130.653536 -50.589942)
		(width 0.127)
		(layer "In5.Cu")
		(net "XM_ADDR_14")
	)
	(segment
		(start 125.6538 -50.494438)
		(end 125.6538 -50.248058)
		(width 0.127)
		(layer "In5.Cu")
		(net "XM_ADDR_14")
	)
	(segment
		(start 124.70892 -50.757836)
		(end 124.70892 -50.94859)
		(width 0.127)
		(layer "In5.Cu")
		(net "XM_ADDR_14")
	)
	(segment
		(start 132.70865 -50.140616)
		(end 132.70865 -50.29835)
		(width 0.127)
		(layer "In5.Cu")
		(net "XM_ADDR_14")
	)
	(segment
		(start 128.113536 -51.205638)
		(end 127.986536 -51.332638)
		(width 0.127)
		(layer "In5.Cu")
		(net "XM_ADDR_14")
	)
	(segment
		(start 117.366796 -52.770786)
		(end 117.178582 -52.959)
		(width 0.127)
		(layer "In5.Cu")
		(net "XM_ADDR_14")
	)
	(segment
		(start 123.210828 -52.463446)
		(end 123.358148 -52.610766)
		(width 0.127)
		(layer "In5.Cu")
		(net "XM_ADDR_14")
	)
	(segment
		(start 127.097536 -51.205638)
		(end 126.970536 -51.332638)
		(width 0.127)
		(layer "In5.Cu")
		(net "XM_ADDR_14")
	)
	(segment
		(start 136.3853 -47.8155)
		(end 136.2583 -47.9425)
		(width 0.127)
		(layer "In5.Cu")
		(net "XM_ADDR_14")
	)
	(segment
		(start 132.618734 -49.780444)
		(end 132.618734 -50.0507)
		(width 0.127)
		(layer "In5.Cu")
		(net "XM_ADDR_14")
	)
	(segment
		(start 137.795 -48.033686)
		(end 137.668 -48.160686)
		(width 0.127)
		(layer "In5.Cu")
		(net "XM_ADDR_14")
	)
	(segment
		(start 136.660128 -47.8155)
		(end 136.3853 -47.8155)
		(width 0.127)
		(layer "In5.Cu")
		(net "XM_ADDR_14")
	)
	(segment
		(start 124.956316 -51.375818)
		(end 124.776738 -51.555396)
		(width 0.127)
		(layer "In5.Cu")
		(net "XM_ADDR_14")
	)
	(segment
		(start 127.605536 -51.205638)
		(end 127.605536 -50.589942)
		(width 0.127)
		(layer "In5.Cu")
		(net "XM_ADDR_14")
	)
	(segment
		(start 136.787128 -47.9425)
		(end 136.660128 -47.8155)
		(width 0.127)
		(layer "In5.Cu")
		(net "XM_ADDR_14")
	)
	(segment
		(start 131.161536 -51.205638)
		(end 131.034536 -51.332638)
		(width 0.127)
		(layer "In5.Cu")
		(net "XM_ADDR_14")
	)
	(segment
		(start 135.7503 -48.0441)
		(end 135.7503 -47.9425)
		(width 0.127)
		(layer "In5.Cu")
		(net "XM_ADDR_14")
	)
	(segment
		(start 127.605536 -50.589942)
		(end 127.478536 -50.462942)
		(width 0.127)
		(layer "In5.Cu")
		(net "XM_ADDR_14")
	)
	(segment
		(start 130.653536 -50.589942)
		(end 130.526536 -50.462942)
		(width 0.127)
		(layer "In5.Cu")
		(net "XM_ADDR_14")
	)
	(segment
		(start 116.8527 -52.959)
		(end 116.459 -53.3527)
		(width 0.127)
		(layer "In5.Cu")
		(net "XM_ADDR_14")
	)
	(segment
		(start 123.231148 -52.959)
		(end 117.915182 -52.959)
		(width 0.127)
		(layer "In5.Cu")
		(net "XM_ADDR_14")
	)
	(segment
		(start 126.589536 -50.589942)
		(end 126.462536 -50.462942)
		(width 0.127)
		(layer "In5.Cu")
		(net "XM_ADDR_14")
	)
	(segment
		(start 123.358148 -52.610766)
		(end 123.358148 -52.832)
		(width 0.127)
		(layer "In5.Cu")
		(net "XM_ADDR_14")
	)
	(segment
		(start 125.700536 -51.332638)
		(end 125.573536 -51.205638)
		(width 0.127)
		(layer "In5.Cu")
		(net "XM_ADDR_14")
	)
	(segment
		(start 117.726968 -52.770786)
		(end 117.366796 -52.770786)
		(width 0.127)
		(layer "In5.Cu")
		(net "XM_ADDR_14")
	)
	(segment
		(start 123.450858 -52.02682)
		(end 123.210828 -52.26685)
		(width 0.127)
		(layer "In5.Cu")
		(net "XM_ADDR_14")
	)
	(segment
		(start 129.129536 -51.205638)
		(end 129.002536 -51.332638)
		(width 0.127)
		(layer "In5.Cu")
		(net "XM_ADDR_14")
	)
	(segment
		(start 126.970536 -51.332638)
		(end 126.716536 -51.332638)
		(width 0.127)
		(layer "In5.Cu")
		(net "XM_ADDR_14")
	)
	(segment
		(start 136.787128 -48.033686)
		(end 136.787128 -47.9425)
		(width 0.127)
		(layer "In5.Cu")
		(net "XM_ADDR_14")
	)
	(segment
		(start 130.145536 -51.205638)
		(end 130.018536 -51.332638)
		(width 0.127)
		(layer "In5.Cu")
		(net "XM_ADDR_14")
	)
	(segment
		(start 128.113536 -50.589942)
		(end 128.113536 -51.205638)
		(width 0.127)
		(layer "In5.Cu")
		(net "XM_ADDR_14")
	)
	(segment
		(start 125.345698 -50.121058)
		(end 124.70892 -50.757836)
		(width 0.127)
		(layer "In5.Cu")
		(net "XM_ADDR_14")
	)
	(segment
		(start 137.668 -48.160686)
		(end 136.914128 -48.160686)
		(width 0.127)
		(layer "In5.Cu")
		(net "XM_ADDR_14")
	)
	(segment
		(start 127.478536 -50.462942)
		(end 127.224536 -50.462942)
		(width 0.127)
		(layer "In5.Cu")
		(net "XM_ADDR_14")
	)
	(segment
		(start 128.240536 -50.462942)
		(end 128.113536 -50.589942)
		(width 0.127)
		(layer "In5.Cu")
		(net "XM_ADDR_14")
	)
	(segment
		(start 135.8773 -48.1711)
		(end 135.7503 -48.0441)
		(width 0.127)
		(layer "In5.Cu")
		(net "XM_ADDR_14")
	)
	(segment
		(start 132.70865 -49.690528)
		(end 132.618734 -49.780444)
		(width 0.127)
		(layer "In5.Cu")
		(net "XM_ADDR_14")
	)
	(segment
		(start 129.637536 -51.205638)
		(end 129.637536 -50.589942)
		(width 0.127)
		(layer "In5.Cu")
		(net "XM_ADDR_14")
	)
	(segment
		(start 125.6538 -50.248058)
		(end 125.5268 -50.121058)
		(width 0.127)
		(layer "In5.Cu")
		(net "XM_ADDR_14")
	)
	(segment
		(start 126.081536 -50.589942)
		(end 126.081536 -51.205638)
		(width 0.127)
		(layer "In5.Cu")
		(net "XM_ADDR_14")
	)
	(segment
		(start 124.169678 -51.308)
		(end 123.9901 -51.487578)
		(width 0.127)
		(layer "In5.Cu")
		(net "XM_ADDR_14")
	)
	(segment
		(start 133.316472 -49.690528)
		(end 132.70865 -49.690528)
		(width 0.127)
		(layer "In5.Cu")
		(net "XM_ADDR_14")
	)
	(segment
		(start 130.145536 -50.589942)
		(end 130.145536 -51.205638)
		(width 0.127)
		(layer "In5.Cu")
		(net "XM_ADDR_14")
	)
	(segment
		(start 124.956316 -51.195986)
		(end 124.956316 -51.375818)
		(width 0.127)
		(layer "In5.Cu")
		(net "XM_ADDR_14")
	)
	(segment
		(start 131.034536 -51.332638)
		(end 130.780536 -51.332638)
		(width 0.127)
		(layer "In5.Cu")
		(net "XM_ADDR_14")
	)
	(segment
		(start 125.573536 -51.205638)
		(end 125.573536 -50.574702)
		(width 0.127)
		(layer "In5.Cu")
		(net "XM_ADDR_14")
	)
	(segment
		(start 136.2583 -47.9425)
		(end 136.2583 -48.0441)
		(width 0.127)
		(layer "In5.Cu")
		(net "XM_ADDR_14")
	)
	(segment
		(start 132.618734 -50.0507)
		(end 132.70865 -50.140616)
		(width 0.127)
		(layer "In5.Cu")
		(net "XM_ADDR_14")
	)
	(segment
		(start 117.915182 -52.959)
		(end 117.726968 -52.770786)
		(width 0.127)
		(layer "In5.Cu")
		(net "XM_ADDR_14")
	)
	(segment
		(start 126.208536 -50.462942)
		(end 126.081536 -50.589942)
		(width 0.127)
		(layer "In5.Cu")
		(net "XM_ADDR_14")
	)
	(segment
		(start 123.210828 -52.26685)
		(end 123.210828 -52.463446)
		(width 0.127)
		(layer "In5.Cu")
		(net "XM_ADDR_14")
	)
	(segment
		(start 129.256536 -50.462942)
		(end 129.129536 -50.589942)
		(width 0.127)
		(layer "In5.Cu")
		(net "XM_ADDR_14")
	)
	(segment
		(start 131.288536 -50.462942)
		(end 131.161536 -50.589942)
		(width 0.127)
		(layer "In5.Cu")
		(net "XM_ADDR_14")
	)
	(segment
		(start 128.621536 -51.205638)
		(end 128.621536 -50.589942)
		(width 0.127)
		(layer "In5.Cu")
		(net "XM_ADDR_14")
	)
	(segment
		(start 125.573536 -50.574702)
		(end 125.6538 -50.494438)
		(width 0.127)
		(layer "In5.Cu")
		(net "XM_ADDR_14")
	)
	(segment
		(start 124.237496 -51.914806)
		(end 124.237496 -52.094638)
		(width 0.127)
		(layer "In5.Cu")
		(net "XM_ADDR_14")
	)
	(segment
		(start 135.6233 -47.8155)
		(end 135.1915 -47.8155)
		(width 0.127)
		(layer "In5.Cu")
		(net "XM_ADDR_14")
	)
	(segment
		(start 129.510536 -50.462942)
		(end 129.256536 -50.462942)
		(width 0.127)
		(layer "In5.Cu")
		(net "XM_ADDR_14")
	)
	(segment
		(start 124.70892 -50.94859)
		(end 124.956316 -51.195986)
		(width 0.127)
		(layer "In5.Cu")
		(net "XM_ADDR_14")
	)
	(segment
		(start 130.780536 -51.332638)
		(end 130.653536 -51.205638)
		(width 0.127)
		(layer "In5.Cu")
		(net "XM_ADDR_14")
	)
	(segment
		(start 129.129536 -50.589942)
		(end 129.129536 -51.205638)
		(width 0.127)
		(layer "In5.Cu")
		(net "XM_ADDR_14")
	)
	(segment
		(start 128.748536 -51.332638)
		(end 128.621536 -51.205638)
		(width 0.127)
		(layer "In5.Cu")
		(net "XM_ADDR_14")
	)
	(segment
		(start 129.637536 -50.589942)
		(end 129.510536 -50.462942)
		(width 0.127)
		(layer "In5.Cu")
		(net "XM_ADDR_14")
	)
	(segment
		(start 128.621536 -50.589942)
		(end 128.494536 -50.462942)
		(width 0.127)
		(layer "In5.Cu")
		(net "XM_ADDR_14")
	)
	(segment
		(start 116.459 -53.3527)
		(end 114.955066 -53.3527)
		(width 0.127)
		(layer "In5.Cu")
		(net "XM_ADDR_14")
	)
	(segment
		(start 123.358148 -52.832)
		(end 123.231148 -52.959)
		(width 0.127)
		(layer "In5.Cu")
		(net "XM_ADDR_14")
	)
	(segment
		(start 126.462536 -50.462942)
		(end 126.208536 -50.462942)
		(width 0.127)
		(layer "In5.Cu")
		(net "XM_ADDR_14")
	)
	(segment
		(start 123.63069 -52.02682)
		(end 123.450858 -52.02682)
		(width 0.127)
		(layer "In5.Cu")
		(net "XM_ADDR_14")
	)
	(segment
		(start 127.097536 -50.589942)
		(end 127.097536 -51.205638)
		(width 0.127)
		(layer "In5.Cu")
		(net "XM_ADDR_14")
	)
	(segment
		(start 124.776738 -51.555396)
		(end 124.596906 -51.555396)
		(width 0.127)
		(layer "In5.Cu")
		(net "XM_ADDR_14")
	)
	(segment
		(start 114.955066 -53.3527)
		(end 114.907822 -53.399944)
		(width 0.127)
		(layer "In5.Cu")
		(net "XM_ADDR_14")
	)
	(segment
		(start 123.9901 -51.487578)
		(end 123.9901 -51.66741)
		(width 0.127)
		(layer "In5.Cu")
		(net "XM_ADDR_14")
	)
	(segment
		(start 130.018536 -51.332638)
		(end 129.764536 -51.332638)
		(width 0.127)
		(layer "In5.Cu")
		(net "XM_ADDR_14")
	)
	(segment
		(start 135.7503 -47.9425)
		(end 135.6233 -47.8155)
		(width 0.127)
		(layer "In5.Cu")
		(net "XM_ADDR_14")
	)
	(segment
		(start 129.764536 -51.332638)
		(end 129.637536 -51.205638)
		(width 0.127)
		(layer "In5.Cu")
		(net "XM_ADDR_14")
	)
	(segment
		(start 136.1313 -48.1711)
		(end 135.8773 -48.1711)
		(width 0.127)
		(layer "In5.Cu")
		(net "XM_ADDR_14")
	)
	(segment
		(start 127.224536 -50.462942)
		(end 127.097536 -50.589942)
		(width 0.127)
		(layer "In5.Cu")
		(net "XM_ADDR_14")
	)
	(segment
		(start 124.596906 -51.555396)
		(end 124.34951 -51.308)
		(width 0.127)
		(layer "In5.Cu")
		(net "XM_ADDR_14")
	)
	(segment
		(start 126.716536 -51.332638)
		(end 126.589536 -51.205638)
		(width 0.127)
		(layer "In5.Cu")
		(net "XM_ADDR_14")
	)
	(segment
		(start 123.878086 -52.274216)
		(end 123.63069 -52.02682)
		(width 0.127)
		(layer "In5.Cu")
		(net "XM_ADDR_14")
	)
	(segment
		(start 130.526536 -50.462942)
		(end 130.272536 -50.462942)
		(width 0.127)
		(layer "In5.Cu")
		(net "XM_ADDR_14")
	)
	(segment
		(start 129.002536 -51.332638)
		(end 128.748536 -51.332638)
		(width 0.127)
		(layer "In5.Cu")
		(net "XM_ADDR_14")
	)
	(segment
		(start 135.1915 -47.8155)
		(end 133.316472 -49.690528)
		(width 0.127)
		(layer "In5.Cu")
		(net "XM_ADDR_14")
	)
	(segment
		(start 124.057918 -52.274216)
		(end 123.878086 -52.274216)
		(width 0.127)
		(layer "In5.Cu")
		(net "XM_ADDR_14")
	)
	(segment
		(start 127.732536 -51.332638)
		(end 127.605536 -51.205638)
		(width 0.127)
		(layer "In5.Cu")
		(net "XM_ADDR_14")
	)
	(segment
		(start 117.178582 -52.959)
		(end 116.8527 -52.959)
		(width 0.127)
		(layer "In5.Cu")
		(net "XM_ADDR_14")
	)
	(segment
		(start 124.237496 -52.094638)
		(end 124.057918 -52.274216)
		(width 0.127)
		(layer "In5.Cu")
		(net "XM_ADDR_14")
	)
	(segment
		(start 126.081536 -51.205638)
		(end 125.954536 -51.332638)
		(width 0.127)
		(layer "In5.Cu")
		(net "XM_ADDR_14")
	)
	(segment
		(start 125.5268 -50.121058)
		(end 125.345698 -50.121058)
		(width 0.127)
		(layer "In5.Cu")
		(net "XM_ADDR_14")
	)
	(segment
		(start 124.34951 -51.308)
		(end 124.169678 -51.308)
		(width 0.127)
		(layer "In5.Cu")
		(net "XM_ADDR_14")
	)
	(segment
		(start 131.237482 -80.461358)
		(end 131.243832 -80.461358)
		(width 0.1016)
		(layer "F.Cu")
		(net "3008_SAS_RX_N0")
	)
	(segment
		(start 131.345432 -80.359758)
		(end 131.345432 -80.01)
		(width 0.1016)
		(layer "F.Cu")
		(net "3008_SAS_RX_N0")
	)
	(segment
		(start 131.135882 -80.867758)
		(end 131.135882 -80.562958)
		(width 0.1016)
		(layer "F.Cu")
		(net "3008_SAS_RX_N0")
	)
	(segment
		(start 93.950028 -34.99993)
		(end 94.349824 -34.600134)
		(width 0.1016)
		(layer "F.Cu")
		(net "3008_SAS_RX_N0")
	)
	(segment
		(start 131.345432 -80.01)
		(end 131.135882 -79.80045)
		(width 0.1016)
		(layer "F.Cu")
		(net "3008_SAS_RX_N0")
	)
	(via
		(at 131.02844 -79.756)
		(size 0.5588)
		(drill 0.3048)
		(layers "F.Cu" "B.Cu")
		(net "3008_SAS_RX_N0")
	)
	(via
		(at 94.349824 -34.600134)
		(size 0.508)
		(drill 0.254)
		(layers "F.Cu" "B.Cu")
		(net "3008_SAS_RX_N0")
	)
	(arc
		(start 131.135882 -79.80045)
		(mid 131.086573 -79.767566)
		(end 131.02844 -79.756)
		(width 0.1016)
		(layer "F.Cu")
		(net "3008_SAS_RX_N0")
	)
	(arc
		(start 131.135882 -80.562958)
		(mid 131.16564 -80.491116)
		(end 131.237482 -80.461358)
		(width 0.1016)
		(layer "F.Cu")
		(net "3008_SAS_RX_N0")
	)
	(arc
		(start 131.243832 -80.461358)
		(mid 131.315674 -80.4316)
		(end 131.345432 -80.359758)
		(width 0.1016)
		(layer "F.Cu")
		(net "3008_SAS_RX_N0")
	)
	(segment
		(start 105.93832 -68.940426)
		(end 109.748574 -72.75068)
		(width 0.1016)
		(layer "In5.Cu")
		(net "3008_SAS_RX_N0")
	)
	(segment
		(start 122.73534 -74.7522)
		(end 126.557278 -74.7522)
		(width 0.1016)
		(layer "In5.Cu")
		(net "3008_SAS_RX_N0")
	)
	(segment
		(start 88.942926 -34.755328)
		(end 83.166204 -40.53205)
		(width 0.1016)
		(layer "In5.Cu")
		(net "3008_SAS_RX_N0")
	)
	(segment
		(start 97.45345 -68.2752)
		(end 104.394 -68.2752)
		(width 0.1016)
		(layer "In5.Cu")
		(net "3008_SAS_RX_N0")
	)
	(segment
		(start 92.964 -34.29)
		(end 92.782898 -34.471102)
		(width 0.1016)
		(layer "In5.Cu")
		(net "3008_SAS_RX_N0")
	)
	(segment
		(start 105.894886 -68.896738)
		(end 105.93832 -68.940426)
		(width 0.1016)
		(layer "In5.Cu")
		(net "3008_SAS_RX_N0")
	)
	(segment
		(start 83.01736 -40.89146)
		(end 83.01736 -53.695854)
		(width 0.1016)
		(layer "In5.Cu")
		(net "3008_SAS_RX_N0")
	)
	(segment
		(start 131.250436 -79.534004)
		(end 131.02844 -79.756)
		(width 0.1016)
		(layer "In5.Cu")
		(net "3008_SAS_RX_N0")
	)
	(segment
		(start 120.255538 -73.392792)
		(end 120.823228 -73.959974)
		(width 0.1016)
		(layer "In5.Cu")
		(net "3008_SAS_RX_N0")
	)
	(segment
		(start 92.973652 -34.280094)
		(end 92.964 -34.29)
		(width 0.1016)
		(layer "In5.Cu")
		(net "3008_SAS_RX_N0")
	)
	(segment
		(start 92.456 -34.606484)
		(end 89.302336 -34.606484)
		(width 0.1016)
		(layer "In5.Cu")
		(net "3008_SAS_RX_N0")
	)
	(segment
		(start 94.349824 -34.600134)
		(end 94.179898 -34.430208)
		(width 0.1016)
		(layer "In5.Cu")
		(net "3008_SAS_RX_N0")
	)
	(segment
		(start 110.717584 -73.152)
		(end 119.67464 -73.152)
		(width 0.1016)
		(layer "In5.Cu")
		(net "3008_SAS_RX_N0")
	)
	(segment
		(start 83.719162 -55.390542)
		(end 96.00311 -67.67449)
		(width 0.1016)
		(layer "In5.Cu")
		(net "3008_SAS_RX_N0")
	)
	(segment
		(start 93.6244 -34.200084)
		(end 93.1672 -34.200084)
		(width 0.0889)
		(layer "In5.Cu")
		(net "3008_SAS_RX_N0")
	)
	(segment
		(start 128.16332 -75.41768)
		(end 130.926332 -78.180692)
		(width 0.1016)
		(layer "In5.Cu")
		(net "3008_SAS_RX_N0")
	)
	(arc
		(start 126.557278 -74.7522)
		(mid 127.426484 -74.925207)
		(end 128.16332 -75.41768)
		(width 0.1016)
		(layer "In5.Cu")
		(net "3008_SAS_RX_N0")
	)
	(arc
		(start 92.782898 -34.471102)
		(mid 92.728141 -34.517782)
		(end 92.66682 -34.55543)
		(width 0.1016)
		(layer "In5.Cu")
		(net "3008_SAS_RX_N0")
	)
	(arc
		(start 92.66682 -34.55543)
		(mid 92.564444 -34.593474)
		(end 92.456 -34.606484)
		(width 0.1016)
		(layer "In5.Cu")
		(net "3008_SAS_RX_N0")
	)
	(arc
		(start 120.823228 -73.959974)
		(mid 121.700497 -74.54624)
		(end 122.73534 -74.7522)
		(width 0.1016)
		(layer "In5.Cu")
		(net "3008_SAS_RX_N0")
	)
	(arc
		(start 104.394 -68.2752)
		(mid 105.20627 -68.436677)
		(end 105.894886 -68.896738)
		(width 0.1016)
		(layer "In5.Cu")
		(net "3008_SAS_RX_N0")
	)
	(arc
		(start 130.926332 -78.180692)
		(mid 131.253768 -78.670451)
		(end 131.3688 -79.248254)
		(width 0.1016)
		(layer "In5.Cu")
		(net "3008_SAS_RX_N0")
	)
	(arc
		(start 83.166204 -40.53205)
		(mid 83.056022 -40.696949)
		(end 83.01736 -40.89146)
		(width 0.1016)
		(layer "In5.Cu")
		(net "3008_SAS_RX_N0")
	)
	(arc
		(start 119.67464 -73.152)
		(mid 119.989033 -73.21463)
		(end 120.255538 -73.392792)
		(width 0.1016)
		(layer "In5.Cu")
		(net "3008_SAS_RX_N0")
	)
	(arc
		(start 93.1672 -34.200084)
		(mid 93.06246 -34.220824)
		(end 92.973652 -34.280094)
		(width 0.1016)
		(layer "In5.Cu")
		(net "3008_SAS_RX_N0")
	)
	(arc
		(start 96.00311 -67.67449)
		(mid 96.668545 -68.119086)
		(end 97.45345 -68.2752)
		(width 0.1016)
		(layer "In5.Cu")
		(net "3008_SAS_RX_N0")
	)
	(arc
		(start 131.3688 -79.248254)
		(mid 131.338039 -79.402902)
		(end 131.250436 -79.534004)
		(width 0.1016)
		(layer "In5.Cu")
		(net "3008_SAS_RX_N0")
	)
	(arc
		(start 83.01736 -53.695854)
		(mid 83.199737 -54.612994)
		(end 83.719162 -55.390542)
		(width 0.1016)
		(layer "In5.Cu")
		(net "3008_SAS_RX_N0")
	)
	(arc
		(start 89.302336 -34.606484)
		(mid 89.107836 -34.645173)
		(end 88.942926 -34.755328)
		(width 0.1016)
		(layer "In5.Cu")
		(net "3008_SAS_RX_N0")
	)
	(arc
		(start 109.748574 -72.75068)
		(mid 110.193173 -73.047718)
		(end 110.717584 -73.152)
		(width 0.1016)
		(layer "In5.Cu")
		(net "3008_SAS_RX_N0")
	)
	(arc
		(start 94.179898 -34.430208)
		(mid 93.925033 -34.259913)
		(end 93.6244 -34.200084)
		(width 0.1016)
		(layer "In5.Cu")
		(net "3008_SAS_RX_N0")
	)
	(segment
		(start 164.592 -116.078)
		(end 163.957 -116.713)
		(width 0.254)
		(layer "F.Cu")
		(net "P0V9_E_SW_R")
	)
	(segment
		(start 164.6555 -116.078)
		(end 164.592 -116.078)
		(width 0.254)
		(layer "F.Cu")
		(net "P0V9_E_SW_R")
	)
	(via
		(at 170.413426 -103.3145)
		(size 0.7112)
		(drill 0.3556)
		(layers "F.Cu" "B.Cu")
		(net "P0V9_E_SW_R")
	)
	(via
		(at 164.465 -108.077)
		(size 0.5588)
		(drill 0.3048)
		(layers "F.Cu" "B.Cu")
		(net "P0V9_E_SW_R")
	)
	(via
		(at 163.957 -116.713)
		(size 0.5588)
		(drill 0.3048)
		(layers "F.Cu" "B.Cu")
		(net "P0V9_E_SW_R")
	)
	(segment
		(start 169.2275 -103.3145)
		(end 170.413426 -103.3145)
		(width 0.254)
		(layer "B.Cu")
		(net "P0V9_E_SW_R")
	)
	(segment
		(start 164.465 -108.077)
		(end 169.2275 -103.3145)
		(width 0.254)
		(layer "B.Cu")
		(net "P0V9_E_SW_R")
	)
	(segment
		(start 172.339 -103.3145)
		(end 170.413426 -103.3145)
		(width 0.254)
		(layer "B.Cu")
		(net "P0V9_E_SW_R")
	)
	(segment
		(start 172.339 -102.2223)
		(end 172.339 -103.3145)
		(width 0.254)
		(layer "B.Cu")
		(net "P0V9_E_SW_R")
	)
	(segment
		(start 172.3136 -102.1969)
		(end 172.339 -102.2223)
		(width 0.254)
		(layer "B.Cu")
		(net "P0V9_E_SW_R")
	)
	(segment
		(start 163.957 -111.379)
		(end 163.957 -116.713)
		(width 0.254)
		(layer "In5.Cu")
		(net "P0V9_E_SW_R")
	)
	(segment
		(start 165.1 -108.712)
		(end 165.1 -110.236)
		(width 0.254)
		(layer "In5.Cu")
		(net "P0V9_E_SW_R")
	)
	(segment
		(start 164.465 -108.077)
		(end 165.1 -108.712)
		(width 0.254)
		(layer "In5.Cu")
		(net "P0V9_E_SW_R")
	)
	(segment
		(start 165.1 -110.236)
		(end 163.957 -111.379)
		(width 0.254)
		(layer "In5.Cu")
		(net "P0V9_E_SW_R")
	)
	(segment
		(start 104.349804 -90.349832)
		(end 103.849678 -89.849706)
		(width 0.1143)
		(layer "F.Cu")
		(net "XM_DATA11")
	)
	(segment
		(start 75.786742 -132.892292)
		(end 73.121774 -132.892292)
		(width 0.1143)
		(layer "F.Cu")
		(net "XM_DATA11")
	)
	(segment
		(start 73.121774 -132.892292)
		(end 72.78497 -133.229096)
		(width 0.1143)
		(layer "F.Cu")
		(net "XM_DATA11")
	)
	(via
		(at 103.849678 -89.849706)
		(size 0.508)
		(drill 0.254)
		(layers "F.Cu" "B.Cu")
		(net "XM_DATA11")
	)
	(via
		(at 82.5754 -92.456)
		(size 0.7112)
		(drill 0.3556)
		(layers "F.Cu" "B.Cu")
		(net "XM_DATA11")
	)
	(via
		(at 72.78497 -133.229096)
		(size 0.5588)
		(drill 0.3048)
		(layers "F.Cu" "B.Cu")
		(net "XM_DATA11")
	)
	(segment
		(start 81.821274 -93.506036)
		(end 81.821274 -93.66758)
		(width 0.1143)
		(layer "B.Cu")
		(net "XM_DATA11")
	)
	(segment
		(start 81.060036 -92.583254)
		(end 81.060036 -92.744798)
		(width 0.1143)
		(layer "B.Cu")
		(net "XM_DATA11")
	)
	(segment
		(start 74.113644 -101.358446)
		(end 73.9521 -101.358446)
		(width 0.1143)
		(layer "B.Cu")
		(net "XM_DATA11")
	)
	(segment
		(start 81.659476 -93.829378)
		(end 81.497932 -93.829378)
		(width 0.1143)
		(layer "B.Cu")
		(net "XM_DATA11")
	)
	(segment
		(start 81.821274 -93.66758)
		(end 81.659476 -93.829378)
		(width 0.1143)
		(layer "B.Cu")
		(net "XM_DATA11")
	)
	(segment
		(start 84.963 -92.24772)
		(end 84.75472 -92.456)
		(width 0.1143)
		(layer "B.Cu")
		(net "XM_DATA11")
	)
	(segment
		(start 79.928466 -93.714824)
		(end 79.766668 -93.876622)
		(width 0.1143)
		(layer "B.Cu")
		(net "XM_DATA11")
	)
	(segment
		(start 72.391016 -101.252274)
		(end 72.229218 -101.414072)
		(width 0.1143)
		(layer "B.Cu")
		(net "XM_DATA11")
	)
	(segment
		(start 72.820276 -102.651814)
		(end 72.658732 -102.651814)
		(width 0.1143)
		(layer "B.Cu")
		(net "XM_DATA11")
	)
	(segment
		(start 80.366108 -95.123254)
		(end 79.459582 -96.02978)
		(width 0.1143)
		(layer "B.Cu")
		(net "XM_DATA11")
	)
	(segment
		(start 72.229218 -101.575616)
		(end 72.982074 -102.328472)
		(width 0.1143)
		(layer "B.Cu")
		(net "XM_DATA11")
	)
	(segment
		(start 73.199244 -100.60559)
		(end 73.0377 -100.60559)
		(width 0.1143)
		(layer "B.Cu")
		(net "XM_DATA11")
	)
	(segment
		(start 81.060036 -92.744798)
		(end 81.821274 -93.506036)
		(width 0.1143)
		(layer "B.Cu")
		(net "XM_DATA11")
	)
	(segment
		(start 102.532434 -91.16695)
		(end 101.167438 -91.16695)
		(width 0.1143)
		(layer "B.Cu")
		(net "XM_DATA11")
	)
	(segment
		(start 79.766668 -93.876622)
		(end 79.766668 -94.038166)
		(width 0.1143)
		(layer "B.Cu")
		(net "XM_DATA11")
	)
	(segment
		(start 74.275442 -101.196648)
		(end 74.113644 -101.358446)
		(width 0.1143)
		(layer "B.Cu")
		(net "XM_DATA11")
	)
	(segment
		(start 99.502976 -91.8337)
		(end 98.93808 -91.268804)
		(width 0.1143)
		(layer "B.Cu")
		(net "XM_DATA11")
	)
	(segment
		(start 81.497932 -93.829378)
		(end 80.736694 -93.06814)
		(width 0.1143)
		(layer "B.Cu")
		(net "XM_DATA11")
	)
	(segment
		(start 81.18729 -92.456)
		(end 81.060036 -92.583254)
		(width 0.1143)
		(layer "B.Cu")
		(net "XM_DATA11")
	)
	(segment
		(start 73.628758 -101.681788)
		(end 73.628758 -101.843332)
		(width 0.1143)
		(layer "B.Cu")
		(net "XM_DATA11")
	)
	(segment
		(start 72.229218 -101.414072)
		(end 72.229218 -101.575616)
		(width 0.1143)
		(layer "B.Cu")
		(net "XM_DATA11")
	)
	(segment
		(start 81.17459 -94.15272)
		(end 81.17459 -94.314264)
		(width 0.1143)
		(layer "B.Cu")
		(net "XM_DATA11")
	)
	(segment
		(start 79.459582 -96.02978)
		(end 77.61351 -96.02978)
		(width 0.1143)
		(layer "B.Cu")
		(net "XM_DATA11")
	)
	(segment
		(start 80.851248 -94.476062)
		(end 80.09001 -93.714824)
		(width 0.1143)
		(layer "B.Cu")
		(net "XM_DATA11")
	)
	(segment
		(start 72.55256 -101.252274)
		(end 72.391016 -101.252274)
		(width 0.1143)
		(layer "B.Cu")
		(net "XM_DATA11")
	)
	(segment
		(start 87.666322 -91.44)
		(end 86.858602 -92.24772)
		(width 0.1143)
		(layer "B.Cu")
		(net "XM_DATA11")
	)
	(segment
		(start 80.413352 -93.391482)
		(end 81.17459 -94.15272)
		(width 0.1143)
		(layer "B.Cu")
		(net "XM_DATA11")
	)
	(segment
		(start 73.522586 -100.282248)
		(end 74.275442 -101.035104)
		(width 0.1143)
		(layer "B.Cu")
		(net "XM_DATA11")
	)
	(segment
		(start 84.75472 -92.456)
		(end 82.5754 -92.456)
		(width 0.1143)
		(layer "B.Cu")
		(net "XM_DATA11")
	)
	(segment
		(start 73.522586 -100.120704)
		(end 73.522586 -100.282248)
		(width 0.1143)
		(layer "B.Cu")
		(net "XM_DATA11")
	)
	(segment
		(start 77.61351 -96.02978)
		(end 73.522586 -100.120704)
		(width 0.1143)
		(layer "B.Cu")
		(net "XM_DATA11")
	)
	(segment
		(start 71.48322 -128.659382)
		(end 72.897492 -130.073654)
		(width 0.1143)
		(layer "B.Cu")
		(net "XM_DATA11")
	)
	(segment
		(start 88.053418 -91.053158)
		(end 87.666576 -91.44)
		(width 0.1143)
		(layer "B.Cu")
		(net "XM_DATA11")
	)
	(segment
		(start 87.666576 -91.44)
		(end 87.666322 -91.44)
		(width 0.1143)
		(layer "B.Cu")
		(net "XM_DATA11")
	)
	(segment
		(start 98.722688 -91.053158)
		(end 88.053418 -91.053158)
		(width 0.1143)
		(layer "B.Cu")
		(net "XM_DATA11")
	)
	(segment
		(start 73.305416 -102.00513)
		(end 72.55256 -101.252274)
		(width 0.1143)
		(layer "B.Cu")
		(net "XM_DATA11")
	)
	(segment
		(start 71.744332 -101.898958)
		(end 71.48322 -102.16007)
		(width 0.1143)
		(layer "B.Cu")
		(net "XM_DATA11")
	)
	(segment
		(start 80.527906 -94.960948)
		(end 80.366108 -95.122746)
		(width 0.1143)
		(layer "B.Cu")
		(net "XM_DATA11")
	)
	(segment
		(start 71.48322 -102.16007)
		(end 71.48322 -128.659382)
		(width 0.1143)
		(layer "B.Cu")
		(net "XM_DATA11")
	)
	(segment
		(start 98.93808 -91.26855)
		(end 98.722688 -91.053158)
		(width 0.1143)
		(layer "B.Cu")
		(net "XM_DATA11")
	)
	(segment
		(start 72.658732 -102.651814)
		(end 71.905876 -101.898958)
		(width 0.1143)
		(layer "B.Cu")
		(net "XM_DATA11")
	)
	(segment
		(start 72.897492 -130.073654)
		(end 72.897492 -130.074416)
		(width 0.1143)
		(layer "B.Cu")
		(net "XM_DATA11")
	)
	(segment
		(start 100.500688 -91.8337)
		(end 99.502976 -91.8337)
		(width 0.1143)
		(layer "B.Cu")
		(net "XM_DATA11")
	)
	(segment
		(start 103.849678 -89.849706)
		(end 102.532434 -91.16695)
		(width 0.1143)
		(layer "B.Cu")
		(net "XM_DATA11")
	)
	(segment
		(start 72.875902 -100.767388)
		(end 72.875902 -100.928932)
		(width 0.1143)
		(layer "B.Cu")
		(net "XM_DATA11")
	)
	(segment
		(start 72.982074 -102.490016)
		(end 72.820276 -102.651814)
		(width 0.1143)
		(layer "B.Cu")
		(net "XM_DATA11")
	)
	(segment
		(start 73.282302 -130.459226)
		(end 73.282302 -132.731764)
		(width 0.1143)
		(layer "B.Cu")
		(net "XM_DATA11")
	)
	(segment
		(start 74.275442 -101.035104)
		(end 74.275442 -101.196648)
		(width 0.1143)
		(layer "B.Cu")
		(net "XM_DATA11")
	)
	(segment
		(start 80.527906 -94.799404)
		(end 80.527906 -94.960948)
		(width 0.1143)
		(layer "B.Cu")
		(net "XM_DATA11")
	)
	(segment
		(start 80.366108 -95.122746)
		(end 80.366108 -95.123254)
		(width 0.1143)
		(layer "B.Cu")
		(net "XM_DATA11")
	)
	(segment
		(start 80.57515 -93.06814)
		(end 80.413352 -93.229938)
		(width 0.1143)
		(layer "B.Cu")
		(net "XM_DATA11")
	)
	(segment
		(start 80.09001 -93.714824)
		(end 79.928466 -93.714824)
		(width 0.1143)
		(layer "B.Cu")
		(net "XM_DATA11")
	)
	(segment
		(start 82.5754 -92.456)
		(end 81.18729 -92.456)
		(width 0.1143)
		(layer "B.Cu")
		(net "XM_DATA11")
	)
	(segment
		(start 73.0377 -100.60559)
		(end 72.875902 -100.767388)
		(width 0.1143)
		(layer "B.Cu")
		(net "XM_DATA11")
	)
	(segment
		(start 72.875902 -100.928932)
		(end 73.628758 -101.681788)
		(width 0.1143)
		(layer "B.Cu")
		(net "XM_DATA11")
	)
	(segment
		(start 80.736694 -93.06814)
		(end 80.57515 -93.06814)
		(width 0.1143)
		(layer "B.Cu")
		(net "XM_DATA11")
	)
	(segment
		(start 73.9521 -101.358446)
		(end 73.199244 -100.60559)
		(width 0.1143)
		(layer "B.Cu")
		(net "XM_DATA11")
	)
	(segment
		(start 79.766668 -94.038166)
		(end 80.527906 -94.799404)
		(width 0.1143)
		(layer "B.Cu")
		(net "XM_DATA11")
	)
	(segment
		(start 81.17459 -94.314264)
		(end 81.012792 -94.476062)
		(width 0.1143)
		(layer "B.Cu")
		(net "XM_DATA11")
	)
	(segment
		(start 72.982074 -102.328472)
		(end 72.982074 -102.490016)
		(width 0.1143)
		(layer "B.Cu")
		(net "XM_DATA11")
	)
	(segment
		(start 81.012792 -94.476062)
		(end 80.851248 -94.476062)
		(width 0.1143)
		(layer "B.Cu")
		(net "XM_DATA11")
	)
	(segment
		(start 101.167438 -91.16695)
		(end 100.500688 -91.8337)
		(width 0.1143)
		(layer "B.Cu")
		(net "XM_DATA11")
	)
	(segment
		(start 86.858602 -92.24772)
		(end 84.963 -92.24772)
		(width 0.1143)
		(layer "B.Cu")
		(net "XM_DATA11")
	)
	(segment
		(start 80.413352 -93.229938)
		(end 80.413352 -93.391482)
		(width 0.1143)
		(layer "B.Cu")
		(net "XM_DATA11")
	)
	(segment
		(start 72.897492 -130.074416)
		(end 73.282302 -130.459226)
		(width 0.1143)
		(layer "B.Cu")
		(net "XM_DATA11")
	)
	(segment
		(start 73.628758 -101.843332)
		(end 73.46696 -102.00513)
		(width 0.1143)
		(layer "B.Cu")
		(net "XM_DATA11")
	)
	(segment
		(start 73.46696 -102.00513)
		(end 73.305416 -102.00513)
		(width 0.1143)
		(layer "B.Cu")
		(net "XM_DATA11")
	)
	(segment
		(start 98.93808 -91.268804)
		(end 98.93808 -91.26855)
		(width 0.1143)
		(layer "B.Cu")
		(net "XM_DATA11")
	)
	(segment
		(start 73.282302 -132.731764)
		(end 72.78497 -133.229096)
		(width 0.1143)
		(layer "B.Cu")
		(net "XM_DATA11")
	)
	(segment
		(start 71.905876 -101.898958)
		(end 71.744332 -101.898958)
		(width 0.1143)
		(layer "B.Cu")
		(net "XM_DATA11")
	)
	(segment
		(start 109.820964 -57.101994)
		(end 109.80928 -57.113678)
		(width 0.1143)
		(layer "F.Cu")
		(net "XM_WP")
	)
	(segment
		(start 109.80928 -57.113678)
		(end 109.805978 -57.113678)
		(width 0.1143)
		(layer "F.Cu")
		(net "XM_WP")
	)
	(segment
		(start 109.949996 -56.599836)
		(end 109.949996 -56.974994)
		(width 0.1143)
		(layer "F.Cu")
		(net "XM_WP")
	)
	(segment
		(start 109.949996 -56.974994)
		(end 109.822996 -57.101994)
		(width 0.1143)
		(layer "F.Cu")
		(net "XM_WP")
	)
	(segment
		(start 109.822996 -57.101994)
		(end 109.820964 -57.101994)
		(width 0.1143)
		(layer "F.Cu")
		(net "XM_WP")
	)
	(via
		(at 109.805978 -57.113678)
		(size 0.508)
		(drill 0.254)
		(layers "F.Cu" "B.Cu")
		(net "XM_WP")
	)
	(segment
		(start 110.657386 -56.734456)
		(end 110.278164 -57.113678)
		(width 0.1143)
		(layer "B.Cu")
		(net "XM_WP")
	)
	(segment
		(start 110.278164 -57.113678)
		(end 109.805978 -57.113678)
		(width 0.1143)
		(layer "B.Cu")
		(net "XM_WP")
	)
	(segment
		(start 170.432222 -119.124222)
		(end 170.942 -119.634)
		(width 0.3048)
		(layer "F.Cu")
		(net "P0V9_E_VREG")
	)
	(segment
		(start 170.942 -119.634)
		(end 170.942 -120.504204)
		(width 0.3048)
		(layer "F.Cu")
		(net "P0V9_E_VREG")
	)
	(segment
		(start 166.1922 -124.5362)
		(end 167.291004 -124.5362)
		(width 0.508)
		(layer "F.Cu")
		(net "P0V9_E_VREG")
	)
	(segment
		(start 170.432222 -118.391178)
		(end 170.432222 -119.124222)
		(width 0.3048)
		(layer "F.Cu")
		(net "P0V9_E_VREG")
	)
	(segment
		(start 167.291004 -124.5362)
		(end 167.503348 -124.323856)
		(width 0.508)
		(layer "F.Cu")
		(net "P0V9_E_VREG")
	)
	(segment
		(start 167.503348 -124.323856)
		(end 167.503348 -122.990356)
		(width 0.508)
		(layer "F.Cu")
		(net "P0V9_E_VREG")
	)
	(segment
		(start 170.942 -120.504204)
		(end 170.94454 -120.506744)
		(width 0.3048)
		(layer "F.Cu")
		(net "P0V9_E_VREG")
	)
	(via
		(at 166.1922 -124.5362)
		(size 0.5588)
		(drill 0.3048)
		(layers "F.Cu" "B.Cu")
		(net "P0V9_E_VREG")
	)
	(via
		(at 168.49344 -122.763534)
		(size 0.7112)
		(drill 0.3556)
		(layers "F.Cu" "B.Cu")
		(net "P0V9_E_VREG")
	)
	(via
		(at 170.94454 -120.506744)
		(size 0.5588)
		(drill 0.3048)
		(layers "F.Cu" "B.Cu")
		(net "P0V9_E_VREG")
	)
	(segment
		(start 166.720774 -124.5362)
		(end 166.1922 -124.5362)
		(width 0.508)
		(layer "B.Cu")
		(net "P0V9_E_VREG")
	)
	(segment
		(start 168.68775 -122.763534)
		(end 168.49344 -122.763534)
		(width 0.508)
		(layer "B.Cu")
		(net "P0V9_E_VREG")
	)
	(segment
		(start 168.49344 -122.763534)
		(end 166.720774 -124.5362)
		(width 0.508)
		(layer "B.Cu")
		(net "P0V9_E_VREG")
	)
	(segment
		(start 170.94454 -120.506744)
		(end 168.68775 -122.763534)
		(width 0.508)
		(layer "B.Cu")
		(net "P0V9_E_VREG")
	)
	(segment
		(start 74.23277 -134.366)
		(end 74.10577 -134.366)
		(width 0.1143)
		(layer "F.Cu")
		(net "XM_DATA12")
	)
	(segment
		(start 74.258932 -134.392162)
		(end 74.23277 -134.366)
		(width 0.1143)
		(layer "F.Cu")
		(net "XM_DATA12")
	)
	(segment
		(start 75.786742 -134.392162)
		(end 74.258932 -134.392162)
		(width 0.1143)
		(layer "F.Cu")
		(net "XM_DATA12")
	)
	(segment
		(start 105.80497 -90.805)
		(end 106.3498 -91.34983)
		(width 0.1143)
		(layer "F.Cu")
		(net "XM_DATA12")
	)
	(via
		(at 74.10577 -134.366)
		(size 0.5588)
		(drill 0.3048)
		(layers "F.Cu" "B.Cu")
		(net "XM_DATA12")
	)
	(via
		(at 87.376 -93.55201)
		(size 0.7112)
		(drill 0.3556)
		(layers "F.Cu" "B.Cu")
		(net "XM_DATA12")
	)
	(via
		(at 105.80497 -90.805)
		(size 0.508)
		(drill 0.254)
		(layers "F.Cu" "B.Cu")
		(net "XM_DATA12")
	)
	(segment
		(start 72.21982 -104.311704)
		(end 82.932524 -93.599)
		(width 0.1143)
		(layer "B.Cu")
		(net "XM_DATA12")
	)
	(segment
		(start 91.754706 -91.789758)
		(end 91.983306 -91.789758)
		(width 0.1143)
		(layer "B.Cu")
		(net "XM_DATA12")
	)
	(segment
		(start 82.932524 -93.599)
		(end 87.32901 -93.599)
		(width 0.1143)
		(layer "B.Cu")
		(net "XM_DATA12")
	)
	(segment
		(start 74.53757 -133.719062)
		(end 74.53757 -132.812028)
		(width 0.1143)
		(layer "B.Cu")
		(net "XM_DATA12")
	)
	(segment
		(start 87.32901 -93.599)
		(end 87.376 -93.55201)
		(width 0.1143)
		(layer "B.Cu")
		(net "XM_DATA12")
	)
	(segment
		(start 74.133456 -132.697728)
		(end 74.019156 -132.583428)
		(width 0.1143)
		(layer "B.Cu")
		(net "XM_DATA12")
	)
	(segment
		(start 95.797878 -93.00972)
		(end 96.026478 -93.00972)
		(width 0.1143)
		(layer "B.Cu")
		(net "XM_DATA12")
	)
	(segment
		(start 91.183206 -91.904058)
		(end 91.183206 -92.89542)
		(width 0.1143)
		(layer "B.Cu")
		(net "XM_DATA12")
	)
	(segment
		(start 74.42327 -132.240528)
		(end 74.53757 -132.126228)
		(width 0.1143)
		(layer "B.Cu")
		(net "XM_DATA12")
	)
	(segment
		(start 89.925906 -91.789758)
		(end 90.154506 -91.789758)
		(width 0.1143)
		(layer "B.Cu")
		(net "XM_DATA12")
	)
	(segment
		(start 97.398078 -91.789758)
		(end 97.512378 -91.904058)
		(width 0.1143)
		(layer "B.Cu")
		(net "XM_DATA12")
	)
	(segment
		(start 91.983306 -91.789758)
		(end 92.097606 -91.904058)
		(width 0.1143)
		(layer "B.Cu")
		(net "XM_DATA12")
	)
	(segment
		(start 97.055178 -91.904058)
		(end 97.169478 -91.789758)
		(width 0.1143)
		(layer "B.Cu")
		(net "XM_DATA12")
	)
	(segment
		(start 74.53757 -132.126228)
		(end 74.53757 -131.897628)
		(width 0.1143)
		(layer "B.Cu")
		(net "XM_DATA12")
	)
	(segment
		(start 92.211906 -93.00972)
		(end 95.112078 -93.00972)
		(width 0.1143)
		(layer "B.Cu")
		(net "XM_DATA12")
	)
	(segment
		(start 89.811606 -91.904058)
		(end 89.925906 -91.789758)
		(width 0.1143)
		(layer "B.Cu")
		(net "XM_DATA12")
	)
	(segment
		(start 95.226378 -91.904058)
		(end 95.340678 -91.789758)
		(width 0.1143)
		(layer "B.Cu")
		(net "XM_DATA12")
	)
	(segment
		(start 74.133456 -131.326128)
		(end 74.42327 -131.326128)
		(width 0.1143)
		(layer "B.Cu")
		(net "XM_DATA12")
	)
	(segment
		(start 95.683578 -91.904058)
		(end 95.683578 -92.89542)
		(width 0.1143)
		(layer "B.Cu")
		(net "XM_DATA12")
	)
	(segment
		(start 74.42327 -131.326128)
		(end 74.53757 -131.211828)
		(width 0.1143)
		(layer "B.Cu")
		(net "XM_DATA12")
	)
	(segment
		(start 74.019156 -131.669028)
		(end 74.019156 -131.440428)
		(width 0.1143)
		(layer "B.Cu")
		(net "XM_DATA12")
	)
	(segment
		(start 74.53757 -131.211828)
		(end 74.53757 -130.672078)
		(width 0.1143)
		(layer "B.Cu")
		(net "XM_DATA12")
	)
	(segment
		(start 89.811606 -92.89542)
		(end 89.811606 -91.904058)
		(width 0.1143)
		(layer "B.Cu")
		(net "XM_DATA12")
	)
	(segment
		(start 74.53757 -130.672078)
		(end 73.634346 -129.768854)
		(width 0.1143)
		(layer "B.Cu")
		(net "XM_DATA12")
	)
	(segment
		(start 90.611706 -93.00972)
		(end 90.726006 -92.89542)
		(width 0.1143)
		(layer "B.Cu")
		(net "XM_DATA12")
	)
	(segment
		(start 97.512378 -92.911168)
		(end 98.31959 -93.71838)
		(width 0.1143)
		(layer "B.Cu")
		(net "XM_DATA12")
	)
	(segment
		(start 97.055178 -92.89542)
		(end 97.055178 -91.904058)
		(width 0.1143)
		(layer "B.Cu")
		(net "XM_DATA12")
	)
	(segment
		(start 90.383106 -93.00972)
		(end 90.611706 -93.00972)
		(width 0.1143)
		(layer "B.Cu")
		(net "XM_DATA12")
	)
	(segment
		(start 89.154 -93.00972)
		(end 89.697306 -93.00972)
		(width 0.1143)
		(layer "B.Cu")
		(net "XM_DATA12")
	)
	(segment
		(start 91.068906 -91.789758)
		(end 91.183206 -91.904058)
		(width 0.1143)
		(layer "B.Cu")
		(net "XM_DATA12")
	)
	(segment
		(start 91.183206 -92.89542)
		(end 91.297506 -93.00972)
		(width 0.1143)
		(layer "B.Cu")
		(net "XM_DATA12")
	)
	(segment
		(start 95.112078 -93.00972)
		(end 95.226378 -92.89542)
		(width 0.1143)
		(layer "B.Cu")
		(net "XM_DATA12")
	)
	(segment
		(start 72.21982 -128.354074)
		(end 72.21982 -104.311704)
		(width 0.1143)
		(layer "B.Cu")
		(net "XM_DATA12")
	)
	(segment
		(start 91.297506 -93.00972)
		(end 91.526106 -93.00972)
		(width 0.1143)
		(layer "B.Cu")
		(net "XM_DATA12")
	)
	(segment
		(start 92.097606 -92.89542)
		(end 92.211906 -93.00972)
		(width 0.1143)
		(layer "B.Cu")
		(net "XM_DATA12")
	)
	(segment
		(start 96.483678 -91.789758)
		(end 96.597978 -91.904058)
		(width 0.1143)
		(layer "B.Cu")
		(net "XM_DATA12")
	)
	(segment
		(start 96.026478 -93.00972)
		(end 96.140778 -92.89542)
		(width 0.1143)
		(layer "B.Cu")
		(net "XM_DATA12")
	)
	(segment
		(start 73.634346 -129.7686)
		(end 72.21982 -128.354074)
		(width 0.1143)
		(layer "B.Cu")
		(net "XM_DATA12")
	)
	(segment
		(start 96.940878 -93.00972)
		(end 97.055178 -92.89542)
		(width 0.1143)
		(layer "B.Cu")
		(net "XM_DATA12")
	)
	(segment
		(start 95.569278 -91.789758)
		(end 95.683578 -91.904058)
		(width 0.1143)
		(layer "B.Cu")
		(net "XM_DATA12")
	)
	(segment
		(start 100.80879 -93.71838)
		(end 103.0732 -91.45397)
		(width 0.1143)
		(layer "B.Cu")
		(net "XM_DATA12")
	)
	(segment
		(start 74.019156 -132.583428)
		(end 74.019156 -132.354828)
		(width 0.1143)
		(layer "B.Cu")
		(net "XM_DATA12")
	)
	(segment
		(start 97.169478 -91.789758)
		(end 97.398078 -91.789758)
		(width 0.1143)
		(layer "B.Cu")
		(net "XM_DATA12")
	)
	(segment
		(start 74.019156 -132.354828)
		(end 74.133456 -132.240528)
		(width 0.1143)
		(layer "B.Cu")
		(net "XM_DATA12")
	)
	(segment
		(start 74.133456 -131.783328)
		(end 74.019156 -131.669028)
		(width 0.1143)
		(layer "B.Cu")
		(net "XM_DATA12")
	)
	(segment
		(start 90.726006 -92.89542)
		(end 90.726006 -91.904058)
		(width 0.1143)
		(layer "B.Cu")
		(net "XM_DATA12")
	)
	(segment
		(start 90.726006 -91.904058)
		(end 90.840306 -91.789758)
		(width 0.1143)
		(layer "B.Cu")
		(net "XM_DATA12")
	)
	(segment
		(start 96.140778 -92.89542)
		(end 96.140778 -91.904058)
		(width 0.1143)
		(layer "B.Cu")
		(net "XM_DATA12")
	)
	(segment
		(start 96.712278 -93.00972)
		(end 96.940878 -93.00972)
		(width 0.1143)
		(layer "B.Cu")
		(net "XM_DATA12")
	)
	(segment
		(start 74.019156 -131.440428)
		(end 74.133456 -131.326128)
		(width 0.1143)
		(layer "B.Cu")
		(net "XM_DATA12")
	)
	(segment
		(start 90.154506 -91.789758)
		(end 90.268806 -91.904058)
		(width 0.1143)
		(layer "B.Cu")
		(net "XM_DATA12")
	)
	(segment
		(start 97.512378 -91.904058)
		(end 97.512378 -92.911168)
		(width 0.1143)
		(layer "B.Cu")
		(net "XM_DATA12")
	)
	(segment
		(start 87.376 -93.55201)
		(end 88.61171 -93.55201)
		(width 0.1143)
		(layer "B.Cu")
		(net "XM_DATA12")
	)
	(segment
		(start 91.640406 -91.904058)
		(end 91.754706 -91.789758)
		(width 0.1143)
		(layer "B.Cu")
		(net "XM_DATA12")
	)
	(segment
		(start 74.10577 -134.366)
		(end 74.10577 -134.150862)
		(width 0.1143)
		(layer "B.Cu")
		(net "XM_DATA12")
	)
	(segment
		(start 90.840306 -91.789758)
		(end 91.068906 -91.789758)
		(width 0.1143)
		(layer "B.Cu")
		(net "XM_DATA12")
	)
	(segment
		(start 90.268806 -92.89542)
		(end 90.383106 -93.00972)
		(width 0.1143)
		(layer "B.Cu")
		(net "XM_DATA12")
	)
	(segment
		(start 74.133456 -132.240528)
		(end 74.42327 -132.240528)
		(width 0.1143)
		(layer "B.Cu")
		(net "XM_DATA12")
	)
	(segment
		(start 96.255078 -91.789758)
		(end 96.483678 -91.789758)
		(width 0.1143)
		(layer "B.Cu")
		(net "XM_DATA12")
	)
	(segment
		(start 74.42327 -132.697728)
		(end 74.133456 -132.697728)
		(width 0.1143)
		(layer "B.Cu")
		(net "XM_DATA12")
	)
	(segment
		(start 74.53757 -131.897628)
		(end 74.42327 -131.783328)
		(width 0.1143)
		(layer "B.Cu")
		(net "XM_DATA12")
	)
	(segment
		(start 90.268806 -91.904058)
		(end 90.268806 -92.89542)
		(width 0.1143)
		(layer "B.Cu")
		(net "XM_DATA12")
	)
	(segment
		(start 74.10577 -134.150862)
		(end 74.53757 -133.719062)
		(width 0.1143)
		(layer "B.Cu")
		(net "XM_DATA12")
	)
	(segment
		(start 96.597978 -91.904058)
		(end 96.597978 -92.89542)
		(width 0.1143)
		(layer "B.Cu")
		(net "XM_DATA12")
	)
	(segment
		(start 95.226378 -92.89542)
		(end 95.226378 -91.904058)
		(width 0.1143)
		(layer "B.Cu")
		(net "XM_DATA12")
	)
	(segment
		(start 92.097606 -91.904058)
		(end 92.097606 -92.89542)
		(width 0.1143)
		(layer "B.Cu")
		(net "XM_DATA12")
	)
	(segment
		(start 91.526106 -93.00972)
		(end 91.640406 -92.89542)
		(width 0.1143)
		(layer "B.Cu")
		(net "XM_DATA12")
	)
	(segment
		(start 95.683578 -92.89542)
		(end 95.797878 -93.00972)
		(width 0.1143)
		(layer "B.Cu")
		(net "XM_DATA12")
	)
	(segment
		(start 103.0732 -91.45397)
		(end 103.214424 -91.313)
		(width 0.1143)
		(layer "B.Cu")
		(net "XM_DATA12")
	)
	(segment
		(start 103.214424 -91.313)
		(end 105.29697 -91.313)
		(width 0.1143)
		(layer "B.Cu")
		(net "XM_DATA12")
	)
	(segment
		(start 96.597978 -92.89542)
		(end 96.712278 -93.00972)
		(width 0.1143)
		(layer "B.Cu")
		(net "XM_DATA12")
	)
	(segment
		(start 89.697306 -93.00972)
		(end 89.811606 -92.89542)
		(width 0.1143)
		(layer "B.Cu")
		(net "XM_DATA12")
	)
	(segment
		(start 74.53757 -132.812028)
		(end 74.42327 -132.697728)
		(width 0.1143)
		(layer "B.Cu")
		(net "XM_DATA12")
	)
	(segment
		(start 98.31959 -93.71838)
		(end 100.80879 -93.71838)
		(width 0.1143)
		(layer "B.Cu")
		(net "XM_DATA12")
	)
	(segment
		(start 91.640406 -92.89542)
		(end 91.640406 -91.904058)
		(width 0.1143)
		(layer "B.Cu")
		(net "XM_DATA12")
	)
	(segment
		(start 74.42327 -131.783328)
		(end 74.133456 -131.783328)
		(width 0.1143)
		(layer "B.Cu")
		(net "XM_DATA12")
	)
	(segment
		(start 105.29697 -91.313)
		(end 105.80497 -90.805)
		(width 0.1143)
		(layer "B.Cu")
		(net "XM_DATA12")
	)
	(segment
		(start 96.140778 -91.904058)
		(end 96.255078 -91.789758)
		(width 0.1143)
		(layer "B.Cu")
		(net "XM_DATA12")
	)
	(segment
		(start 88.61171 -93.55201)
		(end 89.154 -93.00972)
		(width 0.1143)
		(layer "B.Cu")
		(net "XM_DATA12")
	)
	(segment
		(start 95.340678 -91.789758)
		(end 95.569278 -91.789758)
		(width 0.1143)
		(layer "B.Cu")
		(net "XM_DATA12")
	)
	(segment
		(start 73.634346 -129.768854)
		(end 73.634346 -129.7686)
		(width 0.1143)
		(layer "B.Cu")
		(net "XM_DATA12")
	)
	(segment
		(start 137.098786 -42.7101)
		(end 137.098786 -45.49267)
		(width 0.1143)
		(layer "F.Cu")
		(net "XM_ADDR_15")
	)
	(segment
		(start 137.098786 -45.49267)
		(end 137.087356 -45.5041)
		(width 0.1143)
		(layer "F.Cu")
		(net "XM_ADDR_15")
	)
	(segment
		(start 112.350042 -51.799998)
		(end 112.749838 -51.400202)
		(width 0.1143)
		(layer "F.Cu")
		(net "XM_ADDR_15")
	)
	(via
		(at 137.087356 -45.5041)
		(size 0.5588)
		(drill 0.3048)
		(layers "F.Cu" "B.Cu")
		(net "XM_ADDR_15")
	)
	(via
		(at 112.749838 -51.400202)
		(size 0.508)
		(drill 0.254)
		(layers "F.Cu" "B.Cu")
		(net "XM_ADDR_15")
	)
	(via
		(at 138.049 -45.466)
		(size 0.7112)
		(drill 0.3556)
		(layers "F.Cu" "B.Cu")
		(net "XM_ADDR_15")
	)
	(segment
		(start 137.125456 -45.466)
		(end 137.087356 -45.5041)
		(width 0.1143)
		(layer "B.Cu")
		(net "XM_ADDR_15")
	)
	(segment
		(start 138.049 -45.466)
		(end 137.125456 -45.466)
		(width 0.1143)
		(layer "B.Cu")
		(net "XM_ADDR_15")
	)
	(segment
		(start 131.114292 -46.5455)
		(end 131.114292 -46.1264)
		(width 0.127)
		(layer "In5.Cu")
		(net "XM_ADDR_15")
	)
	(segment
		(start 120.704356 -49.76241)
		(end 120.704356 -49.941734)
		(width 0.127)
		(layer "In5.Cu")
		(net "XM_ADDR_15")
	)
	(segment
		(start 128.955292 -45.9994)
		(end 128.701292 -45.9994)
		(width 0.127)
		(layer "In5.Cu")
		(net "XM_ADDR_15")
	)
	(segment
		(start 120.344946 -50.12182)
		(end 120.279922 -50.05705)
		(width 0.127)
		(layer "In5.Cu")
		(net "XM_ADDR_15")
	)
	(segment
		(start 115.137184 -49.8983)
		(end 115.010184 -49.7713)
		(width 0.127)
		(layer "In5.Cu")
		(net "XM_ADDR_15")
	)
	(segment
		(start 133.5913 -45.4406)
		(end 133.218174 -45.4406)
		(width 0.127)
		(layer "In5.Cu")
		(net "XM_ADDR_15")
	)
	(segment
		(start 112.749838 -51.607212)
		(end 112.749838 -51.400202)
		(width 0.127)
		(layer "In5.Cu")
		(net "XM_ADDR_15")
	)
	(segment
		(start 131.241292 -46.6725)
		(end 131.114292 -46.5455)
		(width 0.127)
		(layer "In5.Cu")
		(net "XM_ADDR_15")
	)
	(segment
		(start 112.457738 -48.091852)
		(end 112.928908 -48.091852)
		(width 0.127)
		(layer "In5.Cu")
		(net "XM_ADDR_15")
	)
	(segment
		(start 130.098292 -46.5455)
		(end 130.098292 -46.1264)
		(width 0.127)
		(layer "In5.Cu")
		(net "XM_ADDR_15")
	)
	(segment
		(start 112.330738 -49.539144)
		(end 112.330738 -48.218852)
		(width 0.127)
		(layer "In5.Cu")
		(net "XM_ADDR_15")
	)
	(segment
		(start 133.091428 -46.6725)
		(end 132.257292 -46.6725)
		(width 0.127)
		(layer "In5.Cu")
		(net "XM_ADDR_15")
	)
	(segment
		(start 121.423176 -49.222914)
		(end 121.24309 -49.403)
		(width 0.127)
		(layer "In5.Cu")
		(net "XM_ADDR_15")
	)
	(segment
		(start 135.973566 -44.13758)
		(end 135.973566 -45.328586)
		(width 0.127)
		(layer "In5.Cu")
		(net "XM_ADDR_15")
	)
	(segment
		(start 132.257292 -46.6725)
		(end 132.130292 -46.5455)
		(width 0.127)
		(layer "In5.Cu")
		(net "XM_ADDR_15")
	)
	(segment
		(start 112.330738 -48.218852)
		(end 112.457738 -48.091852)
		(width 0.127)
		(layer "In5.Cu")
		(net "XM_ADDR_15")
	)
	(segment
		(start 121.538238 -48.61941)
		(end 121.358152 -48.799496)
		(width 0.127)
		(layer "In5.Cu")
		(net "XM_ADDR_15")
	)
	(segment
		(start 115.455446 -51.306984)
		(end 115.012978 -51.306984)
		(width 0.127)
		(layer "In5.Cu")
		(net "XM_ADDR_15")
	)
	(segment
		(start 133.224524 -46.128432)
		(end 133.224524 -46.539404)
		(width 0.127)
		(layer "In5.Cu")
		(net "XM_ADDR_15")
	)
	(segment
		(start 113.257584 -48.913796)
		(end 113.257584 -50.059336)
		(width 0.127)
		(layer "In5.Cu")
		(net "XM_ADDR_15")
	)
	(segment
		(start 114.8207 -47.588932)
		(end 114.6937 -47.461932)
		(width 0.127)
		(layer "In5.Cu")
		(net "XM_ADDR_15")
	)
	(segment
		(start 120.998742 -49.33823)
		(end 120.819418 -49.33823)
		(width 0.127)
		(layer "In5.Cu")
		(net "XM_ADDR_15")
	)
	(segment
		(start 112.203738 -49.666144)
		(end 112.330738 -49.539144)
		(width 0.127)
		(layer "In5.Cu")
		(net "XM_ADDR_15")
	)
	(segment
		(start 122.501406 -47.96536)
		(end 122.436382 -47.90059)
		(width 0.127)
		(layer "In5.Cu")
		(net "XM_ADDR_15")
	)
	(segment
		(start 132.961634 -45.69714)
		(end 132.961634 -45.865542)
		(width 0.127)
		(layer "In5.Cu")
		(net "XM_ADDR_15")
	)
	(segment
		(start 128.447292 -46.6725)
		(end 123.485148 -46.6725)
		(width 0.127)
		(layer "In5.Cu")
		(net "XM_ADDR_15")
	)
	(segment
		(start 111.574326 -47.588932)
		(end 111.574326 -49.539144)
		(width 0.127)
		(layer "In5.Cu")
		(net "XM_ADDR_15")
	)
	(segment
		(start 111.701326 -49.666144)
		(end 112.203738 -49.666144)
		(width 0.127)
		(layer "In5.Cu")
		(net "XM_ADDR_15")
	)
	(segment
		(start 121.96191 -48.68418)
		(end 121.782586 -48.68418)
		(width 0.127)
		(layer "In5.Cu")
		(net "XM_ADDR_15")
	)
	(segment
		(start 122.076972 -48.26)
		(end 122.141996 -48.32477)
		(width 0.127)
		(layer "In5.Cu")
		(net "XM_ADDR_15")
	)
	(segment
		(start 114.8207 -48.501046)
		(end 114.8207 -47.588932)
		(width 0.127)
		(layer "In5.Cu")
		(net "XM_ADDR_15")
	)
	(segment
		(start 113.088674 -51.946048)
		(end 112.749838 -51.607212)
		(width 0.127)
		(layer "In5.Cu")
		(net "XM_ADDR_15")
	)
	(segment
		(start 122.076972 -48.080676)
		(end 122.076972 -48.26)
		(width 0.127)
		(layer "In5.Cu")
		(net "XM_ADDR_15")
	)
	(segment
		(start 129.717292 -45.9994)
		(end 129.590292 -46.1264)
		(width 0.127)
		(layer "In5.Cu")
		(net "XM_ADDR_15")
	)
	(segment
		(start 133.224524 -46.539404)
		(end 133.091428 -46.6725)
		(width 0.127)
		(layer "In5.Cu")
		(net "XM_ADDR_15")
	)
	(segment
		(start 128.574292 -46.1264)
		(end 128.574292 -46.5455)
		(width 0.127)
		(layer "In5.Cu")
		(net "XM_ADDR_15")
	)
	(segment
		(start 128.701292 -45.9994)
		(end 128.574292 -46.1264)
		(width 0.127)
		(layer "In5.Cu")
		(net "XM_ADDR_15")
	)
	(segment
		(start 122.860816 -47.785274)
		(end 122.68073 -47.96536)
		(width 0.127)
		(layer "In5.Cu")
		(net "XM_ADDR_15")
	)
	(segment
		(start 129.082292 -46.1264)
		(end 128.955292 -45.9994)
		(width 0.127)
		(layer "In5.Cu")
		(net "XM_ADDR_15")
	)
	(segment
		(start 122.141996 -48.504094)
		(end 121.96191 -48.68418)
		(width 0.127)
		(layer "In5.Cu")
		(net "XM_ADDR_15")
	)
	(segment
		(start 128.574292 -46.5455)
		(end 128.447292 -46.6725)
		(width 0.127)
		(layer "In5.Cu")
		(net "XM_ADDR_15")
	)
	(segment
		(start 132.961634 -45.865542)
		(end 133.224524 -46.128432)
		(width 0.127)
		(layer "In5.Cu")
		(net "XM_ADDR_15")
	)
	(segment
		(start 116.899944 -50.36312)
		(end 116.272564 -50.9905)
		(width 0.127)
		(layer "In5.Cu")
		(net "XM_ADDR_15")
	)
	(segment
		(start 120.639332 -49.69764)
		(end 120.704356 -49.76241)
		(width 0.127)
		(layer "In5.Cu")
		(net "XM_ADDR_15")
	)
	(segment
		(start 131.622292 -46.5455)
		(end 131.495292 -46.6725)
		(width 0.127)
		(layer "In5.Cu")
		(net "XM_ADDR_15")
	)
	(segment
		(start 120.704356 -49.941734)
		(end 120.52427 -50.12182)
		(width 0.127)
		(layer "In5.Cu")
		(net "XM_ADDR_15")
	)
	(segment
		(start 116.272564 -50.9905)
		(end 115.77193 -50.9905)
		(width 0.127)
		(layer "In5.Cu")
		(net "XM_ADDR_15")
	)
	(segment
		(start 114.24285 -50.54727)
		(end 114.24285 -51.846734)
		(width 0.127)
		(layer "In5.Cu")
		(net "XM_ADDR_15")
	)
	(segment
		(start 122.860816 -47.60595)
		(end 122.860816 -47.785274)
		(width 0.127)
		(layer "In5.Cu")
		(net "XM_ADDR_15")
	)
	(segment
		(start 121.358152 -48.799496)
		(end 121.358152 -48.97882)
		(width 0.127)
		(layer "In5.Cu")
		(net "XM_ADDR_15")
	)
	(segment
		(start 120.52427 -50.12182)
		(end 120.344946 -50.12182)
		(width 0.127)
		(layer "In5.Cu")
		(net "XM_ADDR_15")
	)
	(segment
		(start 131.114292 -46.1264)
		(end 130.987292 -45.9994)
		(width 0.127)
		(layer "In5.Cu")
		(net "XM_ADDR_15")
	)
	(segment
		(start 121.782586 -48.68418)
		(end 121.717562 -48.61941)
		(width 0.127)
		(layer "In5.Cu")
		(net "XM_ADDR_15")
	)
	(segment
		(start 115.77193 -50.9905)
		(end 115.455446 -51.306984)
		(width 0.127)
		(layer "In5.Cu")
		(net "XM_ADDR_15")
	)
	(segment
		(start 129.590292 -46.1264)
		(end 129.590292 -46.5455)
		(width 0.127)
		(layer "In5.Cu")
		(net "XM_ADDR_15")
	)
	(segment
		(start 130.606292 -46.5455)
		(end 130.479292 -46.6725)
		(width 0.127)
		(layer "In5.Cu")
		(net "XM_ADDR_15")
	)
	(segment
		(start 114.6937 -47.461932)
		(end 111.701326 -47.461932)
		(width 0.127)
		(layer "In5.Cu")
		(net "XM_ADDR_15")
	)
	(segment
		(start 132.003292 -45.9994)
		(end 131.749292 -45.9994)
		(width 0.127)
		(layer "In5.Cu")
		(net "XM_ADDR_15")
	)
	(segment
		(start 114.472466 -48.84928)
		(end 114.8207 -48.501046)
		(width 0.127)
		(layer "In5.Cu")
		(net "XM_ADDR_15")
	)
	(segment
		(start 122.436382 -47.90059)
		(end 122.257058 -47.90059)
		(width 0.127)
		(layer "In5.Cu")
		(net "XM_ADDR_15")
	)
	(segment
		(start 131.495292 -46.6725)
		(end 131.241292 -46.6725)
		(width 0.127)
		(layer "In5.Cu")
		(net "XM_ADDR_15")
	)
	(segment
		(start 112.928908 -48.091852)
		(end 113.055908 -48.218852)
		(width 0.127)
		(layer "In5.Cu")
		(net "XM_ADDR_15")
	)
	(segment
		(start 115.012978 -51.306984)
		(end 114.885978 -51.179984)
		(width 0.127)
		(layer "In5.Cu")
		(net "XM_ADDR_15")
	)
	(segment
		(start 130.098292 -46.1264)
		(end 129.971292 -45.9994)
		(width 0.127)
		(layer "In5.Cu")
		(net "XM_ADDR_15")
	)
	(segment
		(start 135.973566 -45.328586)
		(end 135.798052 -45.5041)
		(width 0.127)
		(layer "In5.Cu")
		(net "XM_ADDR_15")
	)
	(segment
		(start 121.358152 -48.97882)
		(end 121.423176 -49.04359)
		(width 0.127)
		(layer "In5.Cu")
		(net "XM_ADDR_15")
	)
	(segment
		(start 130.733292 -45.9994)
		(end 130.606292 -46.1264)
		(width 0.127)
		(layer "In5.Cu")
		(net "XM_ADDR_15")
	)
	(segment
		(start 121.423176 -49.04359)
		(end 121.423176 -49.222914)
		(width 0.127)
		(layer "In5.Cu")
		(net "XM_ADDR_15")
	)
	(segment
		(start 115.010184 -49.7713)
		(end 114.71783 -49.7713)
		(width 0.127)
		(layer "In5.Cu")
		(net "XM_ADDR_15")
	)
	(segment
		(start 134.259828 -45.5041)
		(end 134.09676 -45.667168)
		(width 0.127)
		(layer "In5.Cu")
		(net "XM_ADDR_15")
	)
	(segment
		(start 137.087356 -45.5041)
		(end 136.81075 -45.5041)
		(width 0.127)
		(layer "In5.Cu")
		(net "XM_ADDR_15")
	)
	(segment
		(start 121.24309 -49.403)
		(end 121.063766 -49.403)
		(width 0.127)
		(layer "In5.Cu")
		(net "XM_ADDR_15")
	)
	(segment
		(start 122.141996 -48.32477)
		(end 122.141996 -48.504094)
		(width 0.127)
		(layer "In5.Cu")
		(net "XM_ADDR_15")
	)
	(segment
		(start 113.055908 -48.71212)
		(end 113.257584 -48.913796)
		(width 0.127)
		(layer "In5.Cu")
		(net "XM_ADDR_15")
	)
	(segment
		(start 122.257058 -47.90059)
		(end 122.076972 -48.080676)
		(width 0.127)
		(layer "In5.Cu")
		(net "XM_ADDR_15")
	)
	(segment
		(start 132.130292 -46.1264)
		(end 132.003292 -45.9994)
		(width 0.127)
		(layer "In5.Cu")
		(net "XM_ADDR_15")
	)
	(segment
		(start 122.68073 -47.96536)
		(end 122.501406 -47.96536)
		(width 0.127)
		(layer "In5.Cu")
		(net "XM_ADDR_15")
	)
	(segment
		(start 114.885978 -51.179984)
		(end 114.885978 -50.669952)
		(width 0.127)
		(layer "In5.Cu")
		(net "XM_ADDR_15")
	)
	(segment
		(start 131.622292 -46.1264)
		(end 131.622292 -46.5455)
		(width 0.127)
		(layer "In5.Cu")
		(net "XM_ADDR_15")
	)
	(segment
		(start 130.479292 -46.6725)
		(end 130.225292 -46.6725)
		(width 0.127)
		(layer "In5.Cu")
		(net "XM_ADDR_15")
	)
	(segment
		(start 130.987292 -45.9994)
		(end 130.733292 -45.9994)
		(width 0.127)
		(layer "In5.Cu")
		(net "XM_ADDR_15")
	)
	(segment
		(start 114.24285 -51.846734)
		(end 114.143536 -51.946048)
		(width 0.127)
		(layer "In5.Cu")
		(net "XM_ADDR_15")
	)
	(segment
		(start 114.143536 -51.946048)
		(end 113.088674 -51.946048)
		(width 0.127)
		(layer "In5.Cu")
		(net "XM_ADDR_15")
	)
	(segment
		(start 120.639332 -49.518316)
		(end 120.639332 -49.69764)
		(width 0.127)
		(layer "In5.Cu")
		(net "XM_ADDR_15")
	)
	(segment
		(start 111.574326 -49.539144)
		(end 111.701326 -49.666144)
		(width 0.127)
		(layer "In5.Cu")
		(net "XM_ADDR_15")
	)
	(segment
		(start 132.130292 -46.5455)
		(end 132.130292 -46.1264)
		(width 0.127)
		(layer "In5.Cu")
		(net "XM_ADDR_15")
	)
	(segment
		(start 121.063766 -49.403)
		(end 120.998742 -49.33823)
		(width 0.127)
		(layer "In5.Cu")
		(net "XM_ADDR_15")
	)
	(segment
		(start 114.472466 -49.525936)
		(end 114.472466 -48.84928)
		(width 0.127)
		(layer "In5.Cu")
		(net "XM_ADDR_15")
	)
	(segment
		(start 135.798052 -45.5041)
		(end 134.259828 -45.5041)
		(width 0.127)
		(layer "In5.Cu")
		(net "XM_ADDR_15")
	)
	(segment
		(start 113.384584 -50.186336)
		(end 113.881916 -50.186336)
		(width 0.127)
		(layer "In5.Cu")
		(net "XM_ADDR_15")
	)
	(segment
		(start 119.794528 -50.36312)
		(end 116.899944 -50.36312)
		(width 0.127)
		(layer "In5.Cu")
		(net "XM_ADDR_15")
	)
	(segment
		(start 129.082292 -46.5455)
		(end 129.082292 -46.1264)
		(width 0.127)
		(layer "In5.Cu")
		(net "XM_ADDR_15")
	)
	(segment
		(start 136.55675 -44.03979)
		(end 136.071356 -44.03979)
		(width 0.127)
		(layer "In5.Cu")
		(net "XM_ADDR_15")
	)
	(segment
		(start 121.717562 -48.61941)
		(end 121.538238 -48.61941)
		(width 0.127)
		(layer "In5.Cu")
		(net "XM_ADDR_15")
	)
	(segment
		(start 120.100598 -50.05705)
		(end 119.794528 -50.36312)
		(width 0.127)
		(layer "In5.Cu")
		(net "XM_ADDR_15")
	)
	(segment
		(start 120.819418 -49.33823)
		(end 120.639332 -49.518316)
		(width 0.127)
		(layer "In5.Cu")
		(net "XM_ADDR_15")
	)
	(segment
		(start 129.463292 -46.6725)
		(end 129.209292 -46.6725)
		(width 0.127)
		(layer "In5.Cu")
		(net "XM_ADDR_15")
	)
	(segment
		(start 120.279922 -50.05705)
		(end 120.100598 -50.05705)
		(width 0.127)
		(layer "In5.Cu")
		(net "XM_ADDR_15")
	)
	(segment
		(start 130.606292 -46.1264)
		(end 130.606292 -46.5455)
		(width 0.127)
		(layer "In5.Cu")
		(net "XM_ADDR_15")
	)
	(segment
		(start 134.09676 -45.667168)
		(end 133.817868 -45.667168)
		(width 0.127)
		(layer "In5.Cu")
		(net "XM_ADDR_15")
	)
	(segment
		(start 136.68375 -45.3771)
		(end 136.68375 -44.16679)
		(width 0.127)
		(layer "In5.Cu")
		(net "XM_ADDR_15")
	)
	(segment
		(start 113.257584 -50.059336)
		(end 113.384584 -50.186336)
		(width 0.127)
		(layer "In5.Cu")
		(net "XM_ADDR_15")
	)
	(segment
		(start 133.218174 -45.4406)
		(end 132.961634 -45.69714)
		(width 0.127)
		(layer "In5.Cu")
		(net "XM_ADDR_15")
	)
	(segment
		(start 122.795792 -47.54118)
		(end 122.860816 -47.60595)
		(width 0.127)
		(layer "In5.Cu")
		(net "XM_ADDR_15")
	)
	(segment
		(start 131.749292 -45.9994)
		(end 131.622292 -46.1264)
		(width 0.127)
		(layer "In5.Cu")
		(net "XM_ADDR_15")
	)
	(segment
		(start 136.071356 -44.03979)
		(end 135.973566 -44.13758)
		(width 0.127)
		(layer "In5.Cu")
		(net "XM_ADDR_15")
	)
	(segment
		(start 129.971292 -45.9994)
		(end 129.717292 -45.9994)
		(width 0.127)
		(layer "In5.Cu")
		(net "XM_ADDR_15")
	)
	(segment
		(start 114.71783 -49.7713)
		(end 114.472466 -49.525936)
		(width 0.127)
		(layer "In5.Cu")
		(net "XM_ADDR_15")
	)
	(segment
		(start 123.485148 -46.6725)
		(end 122.795792 -47.361856)
		(width 0.127)
		(layer "In5.Cu")
		(net "XM_ADDR_15")
	)
	(segment
		(start 133.817868 -45.667168)
		(end 133.5913 -45.4406)
		(width 0.127)
		(layer "In5.Cu")
		(net "XM_ADDR_15")
	)
	(segment
		(start 129.209292 -46.6725)
		(end 129.082292 -46.5455)
		(width 0.127)
		(layer "In5.Cu")
		(net "XM_ADDR_15")
	)
	(segment
		(start 114.885978 -50.669952)
		(end 115.137184 -50.418746)
		(width 0.127)
		(layer "In5.Cu")
		(net "XM_ADDR_15")
	)
	(segment
		(start 115.137184 -50.418746)
		(end 115.137184 -49.8983)
		(width 0.127)
		(layer "In5.Cu")
		(net "XM_ADDR_15")
	)
	(segment
		(start 136.68375 -44.16679)
		(end 136.55675 -44.03979)
		(width 0.127)
		(layer "In5.Cu")
		(net "XM_ADDR_15")
	)
	(segment
		(start 130.225292 -46.6725)
		(end 130.098292 -46.5455)
		(width 0.127)
		(layer "In5.Cu")
		(net "XM_ADDR_15")
	)
	(segment
		(start 111.701326 -47.461932)
		(end 111.574326 -47.588932)
		(width 0.127)
		(layer "In5.Cu")
		(net "XM_ADDR_15")
	)
	(segment
		(start 122.795792 -47.361856)
		(end 122.795792 -47.54118)
		(width 0.127)
		(layer "In5.Cu")
		(net "XM_ADDR_15")
	)
	(segment
		(start 113.881916 -50.186336)
		(end 114.24285 -50.54727)
		(width 0.127)
		(layer "In5.Cu")
		(net "XM_ADDR_15")
	)
	(segment
		(start 136.81075 -45.5041)
		(end 136.68375 -45.3771)
		(width 0.127)
		(layer "In5.Cu")
		(net "XM_ADDR_15")
	)
	(segment
		(start 129.590292 -46.5455)
		(end 129.463292 -46.6725)
		(width 0.127)
		(layer "In5.Cu")
		(net "XM_ADDR_15")
	)
	(segment
		(start 113.055908 -48.218852)
		(end 113.055908 -48.71212)
		(width 0.127)
		(layer "In5.Cu")
		(net "XM_ADDR_15")
	)
	(segment
		(start 176.657 -116.967)
		(end 176.456848 -116.766848)
		(width 0.508)
		(layer "F.Cu")
		(net "P0V9_E_SNB")
	)
	(segment
		(start 176.456848 -116.766848)
		(end 176.456848 -115.687856)
		(width 0.508)
		(layer "F.Cu")
		(net "P0V9_E_SNB")
	)
	(segment
		(start 176.456848 -115.687856)
		(end 176.456848 -114.811556)
		(width 0.508)
		(layer "F.Cu")
		(net "P0V9_E_SNB")
	)
	(segment
		(start 176.456848 -114.811556)
		(end 176.012348 -114.367056)
		(width 0.508)
		(layer "F.Cu")
		(net "P0V9_E_SNB")
	)
	(via
		(at 176.657 -116.967)
		(size 0.7112)
		(drill 0.3556)
		(layers "F.Cu" "B.Cu")
		(net "P0V9_E_SNB")
	)
	(segment
		(start 120.2944 -76.581)
		(end 120.09247 -76.581)
		(width 0.1397)
		(layer "F.Cu")
		(net "EXP_REF_CLK_N_R")
	)
	(segment
		(start 120.09247 -76.581)
		(end 120.09247 -74.6252)
		(width 0.1397)
		(layer "F.Cu")
		(net "EXP_REF_CLK_N_R")
	)
	(segment
		(start 121.009918 -75.865482)
		(end 120.2944 -76.581)
		(width 0.1397)
		(layer "F.Cu")
		(net "EXP_REF_CLK_N_R")
	)
	(segment
		(start 121.900442 -75.865482)
		(end 121.009918 -75.865482)
		(width 0.1397)
		(layer "F.Cu")
		(net "EXP_REF_CLK_N_R")
	)
	(segment
		(start 107.349798 -92.349828)
		(end 106.849672 -91.849702)
		(width 0.1143)
		(layer "F.Cu")
		(net "XM_DATA13")
	)
	(segment
		(start 75.786742 -135.392922)
		(end 74.30897 -135.392922)
		(width 0.1143)
		(layer "F.Cu")
		(net "XM_DATA13")
	)
	(via
		(at 74.30897 -135.392922)
		(size 0.5588)
		(drill 0.3048)
		(layers "F.Cu" "B.Cu")
		(net "XM_DATA13")
	)
	(via
		(at 74.32167 -136.28624)
		(size 0.7112)
		(drill 0.3556)
		(layers "F.Cu" "B.Cu")
		(net "XM_DATA13")
	)
	(via
		(at 106.849672 -91.849702)
		(size 0.508)
		(drill 0.254)
		(layers "F.Cu" "B.Cu")
		(net "XM_DATA13")
	)
	(segment
		(start 72.58812 -104.464358)
		(end 72.849232 -104.203246)
		(width 0.1143)
		(layer "B.Cu")
		(net "XM_DATA13")
	)
	(segment
		(start 97.836482 -94.11716)
		(end 97.950782 -94.23146)
		(width 0.1143)
		(layer "B.Cu")
		(net "XM_DATA13")
	)
	(segment
		(start 95.664782 -94.23146)
		(end 95.779082 -94.11716)
		(width 0.1143)
		(layer "B.Cu")
		(net "XM_DATA13")
	)
	(segment
		(start 98.522282 -94.11716)
		(end 98.750882 -94.11716)
		(width 0.1143)
		(layer "B.Cu")
		(net "XM_DATA13")
	)
	(segment
		(start 74.834496 -104.572054)
		(end 74.996294 -104.410256)
		(width 0.1143)
		(layer "B.Cu")
		(net "XM_DATA13")
	)
	(segment
		(start 106.18597 -92.329)
		(end 106.665268 -91.849702)
		(width 0.1143)
		(layer "B.Cu")
		(net "XM_DATA13")
	)
	(segment
		(start 98.865182 -94.472252)
		(end 98.979482 -94.586552)
		(width 0.1143)
		(layer "B.Cu")
		(net "XM_DATA13")
	)
	(segment
		(start 97.607882 -94.11716)
		(end 97.836482 -94.11716)
		(width 0.1143)
		(layer "B.Cu")
		(net "XM_DATA13")
	)
	(segment
		(start 73.334118 -103.879904)
		(end 73.334118 -103.71836)
		(width 0.1143)
		(layer "B.Cu")
		(net "XM_DATA13")
	)
	(segment
		(start 74.026268 -105.218738)
		(end 74.187812 -105.218738)
		(width 0.1143)
		(layer "B.Cu")
		(net "XM_DATA13")
	)
	(segment
		(start 99.893882 -94.586552)
		(end 100.122482 -94.586552)
		(width 0.1143)
		(layer "B.Cu")
		(net "XM_DATA13")
	)
	(segment
		(start 74.996294 -104.248712)
		(end 73.980802 -103.23322)
		(width 0.1143)
		(layer "B.Cu")
		(net "XM_DATA13")
	)
	(segment
		(start 99.322382 -94.23146)
		(end 99.436682 -94.11716)
		(width 0.1143)
		(layer "B.Cu")
		(net "XM_DATA13")
	)
	(segment
		(start 73.010776 -104.203246)
		(end 74.026268 -105.218738)
		(width 0.1143)
		(layer "B.Cu")
		(net "XM_DATA13")
	)
	(segment
		(start 96.121982 -94.23146)
		(end 96.121982 -94.472252)
		(width 0.1143)
		(layer "B.Cu")
		(net "XM_DATA13")
	)
	(segment
		(start 74.34961 -104.895396)
		(end 73.334118 -103.879904)
		(width 0.1143)
		(layer "B.Cu")
		(net "XM_DATA13")
	)
	(segment
		(start 97.036382 -94.472252)
		(end 97.150682 -94.586552)
		(width 0.1143)
		(layer "B.Cu")
		(net "XM_DATA13")
	)
	(segment
		(start 95.779082 -94.11716)
		(end 96.007682 -94.11716)
		(width 0.1143)
		(layer "B.Cu")
		(net "XM_DATA13")
	)
	(segment
		(start 100.236782 -94.472252)
		(end 100.236782 -94.23146)
		(width 0.1143)
		(layer "B.Cu")
		(net "XM_DATA13")
	)
	(segment
		(start 73.334118 -103.71836)
		(end 73.495916 -103.556562)
		(width 0.1143)
		(layer "B.Cu")
		(net "XM_DATA13")
	)
	(segment
		(start 72.58812 -128.20142)
		(end 72.58812 -104.464358)
		(width 0.1143)
		(layer "B.Cu")
		(net "XM_DATA13")
	)
	(segment
		(start 96.693482 -94.11716)
		(end 96.922082 -94.11716)
		(width 0.1143)
		(layer "B.Cu")
		(net "XM_DATA13")
	)
	(segment
		(start 99.436682 -94.11716)
		(end 99.665282 -94.11716)
		(width 0.1143)
		(layer "B.Cu")
		(net "XM_DATA13")
	)
	(segment
		(start 99.665282 -94.11716)
		(end 99.779582 -94.23146)
		(width 0.1143)
		(layer "B.Cu")
		(net "XM_DATA13")
	)
	(segment
		(start 94.864682 -94.11716)
		(end 95.093282 -94.11716)
		(width 0.1143)
		(layer "B.Cu")
		(net "XM_DATA13")
	)
	(segment
		(start 74.627486 -102.586536)
		(end 74.627486 -102.424992)
		(width 0.1143)
		(layer "B.Cu")
		(net "XM_DATA13")
	)
	(segment
		(start 74.30897 -135.392922)
		(end 74.30897 -136.27354)
		(width 0.1143)
		(layer "B.Cu")
		(net "XM_DATA13")
	)
	(segment
		(start 99.322382 -94.472252)
		(end 99.322382 -94.23146)
		(width 0.1143)
		(layer "B.Cu")
		(net "XM_DATA13")
	)
	(segment
		(start 75.642978 -103.763572)
		(end 75.642978 -103.602028)
		(width 0.1143)
		(layer "B.Cu")
		(net "XM_DATA13")
	)
	(segment
		(start 98.407982 -94.23146)
		(end 98.522282 -94.11716)
		(width 0.1143)
		(layer "B.Cu")
		(net "XM_DATA13")
	)
	(segment
		(start 96.464882 -94.586552)
		(end 96.579182 -94.472252)
		(width 0.1143)
		(layer "B.Cu")
		(net "XM_DATA13")
	)
	(segment
		(start 97.950782 -94.472252)
		(end 98.065082 -94.586552)
		(width 0.1143)
		(layer "B.Cu")
		(net "XM_DATA13")
	)
	(segment
		(start 74.996294 -104.410256)
		(end 74.996294 -104.248712)
		(width 0.1143)
		(layer "B.Cu")
		(net "XM_DATA13")
	)
	(segment
		(start 98.407982 -94.472252)
		(end 98.407982 -94.23146)
		(width 0.1143)
		(layer "B.Cu")
		(net "XM_DATA13")
	)
	(segment
		(start 95.664782 -94.472252)
		(end 95.664782 -94.23146)
		(width 0.1143)
		(layer "B.Cu")
		(net "XM_DATA13")
	)
	(segment
		(start 96.579182 -94.23146)
		(end 96.693482 -94.11716)
		(width 0.1143)
		(layer "B.Cu")
		(net "XM_DATA13")
	)
	(segment
		(start 94.178882 -94.11716)
		(end 94.293182 -94.23146)
		(width 0.1143)
		(layer "B.Cu")
		(net "XM_DATA13")
	)
	(segment
		(start 94.750382 -94.472252)
		(end 94.750382 -94.23146)
		(width 0.1143)
		(layer "B.Cu")
		(net "XM_DATA13")
	)
	(segment
		(start 95.093282 -94.11716)
		(end 95.207582 -94.23146)
		(width 0.1143)
		(layer "B.Cu")
		(net "XM_DATA13")
	)
	(segment
		(start 99.779582 -94.23146)
		(end 99.779582 -94.472252)
		(width 0.1143)
		(layer "B.Cu")
		(net "XM_DATA13")
	)
	(segment
		(start 100.85324 -94.11716)
		(end 102.6414 -92.329)
		(width 0.1143)
		(layer "B.Cu")
		(net "XM_DATA13")
	)
	(segment
		(start 96.922082 -94.11716)
		(end 97.036382 -94.23146)
		(width 0.1143)
		(layer "B.Cu")
		(net "XM_DATA13")
	)
	(segment
		(start 106.665268 -91.849702)
		(end 106.849672 -91.849702)
		(width 0.1143)
		(layer "B.Cu")
		(net "XM_DATA13")
	)
	(segment
		(start 99.779582 -94.472252)
		(end 99.893882 -94.586552)
		(width 0.1143)
		(layer "B.Cu")
		(net "XM_DATA13")
	)
	(segment
		(start 96.007682 -94.11716)
		(end 96.121982 -94.23146)
		(width 0.1143)
		(layer "B.Cu")
		(net "XM_DATA13")
	)
	(segment
		(start 73.980802 -103.071676)
		(end 74.1426 -102.909878)
		(width 0.1143)
		(layer "B.Cu")
		(net "XM_DATA13")
	)
	(segment
		(start 74.34961 -105.05694)
		(end 74.34961 -104.895396)
		(width 0.1143)
		(layer "B.Cu")
		(net "XM_DATA13")
	)
	(segment
		(start 97.036382 -94.23146)
		(end 97.036382 -94.472252)
		(width 0.1143)
		(layer "B.Cu")
		(net "XM_DATA13")
	)
	(segment
		(start 98.865182 -94.23146)
		(end 98.865182 -94.472252)
		(width 0.1143)
		(layer "B.Cu")
		(net "XM_DATA13")
	)
	(segment
		(start 94.750382 -94.23146)
		(end 94.864682 -94.11716)
		(width 0.1143)
		(layer "B.Cu")
		(net "XM_DATA13")
	)
	(segment
		(start 102.6414 -92.329)
		(end 106.18597 -92.329)
		(width 0.1143)
		(layer "B.Cu")
		(net "XM_DATA13")
	)
	(segment
		(start 75.319636 -103.92537)
		(end 75.48118 -103.92537)
		(width 0.1143)
		(layer "B.Cu")
		(net "XM_DATA13")
	)
	(segment
		(start 75.642978 -103.602028)
		(end 74.627486 -102.586536)
		(width 0.1143)
		(layer "B.Cu")
		(net "XM_DATA13")
	)
	(segment
		(start 100.122482 -94.586552)
		(end 100.236782 -94.472252)
		(width 0.1143)
		(layer "B.Cu")
		(net "XM_DATA13")
	)
	(segment
		(start 74.672952 -104.572054)
		(end 74.834496 -104.572054)
		(width 0.1143)
		(layer "B.Cu")
		(net "XM_DATA13")
	)
	(segment
		(start 74.304144 -102.909878)
		(end 75.319636 -103.92537)
		(width 0.1143)
		(layer "B.Cu")
		(net "XM_DATA13")
	)
	(segment
		(start 97.150682 -94.586552)
		(end 97.379282 -94.586552)
		(width 0.1143)
		(layer "B.Cu")
		(net "XM_DATA13")
	)
	(segment
		(start 100.351082 -94.11716)
		(end 100.85324 -94.11716)
		(width 0.1143)
		(layer "B.Cu")
		(net "XM_DATA13")
	)
	(segment
		(start 97.493582 -94.23146)
		(end 97.607882 -94.11716)
		(width 0.1143)
		(layer "B.Cu")
		(net "XM_DATA13")
	)
	(segment
		(start 97.950782 -94.23146)
		(end 97.950782 -94.472252)
		(width 0.1143)
		(layer "B.Cu")
		(net "XM_DATA13")
	)
	(segment
		(start 95.207582 -94.23146)
		(end 95.207582 -94.472252)
		(width 0.1143)
		(layer "B.Cu")
		(net "XM_DATA13")
	)
	(segment
		(start 96.579182 -94.472252)
		(end 96.579182 -94.23146)
		(width 0.1143)
		(layer "B.Cu")
		(net "XM_DATA13")
	)
	(segment
		(start 74.90587 -130.51917)
		(end 72.58812 -128.20142)
		(width 0.1143)
		(layer "B.Cu")
		(net "XM_DATA13")
	)
	(segment
		(start 73.65746 -103.556562)
		(end 74.672952 -104.572054)
		(width 0.1143)
		(layer "B.Cu")
		(net "XM_DATA13")
	)
	(segment
		(start 82.935318 -94.11716)
		(end 94.178882 -94.11716)
		(width 0.1143)
		(layer "B.Cu")
		(net "XM_DATA13")
	)
	(segment
		(start 75.48118 -103.92537)
		(end 75.642978 -103.763572)
		(width 0.1143)
		(layer "B.Cu")
		(net "XM_DATA13")
	)
	(segment
		(start 94.407482 -94.586552)
		(end 94.636082 -94.586552)
		(width 0.1143)
		(layer "B.Cu")
		(net "XM_DATA13")
	)
	(segment
		(start 74.30897 -136.27354)
		(end 74.32167 -136.28624)
		(width 0.1143)
		(layer "B.Cu")
		(net "XM_DATA13")
	)
	(segment
		(start 95.550482 -94.586552)
		(end 95.664782 -94.472252)
		(width 0.1143)
		(layer "B.Cu")
		(net "XM_DATA13")
	)
	(segment
		(start 94.293182 -94.23146)
		(end 94.293182 -94.472252)
		(width 0.1143)
		(layer "B.Cu")
		(net "XM_DATA13")
	)
	(segment
		(start 96.121982 -94.472252)
		(end 96.236282 -94.586552)
		(width 0.1143)
		(layer "B.Cu")
		(net "XM_DATA13")
	)
	(segment
		(start 74.187812 -105.218738)
		(end 74.34961 -105.05694)
		(width 0.1143)
		(layer "B.Cu")
		(net "XM_DATA13")
	)
	(segment
		(start 94.636082 -94.586552)
		(end 94.750382 -94.472252)
		(width 0.1143)
		(layer "B.Cu")
		(net "XM_DATA13")
	)
	(segment
		(start 98.979482 -94.586552)
		(end 99.208082 -94.586552)
		(width 0.1143)
		(layer "B.Cu")
		(net "XM_DATA13")
	)
	(segment
		(start 98.293682 -94.586552)
		(end 98.407982 -94.472252)
		(width 0.1143)
		(layer "B.Cu")
		(net "XM_DATA13")
	)
	(segment
		(start 73.495916 -103.556562)
		(end 73.65746 -103.556562)
		(width 0.1143)
		(layer "B.Cu")
		(net "XM_DATA13")
	)
	(segment
		(start 74.90587 -134.796022)
		(end 74.90587 -130.51917)
		(width 0.1143)
		(layer "B.Cu")
		(net "XM_DATA13")
	)
	(segment
		(start 74.30897 -135.392922)
		(end 74.90587 -134.796022)
		(width 0.1143)
		(layer "B.Cu")
		(net "XM_DATA13")
	)
	(segment
		(start 95.321882 -94.586552)
		(end 95.550482 -94.586552)
		(width 0.1143)
		(layer "B.Cu")
		(net "XM_DATA13")
	)
	(segment
		(start 72.849232 -104.203246)
		(end 73.010776 -104.203246)
		(width 0.1143)
		(layer "B.Cu")
		(net "XM_DATA13")
	)
	(segment
		(start 97.493582 -94.472252)
		(end 97.493582 -94.23146)
		(width 0.1143)
		(layer "B.Cu")
		(net "XM_DATA13")
	)
	(segment
		(start 74.1426 -102.909878)
		(end 74.304144 -102.909878)
		(width 0.1143)
		(layer "B.Cu")
		(net "XM_DATA13")
	)
	(segment
		(start 100.236782 -94.23146)
		(end 100.351082 -94.11716)
		(width 0.1143)
		(layer "B.Cu")
		(net "XM_DATA13")
	)
	(segment
		(start 73.980802 -103.23322)
		(end 73.980802 -103.071676)
		(width 0.1143)
		(layer "B.Cu")
		(net "XM_DATA13")
	)
	(segment
		(start 94.293182 -94.472252)
		(end 94.407482 -94.586552)
		(width 0.1143)
		(layer "B.Cu")
		(net "XM_DATA13")
	)
	(segment
		(start 97.379282 -94.586552)
		(end 97.493582 -94.472252)
		(width 0.1143)
		(layer "B.Cu")
		(net "XM_DATA13")
	)
	(segment
		(start 74.627486 -102.424992)
		(end 82.935318 -94.11716)
		(width 0.1143)
		(layer "B.Cu")
		(net "XM_DATA13")
	)
	(segment
		(start 96.236282 -94.586552)
		(end 96.464882 -94.586552)
		(width 0.1143)
		(layer "B.Cu")
		(net "XM_DATA13")
	)
	(segment
		(start 99.208082 -94.586552)
		(end 99.322382 -94.472252)
		(width 0.1143)
		(layer "B.Cu")
		(net "XM_DATA13")
	)
	(segment
		(start 98.750882 -94.11716)
		(end 98.865182 -94.23146)
		(width 0.1143)
		(layer "B.Cu")
		(net "XM_DATA13")
	)
	(segment
		(start 98.065082 -94.586552)
		(end 98.293682 -94.586552)
		(width 0.1143)
		(layer "B.Cu")
		(net "XM_DATA13")
	)
	(segment
		(start 95.207582 -94.472252)
		(end 95.321882 -94.586552)
		(width 0.1143)
		(layer "B.Cu")
		(net "XM_DATA13")
	)
	(segment
		(start 142.77975 -58.87847)
		(end 142.77975 -53.98897)
		(width 0.1143)
		(layer "F.Cu")
		(net "XM_DATA_4")
	)
	(segment
		(start 113.150142 -48.599852)
		(end 113.549938 -48.200056)
		(width 0.1143)
		(layer "F.Cu")
		(net "XM_DATA_4")
	)
	(segment
		(start 141.598396 -61.9379)
		(end 141.598396 -60.059824)
		(width 0.1143)
		(layer "F.Cu")
		(net "XM_DATA_4")
	)
	(segment
		(start 142.77975 -53.98897)
		(end 143.404082 -53.364638)
		(width 0.1143)
		(layer "F.Cu")
		(net "XM_DATA_4")
	)
	(segment
		(start 141.598396 -60.059824)
		(end 142.77975 -58.87847)
		(width 0.1143)
		(layer "F.Cu")
		(net "XM_DATA_4")
	)
	(segment
		(start 143.404082 -53.364638)
		(end 143.404082 -52.331112)
		(width 0.1143)
		(layer "F.Cu")
		(net "XM_DATA_4")
	)
	(via
		(at 113.549938 -48.200056)
		(size 0.508)
		(drill 0.254)
		(layers "F.Cu" "B.Cu")
		(net "XM_DATA_4")
	)
	(via
		(at 143.404082 -52.331112)
		(size 0.5588)
		(drill 0.3048)
		(layers "F.Cu" "B.Cu")
		(net "XM_DATA_4")
	)
	(via
		(at 142.860014 -50.564288)
		(size 0.7112)
		(drill 0.3556)
		(layers "F.Cu" "B.Cu")
		(net "XM_DATA_4")
	)
	(segment
		(start 142.073376 -49.77765)
		(end 140.907008 -49.77765)
		(width 0.1143)
		(layer "B.Cu")
		(net "XM_DATA_4")
	)
	(segment
		(start 143.404082 -51.108356)
		(end 142.860014 -50.564288)
		(width 0.1143)
		(layer "B.Cu")
		(net "XM_DATA_4")
	)
	(segment
		(start 119.888 -49.784)
		(end 117.891306 -47.787306)
		(width 0.1143)
		(layer "B.Cu")
		(net "XM_DATA_4")
	)
	(segment
		(start 143.404082 -52.331112)
		(end 143.404082 -51.108356)
		(width 0.1143)
		(layer "B.Cu")
		(net "XM_DATA_4")
	)
	(segment
		(start 135.509 -49.784)
		(end 119.888 -49.784)
		(width 0.1143)
		(layer "B.Cu")
		(net "XM_DATA_4")
	)
	(segment
		(start 140.907008 -49.77765)
		(end 140.151358 -49.022)
		(width 0.1143)
		(layer "B.Cu")
		(net "XM_DATA_4")
	)
	(segment
		(start 140.151358 -49.022)
		(end 136.271 -49.022)
		(width 0.1143)
		(layer "B.Cu")
		(net "XM_DATA_4")
	)
	(segment
		(start 136.271 -49.022)
		(end 135.509 -49.784)
		(width 0.1143)
		(layer "B.Cu")
		(net "XM_DATA_4")
	)
	(segment
		(start 142.860014 -50.564288)
		(end 142.073376 -49.77765)
		(width 0.1143)
		(layer "B.Cu")
		(net "XM_DATA_4")
	)
	(segment
		(start 117.891306 -47.787306)
		(end 113.962688 -47.787306)
		(width 0.1143)
		(layer "B.Cu")
		(net "XM_DATA_4")
	)
	(segment
		(start 113.962688 -47.787306)
		(end 113.549938 -48.200056)
		(width 0.1143)
		(layer "B.Cu")
		(net "XM_DATA_4")
	)
	(segment
		(start 131.897882 -80.867758)
		(end 131.897882 -80.562958)
		(width 0.1016)
		(layer "F.Cu")
		(net "3008_SAS_RX_P0")
	)
	(segment
		(start 131.942332 -79.756)
		(end 132.005324 -79.756)
		(width 0.1016)
		(layer "F.Cu")
		(net "3008_SAS_RX_P0")
	)
	(segment
		(start 131.796282 -80.461358)
		(end 131.789932 -80.461358)
		(width 0.1016)
		(layer "F.Cu")
		(net "3008_SAS_RX_P0")
	)
	(segment
		(start 131.688332 -80.359758)
		(end 131.688332 -80.01)
		(width 0.1016)
		(layer "F.Cu")
		(net "3008_SAS_RX_P0")
	)
	(segment
		(start 93.153738 -34.99993)
		(end 93.547184 -34.606484)
		(width 0.1016)
		(layer "F.Cu")
		(net "3008_SAS_RX_P0")
	)
	(segment
		(start 93.150182 -34.99993)
		(end 93.153738 -34.99993)
		(width 0.1016)
		(layer "F.Cu")
		(net "3008_SAS_RX_P0")
	)
	(via
		(at 132.005324 -79.756)
		(size 0.5588)
		(drill 0.3048)
		(layers "F.Cu" "B.Cu")
		(net "3008_SAS_RX_P0")
	)
	(via
		(at 93.547184 -34.606484)
		(size 0.508)
		(drill 0.254)
		(layers "F.Cu" "B.Cu")
		(net "3008_SAS_RX_P0")
	)
	(arc
		(start 131.789932 -80.461358)
		(mid 131.71809 -80.4316)
		(end 131.688332 -80.359758)
		(width 0.1016)
		(layer "F.Cu")
		(net "3008_SAS_RX_P0")
	)
	(arc
		(start 131.688332 -80.01)
		(mid 131.762727 -79.830395)
		(end 131.942332 -79.756)
		(width 0.1016)
		(layer "F.Cu")
		(net "3008_SAS_RX_P0")
	)
	(arc
		(start 131.897882 -80.562958)
		(mid 131.868124 -80.491116)
		(end 131.796282 -80.461358)
		(width 0.1016)
		(layer "F.Cu")
		(net "3008_SAS_RX_P0")
	)
	(segment
		(start 104.394 -67.945)
		(end 97.453704 -67.945)
		(width 0.1016)
		(layer "In5.Cu")
		(net "3008_SAS_RX_P0")
	)
	(segment
		(start 86.118192 -38.047422)
		(end 86.333584 -37.83203)
		(width 0.1016)
		(layer "In5.Cu")
		(net "3008_SAS_RX_P0")
	)
	(segment
		(start 83.57362 -45.269404)
		(end 83.57362 -44.964604)
		(width 0.1016)
		(layer "In5.Cu")
		(net "3008_SAS_RX_P0")
	)
	(segment
		(start 96.236536 -67.44081)
		(end 87.743792 -58.948066)
		(width 0.1016)
		(layer "In5.Cu")
		(net "3008_SAS_RX_P0")
	)
	(segment
		(start 86.51367 -57.398158)
		(end 86.298024 -57.182512)
		(width 0.1016)
		(layer "In5.Cu")
		(net "3008_SAS_RX_P0")
	)
	(segment
		(start 119.674894 -72.8218)
		(end 110.717838 -72.8218)
		(width 0.1016)
		(layer "In5.Cu")
		(net "3008_SAS_RX_P0")
	)
	(segment
		(start 104.394 -67.944746)
		(end 104.394 -67.945)
		(width 0.1016)
		(layer "In5.Cu")
		(net "3008_SAS_RX_P0")
	)
	(segment
		(start 86.813136 -37.672264)
		(end 87.028782 -37.456618)
		(width 0.1016)
		(layer "In5.Cu")
		(net "3008_SAS_RX_P0")
	)
	(segment
		(start 83.34756 -50.419508)
		(end 83.34756 -50.114708)
		(width 0.1016)
		(layer "In5.Cu")
		(net "3008_SAS_RX_P0")
	)
	(segment
		(start 106.172508 -68.707508)
		(end 106.12882 -68.663566)
		(width 0.1016)
		(layer "In5.Cu")
		(net "3008_SAS_RX_P0")
	)
	(segment
		(start 89.302336 -34.936684)
		(end 92.8624 -34.936684)
		(width 0.1016)
		(layer "In5.Cu")
		(net "3008_SAS_RX_P0")
	)
	(segment
		(start 126.557278 -74.422)
		(end 122.735594 -74.422)
		(width 0.1016)
		(layer "In5.Cu")
		(net "3008_SAS_RX_P0")
	)
	(segment
		(start 84.748116 -55.95239)
		(end 84.019136 -55.22341)
		(width 0.1016)
		(layer "In5.Cu")
		(net "3008_SAS_RX_P0")
	)
	(segment
		(start 85.74278 -38.74262)
		(end 85.958172 -38.526974)
		(width 0.1016)
		(layer "In5.Cu")
		(net "3008_SAS_RX_P0")
	)
	(segment
		(start 86.888828 -58.093102)
		(end 86.673436 -57.87771)
		(width 0.1016)
		(layer "In5.Cu")
		(net "3008_SAS_RX_P0")
	)
	(segment
		(start 93.467682 -34.685986)
		(end 93.547184 -34.606484)
		(width 0.1016)
		(layer "In5.Cu")
		(net "3008_SAS_RX_P0")
	)
	(segment
		(start 87.188548 -36.977066)
		(end 87.40394 -36.761674)
		(width 0.1016)
		(layer "In5.Cu")
		(net "3008_SAS_RX_P0")
	)
	(segment
		(start 131.160012 -77.947012)
		(end 128.397 -75.184)
		(width 0.1016)
		(layer "In5.Cu")
		(net "3008_SAS_RX_P0")
	)
	(segment
		(start 85.818472 -57.022746)
		(end 85.60308 -56.807354)
		(width 0.1016)
		(layer "In5.Cu")
		(net "3008_SAS_RX_P0")
	)
	(segment
		(start 83.57362 -49.662588)
		(end 83.57362 -49.357788)
		(width 0.1016)
		(layer "In5.Cu")
		(net "3008_SAS_RX_P0")
	)
	(segment
		(start 83.57362 -52.690268)
		(end 83.57362 -52.385468)
		(width 0.1016)
		(layer "In5.Cu")
		(net "3008_SAS_RX_P0")
	)
	(segment
		(start 132.005324 -79.756)
		(end 131.841494 -79.592424)
		(width 0.1016)
		(layer "In5.Cu")
		(net "3008_SAS_RX_P0")
	)
	(segment
		(start 85.44306 -56.327802)
		(end 85.227668 -56.112156)
		(width 0.1016)
		(layer "In5.Cu")
		(net "3008_SAS_RX_P0")
	)
	(segment
		(start 83.34756 -53.6956)
		(end 83.34756 -53.142388)
		(width 0.1016)
		(layer "In5.Cu")
		(net "3008_SAS_RX_P0")
	)
	(segment
		(start 87.584026 -58.468514)
		(end 87.36838 -58.253122)
		(width 0.1016)
		(layer "In5.Cu")
		(net "3008_SAS_RX_P0")
	)
	(segment
		(start 83.57362 -51.176428)
		(end 83.57362 -50.871628)
		(width 0.1016)
		(layer "In5.Cu")
		(net "3008_SAS_RX_P0")
	)
	(segment
		(start 87.883492 -36.601654)
		(end 88.099138 -36.386262)
		(width 0.1016)
		(layer "In5.Cu")
		(net "3008_SAS_RX_P0")
	)
	(segment
		(start 83.399884 -40.76573)
		(end 85.263228 -38.902386)
		(width 0.1016)
		(layer "In5.Cu")
		(net "3008_SAS_RX_P0")
	)
	(segment
		(start 109.982 -72.517)
		(end 106.172508 -68.707508)
		(width 0.1016)
		(layer "In5.Cu")
		(net "3008_SAS_RX_P0")
	)
	(segment
		(start 83.34756 -44.512484)
		(end 83.34756 -40.89146)
		(width 0.1016)
		(layer "In5.Cu")
		(net "3008_SAS_RX_P0")
	)
	(segment
		(start 83.34756 -48.905668)
		(end 83.34756 -45.721524)
		(width 0.1016)
		(layer "In5.Cu")
		(net "3008_SAS_RX_P0")
	)
	(segment
		(start 83.34756 -51.933348)
		(end 83.34756 -51.628548)
		(width 0.1016)
		(layer "In5.Cu")
		(net "3008_SAS_RX_P0")
	)
	(segment
		(start 121.056908 -73.726294)
		(end 120.488964 -73.159112)
		(width 0.1016)
		(layer "In5.Cu")
		(net "3008_SAS_RX_P0")
	)
	(segment
		(start 88.258904 -35.90671)
		(end 89.176606 -34.989008)
		(width 0.1016)
		(layer "In5.Cu")
		(net "3008_SAS_RX_P0")
	)
	(segment
		(start 84.019136 -55.22341)
		(end 83.953096 -55.157116)
		(width 0.1016)
		(layer "In5.Cu")
		(net "3008_SAS_RX_P0")
	)
	(arc
		(start 86.333584 -37.83203)
		(mid 86.443814 -37.763096)
		(end 86.57336 -37.75202)
		(width 0.1016)
		(layer "In5.Cu")
		(net "3008_SAS_RX_P0")
	)
	(arc
		(start 87.643716 -36.681664)
		(mid 87.773261 -36.670614)
		(end 87.883492 -36.601654)
		(width 0.1016)
		(layer "In5.Cu")
		(net "3008_SAS_RX_P0")
	)
	(arc
		(start 86.593426 -57.637934)
		(mid 86.582509 -57.508412)
		(end 86.51367 -57.398158)
		(width 0.1016)
		(layer "In5.Cu")
		(net "3008_SAS_RX_P0")
	)
	(arc
		(start 83.57362 -49.357788)
		(mid 83.544381 -49.231127)
		(end 83.46059 -49.131728)
		(width 0.1016)
		(layer "In5.Cu")
		(net "3008_SAS_RX_P0")
	)
	(arc
		(start 83.46059 -49.131728)
		(mid 83.376753 -49.032352)
		(end 83.34756 -48.905668)
		(width 0.1016)
		(layer "In5.Cu")
		(net "3008_SAS_RX_P0")
	)
	(arc
		(start 83.46059 -50.645568)
		(mid 83.376753 -50.546192)
		(end 83.34756 -50.419508)
		(width 0.1016)
		(layer "In5.Cu")
		(net "3008_SAS_RX_P0")
	)
	(arc
		(start 86.673436 -57.87771)
		(mid 86.604502 -57.76748)
		(end 86.593426 -57.637934)
		(width 0.1016)
		(layer "In5.Cu")
		(net "3008_SAS_RX_P0")
	)
	(arc
		(start 83.46059 -45.495464)
		(mid 83.544427 -45.396088)
		(end 83.57362 -45.269404)
		(width 0.1016)
		(layer "In5.Cu")
		(net "3008_SAS_RX_P0")
	)
	(arc
		(start 128.397 -75.184)
		(mid 127.552928 -74.620009)
		(end 126.557278 -74.422)
		(width 0.1016)
		(layer "In5.Cu")
		(net "3008_SAS_RX_P0")
	)
	(arc
		(start 83.57362 -52.385468)
		(mid 83.544381 -52.258807)
		(end 83.46059 -52.159408)
		(width 0.1016)
		(layer "In5.Cu")
		(net "3008_SAS_RX_P0")
	)
	(arc
		(start 87.028782 -37.456618)
		(mid 87.097618 -37.346363)
		(end 87.108538 -37.216842)
		(width 0.1016)
		(layer "In5.Cu")
		(net "3008_SAS_RX_P0")
	)
	(arc
		(start 88.099138 -36.386262)
		(mid 88.168072 -36.276032)
		(end 88.179148 -36.146486)
		(width 0.1016)
		(layer "In5.Cu")
		(net "3008_SAS_RX_P0")
	)
	(arc
		(start 86.298024 -57.182512)
		(mid 86.187769 -57.113676)
		(end 86.058248 -57.102756)
		(width 0.1016)
		(layer "In5.Cu")
		(net "3008_SAS_RX_P0")
	)
	(arc
		(start 87.108538 -37.216842)
		(mid 87.119581 -37.087285)
		(end 87.188548 -36.977066)
		(width 0.1016)
		(layer "In5.Cu")
		(net "3008_SAS_RX_P0")
	)
	(arc
		(start 83.953096 -55.157116)
		(mid 83.504966 -54.486582)
		(end 83.34756 -53.6956)
		(width 0.1016)
		(layer "In5.Cu")
		(net "3008_SAS_RX_P0")
	)
	(arc
		(start 85.60308 -56.807354)
		(mid 85.534083 -56.697135)
		(end 85.52307 -56.567578)
		(width 0.1016)
		(layer "In5.Cu")
		(net "3008_SAS_RX_P0")
	)
	(arc
		(start 85.227668 -56.112156)
		(mid 85.117438 -56.043222)
		(end 84.987892 -56.032146)
		(width 0.1016)
		(layer "In5.Cu")
		(net "3008_SAS_RX_P0")
	)
	(arc
		(start 83.34756 -45.721524)
		(mid 83.376799 -45.594863)
		(end 83.46059 -45.495464)
		(width 0.1016)
		(layer "In5.Cu")
		(net "3008_SAS_RX_P0")
	)
	(arc
		(start 83.57362 -50.871628)
		(mid 83.544381 -50.744967)
		(end 83.46059 -50.645568)
		(width 0.1016)
		(layer "In5.Cu")
		(net "3008_SAS_RX_P0")
	)
	(arc
		(start 131.841494 -79.592424)
		(mid 131.735989 -79.434386)
		(end 131.699 -79.248)
		(width 0.1016)
		(layer "In5.Cu")
		(net "3008_SAS_RX_P0")
	)
	(arc
		(start 83.34756 -51.628548)
		(mid 83.376799 -51.501887)
		(end 83.46059 -51.402488)
		(width 0.1016)
		(layer "In5.Cu")
		(net "3008_SAS_RX_P0")
	)
	(arc
		(start 86.57336 -37.75202)
		(mid 86.702882 -37.741103)
		(end 86.813136 -37.672264)
		(width 0.1016)
		(layer "In5.Cu")
		(net "3008_SAS_RX_P0")
	)
	(arc
		(start 87.743792 -58.948066)
		(mid 87.674956 -58.837811)
		(end 87.664036 -58.70829)
		(width 0.1016)
		(layer "In5.Cu")
		(net "3008_SAS_RX_P0")
	)
	(arc
		(start 83.34756 -53.142388)
		(mid 83.376799 -53.015727)
		(end 83.46059 -52.916328)
		(width 0.1016)
		(layer "In5.Cu")
		(net "3008_SAS_RX_P0")
	)
	(arc
		(start 83.46059 -52.159408)
		(mid 83.376753 -52.060032)
		(end 83.34756 -51.933348)
		(width 0.1016)
		(layer "In5.Cu")
		(net "3008_SAS_RX_P0")
	)
	(arc
		(start 87.36838 -58.253122)
		(mid 87.258161 -58.184125)
		(end 87.128604 -58.173112)
		(width 0.1016)
		(layer "In5.Cu")
		(net "3008_SAS_RX_P0")
	)
	(arc
		(start 87.664036 -58.70829)
		(mid 87.652993 -58.578733)
		(end 87.584026 -58.468514)
		(width 0.1016)
		(layer "In5.Cu")
		(net "3008_SAS_RX_P0")
	)
	(arc
		(start 83.46059 -52.916328)
		(mid 83.544427 -52.816952)
		(end 83.57362 -52.690268)
		(width 0.1016)
		(layer "In5.Cu")
		(net "3008_SAS_RX_P0")
	)
	(arc
		(start 84.987892 -56.032146)
		(mid 84.85837 -56.021229)
		(end 84.748116 -55.95239)
		(width 0.1016)
		(layer "In5.Cu")
		(net "3008_SAS_RX_P0")
	)
	(arc
		(start 89.176606 -34.989008)
		(mid 89.234276 -34.950381)
		(end 89.302336 -34.936684)
		(width 0.1016)
		(layer "In5.Cu")
		(net "3008_SAS_RX_P0")
	)
	(arc
		(start 88.179148 -36.146486)
		(mid 88.190065 -36.016964)
		(end 88.258904 -35.90671)
		(width 0.1016)
		(layer "In5.Cu")
		(net "3008_SAS_RX_P0")
	)
	(arc
		(start 83.34756 -40.89146)
		(mid 83.361196 -40.823375)
		(end 83.399884 -40.76573)
		(width 0.1016)
		(layer "In5.Cu")
		(net "3008_SAS_RX_P0")
	)
	(arc
		(start 83.57362 -44.964604)
		(mid 83.544381 -44.837943)
		(end 83.46059 -44.738544)
		(width 0.1016)
		(layer "In5.Cu")
		(net "3008_SAS_RX_P0")
	)
	(arc
		(start 86.038182 -38.287198)
		(mid 86.049232 -38.157653)
		(end 86.118192 -38.047422)
		(width 0.1016)
		(layer "In5.Cu")
		(net "3008_SAS_RX_P0")
	)
	(arc
		(start 97.453704 -67.945)
		(mid 96.794969 -67.813969)
		(end 96.236536 -67.44081)
		(width 0.1016)
		(layer "In5.Cu")
		(net "3008_SAS_RX_P0")
	)
	(arc
		(start 106.12882 -68.663566)
		(mid 105.332921 -68.131573)
		(end 104.394 -67.944746)
		(width 0.1016)
		(layer "In5.Cu")
		(net "3008_SAS_RX_P0")
	)
	(arc
		(start 110.717838 -72.8218)
		(mid 110.319603 -72.742586)
		(end 109.982 -72.517)
		(width 0.1016)
		(layer "In5.Cu")
		(net "3008_SAS_RX_P0")
	)
	(arc
		(start 87.40394 -36.761674)
		(mid 87.514159 -36.692677)
		(end 87.643716 -36.681664)
		(width 0.1016)
		(layer "In5.Cu")
		(net "3008_SAS_RX_P0")
	)
	(arc
		(start 122.735594 -74.422)
		(mid 121.827036 -74.241147)
		(end 121.056908 -73.726294)
		(width 0.1016)
		(layer "In5.Cu")
		(net "3008_SAS_RX_P0")
	)
	(arc
		(start 83.46059 -44.738544)
		(mid 83.376753 -44.639168)
		(end 83.34756 -44.512484)
		(width 0.1016)
		(layer "In5.Cu")
		(net "3008_SAS_RX_P0")
	)
	(arc
		(start 85.958172 -38.526974)
		(mid 86.027169 -38.416755)
		(end 86.038182 -38.287198)
		(width 0.1016)
		(layer "In5.Cu")
		(net "3008_SAS_RX_P0")
	)
	(arc
		(start 85.263228 -38.902386)
		(mid 85.373483 -38.83355)
		(end 85.503004 -38.82263)
		(width 0.1016)
		(layer "In5.Cu")
		(net "3008_SAS_RX_P0")
	)
	(arc
		(start 83.46059 -51.402488)
		(mid 83.544427 -51.303112)
		(end 83.57362 -51.176428)
		(width 0.1016)
		(layer "In5.Cu")
		(net "3008_SAS_RX_P0")
	)
	(arc
		(start 120.488964 -73.159112)
		(mid 120.115452 -72.909573)
		(end 119.674894 -72.8218)
		(width 0.1016)
		(layer "In5.Cu")
		(net "3008_SAS_RX_P0")
	)
	(arc
		(start 85.52307 -56.567578)
		(mid 85.51202 -56.438033)
		(end 85.44306 -56.327802)
		(width 0.1016)
		(layer "In5.Cu")
		(net "3008_SAS_RX_P0")
	)
	(arc
		(start 92.8624 -34.936684)
		(mid 93.189969 -34.871526)
		(end 93.467682 -34.685986)
		(width 0.1016)
		(layer "In5.Cu")
		(net "3008_SAS_RX_P0")
	)
	(arc
		(start 131.699 -79.248)
		(mid 131.558925 -78.543886)
		(end 131.160012 -77.947012)
		(width 0.1016)
		(layer "In5.Cu")
		(net "3008_SAS_RX_P0")
	)
	(arc
		(start 86.058248 -57.102756)
		(mid 85.928691 -57.091713)
		(end 85.818472 -57.022746)
		(width 0.1016)
		(layer "In5.Cu")
		(net "3008_SAS_RX_P0")
	)
	(arc
		(start 87.128604 -58.173112)
		(mid 86.999059 -58.162062)
		(end 86.888828 -58.093102)
		(width 0.1016)
		(layer "In5.Cu")
		(net "3008_SAS_RX_P0")
	)
	(arc
		(start 85.503004 -38.82263)
		(mid 85.632561 -38.811587)
		(end 85.74278 -38.74262)
		(width 0.1016)
		(layer "In5.Cu")
		(net "3008_SAS_RX_P0")
	)
	(arc
		(start 83.34756 -50.114708)
		(mid 83.376799 -49.988047)
		(end 83.46059 -49.888648)
		(width 0.1016)
		(layer "In5.Cu")
		(net "3008_SAS_RX_P0")
	)
	(arc
		(start 83.46059 -49.888648)
		(mid 83.544427 -49.789272)
		(end 83.57362 -49.662588)
		(width 0.1016)
		(layer "In5.Cu")
		(net "3008_SAS_RX_P0")
	)
	(segment
		(start 169.93235 -113.492534)
		(end 169.93235 -112.19815)
		(width 0.3048)
		(layer "F.Cu")
		(net "P0V9_E_VBST")
	)
	(via
		(at 169.93235 -112.19815)
		(size 0.5588)
		(drill 0.3048)
		(layers "F.Cu" "B.Cu")
		(net "P0V9_E_VBST")
	)
	(via
		(at 168.8846 -112.2172)
		(size 0.7112)
		(drill 0.3556)
		(layers "F.Cu" "B.Cu")
		(net "P0V9_E_VBST")
	)
	(segment
		(start 168.91 -112.2426)
		(end 168.8846 -112.2172)
		(width 0.508)
		(layer "B.Cu")
		(net "P0V9_E_VBST")
	)
	(segment
		(start 168.91 -113.284)
		(end 168.91 -112.2426)
		(width 0.508)
		(layer "B.Cu")
		(net "P0V9_E_VBST")
	)
	(segment
		(start 169.93235 -112.19815)
		(end 168.90365 -112.19815)
		(width 0.508)
		(layer "B.Cu")
		(net "P0V9_E_VBST")
	)
	(segment
		(start 168.90365 -112.19815)
		(end 168.8846 -112.2172)
		(width 0.508)
		(layer "B.Cu")
		(net "P0V9_E_VBST")
	)
	(segment
		(start 64.32169 -129.10058)
		(end 64.43599 -128.98628)
		(width 0.1143)
		(layer "F.Cu")
		(net "EXP_XM_ADDR_7")
	)
	(segment
		(start 56.558942 -129.892552)
		(end 57.340754 -129.892552)
		(width 0.1143)
		(layer "F.Cu")
		(net "EXP_XM_ADDR_7")
	)
	(segment
		(start 63.03899 -129.10058)
		(end 63.40729 -129.10058)
		(width 0.1143)
		(layer "F.Cu")
		(net "EXP_XM_ADDR_7")
	)
	(segment
		(start 64.43599 -127.42672)
		(end 64.53251 -127.3302)
		(width 0.1143)
		(layer "F.Cu")
		(net "EXP_XM_ADDR_7")
	)
	(segment
		(start 65.45453 -128.1557)
		(end 65.69583 -128.1557)
		(width 0.1143)
		(layer "F.Cu")
		(net "EXP_XM_ADDR_7")
	)
	(segment
		(start 61.962284 -129.7432)
		(end 62.076584 -129.6289)
		(width 0.1143)
		(layer "F.Cu")
		(net "EXP_XM_ADDR_7")
	)
	(segment
		(start 61.733684 -129.7432)
		(end 61.962284 -129.7432)
		(width 0.1143)
		(layer "F.Cu")
		(net "EXP_XM_ADDR_7")
	)
	(segment
		(start 62.957964 -129.181606)
		(end 63.03899 -129.10058)
		(width 0.1143)
		(layer "F.Cu")
		(net "EXP_XM_ADDR_7")
	)
	(segment
		(start 64.09309 -129.10058)
		(end 64.32169 -129.10058)
		(width 0.1143)
		(layer "F.Cu")
		(net "EXP_XM_ADDR_7")
	)
	(segment
		(start 65.35039 -128.98628)
		(end 65.35039 -128.25984)
		(width 0.1143)
		(layer "F.Cu")
		(net "EXP_XM_ADDR_7")
	)
	(segment
		(start 60.362084 -129.096008)
		(end 60.590684 -129.096008)
		(width 0.1143)
		(layer "F.Cu")
		(net "EXP_XM_ADDR_7")
	)
	(segment
		(start 61.505084 -129.096008)
		(end 61.619384 -129.210308)
		(width 0.1143)
		(layer "F.Cu")
		(net "EXP_XM_ADDR_7")
	)
	(segment
		(start 63.97879 -128.98628)
		(end 64.09309 -129.10058)
		(width 0.1143)
		(layer "F.Cu")
		(net "EXP_XM_ADDR_7")
	)
	(segment
		(start 60.590684 -129.096008)
		(end 60.704984 -129.210308)
		(width 0.1143)
		(layer "F.Cu")
		(net "EXP_XM_ADDR_7")
	)
	(segment
		(start 60.819284 -129.7432)
		(end 61.047884 -129.7432)
		(width 0.1143)
		(layer "F.Cu")
		(net "EXP_XM_ADDR_7")
	)
	(segment
		(start 65.80759 -128.98628)
		(end 65.92189 -129.10058)
		(width 0.1143)
		(layer "F.Cu")
		(net "EXP_XM_ADDR_7")
	)
	(segment
		(start 62.533784 -129.210308)
		(end 62.533784 -129.6289)
		(width 0.1143)
		(layer "F.Cu")
		(net "EXP_XM_ADDR_7")
	)
	(segment
		(start 63.52159 -127.33274)
		(end 63.62827 -127.22606)
		(width 0.1143)
		(layer "F.Cu")
		(net "EXP_XM_ADDR_7")
	)
	(segment
		(start 65.80759 -128.26746)
		(end 65.80759 -128.98628)
		(width 0.1143)
		(layer "F.Cu")
		(net "EXP_XM_ADDR_7")
	)
	(segment
		(start 61.047884 -129.7432)
		(end 61.162184 -129.6289)
		(width 0.1143)
		(layer "F.Cu")
		(net "EXP_XM_ADDR_7")
	)
	(segment
		(start 61.162184 -129.210308)
		(end 61.276484 -129.096008)
		(width 0.1143)
		(layer "F.Cu")
		(net "EXP_XM_ADDR_7")
	)
	(segment
		(start 61.619384 -129.210308)
		(end 61.619384 -129.6289)
		(width 0.1143)
		(layer "F.Cu")
		(net "EXP_XM_ADDR_7")
	)
	(segment
		(start 57.400952 -129.95275)
		(end 59.830462 -129.95275)
		(width 0.1143)
		(layer "F.Cu")
		(net "EXP_XM_ADDR_7")
	)
	(segment
		(start 64.89319 -127.465074)
		(end 64.89319 -128.98628)
		(width 0.1143)
		(layer "F.Cu")
		(net "EXP_XM_ADDR_7")
	)
	(segment
		(start 64.758316 -127.3302)
		(end 64.89319 -127.465074)
		(width 0.1143)
		(layer "F.Cu")
		(net "EXP_XM_ADDR_7")
	)
	(segment
		(start 61.619384 -129.6289)
		(end 61.733684 -129.7432)
		(width 0.1143)
		(layer "F.Cu")
		(net "EXP_XM_ADDR_7")
	)
	(segment
		(start 102.349808 -91.34983)
		(end 100.39858 -91.34983)
		(width 0.1143)
		(layer "F.Cu")
		(net "EXP_XM_ADDR_7")
	)
	(segment
		(start 64.89319 -128.98628)
		(end 65.00749 -129.10058)
		(width 0.1143)
		(layer "F.Cu")
		(net "EXP_XM_ADDR_7")
	)
	(segment
		(start 62.533784 -129.6289)
		(end 62.648084 -129.7432)
		(width 0.1143)
		(layer "F.Cu")
		(net "EXP_XM_ADDR_7")
	)
	(segment
		(start 63.84036 -127.22606)
		(end 63.97879 -127.36449)
		(width 0.1143)
		(layer "F.Cu")
		(net "EXP_XM_ADDR_7")
	)
	(segment
		(start 61.276484 -129.096008)
		(end 61.505084 -129.096008)
		(width 0.1143)
		(layer "F.Cu")
		(net "EXP_XM_ADDR_7")
	)
	(segment
		(start 65.23609 -129.10058)
		(end 65.35039 -128.98628)
		(width 0.1143)
		(layer "F.Cu")
		(net "EXP_XM_ADDR_7")
	)
	(segment
		(start 63.70447 -129.9337)
		(end 63.51397 -129.7432)
		(width 0.1143)
		(layer "F.Cu")
		(net "EXP_XM_ADDR_7")
	)
	(segment
		(start 100.39858 -91.34983)
		(end 100.37826 -91.37015)
		(width 0.1143)
		(layer "F.Cu")
		(net "EXP_XM_ADDR_7")
	)
	(segment
		(start 63.62827 -127.22606)
		(end 63.84036 -127.22606)
		(width 0.1143)
		(layer "F.Cu")
		(net "EXP_XM_ADDR_7")
	)
	(segment
		(start 62.419484 -129.096008)
		(end 62.533784 -129.210308)
		(width 0.1143)
		(layer "F.Cu")
		(net "EXP_XM_ADDR_7")
	)
	(segment
		(start 62.076584 -129.210308)
		(end 62.190884 -129.096008)
		(width 0.1143)
		(layer "F.Cu")
		(net "EXP_XM_ADDR_7")
	)
	(segment
		(start 65.92189 -129.10058)
		(end 66.47815 -129.10058)
		(width 0.1143)
		(layer "F.Cu")
		(net "EXP_XM_ADDR_7")
	)
	(segment
		(start 59.830462 -129.95275)
		(end 60.040012 -129.7432)
		(width 0.1143)
		(layer "F.Cu")
		(net "EXP_XM_ADDR_7")
	)
	(segment
		(start 65.00749 -129.10058)
		(end 65.23609 -129.10058)
		(width 0.1143)
		(layer "F.Cu")
		(net "EXP_XM_ADDR_7")
	)
	(segment
		(start 57.340754 -129.892552)
		(end 57.400952 -129.95275)
		(width 0.1143)
		(layer "F.Cu")
		(net "EXP_XM_ADDR_7")
	)
	(segment
		(start 62.957964 -129.643886)
		(end 62.957964 -129.181606)
		(width 0.1143)
		(layer "F.Cu")
		(net "EXP_XM_ADDR_7")
	)
	(segment
		(start 60.247784 -129.6289)
		(end 60.247784 -129.210308)
		(width 0.1143)
		(layer "F.Cu")
		(net "EXP_XM_ADDR_7")
	)
	(segment
		(start 62.648084 -129.7432)
		(end 62.85865 -129.7432)
		(width 0.1143)
		(layer "F.Cu")
		(net "EXP_XM_ADDR_7")
	)
	(segment
		(start 60.704984 -129.210308)
		(end 60.704984 -129.6289)
		(width 0.1143)
		(layer "F.Cu")
		(net "EXP_XM_ADDR_7")
	)
	(segment
		(start 64.53251 -127.3302)
		(end 64.758316 -127.3302)
		(width 0.1143)
		(layer "F.Cu")
		(net "EXP_XM_ADDR_7")
	)
	(segment
		(start 60.040012 -129.7432)
		(end 60.133484 -129.7432)
		(width 0.1143)
		(layer "F.Cu")
		(net "EXP_XM_ADDR_7")
	)
	(segment
		(start 65.69583 -128.1557)
		(end 65.80759 -128.26746)
		(width 0.1143)
		(layer "F.Cu")
		(net "EXP_XM_ADDR_7")
	)
	(segment
		(start 63.52159 -128.98628)
		(end 63.52159 -127.33274)
		(width 0.1143)
		(layer "F.Cu")
		(net "EXP_XM_ADDR_7")
	)
	(segment
		(start 62.190884 -129.096008)
		(end 62.419484 -129.096008)
		(width 0.1143)
		(layer "F.Cu")
		(net "EXP_XM_ADDR_7")
	)
	(segment
		(start 66.73088 -129.75971)
		(end 66.55689 -129.9337)
		(width 0.1143)
		(layer "F.Cu")
		(net "EXP_XM_ADDR_7")
	)
	(segment
		(start 63.97879 -127.36449)
		(end 63.97879 -128.98628)
		(width 0.1143)
		(layer "F.Cu")
		(net "EXP_XM_ADDR_7")
	)
	(segment
		(start 66.47815 -129.10058)
		(end 66.73088 -129.35331)
		(width 0.1143)
		(layer "F.Cu")
		(net "EXP_XM_ADDR_7")
	)
	(segment
		(start 64.43599 -128.98628)
		(end 64.43599 -127.42672)
		(width 0.1143)
		(layer "F.Cu")
		(net "EXP_XM_ADDR_7")
	)
	(segment
		(start 60.704984 -129.6289)
		(end 60.819284 -129.7432)
		(width 0.1143)
		(layer "F.Cu")
		(net "EXP_XM_ADDR_7")
	)
	(segment
		(start 66.55689 -129.9337)
		(end 63.70447 -129.9337)
		(width 0.1143)
		(layer "F.Cu")
		(net "EXP_XM_ADDR_7")
	)
	(segment
		(start 61.162184 -129.6289)
		(end 61.162184 -129.210308)
		(width 0.1143)
		(layer "F.Cu")
		(net "EXP_XM_ADDR_7")
	)
	(segment
		(start 63.40729 -129.10058)
		(end 63.52159 -128.98628)
		(width 0.1143)
		(layer "F.Cu")
		(net "EXP_XM_ADDR_7")
	)
	(segment
		(start 100.37826 -91.37015)
		(end 100.30841 -91.37015)
		(width 0.1143)
		(layer "F.Cu")
		(net "EXP_XM_ADDR_7")
	)
	(segment
		(start 60.247784 -129.210308)
		(end 60.362084 -129.096008)
		(width 0.1143)
		(layer "F.Cu")
		(net "EXP_XM_ADDR_7")
	)
	(segment
		(start 65.35039 -128.25984)
		(end 65.45453 -128.1557)
		(width 0.1143)
		(layer "F.Cu")
		(net "EXP_XM_ADDR_7")
	)
	(segment
		(start 62.85865 -129.7432)
		(end 62.957964 -129.643886)
		(width 0.1143)
		(layer "F.Cu")
		(net "EXP_XM_ADDR_7")
	)
	(segment
		(start 66.73088 -129.35331)
		(end 66.73088 -129.75971)
		(width 0.1143)
		(layer "F.Cu")
		(net "EXP_XM_ADDR_7")
	)
	(segment
		(start 60.133484 -129.7432)
		(end 60.247784 -129.6289)
		(width 0.1143)
		(layer "F.Cu")
		(net "EXP_XM_ADDR_7")
	)
	(segment
		(start 62.076584 -129.6289)
		(end 62.076584 -129.210308)
		(width 0.1143)
		(layer "F.Cu")
		(net "EXP_XM_ADDR_7")
	)
	(via
		(at 63.246 -130.4798)
		(size 0.7112)
		(drill 0.3556)
		(layers "F.Cu" "B.Cu")
		(net "EXP_XM_ADDR_7")
	)
	(via
		(at 63.51397 -129.7432)
		(size 0.5588)
		(drill 0.3048)
		(layers "F.Cu" "B.Cu")
		(net "EXP_XM_ADDR_7")
	)
	(via
		(at 100.30841 -91.37015)
		(size 0.508)
		(drill 0.254)
		(layers "F.Cu" "B.Cu")
		(net "EXP_XM_ADDR_7")
	)
	(segment
		(start 63.246 -130.4798)
		(end 63.5 -130.2258)
		(width 0.1143)
		(layer "B.Cu")
		(net "EXP_XM_ADDR_7")
	)
	(segment
		(start 63.5 -130.2258)
		(end 63.5 -129.75717)
		(width 0.1143)
		(layer "B.Cu")
		(net "EXP_XM_ADDR_7")
	)
	(segment
		(start 63.5 -129.75717)
		(end 63.51397 -129.7432)
		(width 0.1143)
		(layer "B.Cu")
		(net "EXP_XM_ADDR_7")
	)
	(segment
		(start 99.66833 -91.618308)
		(end 99.278694 -91.618308)
		(width 0.127)
		(layer "In2.Cu")
		(net "EXP_XM_ADDR_7")
	)
	(segment
		(start 63.93307 -118.923308)
		(end 63.93307 -125.523244)
		(width 0.127)
		(layer "In2.Cu")
		(net "EXP_XM_ADDR_7")
	)
	(segment
		(start 79.16037 -103.696008)
		(end 63.93307 -118.923308)
		(width 0.127)
		(layer "In2.Cu")
		(net "EXP_XM_ADDR_7")
	)
	(segment
		(start 63.53937 -125.916944)
		(end 63.53937 -128.74244)
		(width 0.127)
		(layer "In2.Cu")
		(net "EXP_XM_ADDR_7")
	)
	(segment
		(start 63.53937 -128.74244)
		(end 63.51397 -128.76784)
		(width 0.127)
		(layer "In2.Cu")
		(net "EXP_XM_ADDR_7")
	)
	(segment
		(start 92.588334 -92.403676)
		(end 88.362536 -92.403676)
		(width 0.127)
		(layer "In2.Cu")
		(net "EXP_XM_ADDR_7")
	)
	(segment
		(start 93.41231 -91.5797)
		(end 92.588334 -92.403676)
		(width 0.127)
		(layer "In2.Cu")
		(net "EXP_XM_ADDR_7")
	)
	(segment
		(start 100.30841 -91.37015)
		(end 100.09886 -91.5797)
		(width 0.127)
		(layer "In2.Cu")
		(net "EXP_XM_ADDR_7")
	)
	(segment
		(start 99.240086 -91.5797)
		(end 93.41231 -91.5797)
		(width 0.127)
		(layer "In2.Cu")
		(net "EXP_XM_ADDR_7")
	)
	(segment
		(start 63.93307 -125.523244)
		(end 63.53937 -125.916944)
		(width 0.127)
		(layer "In2.Cu")
		(net "EXP_XM_ADDR_7")
	)
	(segment
		(start 99.278694 -91.618308)
		(end 99.240086 -91.5797)
		(width 0.127)
		(layer "In2.Cu")
		(net "EXP_XM_ADDR_7")
	)
	(segment
		(start 79.16037 -101.605842)
		(end 79.16037 -103.696008)
		(width 0.127)
		(layer "In2.Cu")
		(net "EXP_XM_ADDR_7")
	)
	(segment
		(start 100.09886 -91.5797)
		(end 99.706938 -91.5797)
		(width 0.127)
		(layer "In2.Cu")
		(net "EXP_XM_ADDR_7")
	)
	(segment
		(start 88.362536 -92.403676)
		(end 79.16037 -101.605842)
		(width 0.127)
		(layer "In2.Cu")
		(net "EXP_XM_ADDR_7")
	)
	(segment
		(start 99.706938 -91.5797)
		(end 99.66833 -91.618308)
		(width 0.127)
		(layer "In2.Cu")
		(net "EXP_XM_ADDR_7")
	)
	(segment
		(start 63.51397 -128.76784)
		(end 63.51397 -129.7432)
		(width 0.127)
		(layer "In2.Cu")
		(net "EXP_XM_ADDR_7")
	)
	(segment
		(start 119.857266 -53.934614)
		(end 119.971566 -53.820314)
		(width 0.1143)
		(layer "F.Cu")
		(net "XM_ADDR_16")
	)
	(segment
		(start 117.395752 -51.902614)
		(end 117.268752 -51.775614)
		(width 0.1143)
		(layer "F.Cu")
		(net "XM_ADDR_16")
	)
	(segment
		(start 116.697252 -52.11445)
		(end 115.91417 -52.11445)
		(width 0.1143)
		(layer "F.Cu")
		(net "XM_ADDR_16")
	)
	(segment
		(start 135.952484 -48.697134)
		(end 135.952484 -48.900334)
		(width 0.1143)
		(layer "F.Cu")
		(net "XM_ADDR_16")
	)
	(segment
		(start 118.029736 -52.436014)
		(end 118.029736 -52.029614)
		(width 0.1143)
		(layer "F.Cu")
		(net "XM_ADDR_16")
	)
	(segment
		(start 136.598406 -46.614334)
		(end 136.471406 -46.741334)
		(width 0.1143)
		(layer "F.Cu")
		(net "XM_ADDR_16")
	)
	(segment
		(start 118.029736 -52.029614)
		(end 117.902736 -51.902614)
		(width 0.1143)
		(layer "F.Cu")
		(net "XM_ADDR_16")
	)
	(segment
		(start 119.971566 -52.905914)
		(end 119.971566 -52.677314)
		(width 0.1143)
		(layer "F.Cu")
		(net "XM_ADDR_16")
	)
	(segment
		(start 135.419084 -47.655734)
		(end 135.304784 -47.770034)
		(width 0.1143)
		(layer "F.Cu")
		(net "XM_ADDR_16")
	)
	(segment
		(start 136.471406 -48.112934)
		(end 136.598406 -48.239934)
		(width 0.1143)
		(layer "F.Cu")
		(net "XM_ADDR_16")
	)
	(segment
		(start 136.471406 -46.741334)
		(end 135.419084 -46.741334)
		(width 0.1143)
		(layer "F.Cu")
		(net "XM_ADDR_16")
	)
	(segment
		(start 118.156736 -52.563014)
		(end 118.029736 -52.436014)
		(width 0.1143)
		(layer "F.Cu")
		(net "XM_ADDR_16")
	)
	(segment
		(start 117.902736 -51.902614)
		(end 117.395752 -51.902614)
		(width 0.1143)
		(layer "F.Cu")
		(net "XM_ADDR_16")
	)
	(segment
		(start 136.598406 -45.699934)
		(end 136.471406 -45.826934)
		(width 0.1143)
		(layer "F.Cu")
		(net "XM_ADDR_16")
	)
	(segment
		(start 135.304784 -46.855634)
		(end 135.304784 -47.084234)
		(width 0.1143)
		(layer "F.Cu")
		(net "XM_ADDR_16")
	)
	(segment
		(start 116.811552 -50.781712)
		(end 116.811552 -52.00015)
		(width 0.1143)
		(layer "F.Cu")
		(net "XM_ADDR_16")
	)
	(segment
		(start 119.857266 -52.563014)
		(end 118.156736 -52.563014)
		(width 0.1143)
		(layer "F.Cu")
		(net "XM_ADDR_16")
	)
	(segment
		(start 136.779 -40.64)
		(end 136.779 -40.894)
		(width 0.1143)
		(layer "F.Cu")
		(net "XM_ADDR_16")
	)
	(segment
		(start 118.156736 -53.934614)
		(end 119.857266 -53.934614)
		(width 0.1143)
		(layer "F.Cu")
		(net "XM_ADDR_16")
	)
	(segment
		(start 135.419084 -45.369734)
		(end 136.471406 -45.369734)
		(width 0.1143)
		(layer "F.Cu")
		(net "XM_ADDR_16")
	)
	(segment
		(start 136.779 -40.894)
		(end 136.598406 -41.074594)
		(width 0.1143)
		(layer "F.Cu")
		(net "XM_ADDR_16")
	)
	(segment
		(start 136.471406 -44.912534)
		(end 135.419084 -44.912534)
		(width 0.1143)
		(layer "F.Cu")
		(net "XM_ADDR_16")
	)
	(segment
		(start 118.156736 -53.477414)
		(end 118.029736 -53.350414)
		(width 0.1143)
		(layer "F.Cu")
		(net "XM_ADDR_16")
	)
	(segment
		(start 136.471406 -45.369734)
		(end 136.598406 -45.496734)
		(width 0.1143)
		(layer "F.Cu")
		(net "XM_ADDR_16")
	)
	(segment
		(start 136.598406 -47.528734)
		(end 136.471406 -47.655734)
		(width 0.1143)
		(layer "F.Cu")
		(net "XM_ADDR_16")
	)
	(segment
		(start 135.419084 -46.284134)
		(end 136.471406 -46.284134)
		(width 0.1143)
		(layer "F.Cu")
		(net "XM_ADDR_16")
	)
	(segment
		(start 119.971566 -53.820314)
		(end 119.971566 -53.591714)
		(width 0.1143)
		(layer "F.Cu")
		(net "XM_ADDR_16")
	)
	(segment
		(start 135.304784 -47.998634)
		(end 135.419084 -48.112934)
		(width 0.1143)
		(layer "F.Cu")
		(net "XM_ADDR_16")
	)
	(segment
		(start 118.029736 -53.350414)
		(end 118.029736 -53.147214)
		(width 0.1143)
		(layer "F.Cu")
		(net "XM_ADDR_16")
	)
	(segment
		(start 135.419084 -48.112934)
		(end 136.471406 -48.112934)
		(width 0.1143)
		(layer "F.Cu")
		(net "XM_ADDR_16")
	)
	(segment
		(start 136.471406 -45.826934)
		(end 135.419084 -45.826934)
		(width 0.1143)
		(layer "F.Cu")
		(net "XM_ADDR_16")
	)
	(segment
		(start 136.598406 -48.443134)
		(end 136.471406 -48.570134)
		(width 0.1143)
		(layer "F.Cu")
		(net "XM_ADDR_16")
	)
	(segment
		(start 136.471406 -46.284134)
		(end 136.598406 -46.411134)
		(width 0.1143)
		(layer "F.Cu")
		(net "XM_ADDR_16")
	)
	(segment
		(start 118.029736 -54.061614)
		(end 118.156736 -53.934614)
		(width 0.1143)
		(layer "F.Cu")
		(net "XM_ADDR_16")
	)
	(segment
		(start 135.952484 -48.900334)
		(end 136.079484 -49.027334)
		(width 0.1143)
		(layer "F.Cu")
		(net "XM_ADDR_16")
	)
	(segment
		(start 135.419084 -44.912534)
		(end 135.304784 -45.026834)
		(width 0.1143)
		(layer "F.Cu")
		(net "XM_ADDR_16")
	)
	(segment
		(start 136.598406 -47.325534)
		(end 136.598406 -47.528734)
		(width 0.1143)
		(layer "F.Cu")
		(net "XM_ADDR_16")
	)
	(segment
		(start 136.598406 -41.074594)
		(end 136.598406 -42.7101)
		(width 0.1143)
		(layer "F.Cu")
		(net "XM_ADDR_16")
	)
	(segment
		(start 113.716816 -52.20335)
		(end 113.320322 -52.599844)
		(width 0.1143)
		(layer "F.Cu")
		(net "XM_ADDR_16")
	)
	(segment
		(start 135.419084 -47.198534)
		(end 136.471406 -47.198534)
		(width 0.1143)
		(layer "F.Cu")
		(net "XM_ADDR_16")
	)
	(segment
		(start 136.471406 -47.198534)
		(end 136.598406 -47.325534)
		(width 0.1143)
		(layer "F.Cu")
		(net "XM_ADDR_16")
	)
	(segment
		(start 136.598406 -42.7101)
		(end 136.598406 -44.785534)
		(width 0.1143)
		(layer "F.Cu")
		(net "XM_ADDR_16")
	)
	(segment
		(start 135.304784 -45.941234)
		(end 135.304784 -46.169834)
		(width 0.1143)
		(layer "F.Cu")
		(net "XM_ADDR_16")
	)
	(segment
		(start 119.857266 -53.020214)
		(end 119.971566 -52.905914)
		(width 0.1143)
		(layer "F.Cu")
		(net "XM_ADDR_16")
	)
	(segment
		(start 117.268752 -50.781712)
		(end 117.141752 -50.654712)
		(width 0.1143)
		(layer "F.Cu")
		(net "XM_ADDR_16")
	)
	(segment
		(start 119.857266 -53.477414)
		(end 118.156736 -53.477414)
		(width 0.1143)
		(layer "F.Cu")
		(net "XM_ADDR_16")
	)
	(segment
		(start 136.471406 -47.655734)
		(end 135.419084 -47.655734)
		(width 0.1143)
		(layer "F.Cu")
		(net "XM_ADDR_16")
	)
	(segment
		(start 119.971566 -52.677314)
		(end 119.857266 -52.563014)
		(width 0.1143)
		(layer "F.Cu")
		(net "XM_ADDR_16")
	)
	(segment
		(start 135.419084 -45.826934)
		(end 135.304784 -45.941234)
		(width 0.1143)
		(layer "F.Cu")
		(net "XM_ADDR_16")
	)
	(segment
		(start 115.91417 -52.11445)
		(end 115.82527 -52.20335)
		(width 0.1143)
		(layer "F.Cu")
		(net "XM_ADDR_16")
	)
	(segment
		(start 135.304784 -45.026834)
		(end 135.304784 -45.255434)
		(width 0.1143)
		(layer "F.Cu")
		(net "XM_ADDR_16")
	)
	(segment
		(start 116.811552 -52.00015)
		(end 116.697252 -52.11445)
		(width 0.1143)
		(layer "F.Cu")
		(net "XM_ADDR_16")
	)
	(segment
		(start 136.598406 -46.411134)
		(end 136.598406 -46.614334)
		(width 0.1143)
		(layer "F.Cu")
		(net "XM_ADDR_16")
	)
	(segment
		(start 118.156736 -53.020214)
		(end 119.857266 -53.020214)
		(width 0.1143)
		(layer "F.Cu")
		(net "XM_ADDR_16")
	)
	(segment
		(start 119.971566 -53.591714)
		(end 119.857266 -53.477414)
		(width 0.1143)
		(layer "F.Cu")
		(net "XM_ADDR_16")
	)
	(segment
		(start 117.141752 -50.654712)
		(end 116.938552 -50.654712)
		(width 0.1143)
		(layer "F.Cu")
		(net "XM_ADDR_16")
	)
	(segment
		(start 113.320322 -52.599844)
		(end 113.150142 -52.599844)
		(width 0.1143)
		(layer "F.Cu")
		(net "XM_ADDR_16")
	)
	(segment
		(start 117.268752 -51.775614)
		(end 117.268752 -50.781712)
		(width 0.1143)
		(layer "F.Cu")
		(net "XM_ADDR_16")
	)
	(segment
		(start 136.598406 -50.18151)
		(end 136.519666 -50.26025)
		(width 0.1143)
		(layer "F.Cu")
		(net "XM_ADDR_16")
	)
	(segment
		(start 118.029736 -53.147214)
		(end 118.156736 -53.020214)
		(width 0.1143)
		(layer "F.Cu")
		(net "XM_ADDR_16")
	)
	(segment
		(start 136.471406 -49.027334)
		(end 136.598406 -49.154334)
		(width 0.1143)
		(layer "F.Cu")
		(net "XM_ADDR_16")
	)
	(segment
		(start 135.419084 -46.741334)
		(end 135.304784 -46.855634)
		(width 0.1143)
		(layer "F.Cu")
		(net "XM_ADDR_16")
	)
	(segment
		(start 136.079484 -49.027334)
		(end 136.471406 -49.027334)
		(width 0.1143)
		(layer "F.Cu")
		(net "XM_ADDR_16")
	)
	(segment
		(start 136.598406 -45.496734)
		(end 136.598406 -45.699934)
		(width 0.1143)
		(layer "F.Cu")
		(net "XM_ADDR_16")
	)
	(segment
		(start 135.304784 -47.770034)
		(end 135.304784 -47.998634)
		(width 0.1143)
		(layer "F.Cu")
		(net "XM_ADDR_16")
	)
	(segment
		(start 136.471406 -48.570134)
		(end 136.079484 -48.570134)
		(width 0.1143)
		(layer "F.Cu")
		(net "XM_ADDR_16")
	)
	(segment
		(start 136.598406 -44.785534)
		(end 136.471406 -44.912534)
		(width 0.1143)
		(layer "F.Cu")
		(net "XM_ADDR_16")
	)
	(segment
		(start 115.82527 -52.20335)
		(end 113.716816 -52.20335)
		(width 0.1143)
		(layer "F.Cu")
		(net "XM_ADDR_16")
	)
	(segment
		(start 135.304784 -45.255434)
		(end 135.419084 -45.369734)
		(width 0.1143)
		(layer "F.Cu")
		(net "XM_ADDR_16")
	)
	(segment
		(start 118.00078 -54.8005)
		(end 118.029736 -54.771544)
		(width 0.1143)
		(layer "F.Cu")
		(net "XM_ADDR_16")
	)
	(segment
		(start 135.304784 -46.169834)
		(end 135.419084 -46.284134)
		(width 0.1143)
		(layer "F.Cu")
		(net "XM_ADDR_16")
	)
	(segment
		(start 116.938552 -50.654712)
		(end 116.811552 -50.781712)
		(width 0.1143)
		(layer "F.Cu")
		(net "XM_ADDR_16")
	)
	(segment
		(start 118.029736 -54.771544)
		(end 118.029736 -54.061614)
		(width 0.1143)
		(layer "F.Cu")
		(net "XM_ADDR_16")
	)
	(segment
		(start 136.079484 -48.570134)
		(end 135.952484 -48.697134)
		(width 0.1143)
		(layer "F.Cu")
		(net "XM_ADDR_16")
	)
	(segment
		(start 136.598406 -49.154334)
		(end 136.598406 -50.18151)
		(width 0.1143)
		(layer "F.Cu")
		(net "XM_ADDR_16")
	)
	(segment
		(start 135.304784 -47.084234)
		(end 135.419084 -47.198534)
		(width 0.1143)
		(layer "F.Cu")
		(net "XM_ADDR_16")
	)
	(segment
		(start 136.598406 -48.239934)
		(end 136.598406 -48.443134)
		(width 0.1143)
		(layer "F.Cu")
		(net "XM_ADDR_16")
	)
	(via
		(at 136.519666 -50.26025)
		(size 0.5588)
		(drill 0.3048)
		(layers "F.Cu" "B.Cu")
		(net "XM_ADDR_16")
	)
	(via
		(at 118.00078 -54.8005)
		(size 0.508)
		(drill 0.254)
		(layers "F.Cu" "B.Cu")
		(net "XM_ADDR_16")
	)
	(segment
		(start 131.316222 -53.059838)
		(end 131.316476 -53.060092)
		(width 0.127)
		(layer "In5.Cu")
		(net "XM_ADDR_16")
	)
	(segment
		(start 124.131324 -54.7624)
		(end 125.833886 -53.059838)
		(width 0.127)
		(layer "In5.Cu")
		(net "XM_ADDR_16")
	)
	(segment
		(start 118.03888 -54.7624)
		(end 124.131324 -54.7624)
		(width 0.127)
		(layer "In5.Cu")
		(net "XM_ADDR_16")
	)
	(segment
		(start 125.833886 -53.059838)
		(end 131.316222 -53.059838)
		(width 0.127)
		(layer "In5.Cu")
		(net "XM_ADDR_16")
	)
	(segment
		(start 132.032248 -53.060092)
		(end 132.032502 -53.060346)
		(width 0.127)
		(layer "In5.Cu")
		(net "XM_ADDR_16")
	)
	(segment
		(start 131.316476 -53.060092)
		(end 132.032248 -53.060092)
		(width 0.127)
		(layer "In5.Cu")
		(net "XM_ADDR_16")
	)
	(segment
		(start 118.00078 -54.8005)
		(end 118.03888 -54.7624)
		(width 0.127)
		(layer "In5.Cu")
		(net "XM_ADDR_16")
	)
	(segment
		(start 135.448548 -50.001932)
		(end 136.392666 -50.001932)
		(width 0.127)
		(layer "In5.Cu")
		(net "XM_ADDR_16")
	)
	(segment
		(start 136.519666 -50.128932)
		(end 136.519666 -50.26025)
		(width 0.127)
		(layer "In5.Cu")
		(net "XM_ADDR_16")
	)
	(segment
		(start 132.390134 -53.060346)
		(end 135.448548 -50.001932)
		(width 0.127)
		(layer "In5.Cu")
		(net "XM_ADDR_16")
	)
	(segment
		(start 132.032502 -53.060346)
		(end 132.390134 -53.060346)
		(width 0.127)
		(layer "In5.Cu")
		(net "XM_ADDR_16")
	)
	(segment
		(start 136.392666 -50.001932)
		(end 136.519666 -50.128932)
		(width 0.127)
		(layer "In5.Cu")
		(net "XM_ADDR_16")
	)
	(segment
		(start 164.6555 -112.903)
		(end 164.6555 -111.76)
		(width 0.254)
		(layer "F.Cu")
		(net "P0V9_E_EN")
	)
	(segment
		(start 168.932352 -113.492534)
		(end 168.932352 -112.691672)
		(width 0.254)
		(layer "F.Cu")
		(net "P0V9_E_EN")
	)
	(segment
		(start 165.398704 -111.76)
		(end 164.6555 -111.76)
		(width 0.254)
		(layer "F.Cu")
		(net "P0V9_E_EN")
	)
	(segment
		(start 166.614856 -111.960152)
		(end 165.598856 -111.960152)
		(width 0.254)
		(layer "F.Cu")
		(net "P0V9_E_EN")
	)
	(segment
		(start 168.932352 -112.691672)
		(end 168.00068 -111.76)
		(width 0.254)
		(layer "F.Cu")
		(net "P0V9_E_EN")
	)
	(segment
		(start 168.00068 -111.76)
		(end 167.767 -111.76)
		(width 0.254)
		(layer "F.Cu")
		(net "P0V9_E_EN")
	)
	(segment
		(start 166.614856 -111.960152)
		(end 167.070278 -111.960152)
		(width 0.254)
		(layer "F.Cu")
		(net "P0V9_E_EN")
	)
	(segment
		(start 165.598856 -111.960152)
		(end 165.398704 -111.76)
		(width 0.254)
		(layer "F.Cu")
		(net "P0V9_E_EN")
	)
	(segment
		(start 167.27043 -111.76)
		(end 167.767 -111.76)
		(width 0.254)
		(layer "F.Cu")
		(net "P0V9_E_EN")
	)
	(segment
		(start 167.070278 -111.960152)
		(end 167.27043 -111.76)
		(width 0.254)
		(layer "F.Cu")
		(net "P0V9_E_EN")
	)
	(via
		(at 167.767 -111.76)
		(size 0.7112)
		(drill 0.3556)
		(layers "F.Cu" "B.Cu")
		(net "P0V9_E_EN")
	)
	(segment
		(start 75.786742 -136.392412)
		(end 71.924164 -136.392412)
		(width 0.1143)
		(layer "F.Cu")
		(net "XM_DATA14")
	)
	(segment
		(start 99.821492 -88.56345)
		(end 99.655884 -88.729058)
		(width 0.1143)
		(layer "F.Cu")
		(net "XM_DATA14")
	)
	(segment
		(start 71.924164 -136.392412)
		(end 71.891652 -136.3599)
		(width 0.1143)
		(layer "F.Cu")
		(net "XM_DATA14")
	)
	(segment
		(start 100.834698 -88.321134)
		(end 100.592382 -88.56345)
		(width 0.1143)
		(layer "F.Cu")
		(net "XM_DATA14")
	)
	(segment
		(start 102.349808 -88.349836)
		(end 102.321106 -88.321134)
		(width 0.1143)
		(layer "F.Cu")
		(net "XM_DATA14")
	)
	(segment
		(start 99.655884 -88.729058)
		(end 99.11842 -88.729058)
		(width 0.1143)
		(layer "F.Cu")
		(net "XM_DATA14")
	)
	(segment
		(start 100.592382 -88.56345)
		(end 99.821492 -88.56345)
		(width 0.1143)
		(layer "F.Cu")
		(net "XM_DATA14")
	)
	(segment
		(start 102.321106 -88.321134)
		(end 100.834698 -88.321134)
		(width 0.1143)
		(layer "F.Cu")
		(net "XM_DATA14")
	)
	(via
		(at 71.891652 -136.3599)
		(size 0.5588)
		(drill 0.3048)
		(layers "F.Cu" "B.Cu")
		(net "XM_DATA14")
	)
	(via
		(at 97.89795 -88.57996)
		(size 0.7112)
		(drill 0.3556)
		(layers "F.Cu" "B.Cu")
		(net "XM_DATA14")
	)
	(via
		(at 99.11842 -88.729058)
		(size 0.508)
		(drill 0.254)
		(layers "F.Cu" "B.Cu")
		(net "XM_DATA14")
	)
	(segment
		(start 70.34276 -94.762574)
		(end 70.181216 -94.762574)
		(width 0.1143)
		(layer "B.Cu")
		(net "XM_DATA14")
	)
	(segment
		(start 73.473564 -92.073222)
		(end 73.473564 -92.234766)
		(width 0.1143)
		(layer "B.Cu")
		(net "XM_DATA14")
	)
	(segment
		(start 70.019418 -95.085916)
		(end 70.240144 -95.306642)
		(width 0.1143)
		(layer "B.Cu")
		(net "XM_DATA14")
	)
	(segment
		(start 69.916802 -95.629984)
		(end 69.696076 -95.409258)
		(width 0.1143)
		(layer "B.Cu")
		(net "XM_DATA14")
	)
	(segment
		(start 69.696076 -95.409258)
		(end 69.534532 -95.409258)
		(width 0.1143)
		(layer "B.Cu")
		(net "XM_DATA14")
	)
	(segment
		(start 71.97852 -135.547862)
		(end 71.891652 -135.63473)
		(width 0.1143)
		(layer "B.Cu")
		(net "XM_DATA14")
	)
	(segment
		(start 71.533512 -94.013274)
		(end 71.533512 -94.174818)
		(width 0.1143)
		(layer "B.Cu")
		(net "XM_DATA14")
	)
	(segment
		(start 74.90587 -90.03792)
		(end 74.546206 -90.397584)
		(width 0.1143)
		(layer "B.Cu")
		(net "XM_DATA14")
	)
	(segment
		(start 74.605134 -91.103196)
		(end 74.44359 -91.103196)
		(width 0.1143)
		(layer "B.Cu")
		(net "XM_DATA14")
	)
	(segment
		(start 69.534532 -95.409258)
		(end 69.27342 -95.67037)
		(width 0.1143)
		(layer "B.Cu")
		(net "XM_DATA14")
	)
	(segment
		(start 73.899522 -91.205812)
		(end 74.120248 -91.426538)
		(width 0.1143)
		(layer "B.Cu")
		(net "XM_DATA14")
	)
	(segment
		(start 69.27342 -95.67037)
		(end 69.27342 -129.968244)
		(width 0.1143)
		(layer "B.Cu")
		(net "XM_DATA14")
	)
	(segment
		(start 72.503538 -93.043248)
		(end 72.282812 -92.822522)
		(width 0.1143)
		(layer "B.Cu")
		(net "XM_DATA14")
	)
	(segment
		(start 71.21017 -94.336616)
		(end 70.989444 -94.11589)
		(width 0.1143)
		(layer "B.Cu")
		(net "XM_DATA14")
	)
	(segment
		(start 72.929496 -92.175838)
		(end 72.767952 -92.175838)
		(width 0.1143)
		(layer "B.Cu")
		(net "XM_DATA14")
	)
	(segment
		(start 70.72503 -94.9833)
		(end 70.563486 -94.9833)
		(width 0.1143)
		(layer "B.Cu")
		(net "XM_DATA14")
	)
	(segment
		(start 70.181216 -94.762574)
		(end 70.019418 -94.924372)
		(width 0.1143)
		(layer "B.Cu")
		(net "XM_DATA14")
	)
	(segment
		(start 70.261988 -130.957066)
		(end 70.51167 -131.206748)
		(width 0.1143)
		(layer "B.Cu")
		(net "XM_DATA14")
	)
	(segment
		(start 72.018398 -93.689932)
		(end 71.856854 -93.689932)
		(width 0.1143)
		(layer "B.Cu")
		(net "XM_DATA14")
	)
	(segment
		(start 69.27342 -129.968244)
		(end 70.261988 -130.956812)
		(width 0.1143)
		(layer "B.Cu")
		(net "XM_DATA14")
	)
	(segment
		(start 70.51167 -133.307328)
		(end 71.97852 -134.774178)
		(width 0.1143)
		(layer "B.Cu")
		(net "XM_DATA14")
	)
	(segment
		(start 70.666102 -94.277688)
		(end 70.666102 -94.439232)
		(width 0.1143)
		(layer "B.Cu")
		(net "XM_DATA14")
	)
	(segment
		(start 73.95845 -91.74988)
		(end 73.796906 -91.74988)
		(width 0.1143)
		(layer "B.Cu")
		(net "XM_DATA14")
	)
	(segment
		(start 99.11842 -88.729058)
		(end 98.047048 -88.729058)
		(width 0.1143)
		(layer "B.Cu")
		(net "XM_DATA14")
	)
	(segment
		(start 94.577662 -88.75395)
		(end 87.226902 -88.75395)
		(width 0.1143)
		(layer "B.Cu")
		(net "XM_DATA14")
	)
	(segment
		(start 70.563486 -94.9833)
		(end 70.34276 -94.762574)
		(width 0.1143)
		(layer "B.Cu")
		(net "XM_DATA14")
	)
	(segment
		(start 73.311766 -92.396564)
		(end 73.150222 -92.396564)
		(width 0.1143)
		(layer "B.Cu")
		(net "XM_DATA14")
	)
	(segment
		(start 72.121268 -92.822522)
		(end 71.95947 -92.98432)
		(width 0.1143)
		(layer "B.Cu")
		(net "XM_DATA14")
	)
	(segment
		(start 87.226902 -88.75395)
		(end 86.750652 -89.2302)
		(width 0.1143)
		(layer "B.Cu")
		(net "XM_DATA14")
	)
	(segment
		(start 70.989444 -94.11589)
		(end 70.8279 -94.11589)
		(width 0.1143)
		(layer "B.Cu")
		(net "XM_DATA14")
	)
	(segment
		(start 71.636128 -93.469206)
		(end 71.474584 -93.469206)
		(width 0.1143)
		(layer "B.Cu")
		(net "XM_DATA14")
	)
	(segment
		(start 97.89795 -88.57996)
		(end 97.56013 -88.24214)
		(width 0.1143)
		(layer "B.Cu")
		(net "XM_DATA14")
	)
	(segment
		(start 71.97852 -134.774178)
		(end 71.97852 -135.547862)
		(width 0.1143)
		(layer "B.Cu")
		(net "XM_DATA14")
	)
	(segment
		(start 98.047048 -88.729058)
		(end 97.89795 -88.57996)
		(width 0.1143)
		(layer "B.Cu")
		(net "XM_DATA14")
	)
	(segment
		(start 85.942678 -90.03792)
		(end 74.90587 -90.03792)
		(width 0.1143)
		(layer "B.Cu")
		(net "XM_DATA14")
	)
	(segment
		(start 72.767952 -92.175838)
		(end 72.606154 -92.337636)
		(width 0.1143)
		(layer "B.Cu")
		(net "XM_DATA14")
	)
	(segment
		(start 73.473564 -92.234766)
		(end 73.311766 -92.396564)
		(width 0.1143)
		(layer "B.Cu")
		(net "XM_DATA14")
	)
	(segment
		(start 74.120248 -91.426538)
		(end 74.120248 -91.588082)
		(width 0.1143)
		(layer "B.Cu")
		(net "XM_DATA14")
	)
	(segment
		(start 74.766932 -90.941398)
		(end 74.605134 -91.103196)
		(width 0.1143)
		(layer "B.Cu")
		(net "XM_DATA14")
	)
	(segment
		(start 70.019418 -94.924372)
		(end 70.019418 -95.085916)
		(width 0.1143)
		(layer "B.Cu")
		(net "XM_DATA14")
	)
	(segment
		(start 74.766932 -90.779854)
		(end 74.766932 -90.941398)
		(width 0.1143)
		(layer "B.Cu")
		(net "XM_DATA14")
	)
	(segment
		(start 72.82688 -92.88145)
		(end 72.665082 -93.043248)
		(width 0.1143)
		(layer "B.Cu")
		(net "XM_DATA14")
	)
	(segment
		(start 73.414636 -91.529154)
		(end 73.252838 -91.690952)
		(width 0.1143)
		(layer "B.Cu")
		(net "XM_DATA14")
	)
	(segment
		(start 71.891652 -135.63473)
		(end 71.891652 -136.3599)
		(width 0.1143)
		(layer "B.Cu")
		(net "XM_DATA14")
	)
	(segment
		(start 74.44359 -91.103196)
		(end 74.222864 -90.88247)
		(width 0.1143)
		(layer "B.Cu")
		(net "XM_DATA14")
	)
	(segment
		(start 70.261988 -130.956812)
		(end 70.261988 -130.957066)
		(width 0.1143)
		(layer "B.Cu")
		(net "XM_DATA14")
	)
	(segment
		(start 74.120248 -91.588082)
		(end 73.95845 -91.74988)
		(width 0.1143)
		(layer "B.Cu")
		(net "XM_DATA14")
	)
	(segment
		(start 95.089472 -88.24214)
		(end 94.577662 -88.75395)
		(width 0.1143)
		(layer "B.Cu")
		(net "XM_DATA14")
	)
	(segment
		(start 70.240144 -95.306642)
		(end 70.240144 -95.468186)
		(width 0.1143)
		(layer "B.Cu")
		(net "XM_DATA14")
	)
	(segment
		(start 70.886828 -94.821502)
		(end 70.72503 -94.9833)
		(width 0.1143)
		(layer "B.Cu")
		(net "XM_DATA14")
	)
	(segment
		(start 74.546206 -90.559128)
		(end 74.766932 -90.779854)
		(width 0.1143)
		(layer "B.Cu")
		(net "XM_DATA14")
	)
	(segment
		(start 97.56013 -88.24214)
		(end 95.089472 -88.24214)
		(width 0.1143)
		(layer "B.Cu")
		(net "XM_DATA14")
	)
	(segment
		(start 72.606154 -92.337636)
		(end 72.606154 -92.49918)
		(width 0.1143)
		(layer "B.Cu")
		(net "XM_DATA14")
	)
	(segment
		(start 72.82688 -92.719906)
		(end 72.82688 -92.88145)
		(width 0.1143)
		(layer "B.Cu")
		(net "XM_DATA14")
	)
	(segment
		(start 71.533512 -94.174818)
		(end 71.371714 -94.336616)
		(width 0.1143)
		(layer "B.Cu")
		(net "XM_DATA14")
	)
	(segment
		(start 73.899522 -91.044268)
		(end 73.899522 -91.205812)
		(width 0.1143)
		(layer "B.Cu")
		(net "XM_DATA14")
	)
	(segment
		(start 73.252838 -91.690952)
		(end 73.252838 -91.852496)
		(width 0.1143)
		(layer "B.Cu")
		(net "XM_DATA14")
	)
	(segment
		(start 72.606154 -92.49918)
		(end 72.82688 -92.719906)
		(width 0.1143)
		(layer "B.Cu")
		(net "XM_DATA14")
	)
	(segment
		(start 71.312786 -93.631004)
		(end 71.312786 -93.792548)
		(width 0.1143)
		(layer "B.Cu")
		(net "XM_DATA14")
	)
	(segment
		(start 70.240144 -95.468186)
		(end 70.078346 -95.629984)
		(width 0.1143)
		(layer "B.Cu")
		(net "XM_DATA14")
	)
	(segment
		(start 86.750398 -89.2302)
		(end 85.942678 -90.03792)
		(width 0.1143)
		(layer "B.Cu")
		(net "XM_DATA14")
	)
	(segment
		(start 71.95947 -92.98432)
		(end 71.95947 -93.145864)
		(width 0.1143)
		(layer "B.Cu")
		(net "XM_DATA14")
	)
	(segment
		(start 74.222864 -90.88247)
		(end 74.06132 -90.88247)
		(width 0.1143)
		(layer "B.Cu")
		(net "XM_DATA14")
	)
	(segment
		(start 71.371714 -94.336616)
		(end 71.21017 -94.336616)
		(width 0.1143)
		(layer "B.Cu")
		(net "XM_DATA14")
	)
	(segment
		(start 74.06132 -90.88247)
		(end 73.899522 -91.044268)
		(width 0.1143)
		(layer "B.Cu")
		(net "XM_DATA14")
	)
	(segment
		(start 72.282812 -92.822522)
		(end 72.121268 -92.822522)
		(width 0.1143)
		(layer "B.Cu")
		(net "XM_DATA14")
	)
	(segment
		(start 71.856854 -93.689932)
		(end 71.636128 -93.469206)
		(width 0.1143)
		(layer "B.Cu")
		(net "XM_DATA14")
	)
	(segment
		(start 73.252838 -91.852496)
		(end 73.473564 -92.073222)
		(width 0.1143)
		(layer "B.Cu")
		(net "XM_DATA14")
	)
	(segment
		(start 73.150222 -92.396564)
		(end 72.929496 -92.175838)
		(width 0.1143)
		(layer "B.Cu")
		(net "XM_DATA14")
	)
	(segment
		(start 71.474584 -93.469206)
		(end 71.312786 -93.631004)
		(width 0.1143)
		(layer "B.Cu")
		(net "XM_DATA14")
	)
	(segment
		(start 70.51167 -131.206748)
		(end 70.51167 -133.307328)
		(width 0.1143)
		(layer "B.Cu")
		(net "XM_DATA14")
	)
	(segment
		(start 70.666102 -94.439232)
		(end 70.886828 -94.659958)
		(width 0.1143)
		(layer "B.Cu")
		(net "XM_DATA14")
	)
	(segment
		(start 86.750652 -89.2302)
		(end 86.750398 -89.2302)
		(width 0.1143)
		(layer "B.Cu")
		(net "XM_DATA14")
	)
	(segment
		(start 73.796906 -91.74988)
		(end 73.57618 -91.529154)
		(width 0.1143)
		(layer "B.Cu")
		(net "XM_DATA14")
	)
	(segment
		(start 72.180196 -93.36659)
		(end 72.180196 -93.528134)
		(width 0.1143)
		(layer "B.Cu")
		(net "XM_DATA14")
	)
	(segment
		(start 70.078346 -95.629984)
		(end 69.916802 -95.629984)
		(width 0.1143)
		(layer "B.Cu")
		(net "XM_DATA14")
	)
	(segment
		(start 70.8279 -94.11589)
		(end 70.666102 -94.277688)
		(width 0.1143)
		(layer "B.Cu")
		(net "XM_DATA14")
	)
	(segment
		(start 71.95947 -93.145864)
		(end 72.180196 -93.36659)
		(width 0.1143)
		(layer "B.Cu")
		(net "XM_DATA14")
	)
	(segment
		(start 74.546206 -90.397584)
		(end 74.546206 -90.559128)
		(width 0.1143)
		(layer "B.Cu")
		(net "XM_DATA14")
	)
	(segment
		(start 72.180196 -93.528134)
		(end 72.018398 -93.689932)
		(width 0.1143)
		(layer "B.Cu")
		(net "XM_DATA14")
	)
	(segment
		(start 73.57618 -91.529154)
		(end 73.414636 -91.529154)
		(width 0.1143)
		(layer "B.Cu")
		(net "XM_DATA14")
	)
	(segment
		(start 72.665082 -93.043248)
		(end 72.503538 -93.043248)
		(width 0.1143)
		(layer "B.Cu")
		(net "XM_DATA14")
	)
	(segment
		(start 70.886828 -94.659958)
		(end 70.886828 -94.821502)
		(width 0.1143)
		(layer "B.Cu")
		(net "XM_DATA14")
	)
	(segment
		(start 71.312786 -93.792548)
		(end 71.533512 -94.013274)
		(width 0.1143)
		(layer "B.Cu")
		(net "XM_DATA14")
	)
	(segment
		(start 128.468882 -85.539326)
		(end 128.418844 -85.539326)
		(width 0.0889)
		(layer "F.Cu")
		(net "SAS_HDD_TX15_N")
	)
	(segment
		(start 129.947162 -84.84616)
		(end 129.511552 -85.28177)
		(width 0.1016)
		(layer "F.Cu")
		(net "SAS_HDD_TX15_N")
	)
	(segment
		(start 129.09677 -85.453982)
		(end 128.686052 -85.453982)
		(width 0.1016)
		(layer "F.Cu")
		(net "SAS_HDD_TX15_N")
	)
	(segment
		(start 125.791468 -85.908388)
		(end 125.350016 -86.34984)
		(width 0.0889)
		(layer "F.Cu")
		(net "SAS_HDD_TX15_N")
	)
	(segment
		(start 126.013972 -85.764624)
		(end 125.791468 -85.908388)
		(width 0.0889)
		(layer "F.Cu")
		(net "SAS_HDD_TX15_N")
	)
	(segment
		(start 127.423164 -85.724492)
		(end 126.110746 -85.724492)
		(width 0.0889)
		(layer "F.Cu")
		(net "SAS_HDD_TX15_N")
	)
	(segment
		(start 130.532124 -84.6201)
		(end 130.494024 -84.6201)
		(width 0.1016)
		(layer "F.Cu")
		(net "SAS_HDD_TX15_N")
	)
	(segment
		(start 128.686052 -85.453982)
		(end 128.674876 -85.453982)
		(width 0.0889)
		(layer "F.Cu")
		(net "SAS_HDD_TX15_N")
	)
	(segment
		(start 130.790442 -84.399882)
		(end 130.597148 -84.593176)
		(width 0.1016)
		(layer "F.Cu")
		(net "SAS_HDD_TX15_N")
	)
	(arc
		(start 129.511552 -85.28177)
		(mid 129.321278 -85.409093)
		(end 129.09677 -85.453982)
		(width 0.1016)
		(layer "F.Cu")
		(net "SAS_HDD_TX15_N")
	)
	(arc
		(start 127.869696 -85.539326)
		(mid 127.66484 -85.676299)
		(end 127.423164 -85.724492)
		(width 0.0889)
		(layer "F.Cu")
		(net "SAS_HDD_TX15_N")
	)
	(arc
		(start 128.418844 -85.539326)
		(mid 128.14427 -85.425594)
		(end 127.869696 -85.539326)
		(width 0.0889)
		(layer "F.Cu")
		(net "SAS_HDD_TX15_N")
	)
	(arc
		(start 130.597148 -84.593176)
		(mid 130.567315 -84.61311)
		(end 130.532124 -84.6201)
		(width 0.1016)
		(layer "F.Cu")
		(net "SAS_HDD_TX15_N")
	)
	(arc
		(start 130.494024 -84.6201)
		(mid 130.198093 -84.678701)
		(end 129.947162 -84.84616)
		(width 0.1016)
		(layer "F.Cu")
		(net "SAS_HDD_TX15_N")
	)
	(arc
		(start 128.674876 -85.453982)
		(mid 128.580365 -85.517132)
		(end 128.468882 -85.539326)
		(width 0.0889)
		(layer "F.Cu")
		(net "SAS_HDD_TX15_N")
	)
	(arc
		(start 126.110746 -85.724492)
		(mid 126.058354 -85.734913)
		(end 126.013972 -85.764624)
		(width 0.0889)
		(layer "F.Cu")
		(net "SAS_HDD_TX15_N")
	)
	(segment
		(start 151.5745 -52.07)
		(end 151.5745 -53.213)
		(width 0.1143)
		(layer "F.Cu")
		(net "XM_ADDR_4")
	)
	(segment
		(start 148.717 -51.689)
		(end 148.6535 -51.6255)
		(width 0.1143)
		(layer "F.Cu")
		(net "XM_ADDR_4")
	)
	(segment
		(start 148.6535 -51.6255)
		(end 148.6535 -51.2445)
		(width 0.1143)
		(layer "F.Cu")
		(net "XM_ADDR_4")
	)
	(segment
		(start 148.67255 -51.22545)
		(end 148.67255 -50.292)
		(width 0.1143)
		(layer "F.Cu")
		(net "XM_ADDR_4")
	)
	(segment
		(start 112.110266 -57.011824)
		(end 112.110266 -58.3438)
		(width 0.1143)
		(layer "F.Cu")
		(net "XM_ADDR_4")
	)
	(segment
		(start 147.098766 -42.7101)
		(end 147.098766 -43.847766)
		(width 0.1143)
		(layer "F.Cu")
		(net "XM_ADDR_4")
	)
	(segment
		(start 148.717 -51.816)
		(end 148.717 -51.689)
		(width 0.1143)
		(layer "F.Cu")
		(net "XM_ADDR_4")
	)
	(segment
		(start 148.67255 -45.42155)
		(end 148.67255 -50.292)
		(width 0.1143)
		(layer "F.Cu")
		(net "XM_ADDR_4")
	)
	(segment
		(start 112.350042 -56.772048)
		(end 112.110266 -57.011824)
		(width 0.1143)
		(layer "F.Cu")
		(net "XM_ADDR_4")
	)
	(segment
		(start 150.495 -52.07)
		(end 151.5745 -52.07)
		(width 0.1143)
		(layer "F.Cu")
		(net "XM_ADDR_4")
	)
	(segment
		(start 148.6535 -51.2445)
		(end 148.67255 -51.22545)
		(width 0.1143)
		(layer "F.Cu")
		(net "XM_ADDR_4")
	)
	(segment
		(start 148.971 -52.07)
		(end 148.717 -51.816)
		(width 0.1143)
		(layer "F.Cu")
		(net "XM_ADDR_4")
	)
	(segment
		(start 150.495 -52.07)
		(end 148.971 -52.07)
		(width 0.1143)
		(layer "F.Cu")
		(net "XM_ADDR_4")
	)
	(segment
		(start 147.098766 -43.847766)
		(end 148.67255 -45.42155)
		(width 0.1143)
		(layer "F.Cu")
		(net "XM_ADDR_4")
	)
	(segment
		(start 112.350042 -56.599836)
		(end 112.350042 -56.772048)
		(width 0.1143)
		(layer "F.Cu")
		(net "XM_ADDR_4")
	)
	(via
		(at 150.495 -52.07)
		(size 0.7112)
		(drill 0.3556)
		(layers "F.Cu" "B.Cu")
		(net "XM_ADDR_4")
	)
	(via
		(at 148.67255 -50.292)
		(size 0.5588)
		(drill 0.3048)
		(layers "F.Cu" "B.Cu")
		(net "XM_ADDR_4")
	)
	(via
		(at 112.110266 -58.3438)
		(size 0.508)
		(drill 0.254)
		(layers "F.Cu" "B.Cu")
		(net "XM_ADDR_4")
	)
	(segment
		(start 142.359634 -56.858662)
		(end 142.232634 -56.731662)
		(width 0.127)
		(layer "In5.Cu")
		(net "XM_ADDR_4")
	)
	(segment
		(start 140.200634 -56.731662)
		(end 138.705844 -56.731662)
		(width 0.127)
		(layer "In5.Cu")
		(net "XM_ADDR_4")
	)
	(segment
		(start 142.867634 -56.858662)
		(end 142.867634 -57.129172)
		(width 0.127)
		(layer "In5.Cu")
		(net "XM_ADDR_4")
	)
	(segment
		(start 141.343634 -56.858662)
		(end 141.216634 -56.731662)
		(width 0.127)
		(layer "In5.Cu")
		(net "XM_ADDR_4")
	)
	(segment
		(start 141.851634 -56.858662)
		(end 141.851634 -57.129172)
		(width 0.127)
		(layer "In5.Cu")
		(net "XM_ADDR_4")
	)
	(segment
		(start 138.705844 -56.731662)
		(end 138.176 -57.261506)
		(width 0.127)
		(layer "In5.Cu")
		(net "XM_ADDR_4")
	)
	(segment
		(start 118.152418 -58.362088)
		(end 117.218206 -59.2963)
		(width 0.127)
		(layer "In5.Cu")
		(net "XM_ADDR_4")
	)
	(segment
		(start 140.327634 -56.858662)
		(end 140.200634 -56.731662)
		(width 0.127)
		(layer "In5.Cu")
		(net "XM_ADDR_4")
	)
	(segment
		(start 141.978634 -56.731662)
		(end 141.851634 -56.858662)
		(width 0.127)
		(layer "In5.Cu")
		(net "XM_ADDR_4")
	)
	(segment
		(start 113.935256 -59.2963)
		(end 112.982756 -58.3438)
		(width 0.127)
		(layer "In5.Cu")
		(net "XM_ADDR_4")
	)
	(segment
		(start 138.176 -57.261506)
		(end 126.519178 -57.261506)
		(width 0.127)
		(layer "In5.Cu")
		(net "XM_ADDR_4")
	)
	(segment
		(start 141.851634 -57.129172)
		(end 141.724634 -57.256172)
		(width 0.127)
		(layer "In5.Cu")
		(net "XM_ADDR_4")
	)
	(segment
		(start 142.232634 -56.731662)
		(end 141.978634 -56.731662)
		(width 0.127)
		(layer "In5.Cu")
		(net "XM_ADDR_4")
	)
	(segment
		(start 140.962634 -56.731662)
		(end 140.835634 -56.858662)
		(width 0.127)
		(layer "In5.Cu")
		(net "XM_ADDR_4")
	)
	(segment
		(start 140.835634 -57.129172)
		(end 140.708634 -57.256172)
		(width 0.127)
		(layer "In5.Cu")
		(net "XM_ADDR_4")
	)
	(segment
		(start 141.216634 -56.731662)
		(end 140.962634 -56.731662)
		(width 0.127)
		(layer "In5.Cu")
		(net "XM_ADDR_4")
	)
	(segment
		(start 141.343634 -57.129172)
		(end 141.343634 -56.858662)
		(width 0.127)
		(layer "In5.Cu")
		(net "XM_ADDR_4")
	)
	(segment
		(start 117.218206 -59.2963)
		(end 113.935256 -59.2963)
		(width 0.127)
		(layer "In5.Cu")
		(net "XM_ADDR_4")
	)
	(segment
		(start 142.486634 -57.256172)
		(end 142.359634 -57.129172)
		(width 0.127)
		(layer "In5.Cu")
		(net "XM_ADDR_4")
	)
	(segment
		(start 148.693632 -50.292)
		(end 149.63775 -51.236118)
		(width 0.127)
		(layer "In5.Cu")
		(net "XM_ADDR_4")
	)
	(segment
		(start 146.05635 -56.731662)
		(end 142.994634 -56.731662)
		(width 0.127)
		(layer "In5.Cu")
		(net "XM_ADDR_4")
	)
	(segment
		(start 142.740634 -57.256172)
		(end 142.486634 -57.256172)
		(width 0.127)
		(layer "In5.Cu")
		(net "XM_ADDR_4")
	)
	(segment
		(start 142.867634 -57.129172)
		(end 142.740634 -57.256172)
		(width 0.127)
		(layer "In5.Cu")
		(net "XM_ADDR_4")
	)
	(segment
		(start 126.519178 -57.261506)
		(end 125.418596 -58.362088)
		(width 0.127)
		(layer "In5.Cu")
		(net "XM_ADDR_4")
	)
	(segment
		(start 141.470634 -57.256172)
		(end 141.343634 -57.129172)
		(width 0.127)
		(layer "In5.Cu")
		(net "XM_ADDR_4")
	)
	(segment
		(start 140.835634 -56.858662)
		(end 140.835634 -57.129172)
		(width 0.127)
		(layer "In5.Cu")
		(net "XM_ADDR_4")
	)
	(segment
		(start 125.418596 -58.362088)
		(end 118.152418 -58.362088)
		(width 0.127)
		(layer "In5.Cu")
		(net "XM_ADDR_4")
	)
	(segment
		(start 140.454634 -57.256172)
		(end 140.327634 -57.129172)
		(width 0.127)
		(layer "In5.Cu")
		(net "XM_ADDR_4")
	)
	(segment
		(start 149.63775 -53.150262)
		(end 146.05635 -56.731662)
		(width 0.127)
		(layer "In5.Cu")
		(net "XM_ADDR_4")
	)
	(segment
		(start 112.982756 -58.3438)
		(end 112.110266 -58.3438)
		(width 0.127)
		(layer "In5.Cu")
		(net "XM_ADDR_4")
	)
	(segment
		(start 140.327634 -57.129172)
		(end 140.327634 -56.858662)
		(width 0.127)
		(layer "In5.Cu")
		(net "XM_ADDR_4")
	)
	(segment
		(start 148.67255 -50.292)
		(end 148.693632 -50.292)
		(width 0.127)
		(layer "In5.Cu")
		(net "XM_ADDR_4")
	)
	(segment
		(start 142.994634 -56.731662)
		(end 142.867634 -56.858662)
		(width 0.127)
		(layer "In5.Cu")
		(net "XM_ADDR_4")
	)
	(segment
		(start 149.63775 -51.236118)
		(end 149.63775 -53.150262)
		(width 0.127)
		(layer "In5.Cu")
		(net "XM_ADDR_4")
	)
	(segment
		(start 141.724634 -57.256172)
		(end 141.470634 -57.256172)
		(width 0.127)
		(layer "In5.Cu")
		(net "XM_ADDR_4")
	)
	(segment
		(start 142.359634 -57.129172)
		(end 142.359634 -56.858662)
		(width 0.127)
		(layer "In5.Cu")
		(net "XM_ADDR_4")
	)
	(segment
		(start 140.708634 -57.256172)
		(end 140.454634 -57.256172)
		(width 0.127)
		(layer "In5.Cu")
		(net "XM_ADDR_4")
	)
	(segment
		(start 85.703664 -36.46805)
		(end 82.299302 -36.46805)
		(width 0.1016)
		(layer "F.Cu")
		(net "SAS3008_RAID_TX_N2")
	)
	(segment
		(start 86.21776 -36.322)
		(end 85.934042 -36.322)
		(width 0.1016)
		(layer "F.Cu")
		(net "SAS3008_RAID_TX_N2")
	)
	(segment
		(start 82.077052 -36.560252)
		(end 81.98485 -36.6522)
		(width 0.1016)
		(layer "F.Cu")
		(net "SAS3008_RAID_TX_N2")
	)
	(segment
		(start 122.350022 -84.349844)
		(end 122.850148 -83.849718)
		(width 0.1016)
		(layer "F.Cu")
		(net "SAS3008_RAID_TX_N2")
	)
	(segment
		(start 85.86216 -36.351718)
		(end 85.775546 -36.438332)
		(width 0.1016)
		(layer "F.Cu")
		(net "SAS3008_RAID_TX_N2")
	)
	(segment
		(start 81.98485 -36.6522)
		(end 81.588356 -36.6522)
		(width 0.1016)
		(layer "F.Cu")
		(net "SAS3008_RAID_TX_N2")
	)
	(segment
		(start 81.516474 -36.622482)
		(end 81.2292 -36.335208)
		(width 0.1016)
		(layer "F.Cu")
		(net "SAS3008_RAID_TX_N2")
	)
	(via
		(at 122.850148 -83.849718)
		(size 0.508)
		(drill 0.254)
		(layers "F.Cu" "B.Cu")
		(net "SAS3008_RAID_TX_N2")
	)
	(via
		(at 127.154178 -79.8068)
		(size 0.5588)
		(drill 0.3048)
		(layers "F.Cu" "B.Cu")
		(net "SAS3008_RAID_TX_N2")
	)
	(via
		(at 79.604108 -39.624)
		(size 0.5588)
		(drill 0.254)
		(layers "F.Cu" "B.Cu")
		(net "SAS3008_RAID_TX_N2")
	)
	(via
		(at 81.2292 -36.335208)
		(size 0.5588)
		(drill 0.3048)
		(layers "F.Cu" "B.Cu")
		(net "SAS3008_RAID_TX_N2")
	)
	(arc
		(start 85.775546 -36.438332)
		(mid 85.742552 -36.460315)
		(end 85.703664 -36.46805)
		(width 0.1016)
		(layer "F.Cu")
		(net "SAS3008_RAID_TX_N2")
	)
	(arc
		(start 81.588356 -36.6522)
		(mid 81.549461 -36.644481)
		(end 81.516474 -36.622482)
		(width 0.1016)
		(layer "F.Cu")
		(net "SAS3008_RAID_TX_N2")
	)
	(arc
		(start 85.934042 -36.322)
		(mid 85.895147 -36.329719)
		(end 85.86216 -36.351718)
		(width 0.1016)
		(layer "F.Cu")
		(net "SAS3008_RAID_TX_N2")
	)
	(arc
		(start 82.299302 -36.46805)
		(mid 82.178981 -36.492001)
		(end 82.077052 -36.560252)
		(width 0.1016)
		(layer "F.Cu")
		(net "SAS3008_RAID_TX_N2")
	)
	(segment
		(start 80.4672 -36.6522)
		(end 80.870044 -36.6522)
		(width 0.1016)
		(layer "B.Cu")
		(net "SAS3008_RAID_TX_N2")
	)
	(segment
		(start 79.8703 -39.1922)
		(end 79.8703 -37.2491)
		(width 0.1016)
		(layer "B.Cu")
		(net "SAS3008_RAID_TX_N2")
	)
	(segment
		(start 125.631448 -82.2579)
		(end 125.135894 -82.472276)
		(width 0.1016)
		(layer "B.Cu")
		(net "SAS3008_RAID_TX_N2")
	)
	(segment
		(start 123.257818 -83.442048)
		(end 122.850148 -83.849718)
		(width 0.1016)
		(layer "B.Cu")
		(net "SAS3008_RAID_TX_N2")
	)
	(segment
		(start 124.41047 -83.1977)
		(end 124.400056 -83.20786)
		(width 0.1016)
		(layer "B.Cu")
		(net "SAS3008_RAID_TX_N2")
	)
	(segment
		(start 80.941926 -36.622482)
		(end 81.2292 -36.335208)
		(width 0.1016)
		(layer "B.Cu")
		(net "SAS3008_RAID_TX_N2")
	)
	(segment
		(start 127.2286 -82.2579)
		(end 125.631448 -82.2579)
		(width 0.1016)
		(layer "B.Cu")
		(net "SAS3008_RAID_TX_N2")
	)
	(segment
		(start 125.135894 -82.472276)
		(end 124.41047 -83.1977)
		(width 0.1016)
		(layer "B.Cu")
		(net "SAS3008_RAID_TX_N2")
	)
	(segment
		(start 79.604108 -39.624)
		(end 79.753206 -39.474902)
		(width 0.1016)
		(layer "B.Cu")
		(net "SAS3008_RAID_TX_N2")
	)
	(segment
		(start 127.154178 -79.8068)
		(end 127.32639 -79.979266)
		(width 0.1016)
		(layer "B.Cu")
		(net "SAS3008_RAID_TX_N2")
	)
	(segment
		(start 127.4445 -80.264)
		(end 127.4445 -82.042)
		(width 0.1016)
		(layer "B.Cu")
		(net "SAS3008_RAID_TX_N2")
	)
	(segment
		(start 124.11837 -83.3247)
		(end 123.541028 -83.3247)
		(width 0.1016)
		(layer "B.Cu")
		(net "SAS3008_RAID_TX_N2")
	)
	(arc
		(start 124.400056 -83.20786)
		(mid 124.270832 -83.294297)
		(end 124.11837 -83.3247)
		(width 0.1016)
		(layer "B.Cu")
		(net "SAS3008_RAID_TX_N2")
	)
	(arc
		(start 127.4445 -82.042)
		(mid 127.381264 -82.194664)
		(end 127.2286 -82.2579)
		(width 0.1016)
		(layer "B.Cu")
		(net "SAS3008_RAID_TX_N2")
	)
	(arc
		(start 127.32639 -79.979266)
		(mid 127.413762 -80.109888)
		(end 127.4445 -80.264)
		(width 0.1016)
		(layer "B.Cu")
		(net "SAS3008_RAID_TX_N2")
	)
	(arc
		(start 80.870044 -36.6522)
		(mid 80.908939 -36.644481)
		(end 80.941926 -36.622482)
		(width 0.1016)
		(layer "B.Cu")
		(net "SAS3008_RAID_TX_N2")
	)
	(arc
		(start 123.541028 -83.3247)
		(mid 123.387741 -83.355191)
		(end 123.257818 -83.442048)
		(width 0.1016)
		(layer "B.Cu")
		(net "SAS3008_RAID_TX_N2")
	)
	(arc
		(start 79.8703 -37.2491)
		(mid 80.045128 -36.827028)
		(end 80.4672 -36.6522)
		(width 0.1016)
		(layer "B.Cu")
		(net "SAS3008_RAID_TX_N2")
	)
	(arc
		(start 79.753206 -39.474902)
		(mid 79.839872 -39.345197)
		(end 79.8703 -39.1922)
		(width 0.1016)
		(layer "B.Cu")
		(net "SAS3008_RAID_TX_N2")
	)
	(segment
		(start 98.675952 -65.5828)
		(end 99.291394 -65.5828)
		(width 0.1016)
		(layer "In2.Cu")
		(net "SAS3008_RAID_TX_N2")
	)
	(segment
		(start 79.915766 -40.132)
		(end 79.915766 -46.90618)
		(width 0.1016)
		(layer "In2.Cu")
		(net "SAS3008_RAID_TX_N2")
	)
	(segment
		(start 80.071722 -47.28337)
		(end 85.422232 -52.63388)
		(width 0.1016)
		(layer "In2.Cu")
		(net "SAS3008_RAID_TX_N2")
	)
	(segment
		(start 79.604108 -39.624)
		(end 79.776828 -39.796974)
		(width 0.1016)
		(layer "In2.Cu")
		(net "SAS3008_RAID_TX_N2")
	)
	(segment
		(start 125.40869 -73.334626)
		(end 127.28829 -75.214226)
		(width 0.1016)
		(layer "In2.Cu")
		(net "SAS3008_RAID_TX_N2")
	)
	(segment
		(start 85.422232 -52.63388)
		(end 85.422486 -52.63388)
		(width 0.1016)
		(layer "In2.Cu")
		(net "SAS3008_RAID_TX_N2")
	)
	(segment
		(start 92.750386 -59.961526)
		(end 98.156776 -65.367916)
		(width 0.1016)
		(layer "In2.Cu")
		(net "SAS3008_RAID_TX_N2")
	)
	(segment
		(start 100.570538 -66.112644)
		(end 102.001574 -67.54368)
		(width 0.1016)
		(layer "In2.Cu")
		(net "SAS3008_RAID_TX_N2")
	)
	(segment
		(start 116.58219 -71.229474)
		(end 117.735858 -72.382634)
		(width 0.1016)
		(layer "In2.Cu")
		(net "SAS3008_RAID_TX_N2")
	)
	(segment
		(start 102.847902 -67.8942)
		(end 104.14 -67.8942)
		(width 0.1016)
		(layer "In2.Cu")
		(net "SAS3008_RAID_TX_N2")
	)
	(segment
		(start 104.990392 -68.246752)
		(end 106.824272 -70.080632)
		(width 0.1016)
		(layer "In2.Cu")
		(net "SAS3008_RAID_TX_N2")
	)
	(segment
		(start 108.966 -70.9676)
		(end 115.950746 -70.9676)
		(width 0.1016)
		(layer "In2.Cu")
		(net "SAS3008_RAID_TX_N2")
	)
	(segment
		(start 127.318262 -79.64297)
		(end 127.154178 -79.8068)
		(width 0.1016)
		(layer "In2.Cu")
		(net "SAS3008_RAID_TX_N2")
	)
	(segment
		(start 119.40921 -73.0758)
		(end 124.78385 -73.0758)
		(width 0.1016)
		(layer "In2.Cu")
		(net "SAS3008_RAID_TX_N2")
	)
	(segment
		(start 127.47117 -75.655678)
		(end 127.47117 -79.2734)
		(width 0.1016)
		(layer "In2.Cu")
		(net "SAS3008_RAID_TX_N2")
	)
	(segment
		(start 92.750132 -59.961526)
		(end 92.750386 -59.961526)
		(width 0.1016)
		(layer "In2.Cu")
		(net "SAS3008_RAID_TX_N2")
	)
	(segment
		(start 85.422486 -52.63388)
		(end 92.750132 -59.961526)
		(width 0.1016)
		(layer "In2.Cu")
		(net "SAS3008_RAID_TX_N2")
	)
	(arc
		(start 127.47117 -79.2734)
		(mid 127.431482 -79.473397)
		(end 127.318262 -79.64297)
		(width 0.1016)
		(layer "In2.Cu")
		(net "SAS3008_RAID_TX_N2")
	)
	(arc
		(start 124.78385 -73.0758)
		(mid 125.122014 -73.143065)
		(end 125.40869 -73.334626)
		(width 0.1016)
		(layer "In2.Cu")
		(net "SAS3008_RAID_TX_N2")
	)
	(arc
		(start 106.824272 -70.080632)
		(mid 107.80692 -70.737124)
		(end 108.966 -70.9676)
		(width 0.1016)
		(layer "In2.Cu")
		(net "SAS3008_RAID_TX_N2")
	)
	(arc
		(start 115.950746 -70.9676)
		(mid 116.292522 -71.035713)
		(end 116.58219 -71.229474)
		(width 0.1016)
		(layer "In2.Cu")
		(net "SAS3008_RAID_TX_N2")
	)
	(arc
		(start 117.735858 -72.382634)
		(mid 118.503598 -72.895622)
		(end 119.40921 -73.0758)
		(width 0.1016)
		(layer "In2.Cu")
		(net "SAS3008_RAID_TX_N2")
	)
	(arc
		(start 99.291394 -65.5828)
		(mid 99.983678 -65.720486)
		(end 100.570538 -66.112644)
		(width 0.1016)
		(layer "In2.Cu")
		(net "SAS3008_RAID_TX_N2")
	)
	(arc
		(start 79.915766 -46.90618)
		(mid 79.956251 -47.110274)
		(end 80.071722 -47.28337)
		(width 0.1016)
		(layer "In2.Cu")
		(net "SAS3008_RAID_TX_N2")
	)
	(arc
		(start 79.776828 -39.796974)
		(mid 79.879618 -39.95067)
		(end 79.915766 -40.132)
		(width 0.1016)
		(layer "In2.Cu")
		(net "SAS3008_RAID_TX_N2")
	)
	(arc
		(start 104.14 -67.8942)
		(mid 104.600279 -67.985867)
		(end 104.990392 -68.246752)
		(width 0.1016)
		(layer "In2.Cu")
		(net "SAS3008_RAID_TX_N2")
	)
	(arc
		(start 102.001574 -67.54368)
		(mid 102.389886 -67.803108)
		(end 102.847902 -67.8942)
		(width 0.1016)
		(layer "In2.Cu")
		(net "SAS3008_RAID_TX_N2")
	)
	(arc
		(start 127.28829 -75.214226)
		(mid 127.423623 -75.416766)
		(end 127.47117 -75.655678)
		(width 0.1016)
		(layer "In2.Cu")
		(net "SAS3008_RAID_TX_N2")
	)
	(arc
		(start 98.156776 -65.367916)
		(mid 98.394978 -65.527018)
		(end 98.675952 -65.5828)
		(width 0.1016)
		(layer "In2.Cu")
		(net "SAS3008_RAID_TX_N2")
	)
	(segment
		(start 173.43247 -112.82553)
		(end 174.371 -111.887)
		(width 0.3048)
		(layer "F.Cu")
		(net "P0V9_E_LX")
	)
	(segment
		(start 174.371 -111.887)
		(end 174.625 -111.887)
		(width 0.3048)
		(layer "F.Cu")
		(net "P0V9_E_LX")
	)
	(segment
		(start 173.43247 -113.492534)
		(end 173.43247 -112.82553)
		(width 0.3048)
		(layer "F.Cu")
		(net "P0V9_E_LX")
	)
	(via
		(at 176.0474 -113.2332)
		(size 0.7112)
		(drill 0.3556)
		(layers "F.Cu" "B.Cu")
		(net "P0V9_E_LX")
	)
	(via
		(at 170.307 -105.156)
		(size 0.7112)
		(drill 0.4064)
		(layers "F.Cu" "B.Cu")
		(net "P0V9_E_LX")
	)
	(via
		(at 174.625 -111.887)
		(size 0.5588)
		(drill 0.3048)
		(layers "F.Cu" "B.Cu")
		(net "P0V9_E_LX")
	)
	(segment
		(start 171.2595 -104.2035)
		(end 170.307 -105.156)
		(width 0.508)
		(layer "B.Cu")
		(net "P0V9_E_LX")
	)
	(segment
		(start 174.8282 -112.0902)
		(end 174.8282 -113.284)
		(width 0.508)
		(layer "B.Cu")
		(net "P0V9_E_LX")
	)
	(segment
		(start 174.8282 -113.284)
		(end 174.879 -113.2332)
		(width 0.508)
		(layer "B.Cu")
		(net "P0V9_E_LX")
	)
	(segment
		(start 174.879 -113.2332)
		(end 176.0474 -113.2332)
		(width 0.508)
		(layer "B.Cu")
		(net "P0V9_E_LX")
	)
	(segment
		(start 172.339 -104.2035)
		(end 171.2595 -104.2035)
		(width 0.508)
		(layer "B.Cu")
		(net "P0V9_E_LX")
	)
	(segment
		(start 174.625 -111.887)
		(end 174.8282 -112.0902)
		(width 0.508)
		(layer "B.Cu")
		(net "P0V9_E_LX")
	)
	(segment
		(start 103.315008 -87.349838)
		(end 102.86111 -86.89594)
		(width 0.1143)
		(layer "F.Cu")
		(net "XM_DATA5")
	)
	(segment
		(start 102.86111 -86.89594)
		(end 102.86111 -86.89848)
		(width 0.1143)
		(layer "F.Cu")
		(net "XM_DATA5")
	)
	(segment
		(start 103.349806 -87.349838)
		(end 103.315008 -87.349838)
		(width 0.1143)
		(layer "F.Cu")
		(net "XM_DATA5")
	)
	(segment
		(start 70.284848 -134.51205)
		(end 68.12407 -134.51205)
		(width 0.1143)
		(layer "F.Cu")
		(net "XM_DATA5")
	)
	(segment
		(start 70.66534 -134.892542)
		(end 70.284848 -134.51205)
		(width 0.1143)
		(layer "F.Cu")
		(net "XM_DATA5")
	)
	(segment
		(start 75.786742 -134.892542)
		(end 70.66534 -134.892542)
		(width 0.1143)
		(layer "F.Cu")
		(net "XM_DATA5")
	)
	(segment
		(start 68.12407 -134.51205)
		(end 67.57797 -135.05815)
		(width 0.1143)
		(layer "F.Cu")
		(net "XM_DATA5")
	)
	(via
		(at 67.72529 -136.42848)
		(size 0.7112)
		(drill 0.3556)
		(layers "F.Cu" "B.Cu")
		(net "XM_DATA5")
	)
	(via
		(at 102.86111 -86.89848)
		(size 0.508)
		(drill 0.254)
		(layers "F.Cu" "B.Cu")
		(net "XM_DATA5")
	)
	(via
		(at 67.57797 -135.05815)
		(size 0.5588)
		(drill 0.3048)
		(layers "F.Cu" "B.Cu")
		(net "XM_DATA5")
	)
	(segment
		(start 99.826318 -86.746334)
		(end 102.480364 -86.746334)
		(width 0.1143)
		(layer "B.Cu")
		(net "XM_DATA5")
	)
	(segment
		(start 102.480364 -86.746334)
		(end 102.63251 -86.89848)
		(width 0.1143)
		(layer "B.Cu")
		(net "XM_DATA5")
	)
	(segment
		(start 93.41485 -86.67115)
		(end 99.008692 -86.67115)
		(width 0.1143)
		(layer "B.Cu")
		(net "XM_DATA5")
	)
	(segment
		(start 73.265284 -87.757)
		(end 86.13267 -87.757)
		(width 0.1143)
		(layer "B.Cu")
		(net "XM_DATA5")
	)
	(segment
		(start 67.799966 -93.222318)
		(end 73.265284 -87.757)
		(width 0.1143)
		(layer "B.Cu")
		(net "XM_DATA5")
	)
	(segment
		(start 67.80022 -93.527372)
		(end 67.799966 -93.527118)
		(width 0.1143)
		(layer "B.Cu")
		(net "XM_DATA5")
	)
	(segment
		(start 67.57797 -135.05815)
		(end 67.80022 -134.8359)
		(width 0.1143)
		(layer "B.Cu")
		(net "XM_DATA5")
	)
	(segment
		(start 67.72529 -135.20547)
		(end 67.72529 -136.42848)
		(width 0.1143)
		(layer "B.Cu")
		(net "XM_DATA5")
	)
	(segment
		(start 86.60892 -87.28075)
		(end 92.80525 -87.28075)
		(width 0.1143)
		(layer "B.Cu")
		(net "XM_DATA5")
	)
	(segment
		(start 67.80022 -134.8359)
		(end 67.80022 -93.527372)
		(width 0.1143)
		(layer "B.Cu")
		(net "XM_DATA5")
	)
	(segment
		(start 92.80525 -87.28075)
		(end 93.41485 -86.67115)
		(width 0.1143)
		(layer "B.Cu")
		(net "XM_DATA5")
	)
	(segment
		(start 102.63251 -86.89848)
		(end 102.86111 -86.89848)
		(width 0.1143)
		(layer "B.Cu")
		(net "XM_DATA5")
	)
	(segment
		(start 67.57797 -135.05815)
		(end 67.72529 -135.20547)
		(width 0.1143)
		(layer "B.Cu")
		(net "XM_DATA5")
	)
	(segment
		(start 99.008692 -86.67115)
		(end 99.110292 -86.77275)
		(width 0.1143)
		(layer "B.Cu")
		(net "XM_DATA5")
	)
	(segment
		(start 99.799902 -86.77275)
		(end 99.826318 -86.746334)
		(width 0.1143)
		(layer "B.Cu")
		(net "XM_DATA5")
	)
	(segment
		(start 99.110292 -86.77275)
		(end 99.799902 -86.77275)
		(width 0.1143)
		(layer "B.Cu")
		(net "XM_DATA5")
	)
	(segment
		(start 86.13267 -87.757)
		(end 86.60892 -87.28075)
		(width 0.1143)
		(layer "B.Cu")
		(net "XM_DATA5")
	)
	(segment
		(start 67.799966 -93.527118)
		(end 67.799966 -93.222318)
		(width 0.1143)
		(layer "B.Cu")
		(net "XM_DATA5")
	)
	(segment
		(start 109.743494 -55.79999)
		(end 109.73054 -55.812944)
		(width 0.1143)
		(layer "F.Cu")
		(net "XM_ADDR_0")
	)
	(segment
		(start 109.613192 -55.812944)
		(end 109.390434 -56.035702)
		(width 0.1143)
		(layer "F.Cu")
		(net "XM_ADDR_0")
	)
	(segment
		(start 109.390434 -56.364124)
		(end 109.4867 -56.46039)
		(width 0.1143)
		(layer "F.Cu")
		(net "XM_ADDR_0")
	)
	(segment
		(start 109.390434 -58.341768)
		(end 109.263434 -58.468768)
		(width 0.1143)
		(layer "F.Cu")
		(net "XM_ADDR_0")
	)
	(segment
		(start 109.73054 -55.812944)
		(end 109.613192 -55.812944)
		(width 0.1143)
		(layer "F.Cu")
		(net "XM_ADDR_0")
	)
	(segment
		(start 109.728 -59.117992)
		(end 109.078776 -58.468768)
		(width 0.1143)
		(layer "F.Cu")
		(net "XM_ADDR_0")
	)
	(segment
		(start 109.728 -59.6265)
		(end 109.728 -59.117992)
		(width 0.1143)
		(layer "F.Cu")
		(net "XM_ADDR_0")
	)
	(segment
		(start 109.4867 -56.46039)
		(end 109.4867 -56.739282)
		(width 0.1143)
		(layer "F.Cu")
		(net "XM_ADDR_0")
	)
	(segment
		(start 111.76 -60.0075)
		(end 110.109 -60.0075)
		(width 0.1143)
		(layer "F.Cu")
		(net "XM_ADDR_0")
	)
	(segment
		(start 109.949996 -55.79999)
		(end 109.743494 -55.79999)
		(width 0.1143)
		(layer "F.Cu")
		(net "XM_ADDR_0")
	)
	(segment
		(start 109.263434 -58.468768)
		(end 109.078776 -58.468768)
		(width 0.1143)
		(layer "F.Cu")
		(net "XM_ADDR_0")
	)
	(segment
		(start 109.390434 -56.835548)
		(end 109.390434 -58.341768)
		(width 0.1143)
		(layer "F.Cu")
		(net "XM_ADDR_0")
	)
	(segment
		(start 110.109 -60.0075)
		(end 109.728 -59.6265)
		(width 0.1143)
		(layer "F.Cu")
		(net "XM_ADDR_0")
	)
	(segment
		(start 109.4867 -56.739282)
		(end 109.390434 -56.835548)
		(width 0.1143)
		(layer "F.Cu")
		(net "XM_ADDR_0")
	)
	(segment
		(start 109.390434 -56.035702)
		(end 109.390434 -56.364124)
		(width 0.1143)
		(layer "F.Cu")
		(net "XM_ADDR_0")
	)
	(via
		(at 109.078776 -58.468768)
		(size 0.508)
		(drill 0.254)
		(layers "F.Cu" "B.Cu")
		(net "XM_ADDR_0")
	)
	(segment
		(start 109.555534 -59.15152)
		(end 109.555534 -58.945526)
		(width 0.1143)
		(layer "B.Cu")
		(net "XM_ADDR_0")
	)
	(segment
		(start 109.555534 -58.945526)
		(end 109.078776 -58.468768)
		(width 0.1143)
		(layer "B.Cu")
		(net "XM_ADDR_0")
	)
	(segment
		(start 128.32207 -85.7123)
		(end 128.28397 -85.6742)
		(width 0.0889)
		(layer "F.Cu")
		(net "SAS_HDD_TX15_P")
	)
	(segment
		(start 126.193042 -85.960458)
		(end 126.1237 -86.0298)
		(width 0.0889)
		(layer "F.Cu")
		(net "SAS_HDD_TX15_P")
	)
	(segment
		(start 127.423164 -85.914992)
		(end 126.30277 -85.914992)
		(width 0.0889)
		(layer "F.Cu")
		(net "SAS_HDD_TX15_P")
	)
	(segment
		(start 128.686052 -85.796882)
		(end 128.526286 -85.796882)
		(width 0.0889)
		(layer "F.Cu")
		(net "SAS_HDD_TX15_P")
	)
	(segment
		(start 129.09677 -85.796882)
		(end 128.686052 -85.796882)
		(width 0.1016)
		(layer "F.Cu")
		(net "SAS_HDD_TX15_P")
	)
	(segment
		(start 126.181866 -86.181692)
		(end 126.350014 -86.34984)
		(width 0.0889)
		(layer "F.Cu")
		(net "SAS_HDD_TX15_P")
	)
	(segment
		(start 130.61696 -84.963)
		(end 130.49377 -84.963)
		(width 0.1016)
		(layer "F.Cu")
		(net "SAS_HDD_TX15_P")
	)
	(segment
		(start 130.189732 -85.08873)
		(end 129.754376 -85.52434)
		(width 0.1016)
		(layer "F.Cu")
		(net "SAS_HDD_TX15_P")
	)
	(arc
		(start 128.28397 -85.6742)
		(mid 128.14427 -85.616334)
		(end 128.00457 -85.6742)
		(width 0.0889)
		(layer "F.Cu")
		(net "SAS_HDD_TX15_P")
	)
	(arc
		(start 128.526286 -85.796882)
		(mid 128.415768 -85.774899)
		(end 128.32207 -85.7123)
		(width 0.0889)
		(layer "F.Cu")
		(net "SAS_HDD_TX15_P")
	)
	(arc
		(start 126.1237 -86.0298)
		(mid 126.13656 -86.111967)
		(end 126.181866 -86.181692)
		(width 0.0889)
		(layer "F.Cu")
		(net "SAS_HDD_TX15_P")
	)
	(arc
		(start 126.30277 -85.914992)
		(mid 126.24338 -85.926805)
		(end 126.193042 -85.960458)
		(width 0.0889)
		(layer "F.Cu")
		(net "SAS_HDD_TX15_P")
	)
	(arc
		(start 128.00457 -85.6742)
		(mid 127.737819 -85.852438)
		(end 127.423164 -85.914992)
		(width 0.0889)
		(layer "F.Cu")
		(net "SAS_HDD_TX15_P")
	)
	(arc
		(start 129.754376 -85.52434)
		(mid 129.452679 -85.726021)
		(end 129.09677 -85.796882)
		(width 0.1016)
		(layer "F.Cu")
		(net "SAS_HDD_TX15_P")
	)
	(arc
		(start 130.49377 -84.963)
		(mid 130.329251 -84.995631)
		(end 130.189732 -85.08873)
		(width 0.1016)
		(layer "F.Cu")
		(net "SAS_HDD_TX15_P")
	)
	(arc
		(start 130.790442 -85.034882)
		(mid 130.710848 -84.981699)
		(end 130.61696 -84.963)
		(width 0.1016)
		(layer "F.Cu")
		(net "SAS_HDD_TX15_P")
	)
	(segment
		(start 112.350042 -54.99989)
		(end 112.538256 -54.99989)
		(width 0.1143)
		(layer "F.Cu")
		(net "XM_ADDR_5")
	)
	(segment
		(start 150.114 -53.848)
		(end 150.495 -53.848)
		(width 0.1143)
		(layer "F.Cu")
		(net "XM_ADDR_5")
	)
	(segment
		(start 148.1201 -51.6001)
		(end 148.209 -51.689)
		(width 0.1143)
		(layer "F.Cu")
		(net "XM_ADDR_5")
	)
	(segment
		(start 146.598386 -42.7101)
		(end 146.598386 -43.982386)
		(width 0.1143)
		(layer "F.Cu")
		(net "XM_ADDR_5")
	)
	(segment
		(start 113.293906 -55.43169)
		(end 113.518442 -55.656226)
		(width 0.1143)
		(layer "F.Cu")
		(net "XM_ADDR_5")
	)
	(segment
		(start 112.538256 -54.99989)
		(end 112.970056 -55.43169)
		(width 0.1143)
		(layer "F.Cu")
		(net "XM_ADDR_5")
	)
	(segment
		(start 148.209 -51.689)
		(end 148.209 -51.943)
		(width 0.1143)
		(layer "F.Cu")
		(net "XM_ADDR_5")
	)
	(segment
		(start 148.209 -51.943)
		(end 150.114 -53.848)
		(width 0.1143)
		(layer "F.Cu")
		(net "XM_ADDR_5")
	)
	(segment
		(start 148.1201 -45.5041)
		(end 148.1201 -51.6001)
		(width 0.1143)
		(layer "F.Cu")
		(net "XM_ADDR_5")
	)
	(segment
		(start 114.789966 -57.2516)
		(end 114.789966 -58.3692)
		(width 0.1143)
		(layer "F.Cu")
		(net "XM_ADDR_5")
	)
	(segment
		(start 146.598386 -43.982386)
		(end 148.1201 -45.5041)
		(width 0.1143)
		(layer "F.Cu")
		(net "XM_ADDR_5")
	)
	(segment
		(start 151.5745 -54.356)
		(end 151.003 -54.356)
		(width 0.1143)
		(layer "F.Cu")
		(net "XM_ADDR_5")
	)
	(segment
		(start 113.518442 -55.656226)
		(end 113.518442 -55.980076)
		(width 0.1143)
		(layer "F.Cu")
		(net "XM_ADDR_5")
	)
	(segment
		(start 150.495 -53.848)
		(end 150.622 -53.975)
		(width 0.1143)
		(layer "F.Cu")
		(net "XM_ADDR_5")
	)
	(segment
		(start 151.003 -54.356)
		(end 150.622 -53.975)
		(width 0.1143)
		(layer "F.Cu")
		(net "XM_ADDR_5")
	)
	(segment
		(start 113.518442 -55.980076)
		(end 114.789966 -57.2516)
		(width 0.1143)
		(layer "F.Cu")
		(net "XM_ADDR_5")
	)
	(segment
		(start 112.970056 -55.43169)
		(end 113.293906 -55.43169)
		(width 0.1143)
		(layer "F.Cu")
		(net "XM_ADDR_5")
	)
	(via
		(at 150.622 -53.975)
		(size 0.7112)
		(drill 0.3556)
		(layers "F.Cu" "B.Cu")
		(net "XM_ADDR_5")
	)
	(via
		(at 114.789966 -58.3692)
		(size 0.508)
		(drill 0.254)
		(layers "F.Cu" "B.Cu")
		(net "XM_ADDR_5")
	)
	(via
		(at 148.209 -51.943)
		(size 0.5588)
		(drill 0.3048)
		(layers "F.Cu" "B.Cu")
		(net "XM_ADDR_5")
	)
	(segment
		(start 115.966748 -58.3692)
		(end 114.789966 -58.3692)
		(width 0.127)
		(layer "In5.Cu")
		(net "XM_ADDR_5")
	)
	(segment
		(start 124.881386 -57.066688)
		(end 117.26926 -57.066688)
		(width 0.127)
		(layer "In5.Cu")
		(net "XM_ADDR_5")
	)
	(segment
		(start 140.83792 -54.30774)
		(end 140.072618 -53.542438)
		(width 0.127)
		(layer "In5.Cu")
		(net "XM_ADDR_5")
	)
	(segment
		(start 142.946628 -52.697126)
		(end 140.738098 -52.697126)
		(width 0.127)
		(layer "In5.Cu")
		(net "XM_ADDR_5")
	)
	(segment
		(start 140.432028 -53.183028)
		(end 141.19733 -53.94833)
		(width 0.127)
		(layer "In5.Cu")
		(net "XM_ADDR_5")
	)
	(segment
		(start 140.072618 -53.542438)
		(end 139.892786 -53.542438)
		(width 0.127)
		(layer "In5.Cu")
		(net "XM_ADDR_5")
	)
	(segment
		(start 140.738098 -52.697126)
		(end 140.432028 -53.003196)
		(width 0.127)
		(layer "In5.Cu")
		(net "XM_ADDR_5")
	)
	(segment
		(start 137.469118 -55.966106)
		(end 125.981968 -55.966106)
		(width 0.127)
		(layer "In5.Cu")
		(net "XM_ADDR_5")
	)
	(segment
		(start 141.19733 -53.94833)
		(end 141.19733 -54.128162)
		(width 0.127)
		(layer "In5.Cu")
		(net "XM_ADDR_5")
	)
	(segment
		(start 143.551402 -54.341268)
		(end 143.551402 -53.3019)
		(width 0.127)
		(layer "In5.Cu")
		(net "XM_ADDR_5")
	)
	(segment
		(start 117.26926 -57.066688)
		(end 115.966748 -58.3692)
		(width 0.127)
		(layer "In5.Cu")
		(net "XM_ADDR_5")
	)
	(segment
		(start 148.209 -51.943)
		(end 145.5293 -54.6227)
		(width 0.127)
		(layer "In5.Cu")
		(net "XM_ADDR_5")
	)
	(segment
		(start 145.5293 -54.6227)
		(end 143.832834 -54.6227)
		(width 0.127)
		(layer "In5.Cu")
		(net "XM_ADDR_5")
	)
	(segment
		(start 141.19733 -54.128162)
		(end 141.017752 -54.30774)
		(width 0.127)
		(layer "In5.Cu")
		(net "XM_ADDR_5")
	)
	(segment
		(start 143.832834 -54.6227)
		(end 143.551402 -54.341268)
		(width 0.127)
		(layer "In5.Cu")
		(net "XM_ADDR_5")
	)
	(segment
		(start 141.017752 -54.30774)
		(end 140.83792 -54.30774)
		(width 0.127)
		(layer "In5.Cu")
		(net "XM_ADDR_5")
	)
	(segment
		(start 140.432028 -53.003196)
		(end 140.432028 -53.183028)
		(width 0.127)
		(layer "In5.Cu")
		(net "XM_ADDR_5")
	)
	(segment
		(start 139.892786 -53.542438)
		(end 137.469118 -55.966106)
		(width 0.127)
		(layer "In5.Cu")
		(net "XM_ADDR_5")
	)
	(segment
		(start 125.981968 -55.966106)
		(end 124.881386 -57.066688)
		(width 0.127)
		(layer "In5.Cu")
		(net "XM_ADDR_5")
	)
	(segment
		(start 143.551402 -53.3019)
		(end 142.946628 -52.697126)
		(width 0.127)
		(layer "In5.Cu")
		(net "XM_ADDR_5")
	)
	(segment
		(start 164.6555 -115.062)
		(end 163.576 -115.062)
		(width 0.254)
		(layer "F.Cu")
		(net "P0V9_E_VFB_R")
	)
	(segment
		(start 163.576 -115.062)
		(end 162.3695 -115.062)
		(width 0.254)
		(layer "F.Cu")
		(net "P0V9_E_VFB_R")
	)
	(via
		(at 163.576 -115.062)
		(size 0.7112)
		(drill 0.3556)
		(layers "F.Cu" "B.Cu")
		(net "P0V9_E_VFB_R")
	)
	(segment
		(start 104.349804 -88.349836)
		(end 103.849678 -87.84971)
		(width 0.1143)
		(layer "F.Cu")
		(net "XM_DATA7")
	)
	(segment
		(start 70.967854 -136.84885)
		(end 70.783704 -137.033)
		(width 0.1143)
		(layer "F.Cu")
		(net "XM_DATA7")
	)
	(segment
		(start 73.392538 -136.84885)
		(end 70.967854 -136.84885)
		(width 0.1143)
		(layer "F.Cu")
		(net "XM_DATA7")
	)
	(segment
		(start 75.786742 -136.892792)
		(end 73.43648 -136.892792)
		(width 0.1143)
		(layer "F.Cu")
		(net "XM_DATA7")
	)
	(segment
		(start 73.43648 -136.892792)
		(end 73.392538 -136.84885)
		(width 0.1143)
		(layer "F.Cu")
		(net "XM_DATA7")
	)
	(via
		(at 69.084444 -132.948934)
		(size 0.7112)
		(drill 0.3556)
		(layers "F.Cu" "B.Cu")
		(net "XM_DATA7")
	)
	(via
		(at 70.783704 -137.033)
		(size 0.5588)
		(drill 0.3048)
		(layers "F.Cu" "B.Cu")
		(net "XM_DATA7")
	)
	(via
		(at 103.849678 -87.84971)
		(size 0.508)
		(drill 0.254)
		(layers "F.Cu" "B.Cu")
		(net "XM_DATA7")
	)
	(segment
		(start 99.915218 -87.50935)
		(end 98.80473 -87.50935)
		(width 0.1143)
		(layer "B.Cu")
		(net "XM_DATA7")
	)
	(segment
		(start 73.488804 -89.30132)
		(end 68.53682 -94.253304)
		(width 0.1143)
		(layer "B.Cu")
		(net "XM_DATA7")
	)
	(segment
		(start 93.344746 -88.01735)
		(end 86.921594 -88.01735)
		(width 0.1143)
		(layer "B.Cu")
		(net "XM_DATA7")
	)
	(segment
		(start 98.80473 -87.50935)
		(end 98.70313 -87.40775)
		(width 0.1143)
		(layer "B.Cu")
		(net "XM_DATA7")
	)
	(segment
		(start 69.053964 -132.948934)
		(end 69.084444 -132.948934)
		(width 0.1143)
		(layer "B.Cu")
		(net "XM_DATA7")
	)
	(segment
		(start 70.216268 -136.465564)
		(end 70.216268 -135.468868)
		(width 0.1143)
		(layer "B.Cu")
		(net "XM_DATA7")
	)
	(segment
		(start 70.783704 -137.033)
		(end 70.216268 -136.465564)
		(width 0.1143)
		(layer "B.Cu")
		(net "XM_DATA7")
	)
	(segment
		(start 70.47992 -135.205216)
		(end 70.47992 -134.34441)
		(width 0.1143)
		(layer "B.Cu")
		(net "XM_DATA7")
	)
	(segment
		(start 68.53682 -132.43179)
		(end 69.053964 -132.948934)
		(width 0.1143)
		(layer "B.Cu")
		(net "XM_DATA7")
	)
	(segment
		(start 103.619554 -88.079834)
		(end 100.485702 -88.079834)
		(width 0.1143)
		(layer "B.Cu")
		(net "XM_DATA7")
	)
	(segment
		(start 93.954346 -87.40775)
		(end 93.344746 -88.01735)
		(width 0.1143)
		(layer "B.Cu")
		(net "XM_DATA7")
	)
	(segment
		(start 103.849678 -87.84971)
		(end 103.619554 -88.079834)
		(width 0.1143)
		(layer "B.Cu")
		(net "XM_DATA7")
	)
	(segment
		(start 100.485702 -88.079834)
		(end 99.915218 -87.50935)
		(width 0.1143)
		(layer "B.Cu")
		(net "XM_DATA7")
	)
	(segment
		(start 70.216268 -135.468868)
		(end 70.47992 -135.205216)
		(width 0.1143)
		(layer "B.Cu")
		(net "XM_DATA7")
	)
	(segment
		(start 86.445344 -88.4936)
		(end 86.44509 -88.4936)
		(width 0.1143)
		(layer "B.Cu")
		(net "XM_DATA7")
	)
	(segment
		(start 85.63737 -89.30132)
		(end 73.488804 -89.30132)
		(width 0.1143)
		(layer "B.Cu")
		(net "XM_DATA7")
	)
	(segment
		(start 70.47992 -134.34441)
		(end 69.084444 -132.948934)
		(width 0.1143)
		(layer "B.Cu")
		(net "XM_DATA7")
	)
	(segment
		(start 86.921594 -88.01735)
		(end 86.445344 -88.4936)
		(width 0.1143)
		(layer "B.Cu")
		(net "XM_DATA7")
	)
	(segment
		(start 68.53682 -94.253304)
		(end 68.53682 -132.43179)
		(width 0.1143)
		(layer "B.Cu")
		(net "XM_DATA7")
	)
	(segment
		(start 98.70313 -87.40775)
		(end 93.954346 -87.40775)
		(width 0.1143)
		(layer "B.Cu")
		(net "XM_DATA7")
	)
	(segment
		(start 86.44509 -88.4936)
		(end 85.63737 -89.30132)
		(width 0.1143)
		(layer "B.Cu")
		(net "XM_DATA7")
	)
	(segment
		(start 131.669536 -83.656932)
		(end 130.193542 -83.656932)
		(width 0.1016)
		(layer "F.Cu")
		(net "SAS_HDD_TX14_N")
	)
	(segment
		(start 133.232398 -83.9851)
		(end 132.461762 -83.9851)
		(width 0.1016)
		(layer "F.Cu")
		(net "SAS_HDD_TX14_N")
	)
	(segment
		(start 128.639824 -84.818982)
		(end 127.191262 -84.818982)
		(width 0.1016)
		(layer "F.Cu")
		(net "SAS_HDD_TX14_N")
	)
	(segment
		(start 126.621286 -85.07857)
		(end 126.350014 -85.349842)
		(width 0.1016)
		(layer "F.Cu")
		(net "SAS_HDD_TX14_N")
	)
	(segment
		(start 129.6797 -83.869784)
		(end 128.795018 -84.754466)
		(width 0.1016)
		(layer "F.Cu")
		(net "SAS_HDD_TX14_N")
	)
	(segment
		(start 126.66091 -85.038692)
		(end 126.621286 -85.07857)
		(width 0.1016)
		(layer "F.Cu")
		(net "SAS_HDD_TX14_N")
	)
	(arc
		(start 130.193542 -83.656932)
		(mid 129.915488 -83.712316)
		(end 129.6797 -83.869784)
		(width 0.1016)
		(layer "F.Cu")
		(net "SAS_HDD_TX14_N")
	)
	(arc
		(start 128.795018 -84.754466)
		(mid 128.72383 -84.802155)
		(end 128.639824 -84.818982)
		(width 0.1016)
		(layer "F.Cu")
		(net "SAS_HDD_TX14_N")
	)
	(arc
		(start 132.461762 -83.9851)
		(mid 132.393955 -83.971537)
		(end 132.33654 -83.93303)
		(width 0.1016)
		(layer "F.Cu")
		(net "SAS_HDD_TX14_N")
	)
	(arc
		(start 132.33654 -83.93303)
		(mid 132.030501 -83.728634)
		(end 131.669536 -83.656932)
		(width 0.1016)
		(layer "F.Cu")
		(net "SAS_HDD_TX14_N")
	)
	(arc
		(start 133.457442 -83.891882)
		(mid 133.354191 -83.960872)
		(end 133.232398 -83.9851)
		(width 0.1016)
		(layer "F.Cu")
		(net "SAS_HDD_TX14_N")
	)
	(arc
		(start 127.191262 -84.818982)
		(mid 126.904226 -84.876077)
		(end 126.66091 -85.038692)
		(width 0.1016)
		(layer "F.Cu")
		(net "SAS_HDD_TX14_N")
	)
	(segment
		(start 113.150142 -50.999898)
		(end 113.15954 -50.999898)
		(width 0.1143)
		(layer "F.Cu")
		(net "XM_ADDR_25")
	)
	(segment
		(start 113.15954 -50.999898)
		(end 113.554002 -50.605436)
		(width 0.1143)
		(layer "F.Cu")
		(net "XM_ADDR_25")
	)
	(via
		(at 113.554002 -50.605436)
		(size 0.508)
		(drill 0.254)
		(layers "F.Cu" "B.Cu")
		(net "XM_ADDR_25")
	)
	(segment
		(start 114.360198 -50.89525)
		(end 113.843816 -50.89525)
		(width 0.1143)
		(layer "B.Cu")
		(net "XM_ADDR_25")
	)
	(segment
		(start 113.843816 -50.89525)
		(end 113.554002 -50.605436)
		(width 0.1143)
		(layer "B.Cu")
		(net "XM_ADDR_25")
	)
	(segment
		(start 165.789356 -109.864652)
		(end 165.789356 -108.766356)
		(width 0.254)
		(layer "F.Cu")
		(net "P0V9_E_MODE")
	)
	(segment
		(start 169.432224 -120.777)
		(end 169.926 -120.777)
		(width 0.254)
		(layer "F.Cu")
		(net "P0V9_E_MODE")
	)
	(segment
		(start 169.432224 -120.777)
		(end 169.432224 -118.391178)
		(width 0.254)
		(layer "F.Cu")
		(net "P0V9_E_MODE")
	)
	(segment
		(start 169.926 -120.777)
		(end 170.18 -121.031)
		(width 0.254)
		(layer "F.Cu")
		(net "P0V9_E_MODE")
	)
	(segment
		(start 169.432224 -121.744232)
		(end 169.432224 -120.777)
		(width 0.254)
		(layer "F.Cu")
		(net "P0V9_E_MODE")
	)
	(segment
		(start 169.789348 -122.101356)
		(end 169.432224 -121.744232)
		(width 0.254)
		(layer "F.Cu")
		(net "P0V9_E_MODE")
	)
	(via
		(at 165.789356 -108.766356)
		(size 0.5588)
		(drill 0.3048)
		(layers "F.Cu" "B.Cu")
		(net "P0V9_E_MODE")
	)
	(via
		(at 169.432224 -120.777)
		(size 0.5588)
		(drill 0.3048)
		(layers "F.Cu" "B.Cu")
		(net "P0V9_E_MODE")
	)
	(via
		(at 170.18 -121.031)
		(size 0.7112)
		(drill 0.3556)
		(layers "F.Cu" "B.Cu")
		(net "P0V9_E_MODE")
	)
	(segment
		(start 167.259 -113.157)
		(end 167.259 -118.603776)
		(width 0.254)
		(layer "In5.Cu")
		(net "P0V9_E_MODE")
	)
	(segment
		(start 167.259 -118.603776)
		(end 169.432224 -120.777)
		(width 0.254)
		(layer "In5.Cu")
		(net "P0V9_E_MODE")
	)
	(segment
		(start 167.005 -109.982)
		(end 167.005 -112.903)
		(width 0.254)
		(layer "In5.Cu")
		(net "P0V9_E_MODE")
	)
	(segment
		(start 165.789356 -108.766356)
		(end 167.005 -109.982)
		(width 0.254)
		(layer "In5.Cu")
		(net "P0V9_E_MODE")
	)
	(segment
		(start 167.005 -112.903)
		(end 167.259 -113.157)
		(width 0.254)
		(layer "In5.Cu")
		(net "P0V9_E_MODE")
	)
	(segment
		(start 74.728832 -129.892552)
		(end 74.719434 -129.90195)
		(width 0.1143)
		(layer "F.Cu")
		(net "XM_DATA8")
	)
	(segment
		(start 75.786742 -129.892552)
		(end 74.728832 -129.892552)
		(width 0.1143)
		(layer "F.Cu")
		(net "XM_DATA8")
	)
	(segment
		(start 74.022712 -129.90195)
		(end 73.940162 -129.8194)
		(width 0.1143)
		(layer "F.Cu")
		(net "XM_DATA8")
	)
	(segment
		(start 74.719434 -129.90195)
		(end 74.022712 -129.90195)
		(width 0.1143)
		(layer "F.Cu")
		(net "XM_DATA8")
	)
	(segment
		(start 102.349808 -86.34984)
		(end 102.17785 -86.177882)
		(width 0.1143)
		(layer "F.Cu")
		(net "XM_DATA8")
	)
	(segment
		(start 73.940162 -129.8194)
		(end 67.22237 -129.8194)
		(width 0.1143)
		(layer "F.Cu")
		(net "XM_DATA8")
	)
	(segment
		(start 102.17785 -86.177882)
		(end 101.23297 -86.177882)
		(width 0.1143)
		(layer "F.Cu")
		(net "XM_DATA8")
	)
	(via
		(at 67.22237 -129.8194)
		(size 0.5588)
		(drill 0.3048)
		(layers "F.Cu" "B.Cu")
		(net "XM_DATA8")
	)
	(via
		(at 101.23297 -86.177882)
		(size 0.508)
		(drill 0.254)
		(layers "F.Cu" "B.Cu")
		(net "XM_DATA8")
	)
	(via
		(at 67.22491 -123.88342)
		(size 0.7112)
		(drill 0.3556)
		(layers "F.Cu" "B.Cu")
		(net "XM_DATA8")
	)
	(segment
		(start 67.22237 -123.88088)
		(end 67.22237 -93.27896)
		(width 0.1143)
		(layer "B.Cu")
		(net "XM_DATA8")
	)
	(segment
		(start 83.338162 -87.3887)
		(end 83.452462 -87.2744)
		(width 0.1143)
		(layer "B.Cu")
		(net "XM_DATA8")
	)
	(segment
		(start 100.856034 -86.177882)
		(end 101.23297 -86.177882)
		(width 0.1143)
		(layer "B.Cu")
		(net "XM_DATA8")
	)
	(segment
		(start 82.652362 -86.3219)
		(end 82.880962 -86.3219)
		(width 0.1143)
		(layer "B.Cu")
		(net "XM_DATA8")
	)
	(segment
		(start 83.109562 -87.3887)
		(end 83.338162 -87.3887)
		(width 0.1143)
		(layer "B.Cu")
		(net "XM_DATA8")
	)
	(segment
		(start 82.538062 -87.2744)
		(end 82.538062 -86.4362)
		(width 0.1143)
		(layer "B.Cu")
		(net "XM_DATA8")
	)
	(segment
		(start 82.995262 -87.2744)
		(end 83.109562 -87.3887)
		(width 0.1143)
		(layer "B.Cu")
		(net "XM_DATA8")
	)
	(segment
		(start 99.647248 -86.40445)
		(end 99.742498 -86.3092)
		(width 0.1143)
		(layer "B.Cu")
		(net "XM_DATA8")
	)
	(segment
		(start 88.9 -85.99805)
		(end 98.86442 -85.99805)
		(width 0.1143)
		(layer "B.Cu")
		(net "XM_DATA8")
	)
	(segment
		(start 99.742498 -86.3092)
		(end 100.724716 -86.3092)
		(width 0.1143)
		(layer "B.Cu")
		(net "XM_DATA8")
	)
	(segment
		(start 98.99142 -86.12505)
		(end 98.99142 -86.133178)
		(width 0.1143)
		(layer "B.Cu")
		(net "XM_DATA8")
	)
	(segment
		(start 84.252562 -87.3887)
		(end 84.366862 -87.2744)
		(width 0.1143)
		(layer "B.Cu")
		(net "XM_DATA8")
	)
	(segment
		(start 85.217 -87.3887)
		(end 85.73135 -86.87435)
		(width 0.1143)
		(layer "B.Cu")
		(net "XM_DATA8")
	)
	(segment
		(start 99.262692 -86.40445)
		(end 99.647248 -86.40445)
		(width 0.1143)
		(layer "B.Cu")
		(net "XM_DATA8")
	)
	(segment
		(start 82.995262 -86.4362)
		(end 82.995262 -87.2744)
		(width 0.1143)
		(layer "B.Cu")
		(net "XM_DATA8")
	)
	(segment
		(start 73.112376 -87.3887)
		(end 82.423762 -87.3887)
		(width 0.1143)
		(layer "B.Cu")
		(net "XM_DATA8")
	)
	(segment
		(start 98.86442 -85.99805)
		(end 98.99142 -86.12505)
		(width 0.1143)
		(layer "B.Cu")
		(net "XM_DATA8")
	)
	(segment
		(start 67.22491 -123.88342)
		(end 67.22237 -123.88088)
		(width 0.1143)
		(layer "B.Cu")
		(net "XM_DATA8")
	)
	(segment
		(start 84.824062 -86.726522)
		(end 84.824062 -87.2744)
		(width 0.1143)
		(layer "B.Cu")
		(net "XM_DATA8")
	)
	(segment
		(start 100.724716 -86.3092)
		(end 100.856034 -86.177882)
		(width 0.1143)
		(layer "B.Cu")
		(net "XM_DATA8")
	)
	(segment
		(start 82.538062 -86.4362)
		(end 82.652362 -86.3219)
		(width 0.1143)
		(layer "B.Cu")
		(net "XM_DATA8")
	)
	(segment
		(start 83.452462 -87.2744)
		(end 83.452462 -86.4362)
		(width 0.1143)
		(layer "B.Cu")
		(net "XM_DATA8")
	)
	(segment
		(start 84.493862 -86.599522)
		(end 84.697062 -86.599522)
		(width 0.1143)
		(layer "B.Cu")
		(net "XM_DATA8")
	)
	(segment
		(start 84.366862 -86.726522)
		(end 84.493862 -86.599522)
		(width 0.1143)
		(layer "B.Cu")
		(net "XM_DATA8")
	)
	(segment
		(start 72.896984 -87.604092)
		(end 73.112376 -87.3887)
		(width 0.1143)
		(layer "B.Cu")
		(net "XM_DATA8")
	)
	(segment
		(start 83.795362 -86.3219)
		(end 83.909662 -86.4362)
		(width 0.1143)
		(layer "B.Cu")
		(net "XM_DATA8")
	)
	(segment
		(start 72.896984 -87.604346)
		(end 72.896984 -87.604092)
		(width 0.1143)
		(layer "B.Cu")
		(net "XM_DATA8")
	)
	(segment
		(start 67.22237 -123.88596)
		(end 67.22491 -123.88342)
		(width 0.1143)
		(layer "B.Cu")
		(net "XM_DATA8")
	)
	(segment
		(start 67.22237 -129.8194)
		(end 67.22237 -123.88596)
		(width 0.1143)
		(layer "B.Cu")
		(net "XM_DATA8")
	)
	(segment
		(start 82.880962 -86.3219)
		(end 82.995262 -86.4362)
		(width 0.1143)
		(layer "B.Cu")
		(net "XM_DATA8")
	)
	(segment
		(start 84.697062 -86.599522)
		(end 84.824062 -86.726522)
		(width 0.1143)
		(layer "B.Cu")
		(net "XM_DATA8")
	)
	(segment
		(start 84.938362 -87.3887)
		(end 85.217 -87.3887)
		(width 0.1143)
		(layer "B.Cu")
		(net "XM_DATA8")
	)
	(segment
		(start 83.909662 -87.2744)
		(end 84.023962 -87.3887)
		(width 0.1143)
		(layer "B.Cu")
		(net "XM_DATA8")
	)
	(segment
		(start 84.023962 -87.3887)
		(end 84.252562 -87.3887)
		(width 0.1143)
		(layer "B.Cu")
		(net "XM_DATA8")
	)
	(segment
		(start 83.452462 -86.4362)
		(end 83.566762 -86.3219)
		(width 0.1143)
		(layer "B.Cu")
		(net "XM_DATA8")
	)
	(segment
		(start 84.366862 -87.2744)
		(end 84.366862 -86.726522)
		(width 0.1143)
		(layer "B.Cu")
		(net "XM_DATA8")
	)
	(segment
		(start 83.566762 -86.3219)
		(end 83.795362 -86.3219)
		(width 0.1143)
		(layer "B.Cu")
		(net "XM_DATA8")
	)
	(segment
		(start 88.0237 -86.87435)
		(end 88.9 -85.99805)
		(width 0.1143)
		(layer "B.Cu")
		(net "XM_DATA8")
	)
	(segment
		(start 82.423762 -87.3887)
		(end 82.538062 -87.2744)
		(width 0.1143)
		(layer "B.Cu")
		(net "XM_DATA8")
	)
	(segment
		(start 83.909662 -86.4362)
		(end 83.909662 -87.2744)
		(width 0.1143)
		(layer "B.Cu")
		(net "XM_DATA8")
	)
	(segment
		(start 98.99142 -86.133178)
		(end 99.262692 -86.40445)
		(width 0.1143)
		(layer "B.Cu")
		(net "XM_DATA8")
	)
	(segment
		(start 85.73135 -86.87435)
		(end 88.0237 -86.87435)
		(width 0.1143)
		(layer "B.Cu")
		(net "XM_DATA8")
	)
	(segment
		(start 67.22237 -93.27896)
		(end 72.896984 -87.604346)
		(width 0.1143)
		(layer "B.Cu")
		(net "XM_DATA8")
	)
	(segment
		(start 84.824062 -87.2744)
		(end 84.938362 -87.3887)
		(width 0.1143)
		(layer "B.Cu")
		(net "XM_DATA8")
	)
	(segment
		(start 132.977382 -84.328)
		(end 132.462016 -84.328)
		(width 0.1016)
		(layer "F.Cu")
		(net "SAS_HDD_TX14_P")
	)
	(segment
		(start 129.92227 -84.112354)
		(end 129.037588 -84.997036)
		(width 0.1016)
		(layer "F.Cu")
		(net "SAS_HDD_TX14_P")
	)
	(segment
		(start 128.63957 -85.161882)
		(end 127.80137 -85.161882)
		(width 0.1016)
		(layer "F.Cu")
		(net "SAS_HDD_TX14_P")
	)
	(segment
		(start 131.669536 -83.999832)
		(end 130.193796 -83.999832)
		(width 0.1016)
		(layer "F.Cu")
		(net "SAS_HDD_TX14_P")
	)
	(segment
		(start 127.351536 -85.348064)
		(end 127.350012 -85.349842)
		(width 0.1016)
		(layer "F.Cu")
		(net "SAS_HDD_TX14_P")
	)
	(arc
		(start 127.355346 -85.344)
		(mid 127.353437 -85.346028)
		(end 127.351536 -85.348064)
		(width 0.1016)
		(layer "F.Cu")
		(net "SAS_HDD_TX14_P")
	)
	(arc
		(start 130.193796 -83.999832)
		(mid 130.046827 -84.029066)
		(end 129.92227 -84.112354)
		(width 0.1016)
		(layer "F.Cu")
		(net "SAS_HDD_TX14_P")
	)
	(arc
		(start 133.457442 -84.526882)
		(mid 133.237189 -84.379713)
		(end 132.977382 -84.328)
		(width 0.1016)
		(layer "F.Cu")
		(net "SAS_HDD_TX14_P")
	)
	(arc
		(start 132.462016 -84.328)
		(mid 132.26285 -84.288383)
		(end 132.09397 -84.1756)
		(width 0.1016)
		(layer "F.Cu")
		(net "SAS_HDD_TX14_P")
	)
	(arc
		(start 127.703326 -85.169248)
		(mid 127.515631 -85.229337)
		(end 127.355346 -85.344)
		(width 0.1016)
		(layer "F.Cu")
		(net "SAS_HDD_TX14_P")
	)
	(arc
		(start 129.037588 -84.997036)
		(mid 128.854976 -85.119054)
		(end 128.63957 -85.161882)
		(width 0.1016)
		(layer "F.Cu")
		(net "SAS_HDD_TX14_P")
	)
	(arc
		(start 132.09397 -84.1756)
		(mid 131.899238 -84.045484)
		(end 131.669536 -83.999832)
		(width 0.1016)
		(layer "F.Cu")
		(net "SAS_HDD_TX14_P")
	)
	(arc
		(start 127.80137 -85.161882)
		(mid 127.752205 -85.163666)
		(end 127.703326 -85.169248)
		(width 0.1016)
		(layer "F.Cu")
		(net "SAS_HDD_TX14_P")
	)
	(segment
		(start 111.694468 -58.79211)
		(end 111.694468 -57.002934)
		(width 0.1143)
		(layer "F.Cu")
		(net "XM_ADDR_2")
	)
	(segment
		(start 150.577804 -50.927)
		(end 151.5745 -50.927)
		(width 0.1143)
		(layer "F.Cu")
		(net "XM_ADDR_2")
	)
	(segment
		(start 150.218902 -45.570902)
		(end 150.218902 -50.568098)
		(width 0.1143)
		(layer "F.Cu")
		(net "XM_ADDR_2")
	)
	(segment
		(start 111.549942 -55.078376)
		(end 111.549942 -54.99989)
		(width 0.1143)
		(layer "F.Cu")
		(net "XM_ADDR_2")
	)
	(segment
		(start 111.75492 -58.960004)
		(end 111.75492 -58.852562)
		(width 0.1143)
		(layer "F.Cu")
		(net "XM_ADDR_2")
	)
	(segment
		(start 151.5745 -50.927)
		(end 151.638 -50.8635)
		(width 0.1143)
		(layer "F.Cu")
		(net "XM_ADDR_2")
	)
	(segment
		(start 148.099526 -43.451526)
		(end 150.218902 -45.570902)
		(width 0.1143)
		(layer "F.Cu")
		(net "XM_ADDR_2")
	)
	(segment
		(start 151.638 -50.8635)
		(end 151.638 -49.911)
		(width 0.1143)
		(layer "F.Cu")
		(net "XM_ADDR_2")
	)
	(segment
		(start 148.099526 -42.7101)
		(end 148.099526 -43.451526)
		(width 0.1143)
		(layer "F.Cu")
		(net "XM_ADDR_2")
	)
	(segment
		(start 111.886492 -55.414926)
		(end 111.549942 -55.078376)
		(width 0.1143)
		(layer "F.Cu")
		(net "XM_ADDR_2")
	)
	(segment
		(start 111.886492 -56.81091)
		(end 111.886492 -55.414926)
		(width 0.1143)
		(layer "F.Cu")
		(net "XM_ADDR_2")
	)
	(segment
		(start 111.75492 -58.852562)
		(end 111.694468 -58.79211)
		(width 0.1143)
		(layer "F.Cu")
		(net "XM_ADDR_2")
	)
	(segment
		(start 150.218902 -50.568098)
		(end 150.577804 -50.927)
		(width 0.1143)
		(layer "F.Cu")
		(net "XM_ADDR_2")
	)
	(segment
		(start 111.694468 -57.002934)
		(end 111.886492 -56.81091)
		(width 0.1143)
		(layer "F.Cu")
		(net "XM_ADDR_2")
	)
	(via
		(at 111.75492 -58.960004)
		(size 0.508)
		(drill 0.254)
		(layers "F.Cu" "B.Cu")
		(net "XM_ADDR_2")
	)
	(via
		(at 151.638 -49.911)
		(size 0.7112)
		(drill 0.3556)
		(layers "F.Cu" "B.Cu")
		(net "XM_ADDR_2")
	)
	(via
		(at 150.218902 -50.568098)
		(size 0.5588)
		(drill 0.3048)
		(layers "F.Cu" "B.Cu")
		(net "XM_ADDR_2")
	)
	(segment
		(start 138.893296 -57.693306)
		(end 138.922252 -57.722262)
		(width 0.127)
		(layer "In5.Cu")
		(net "XM_ADDR_2")
	)
	(segment
		(start 113.23955 -58.960004)
		(end 114.007646 -59.7281)
		(width 0.127)
		(layer "In5.Cu")
		(net "XM_ADDR_2")
	)
	(segment
		(start 150.114 -50.673)
		(end 150.218902 -50.568098)
		(width 0.127)
		(layer "In5.Cu")
		(net "XM_ADDR_2")
	)
	(segment
		(start 145.71091 -57.687972)
		(end 150.114 -53.284882)
		(width 0.127)
		(layer "In5.Cu")
		(net "XM_ADDR_2")
	)
	(segment
		(start 126.02845 -58.793888)
		(end 127.129032 -57.693306)
		(width 0.127)
		(layer "In5.Cu")
		(net "XM_ADDR_2")
	)
	(segment
		(start 117.397276 -59.7281)
		(end 118.331488 -58.793888)
		(width 0.127)
		(layer "In5.Cu")
		(net "XM_ADDR_2")
	)
	(segment
		(start 139.332716 -57.722262)
		(end 139.367006 -57.687972)
		(width 0.127)
		(layer "In5.Cu")
		(net "XM_ADDR_2")
	)
	(segment
		(start 118.331488 -58.793888)
		(end 126.02845 -58.793888)
		(width 0.127)
		(layer "In5.Cu")
		(net "XM_ADDR_2")
	)
	(segment
		(start 114.007646 -59.7281)
		(end 117.397276 -59.7281)
		(width 0.127)
		(layer "In5.Cu")
		(net "XM_ADDR_2")
	)
	(segment
		(start 138.922252 -57.722262)
		(end 139.332716 -57.722262)
		(width 0.127)
		(layer "In5.Cu")
		(net "XM_ADDR_2")
	)
	(segment
		(start 139.367006 -57.687972)
		(end 145.71091 -57.687972)
		(width 0.127)
		(layer "In5.Cu")
		(net "XM_ADDR_2")
	)
	(segment
		(start 150.114 -53.284882)
		(end 150.114 -50.673)
		(width 0.127)
		(layer "In5.Cu")
		(net "XM_ADDR_2")
	)
	(segment
		(start 127.129032 -57.693306)
		(end 138.893296 -57.693306)
		(width 0.127)
		(layer "In5.Cu")
		(net "XM_ADDR_2")
	)
	(segment
		(start 111.75492 -58.960004)
		(end 113.23955 -58.960004)
		(width 0.127)
		(layer "In5.Cu")
		(net "XM_ADDR_2")
	)
	(segment
		(start 166.61638 -113.8682)
		(end 166.560754 -113.923826)
		(width 0.254)
		(layer "F.Cu")
		(net "P0V9_E_VFB")
	)
	(segment
		(start 167.990266 -113.492534)
		(end 167.6146 -113.8682)
		(width 0.254)
		(layer "F.Cu")
		(net "P0V9_E_VFB")
	)
	(segment
		(start 165.5445 -113.919)
		(end 166.5605 -113.919)
		(width 0.254)
		(layer "F.Cu")
		(net "P0V9_E_VFB")
	)
	(segment
		(start 167.6146 -113.8682)
		(end 166.61638 -113.8682)
		(width 0.254)
		(layer "F.Cu")
		(net "P0V9_E_VFB")
	)
	(segment
		(start 168.432226 -113.492534)
		(end 167.990266 -113.492534)
		(width 0.254)
		(layer "F.Cu")
		(net "P0V9_E_VFB")
	)
	(segment
		(start 165.5445 -115.062)
		(end 165.5445 -113.919)
		(width 0.254)
		(layer "F.Cu")
		(net "P0V9_E_VFB")
	)
	(segment
		(start 165.5445 -116.078)
		(end 165.5445 -115.062)
		(width 0.254)
		(layer "F.Cu")
		(net "P0V9_E_VFB")
	)
	(segment
		(start 166.5605 -113.919)
		(end 166.560754 -113.923826)
		(width 0.254)
		(layer "F.Cu")
		(net "P0V9_E_VFB")
	)
	(via
		(at 166.560754 -113.923826)
		(size 0.7112)
		(drill 0.3556)
		(layers "F.Cu" "B.Cu")
		(net "P0V9_E_VFB")
	)
	(segment
		(start 65.11798 -130.76301)
		(end 65.11798 -130.42265)
		(width 0.1143)
		(layer "F.Cu")
		(net "EXP_XM_ADDR_18")
	)
	(segment
		(start 61.971936 -130.831336)
		(end 61.971936 -130.2258)
		(width 0.1143)
		(layer "F.Cu")
		(net "EXP_XM_ADDR_18")
	)
	(segment
		(start 61.514736 -130.831336)
		(end 61.629036 -130.945636)
		(width 0.1143)
		(layer "F.Cu")
		(net "EXP_XM_ADDR_18")
	)
	(segment
		(start 65.57137 -130.97764)
		(end 65.82283 -131.2291)
		(width 0.1143)
		(layer "F.Cu")
		(net "EXP_XM_ADDR_18")
	)
	(segment
		(start 68.71335 -130.81508)
		(end 68.82765 -130.92938)
		(width 0.1143)
		(layer "F.Cu")
		(net "EXP_XM_ADDR_18")
	)
	(segment
		(start 104.349804 -94.349824)
		(end 103.849678 -93.849698)
		(width 0.1143)
		(layer "F.Cu")
		(net "EXP_XM_ADDR_18")
	)
	(segment
		(start 61.057536 -130.2258)
		(end 61.171836 -130.1115)
		(width 0.1143)
		(layer "F.Cu")
		(net "EXP_XM_ADDR_18")
	)
	(segment
		(start 69.28485 -131.63042)
		(end 69.28485 -130.92938)
		(width 0.1143)
		(layer "F.Cu")
		(net "EXP_XM_ADDR_18")
	)
	(segment
		(start 62.543436 -130.945636)
		(end 63.106554 -130.945636)
		(width 0.1143)
		(layer "F.Cu")
		(net "EXP_XM_ADDR_18")
	)
	(segment
		(start 64.592454 -130.4163)
		(end 64.592454 -130.831336)
		(width 0.1143)
		(layer "F.Cu")
		(net "EXP_XM_ADDR_18")
	)
	(segment
		(start 62.429136 -130.2258)
		(end 62.429136 -130.831336)
		(width 0.1143)
		(layer "F.Cu")
		(net "EXP_XM_ADDR_18")
	)
	(segment
		(start 63.792354 -130.945636)
		(end 64.020954 -130.945636)
		(width 0.1143)
		(layer "F.Cu")
		(net "EXP_XM_ADDR_18")
	)
	(segment
		(start 61.400436 -130.1115)
		(end 61.514736 -130.2258)
		(width 0.1143)
		(layer "F.Cu")
		(net "EXP_XM_ADDR_18")
	)
	(segment
		(start 64.020954 -130.945636)
		(end 64.135254 -130.831336)
		(width 0.1143)
		(layer "F.Cu")
		(net "EXP_XM_ADDR_18")
	)
	(segment
		(start 64.592454 -130.831336)
		(end 64.706754 -130.945636)
		(width 0.1143)
		(layer "F.Cu")
		(net "EXP_XM_ADDR_18")
	)
	(segment
		(start 60.943236 -130.945636)
		(end 61.057536 -130.831336)
		(width 0.1143)
		(layer "F.Cu")
		(net "EXP_XM_ADDR_18")
	)
	(segment
		(start 64.935354 -130.945636)
		(end 65.11798 -130.76301)
		(width 0.1143)
		(layer "F.Cu")
		(net "EXP_XM_ADDR_18")
	)
	(segment
		(start 62.086236 -130.1115)
		(end 62.314836 -130.1115)
		(width 0.1143)
		(layer "F.Cu")
		(net "EXP_XM_ADDR_18")
	)
	(segment
		(start 64.478154 -130.302)
		(end 64.592454 -130.4163)
		(width 0.1143)
		(layer "F.Cu")
		(net "EXP_XM_ADDR_18")
	)
	(segment
		(start 70.55993 -130.4671)
		(end 70.54723 -130.4671)
		(width 0.1143)
		(layer "F.Cu")
		(net "EXP_XM_ADDR_18")
	)
	(segment
		(start 93.48597 -95.504)
		(end 93.61297 -95.631)
		(width 0.1143)
		(layer "F.Cu")
		(net "EXP_XM_ADDR_18")
	)
	(segment
		(start 64.706754 -130.945636)
		(end 64.935354 -130.945636)
		(width 0.1143)
		(layer "F.Cu")
		(net "EXP_XM_ADDR_18")
	)
	(segment
		(start 61.514736 -130.2258)
		(end 61.514736 -130.831336)
		(width 0.1143)
		(layer "F.Cu")
		(net "EXP_XM_ADDR_18")
	)
	(segment
		(start 69.28485 -130.92938)
		(end 69.39915 -130.81508)
		(width 0.1143)
		(layer "F.Cu")
		(net "EXP_XM_ADDR_18")
	)
	(segment
		(start 68.82765 -130.92938)
		(end 68.82765 -131.61518)
		(width 0.1143)
		(layer "F.Cu")
		(net "EXP_XM_ADDR_18")
	)
	(segment
		(start 61.057536 -130.831336)
		(end 61.057536 -130.2258)
		(width 0.1143)
		(layer "F.Cu")
		(net "EXP_XM_ADDR_18")
	)
	(segment
		(start 65.82283 -131.2291)
		(end 67.082162 -131.2291)
		(width 0.1143)
		(layer "F.Cu")
		(net "EXP_XM_ADDR_18")
	)
	(segment
		(start 61.171836 -130.1115)
		(end 61.400436 -130.1115)
		(width 0.1143)
		(layer "F.Cu")
		(net "EXP_XM_ADDR_18")
	)
	(segment
		(start 57.298336 -130.892042)
		(end 57.35193 -130.945636)
		(width 0.1143)
		(layer "F.Cu")
		(net "EXP_XM_ADDR_18")
	)
	(segment
		(start 68.94195 -131.72948)
		(end 69.18579 -131.72948)
		(width 0.1143)
		(layer "F.Cu")
		(net "EXP_XM_ADDR_18")
	)
	(segment
		(start 92.66047 -95.504)
		(end 93.48597 -95.504)
		(width 0.1143)
		(layer "F.Cu")
		(net "EXP_XM_ADDR_18")
	)
	(segment
		(start 63.678054 -130.4163)
		(end 63.678054 -130.831336)
		(width 0.1143)
		(layer "F.Cu")
		(net "EXP_XM_ADDR_18")
	)
	(segment
		(start 62.314836 -130.1115)
		(end 62.429136 -130.2258)
		(width 0.1143)
		(layer "F.Cu")
		(net "EXP_XM_ADDR_18")
	)
	(segment
		(start 56.558942 -130.892042)
		(end 57.298336 -130.892042)
		(width 0.1143)
		(layer "F.Cu")
		(net "EXP_XM_ADDR_18")
	)
	(segment
		(start 64.249554 -130.302)
		(end 64.478154 -130.302)
		(width 0.1143)
		(layer "F.Cu")
		(net "EXP_XM_ADDR_18")
	)
	(segment
		(start 70.42023 -130.3401)
		(end 66.478658 -130.3401)
		(width 0.1143)
		(layer "F.Cu")
		(net "EXP_XM_ADDR_18")
	)
	(segment
		(start 67.082162 -131.2291)
		(end 67.496182 -130.81508)
		(width 0.1143)
		(layer "F.Cu")
		(net "EXP_XM_ADDR_18")
	)
	(segment
		(start 65.11798 -130.42265)
		(end 65.23863 -130.302)
		(width 0.1143)
		(layer "F.Cu")
		(net "EXP_XM_ADDR_18")
	)
	(segment
		(start 63.106554 -130.945636)
		(end 63.220854 -130.831336)
		(width 0.1143)
		(layer "F.Cu")
		(net "EXP_XM_ADDR_18")
	)
	(segment
		(start 61.857636 -130.945636)
		(end 61.971936 -130.831336)
		(width 0.1143)
		(layer "F.Cu")
		(net "EXP_XM_ADDR_18")
	)
	(segment
		(start 65.57137 -130.39598)
		(end 65.57137 -130.97764)
		(width 0.1143)
		(layer "F.Cu")
		(net "EXP_XM_ADDR_18")
	)
	(segment
		(start 65.47739 -130.302)
		(end 65.57137 -130.39598)
		(width 0.1143)
		(layer "F.Cu")
		(net "EXP_XM_ADDR_18")
	)
	(segment
		(start 70.39737 -130.81508)
		(end 70.55993 -130.65252)
		(width 0.1143)
		(layer "F.Cu")
		(net "EXP_XM_ADDR_18")
	)
	(segment
		(start 63.220854 -130.831336)
		(end 63.220854 -130.4163)
		(width 0.1143)
		(layer "F.Cu")
		(net "EXP_XM_ADDR_18")
	)
	(segment
		(start 70.54723 -130.4671)
		(end 70.42023 -130.3401)
		(width 0.1143)
		(layer "F.Cu")
		(net "EXP_XM_ADDR_18")
	)
	(segment
		(start 64.135254 -130.831336)
		(end 64.135254 -130.4163)
		(width 0.1143)
		(layer "F.Cu")
		(net "EXP_XM_ADDR_18")
	)
	(segment
		(start 63.220854 -130.4163)
		(end 63.335154 -130.302)
		(width 0.1143)
		(layer "F.Cu")
		(net "EXP_XM_ADDR_18")
	)
	(segment
		(start 69.18579 -131.72948)
		(end 69.28485 -131.63042)
		(width 0.1143)
		(layer "F.Cu")
		(net "EXP_XM_ADDR_18")
	)
	(segment
		(start 66.478658 -130.3401)
		(end 66.113152 -130.705606)
		(width 0.1143)
		(layer "F.Cu")
		(net "EXP_XM_ADDR_18")
	)
	(segment
		(start 64.135254 -130.4163)
		(end 64.249554 -130.302)
		(width 0.1143)
		(layer "F.Cu")
		(net "EXP_XM_ADDR_18")
	)
	(segment
		(start 63.563754 -130.302)
		(end 63.678054 -130.4163)
		(width 0.1143)
		(layer "F.Cu")
		(net "EXP_XM_ADDR_18")
	)
	(segment
		(start 62.429136 -130.831336)
		(end 62.543436 -130.945636)
		(width 0.1143)
		(layer "F.Cu")
		(net "EXP_XM_ADDR_18")
	)
	(segment
		(start 61.629036 -130.945636)
		(end 61.857636 -130.945636)
		(width 0.1143)
		(layer "F.Cu")
		(net "EXP_XM_ADDR_18")
	)
	(segment
		(start 65.23863 -130.302)
		(end 65.47739 -130.302)
		(width 0.1143)
		(layer "F.Cu")
		(net "EXP_XM_ADDR_18")
	)
	(segment
		(start 68.82765 -131.61518)
		(end 68.94195 -131.72948)
		(width 0.1143)
		(layer "F.Cu")
		(net "EXP_XM_ADDR_18")
	)
	(segment
		(start 67.496182 -130.81508)
		(end 68.71335 -130.81508)
		(width 0.1143)
		(layer "F.Cu")
		(net "EXP_XM_ADDR_18")
	)
	(segment
		(start 57.35193 -130.945636)
		(end 60.943236 -130.945636)
		(width 0.1143)
		(layer "F.Cu")
		(net "EXP_XM_ADDR_18")
	)
	(segment
		(start 70.55993 -130.65252)
		(end 70.55993 -130.4671)
		(width 0.1143)
		(layer "F.Cu")
		(net "EXP_XM_ADDR_18")
	)
	(segment
		(start 61.971936 -130.2258)
		(end 62.086236 -130.1115)
		(width 0.1143)
		(layer "F.Cu")
		(net "EXP_XM_ADDR_18")
	)
	(segment
		(start 63.335154 -130.302)
		(end 63.563754 -130.302)
		(width 0.1143)
		(layer "F.Cu")
		(net "EXP_XM_ADDR_18")
	)
	(segment
		(start 69.39915 -130.81508)
		(end 70.39737 -130.81508)
		(width 0.1143)
		(layer "F.Cu")
		(net "EXP_XM_ADDR_18")
	)
	(segment
		(start 63.678054 -130.831336)
		(end 63.792354 -130.945636)
		(width 0.1143)
		(layer "F.Cu")
		(net "EXP_XM_ADDR_18")
	)
	(via
		(at 65.682368 -130.046222)
		(size 0.7112)
		(drill 0.3556)
		(layers "F.Cu" "B.Cu")
		(net "EXP_XM_ADDR_18")
	)
	(via
		(at 93.61297 -95.631)
		(size 0.508)
		(drill 0.254)
		(layers "F.Cu" "B.Cu")
		(net "EXP_XM_ADDR_18")
	)
	(via
		(at 103.849678 -93.849698)
		(size 0.508)
		(drill 0.254)
		(layers "F.Cu" "B.Cu")
		(net "EXP_XM_ADDR_18")
	)
	(via
		(at 66.113152 -130.705606)
		(size 0.5588)
		(drill 0.3048)
		(layers "F.Cu" "B.Cu")
		(net "EXP_XM_ADDR_18")
	)
	(segment
		(start 66.113152 -130.705606)
		(end 66.113152 -130.477006)
		(width 0.1143)
		(layer "B.Cu")
		(net "EXP_XM_ADDR_18")
	)
	(segment
		(start 66.113152 -130.477006)
		(end 65.682368 -130.046222)
		(width 0.1143)
		(layer "B.Cu")
		(net "EXP_XM_ADDR_18")
	)
	(segment
		(start 101.655372 -93.430598)
		(end 103.05923 -93.430598)
		(width 0.127)
		(layer "In2.Cu")
		(net "EXP_XM_ADDR_18")
	)
	(segment
		(start 94.00921 -95.631)
		(end 95.15221 -94.488)
		(width 0.127)
		(layer "In2.Cu")
		(net "EXP_XM_ADDR_18")
	)
	(segment
		(start 66.113152 -130.686302)
		(end 65.96507 -130.53822)
		(width 0.127)
		(layer "In2.Cu")
		(net "EXP_XM_ADDR_18")
	)
	(segment
		(start 81.446624 -102.553516)
		(end 89.3064 -94.69374)
		(width 0.127)
		(layer "In2.Cu")
		(net "EXP_XM_ADDR_18")
	)
	(segment
		(start 95.15221 -94.488)
		(end 95.298006 -94.488)
		(width 0.127)
		(layer "In2.Cu")
		(net "EXP_XM_ADDR_18")
	)
	(segment
		(start 95.29826 -94.487746)
		(end 96.24568 -94.487746)
		(width 0.127)
		(layer "In2.Cu")
		(net "EXP_XM_ADDR_18")
	)
	(segment
		(start 66.29527 -127.332232)
		(end 66.29527 -119.795036)
		(width 0.127)
		(layer "In2.Cu")
		(net "EXP_XM_ADDR_18")
	)
	(segment
		(start 100.59797 -94.488)
		(end 101.655372 -93.430598)
		(width 0.127)
		(layer "In2.Cu")
		(net "EXP_XM_ADDR_18")
	)
	(segment
		(start 66.113152 -130.705606)
		(end 66.113152 -130.686302)
		(width 0.127)
		(layer "In2.Cu")
		(net "EXP_XM_ADDR_18")
	)
	(segment
		(start 93.61297 -95.631)
		(end 94.00921 -95.631)
		(width 0.127)
		(layer "In2.Cu")
		(net "EXP_XM_ADDR_18")
	)
	(segment
		(start 65.96507 -130.53822)
		(end 65.96507 -127.662432)
		(width 0.127)
		(layer "In2.Cu")
		(net "EXP_XM_ADDR_18")
	)
	(segment
		(start 81.446624 -104.320086)
		(end 81.446624 -102.553516)
		(width 0.127)
		(layer "In2.Cu")
		(net "EXP_XM_ADDR_18")
	)
	(segment
		(start 96.245934 -94.488)
		(end 100.59797 -94.488)
		(width 0.127)
		(layer "In2.Cu")
		(net "EXP_XM_ADDR_18")
	)
	(segment
		(start 66.29527 -119.795036)
		(end 81.44637 -104.643936)
		(width 0.127)
		(layer "In2.Cu")
		(net "EXP_XM_ADDR_18")
	)
	(segment
		(start 81.44637 -104.643936)
		(end 81.44637 -104.32034)
		(width 0.127)
		(layer "In2.Cu")
		(net "EXP_XM_ADDR_18")
	)
	(segment
		(start 96.24568 -94.487746)
		(end 96.245934 -94.488)
		(width 0.127)
		(layer "In2.Cu")
		(net "EXP_XM_ADDR_18")
	)
	(segment
		(start 103.05923 -93.430598)
		(end 103.47833 -93.849698)
		(width 0.127)
		(layer "In2.Cu")
		(net "EXP_XM_ADDR_18")
	)
	(segment
		(start 95.298006 -94.488)
		(end 95.29826 -94.487746)
		(width 0.127)
		(layer "In2.Cu")
		(net "EXP_XM_ADDR_18")
	)
	(segment
		(start 65.96507 -127.662432)
		(end 66.29527 -127.332232)
		(width 0.127)
		(layer "In2.Cu")
		(net "EXP_XM_ADDR_18")
	)
	(segment
		(start 89.3064 -94.69374)
		(end 92.67571 -94.69374)
		(width 0.127)
		(layer "In2.Cu")
		(net "EXP_XM_ADDR_18")
	)
	(segment
		(start 81.44637 -104.32034)
		(end 81.446624 -104.320086)
		(width 0.127)
		(layer "In2.Cu")
		(net "EXP_XM_ADDR_18")
	)
	(segment
		(start 92.67571 -94.69374)
		(end 93.61297 -95.631)
		(width 0.127)
		(layer "In2.Cu")
		(net "EXP_XM_ADDR_18")
	)
	(segment
		(start 103.47833 -93.849698)
		(end 103.849678 -93.849698)
		(width 0.127)
		(layer "In2.Cu")
		(net "EXP_XM_ADDR_18")
	)
	(segment
		(start 126.45517 -83.82)
		(end 126.25197 -83.82)
		(width 0.0889)
		(layer "F.Cu")
		(net "SAS_HDD_TX13_N")
	)
	(segment
		(start 127.54737 -83.7565)
		(end 126.608586 -83.7565)
		(width 0.0889)
		(layer "F.Cu")
		(net "SAS_HDD_TX13_N")
	)
	(segment
		(start 125.616716 -84.083144)
		(end 125.350016 -84.349844)
		(width 0.0889)
		(layer "F.Cu")
		(net "SAS_HDD_TX13_N")
	)
	(segment
		(start 127.98933 -83.39836)
		(end 127.940816 -83.447128)
		(width 0.0889)
		(layer "F.Cu")
		(net "SAS_HDD_TX13_N")
	)
	(segment
		(start 131.572 -82.7151)
		(end 129.020316 -82.7151)
		(width 0.1016)
		(layer "F.Cu")
		(net "SAS_HDD_TX13_N")
	)
	(segment
		(start 127.92456 -83.48599)
		(end 127.729488 -83.681062)
		(width 0.0889)
		(layer "F.Cu")
		(net "SAS_HDD_TX13_N")
	)
	(segment
		(start 131.933442 -82.494882)
		(end 131.813046 -82.615278)
		(width 0.1016)
		(layer "F.Cu")
		(net "SAS_HDD_TX13_N")
	)
	(segment
		(start 128.426718 -82.960972)
		(end 127.98933 -83.39836)
		(width 0.1016)
		(layer "F.Cu")
		(net "SAS_HDD_TX13_N")
	)
	(arc
		(start 127.940816 -83.447128)
		(mid 127.92882 -83.464943)
		(end 127.92456 -83.48599)
		(width 0.0889)
		(layer "F.Cu")
		(net "SAS_HDD_TX13_N")
	)
	(arc
		(start 126.608586 -83.7565)
		(mid 126.525576 -83.773012)
		(end 126.45517 -83.82)
		(width 0.0889)
		(layer "F.Cu")
		(net "SAS_HDD_TX13_N")
	)
	(arc
		(start 126.101602 -83.8327)
		(mid 125.839685 -83.920217)
		(end 125.616716 -84.083144)
		(width 0.0889)
		(layer "F.Cu")
		(net "SAS_HDD_TX13_N")
	)
	(arc
		(start 131.813046 -82.615278)
		(mid 131.702453 -82.689174)
		(end 131.572 -82.7151)
		(width 0.1016)
		(layer "F.Cu")
		(net "SAS_HDD_TX13_N")
	)
	(arc
		(start 129.020316 -82.7151)
		(mid 128.699051 -82.778986)
		(end 128.426718 -82.960972)
		(width 0.1016)
		(layer "F.Cu")
		(net "SAS_HDD_TX13_N")
	)
	(arc
		(start 127.729488 -83.681062)
		(mid 127.645932 -83.736893)
		(end 127.54737 -83.7565)
		(width 0.0889)
		(layer "F.Cu")
		(net "SAS_HDD_TX13_N")
	)
	(arc
		(start 126.25197 -83.82)
		(mid 126.17652 -83.823195)
		(end 126.101602 -83.8327)
		(width 0.0889)
		(layer "F.Cu")
		(net "SAS_HDD_TX13_N")
	)
	(segment
		(start 113.949988 -49.399952)
		(end 114.843814 -49.399952)
		(width 0.1143)
		(layer "F.Cu")
		(net "XM_DATA_1")
	)
	(segment
		(start 114.843814 -49.399952)
		(end 114.891566 -49.3522)
		(width 0.1143)
		(layer "F.Cu")
		(net "XM_DATA_1")
	)
	(segment
		(start 144.558258 -54.323742)
		(end 144.558258 -54.1274)
		(width 0.1143)
		(layer "F.Cu")
		(net "XM_DATA_1")
	)
	(segment
		(start 145.098516 -59.249056)
		(end 144.03705 -58.18759)
		(width 0.1143)
		(layer "F.Cu")
		(net "XM_DATA_1")
	)
	(segment
		(start 145.098516 -61.9379)
		(end 145.098516 -59.249056)
		(width 0.1143)
		(layer "F.Cu")
		(net "XM_DATA_1")
	)
	(segment
		(start 144.03705 -54.84495)
		(end 144.558258 -54.323742)
		(width 0.1143)
		(layer "F.Cu")
		(net "XM_DATA_1")
	)
	(segment
		(start 144.03705 -58.18759)
		(end 144.03705 -54.84495)
		(width 0.1143)
		(layer "F.Cu")
		(net "XM_DATA_1")
	)
	(via
		(at 114.891566 -49.3522)
		(size 0.508)
		(drill 0.254)
		(layers "F.Cu" "B.Cu")
		(net "XM_DATA_1")
	)
	(via
		(at 144.558258 -54.1274)
		(size 0.5588)
		(drill 0.3048)
		(layers "F.Cu" "B.Cu")
		(net "XM_DATA_1")
	)
	(via
		(at 143.256 -53.848)
		(size 0.7112)
		(drill 0.3556)
		(layers "F.Cu" "B.Cu")
		(net "XM_DATA_1")
	)
	(segment
		(start 122.39371 -51.6382)
		(end 122.27941 -51.7525)
		(width 0.1143)
		(layer "B.Cu")
		(net "XM_DATA_1")
	)
	(segment
		(start 121.47931 -51.6382)
		(end 121.36501 -51.7525)
		(width 0.1143)
		(layer "B.Cu")
		(net "XM_DATA_1")
	)
	(segment
		(start 121.02211 -52.197)
		(end 120.90781 -52.0827)
		(width 0.1143)
		(layer "B.Cu")
		(net "XM_DATA_1")
	)
	(segment
		(start 122.73661 -51.7525)
		(end 122.62231 -51.6382)
		(width 0.1143)
		(layer "B.Cu")
		(net "XM_DATA_1")
	)
	(segment
		(start 120.33631 -52.197)
		(end 119.888 -52.197)
		(width 0.1143)
		(layer "B.Cu")
		(net "XM_DATA_1")
	)
	(segment
		(start 121.36501 -51.7525)
		(end 121.36501 -52.0827)
		(width 0.1143)
		(layer "B.Cu")
		(net "XM_DATA_1")
	)
	(segment
		(start 136.652 -51.943)
		(end 136.398 -52.197)
		(width 0.1143)
		(layer "B.Cu")
		(net "XM_DATA_1")
	)
	(segment
		(start 115.088416 -49.810416)
		(end 115.088416 -49.54905)
		(width 0.1143)
		(layer "B.Cu")
		(net "XM_DATA_1")
	)
	(segment
		(start 122.62231 -51.6382)
		(end 122.39371 -51.6382)
		(width 0.1143)
		(layer "B.Cu")
		(net "XM_DATA_1")
	)
	(segment
		(start 121.70791 -51.6382)
		(end 121.47931 -51.6382)
		(width 0.1143)
		(layer "B.Cu")
		(net "XM_DATA_1")
	)
	(segment
		(start 143.256 -53.848)
		(end 144.278858 -53.848)
		(width 0.1143)
		(layer "B.Cu")
		(net "XM_DATA_1")
	)
	(segment
		(start 122.16511 -52.197)
		(end 121.93651 -52.197)
		(width 0.1143)
		(layer "B.Cu")
		(net "XM_DATA_1")
	)
	(segment
		(start 141.741144 -53.184298)
		(end 139.883896 -51.32705)
		(width 0.1143)
		(layer "B.Cu")
		(net "XM_DATA_1")
	)
	(segment
		(start 120.45061 -52.0827)
		(end 120.33631 -52.197)
		(width 0.1143)
		(layer "B.Cu")
		(net "XM_DATA_1")
	)
	(segment
		(start 138.811 -51.943)
		(end 136.652 -51.943)
		(width 0.1143)
		(layer "B.Cu")
		(net "XM_DATA_1")
	)
	(segment
		(start 122.27941 -52.0827)
		(end 122.16511 -52.197)
		(width 0.1143)
		(layer "B.Cu")
		(net "XM_DATA_1")
	)
	(segment
		(start 117.221 -51.562)
		(end 116.8273 -51.1683)
		(width 0.1143)
		(layer "B.Cu")
		(net "XM_DATA_1")
	)
	(segment
		(start 121.25071 -52.197)
		(end 121.02211 -52.197)
		(width 0.1143)
		(layer "B.Cu")
		(net "XM_DATA_1")
	)
	(segment
		(start 119.888 -52.197)
		(end 119.253 -51.562)
		(width 0.1143)
		(layer "B.Cu")
		(net "XM_DATA_1")
	)
	(segment
		(start 139.883896 -51.32705)
		(end 139.42695 -51.32705)
		(width 0.1143)
		(layer "B.Cu")
		(net "XM_DATA_1")
	)
	(segment
		(start 120.90781 -52.0827)
		(end 120.90781 -51.7525)
		(width 0.1143)
		(layer "B.Cu")
		(net "XM_DATA_1")
	)
	(segment
		(start 120.90781 -51.7525)
		(end 120.79351 -51.6382)
		(width 0.1143)
		(layer "B.Cu")
		(net "XM_DATA_1")
	)
	(segment
		(start 144.278858 -53.848)
		(end 144.558258 -54.1274)
		(width 0.1143)
		(layer "B.Cu")
		(net "XM_DATA_1")
	)
	(segment
		(start 115.088416 -49.54905)
		(end 114.891566 -49.3522)
		(width 0.1143)
		(layer "B.Cu")
		(net "XM_DATA_1")
	)
	(segment
		(start 141.741144 -53.395118)
		(end 141.741144 -53.184298)
		(width 0.1143)
		(layer "B.Cu")
		(net "XM_DATA_1")
	)
	(segment
		(start 122.73661 -52.0827)
		(end 122.73661 -51.7525)
		(width 0.1143)
		(layer "B.Cu")
		(net "XM_DATA_1")
	)
	(segment
		(start 120.79351 -51.6382)
		(end 120.56491 -51.6382)
		(width 0.1143)
		(layer "B.Cu")
		(net "XM_DATA_1")
	)
	(segment
		(start 119.253 -51.562)
		(end 117.221 -51.562)
		(width 0.1143)
		(layer "B.Cu")
		(net "XM_DATA_1")
	)
	(segment
		(start 120.45061 -51.7525)
		(end 120.45061 -52.0827)
		(width 0.1143)
		(layer "B.Cu")
		(net "XM_DATA_1")
	)
	(segment
		(start 116.4463 -51.1683)
		(end 115.088416 -49.810416)
		(width 0.1143)
		(layer "B.Cu")
		(net "XM_DATA_1")
	)
	(segment
		(start 142.194026 -53.848)
		(end 141.741144 -53.395118)
		(width 0.1143)
		(layer "B.Cu")
		(net "XM_DATA_1")
	)
	(segment
		(start 121.82221 -51.7525)
		(end 121.70791 -51.6382)
		(width 0.1143)
		(layer "B.Cu")
		(net "XM_DATA_1")
	)
	(segment
		(start 120.56491 -51.6382)
		(end 120.45061 -51.7525)
		(width 0.1143)
		(layer "B.Cu")
		(net "XM_DATA_1")
	)
	(segment
		(start 122.85091 -52.197)
		(end 122.73661 -52.0827)
		(width 0.1143)
		(layer "B.Cu")
		(net "XM_DATA_1")
	)
	(segment
		(start 121.36501 -52.0827)
		(end 121.25071 -52.197)
		(width 0.1143)
		(layer "B.Cu")
		(net "XM_DATA_1")
	)
	(segment
		(start 121.82221 -52.0827)
		(end 121.82221 -51.7525)
		(width 0.1143)
		(layer "B.Cu")
		(net "XM_DATA_1")
	)
	(segment
		(start 139.42695 -51.32705)
		(end 138.811 -51.943)
		(width 0.1143)
		(layer "B.Cu")
		(net "XM_DATA_1")
	)
	(segment
		(start 116.8273 -51.1683)
		(end 116.4463 -51.1683)
		(width 0.1143)
		(layer "B.Cu")
		(net "XM_DATA_1")
	)
	(segment
		(start 122.27941 -51.7525)
		(end 122.27941 -52.0827)
		(width 0.1143)
		(layer "B.Cu")
		(net "XM_DATA_1")
	)
	(segment
		(start 121.93651 -52.197)
		(end 121.82221 -52.0827)
		(width 0.1143)
		(layer "B.Cu")
		(net "XM_DATA_1")
	)
	(segment
		(start 136.398 -52.197)
		(end 122.85091 -52.197)
		(width 0.1143)
		(layer "B.Cu")
		(net "XM_DATA_1")
	)
	(segment
		(start 143.256 -53.848)
		(end 142.194026 -53.848)
		(width 0.1143)
		(layer "B.Cu")
		(net "XM_DATA_1")
	)
	(segment
		(start 169.93235 -119.51335)
		(end 170.043348 -119.624348)
		(width 0.3048)
		(layer "F.Cu")
		(net "P0V9_E_VDD")
	)
	(segment
		(start 170.043348 -119.624348)
		(end 170.043348 -120.015)
		(width 0.3048)
		(layer "F.Cu")
		(net "P0V9_E_VDD")
	)
	(segment
		(start 169.93235 -118.391178)
		(end 169.93235 -119.51335)
		(width 0.3048)
		(layer "F.Cu")
		(net "P0V9_E_VDD")
	)
	(via
		(at 170.043348 -120.015)
		(size 0.5588)
		(drill 0.3048)
		(layers "F.Cu" "B.Cu")
		(net "P0V9_E_VDD")
	)
	(via
		(at 169.8752 -118.362222)
		(size 0.7112)
		(drill 0.3556)
		(layers "F.Cu" "B.Cu")
		(net "P0V9_E_VDD")
	)
	(segment
		(start 170.942 -118.364)
		(end 170.942 -118.872)
		(width 0.508)
		(layer "B.Cu")
		(net "P0V9_E_VDD")
	)
	(segment
		(start 169.789856 -118.354856)
		(end 169.797222 -118.362222)
		(width 0.508)
		(layer "B.Cu")
		(net "P0V9_E_VDD")
	)
	(segment
		(start 168.595548 -118.354856)
		(end 169.789856 -118.354856)
		(width 0.508)
		(layer "B.Cu")
		(net "P0V9_E_VDD")
	)
	(segment
		(start 170.942 -118.872)
		(end 170.043348 -119.770652)
		(width 0.508)
		(layer "B.Cu")
		(net "P0V9_E_VDD")
	)
	(segment
		(start 169.8752 -118.362222)
		(end 170.382692 -118.362222)
		(width 0.508)
		(layer "B.Cu")
		(net "P0V9_E_VDD")
	)
	(segment
		(start 169.797222 -118.362222)
		(end 169.8752 -118.362222)
		(width 0.508)
		(layer "B.Cu")
		(net "P0V9_E_VDD")
	)
	(segment
		(start 170.382692 -118.362222)
		(end 170.942 -118.364)
		(width 0.508)
		(layer "B.Cu")
		(net "P0V9_E_VDD")
	)
	(segment
		(start 170.043348 -119.770652)
		(end 170.043348 -120.015)
		(width 0.508)
		(layer "B.Cu")
		(net "P0V9_E_VDD")
	)
	(segment
		(start 60.969652 -138.893042)
		(end 61.58738 -139.51077)
		(width 0.1143)
		(layer "F.Cu")
		(net "EXP_XM_ADDR_16")
	)
	(segment
		(start 56.558942 -138.893042)
		(end 60.969652 -138.893042)
		(width 0.1143)
		(layer "F.Cu")
		(net "EXP_XM_ADDR_16")
	)
	(segment
		(start 61.58738 -142.09903)
		(end 61.82233 -142.33398)
		(width 0.1143)
		(layer "F.Cu")
		(net "EXP_XM_ADDR_16")
	)
	(segment
		(start 63.689992 -138.893042)
		(end 64.408812 -138.893042)
		(width 0.1143)
		(layer "F.Cu")
		(net "EXP_XM_ADDR_16")
	)
	(segment
		(start 61.58738 -139.51077)
		(end 61.58738 -142.09903)
		(width 0.1143)
		(layer "F.Cu")
		(net "EXP_XM_ADDR_16")
	)
	(segment
		(start 63.43269 -142.07998)
		(end 63.43269 -139.150344)
		(width 0.1143)
		(layer "F.Cu")
		(net "EXP_XM_ADDR_16")
	)
	(segment
		(start 61.82233 -142.33398)
		(end 63.17869 -142.33398)
		(width 0.1143)
		(layer "F.Cu")
		(net "EXP_XM_ADDR_16")
	)
	(segment
		(start 64.408812 -138.893042)
		(end 64.96177 -139.446)
		(width 0.1143)
		(layer "F.Cu")
		(net "EXP_XM_ADDR_16")
	)
	(segment
		(start 63.17869 -142.33398)
		(end 63.43269 -142.07998)
		(width 0.1143)
		(layer "F.Cu")
		(net "EXP_XM_ADDR_16")
	)
	(segment
		(start 92.66047 -97.79)
		(end 93.61297 -97.79)
		(width 0.1143)
		(layer "F.Cu")
		(net "EXP_XM_ADDR_16")
	)
	(segment
		(start 63.43269 -139.150344)
		(end 63.689992 -138.893042)
		(width 0.1143)
		(layer "F.Cu")
		(net "EXP_XM_ADDR_16")
	)
	(segment
		(start 64.96177 -139.446)
		(end 65.41897 -139.446)
		(width 0.1143)
		(layer "F.Cu")
		(net "EXP_XM_ADDR_16")
	)
	(segment
		(start 105.349802 -94.349824)
		(end 104.849676 -93.849698)
		(width 0.1143)
		(layer "F.Cu")
		(net "EXP_XM_ADDR_16")
	)
	(via
		(at 93.61297 -97.79)
		(size 0.508)
		(drill 0.254)
		(layers "F.Cu" "B.Cu")
		(net "EXP_XM_ADDR_16")
	)
	(via
		(at 104.849676 -93.849698)
		(size 0.508)
		(drill 0.254)
		(layers "F.Cu" "B.Cu")
		(net "EXP_XM_ADDR_16")
	)
	(via
		(at 65.41897 -139.446)
		(size 0.5588)
		(drill 0.3048)
		(layers "F.Cu" "B.Cu")
		(net "EXP_XM_ADDR_16")
	)
	(via
		(at 64.897 -140.3604)
		(size 0.7112)
		(drill 0.3556)
		(layers "F.Cu" "B.Cu")
		(net "EXP_XM_ADDR_16")
	)
	(segment
		(start 64.897 -139.96797)
		(end 65.41897 -139.446)
		(width 0.1143)
		(layer "B.Cu")
		(net "EXP_XM_ADDR_16")
	)
	(segment
		(start 64.897 -140.3604)
		(end 64.897 -139.96797)
		(width 0.1143)
		(layer "B.Cu")
		(net "EXP_XM_ADDR_16")
	)
	(segment
		(start 67.548506 -129.067052)
		(end 67.548506 -129.246884)
		(width 0.127)
		(layer "In2.Cu")
		(net "EXP_XM_ADDR_16")
	)
	(segment
		(start 102.32009 -94.41434)
		(end 101.10343 -95.631)
		(width 0.127)
		(layer "In2.Cu")
		(net "EXP_XM_ADDR_16")
	)
	(segment
		(start 66.67627 -133.682232)
		(end 65.92697 -134.431532)
		(width 0.127)
		(layer "In2.Cu")
		(net "EXP_XM_ADDR_16")
	)
	(segment
		(start 104.849676 -93.849698)
		(end 104.478328 -93.849698)
		(width 0.127)
		(layer "In2.Cu")
		(net "EXP_XM_ADDR_16")
	)
	(segment
		(start 94.95917 -96.4438)
		(end 93.61297 -97.79)
		(width 0.127)
		(layer "In2.Cu")
		(net "EXP_XM_ADDR_16")
	)
	(segment
		(start 85.292438 -106.11612)
		(end 81.611216 -106.11612)
		(width 0.127)
		(layer "In2.Cu")
		(net "EXP_XM_ADDR_16")
	)
	(segment
		(start 66.67627 -132.834126)
		(end 66.67627 -133.682232)
		(width 0.127)
		(layer "In2.Cu")
		(net "EXP_XM_ADDR_16")
	)
	(segment
		(start 69.53123 -125.223778)
		(end 68.76923 -125.223778)
		(width 0.127)
		(layer "In2.Cu")
		(net "EXP_XM_ADDR_16")
	)
	(segment
		(start 68.64223 -127.973328)
		(end 67.548506 -129.067052)
		(width 0.127)
		(layer "In2.Cu")
		(net "EXP_XM_ADDR_16")
	)
	(segment
		(start 81.611216 -106.11612)
		(end 69.65823 -118.06936)
		(width 0.127)
		(layer "In2.Cu")
		(net "EXP_XM_ADDR_16")
	)
	(segment
		(start 102.6795 -94.41434)
		(end 102.32009 -94.41434)
		(width 0.127)
		(layer "In2.Cu")
		(net "EXP_XM_ADDR_16")
	)
	(segment
		(start 94.95917 -96.378268)
		(end 94.95917 -96.4438)
		(width 0.127)
		(layer "In2.Cu")
		(net "EXP_XM_ADDR_16")
	)
	(segment
		(start 68.76923 -125.223778)
		(end 68.64223 -125.350778)
		(width 0.127)
		(layer "In2.Cu")
		(net "EXP_XM_ADDR_16")
	)
	(segment
		(start 67.548506 -129.246884)
		(end 67.932046 -129.630424)
		(width 0.127)
		(layer "In2.Cu")
		(net "EXP_XM_ADDR_16")
	)
	(segment
		(start 69.65823 -125.096778)
		(end 69.53123 -125.223778)
		(width 0.127)
		(layer "In2.Cu")
		(net "EXP_XM_ADDR_16")
	)
	(segment
		(start 92.851224 -97.21596)
		(end 88.523826 -97.21596)
		(width 0.127)
		(layer "In2.Cu")
		(net "EXP_XM_ADDR_16")
	)
	(segment
		(start 86.530434 -104.878124)
		(end 85.292438 -106.11612)
		(width 0.127)
		(layer "In2.Cu")
		(net "EXP_XM_ADDR_16")
	)
	(segment
		(start 65.92697 -138.216894)
		(end 65.41897 -138.724894)
		(width 0.127)
		(layer "In2.Cu")
		(net "EXP_XM_ADDR_16")
	)
	(segment
		(start 95.77197 -95.631)
		(end 95.31477 -96.0882)
		(width 0.127)
		(layer "In2.Cu")
		(net "EXP_XM_ADDR_16")
	)
	(segment
		(start 68.64223 -125.350778)
		(end 68.64223 -127.973328)
		(width 0.127)
		(layer "In2.Cu")
		(net "EXP_XM_ADDR_16")
	)
	(segment
		(start 104.478328 -93.849698)
		(end 104.015286 -94.31274)
		(width 0.127)
		(layer "In2.Cu")
		(net "EXP_XM_ADDR_16")
	)
	(segment
		(start 67.41287 -132.097526)
		(end 66.67627 -132.834126)
		(width 0.127)
		(layer "In2.Cu")
		(net "EXP_XM_ADDR_16")
	)
	(segment
		(start 104.015286 -94.31274)
		(end 102.7811 -94.31274)
		(width 0.127)
		(layer "In2.Cu")
		(net "EXP_XM_ADDR_16")
	)
	(segment
		(start 67.932046 -129.810256)
		(end 67.41287 -130.329432)
		(width 0.127)
		(layer "In2.Cu")
		(net "EXP_XM_ADDR_16")
	)
	(segment
		(start 65.92697 -134.431532)
		(end 65.92697 -138.216894)
		(width 0.127)
		(layer "In2.Cu")
		(net "EXP_XM_ADDR_16")
	)
	(segment
		(start 102.7811 -94.31274)
		(end 102.6795 -94.41434)
		(width 0.127)
		(layer "In2.Cu")
		(net "EXP_XM_ADDR_16")
	)
	(segment
		(start 93.61297 -97.79)
		(end 93.425264 -97.79)
		(width 0.127)
		(layer "In2.Cu")
		(net "EXP_XM_ADDR_16")
	)
	(segment
		(start 88.523826 -97.21596)
		(end 86.530434 -99.209352)
		(width 0.127)
		(layer "In2.Cu")
		(net "EXP_XM_ADDR_16")
	)
	(segment
		(start 95.249238 -96.0882)
		(end 94.95917 -96.378268)
		(width 0.127)
		(layer "In2.Cu")
		(net "EXP_XM_ADDR_16")
	)
	(segment
		(start 67.932046 -129.630424)
		(end 67.932046 -129.810256)
		(width 0.127)
		(layer "In2.Cu")
		(net "EXP_XM_ADDR_16")
	)
	(segment
		(start 86.530434 -99.209352)
		(end 86.530434 -104.878124)
		(width 0.127)
		(layer "In2.Cu")
		(net "EXP_XM_ADDR_16")
	)
	(segment
		(start 69.65823 -118.06936)
		(end 69.65823 -125.096778)
		(width 0.127)
		(layer "In2.Cu")
		(net "EXP_XM_ADDR_16")
	)
	(segment
		(start 65.41897 -138.724894)
		(end 65.41897 -139.446)
		(width 0.127)
		(layer "In2.Cu")
		(net "EXP_XM_ADDR_16")
	)
	(segment
		(start 67.41287 -130.329432)
		(end 67.41287 -132.097526)
		(width 0.127)
		(layer "In2.Cu")
		(net "EXP_XM_ADDR_16")
	)
	(segment
		(start 93.425264 -97.79)
		(end 92.851224 -97.21596)
		(width 0.127)
		(layer "In2.Cu")
		(net "EXP_XM_ADDR_16")
	)
	(segment
		(start 95.31477 -96.0882)
		(end 95.249238 -96.0882)
		(width 0.127)
		(layer "In2.Cu")
		(net "EXP_XM_ADDR_16")
	)
	(segment
		(start 101.10343 -95.631)
		(end 95.77197 -95.631)
		(width 0.127)
		(layer "In2.Cu")
		(net "EXP_XM_ADDR_16")
	)
	(segment
		(start 147.701 -45.72)
		(end 147.701 -52.49545)
		(width 0.1143)
		(layer "F.Cu")
		(net "XM_ADDR_6")
	)
	(segment
		(start 146.429222 -44.448222)
		(end 146.429222 -44.609766)
		(width 0.1143)
		(layer "F.Cu")
		(net "XM_ADDR_6")
	)
	(segment
		(start 150.495 -55.245)
		(end 150.136098 -54.886098)
		(width 0.1143)
		(layer "F.Cu")
		(net "XM_ADDR_6")
	)
	(segment
		(start 146.099276 -42.7101)
		(end 146.099276 -44.118276)
		(width 0.1143)
		(layer "F.Cu")
		(net "XM_ADDR_6")
	)
	(segment
		(start 146.914108 -44.933108)
		(end 147.701 -45.72)
		(width 0.1143)
		(layer "F.Cu")
		(net "XM_ADDR_6")
	)
	(segment
		(start 146.752564 -44.933108)
		(end 146.914108 -44.933108)
		(width 0.1143)
		(layer "F.Cu")
		(net "XM_ADDR_6")
	)
	(segment
		(start 150.091648 -54.886098)
		(end 148.16455 -52.959)
		(width 0.1143)
		(layer "F.Cu")
		(net "XM_ADDR_6")
	)
	(segment
		(start 146.429222 -44.609766)
		(end 146.180556 -44.858432)
		(width 0.1143)
		(layer "F.Cu")
		(net "XM_ADDR_6")
	)
	(segment
		(start 112.711992 -56.412892)
		(end 112.711992 -57.328816)
		(width 0.1143)
		(layer "F.Cu")
		(net "XM_ADDR_6")
	)
	(segment
		(start 147.701 -52.49545)
		(end 148.16455 -52.959)
		(width 0.1143)
		(layer "F.Cu")
		(net "XM_ADDR_6")
	)
	(segment
		(start 112.711992 -57.328816)
		(end 112.550702 -57.490106)
		(width 0.1143)
		(layer "F.Cu")
		(net "XM_ADDR_6")
	)
	(segment
		(start 146.503898 -45.181774)
		(end 146.752564 -44.933108)
		(width 0.1143)
		(layer "F.Cu")
		(net "XM_ADDR_6")
	)
	(segment
		(start 150.136098 -54.886098)
		(end 150.091648 -54.886098)
		(width 0.1143)
		(layer "F.Cu")
		(net "XM_ADDR_6")
	)
	(segment
		(start 151.5745 -55.499)
		(end 150.749 -55.499)
		(width 0.1143)
		(layer "F.Cu")
		(net "XM_ADDR_6")
	)
	(segment
		(start 146.180556 -45.019976)
		(end 146.342354 -45.181774)
		(width 0.1143)
		(layer "F.Cu")
		(net "XM_ADDR_6")
	)
	(segment
		(start 112.350042 -55.79999)
		(end 112.350042 -56.050942)
		(width 0.1143)
		(layer "F.Cu")
		(net "XM_ADDR_6")
	)
	(segment
		(start 112.350042 -56.050942)
		(end 112.711992 -56.412892)
		(width 0.1143)
		(layer "F.Cu")
		(net "XM_ADDR_6")
	)
	(segment
		(start 150.749 -55.499)
		(end 150.495 -55.245)
		(width 0.1143)
		(layer "F.Cu")
		(net "XM_ADDR_6")
	)
	(segment
		(start 146.099276 -44.118276)
		(end 146.429222 -44.448222)
		(width 0.1143)
		(layer "F.Cu")
		(net "XM_ADDR_6")
	)
	(segment
		(start 146.180556 -44.858432)
		(end 146.180556 -45.019976)
		(width 0.1143)
		(layer "F.Cu")
		(net "XM_ADDR_6")
	)
	(segment
		(start 146.342354 -45.181774)
		(end 146.503898 -45.181774)
		(width 0.1143)
		(layer "F.Cu")
		(net "XM_ADDR_6")
	)
	(via
		(at 148.16455 -52.959)
		(size 0.5588)
		(drill 0.3048)
		(layers "F.Cu" "B.Cu")
		(net "XM_ADDR_6")
	)
	(via
		(at 112.550702 -57.490106)
		(size 0.508)
		(drill 0.254)
		(layers "F.Cu" "B.Cu")
		(net "XM_ADDR_6")
	)
	(via
		(at 150.495 -55.245)
		(size 0.7112)
		(drill 0.3556)
		(layers "F.Cu" "B.Cu")
		(net "XM_ADDR_6")
	)
	(segment
		(start 112.613694 -57.490106)
		(end 112.550702 -57.490106)
		(width 0.127)
		(layer "In5.Cu")
		(net "XM_ADDR_6")
	)
	(segment
		(start 142.233396 -55.868062)
		(end 138.178794 -55.868062)
		(width 0.127)
		(layer "In5.Cu")
		(net "XM_ADDR_6")
	)
	(segment
		(start 144.90954 -55.868062)
		(end 142.995396 -55.868062)
		(width 0.127)
		(layer "In5.Cu")
		(net "XM_ADDR_6")
	)
	(segment
		(start 142.487396 -54.240684)
		(end 142.360396 -54.367684)
		(width 0.127)
		(layer "In5.Cu")
		(net "XM_ADDR_6")
	)
	(segment
		(start 112.959388 -57.8358)
		(end 112.613694 -57.490106)
		(width 0.127)
		(layer "In5.Cu")
		(net "XM_ADDR_6")
	)
	(segment
		(start 117.507512 -57.498488)
		(end 116.2177 -58.7883)
		(width 0.127)
		(layer "In5.Cu")
		(net "XM_ADDR_6")
	)
	(segment
		(start 125.060456 -57.498488)
		(end 117.507512 -57.498488)
		(width 0.127)
		(layer "In5.Cu")
		(net "XM_ADDR_6")
	)
	(segment
		(start 147.818602 -52.959)
		(end 144.90954 -55.868062)
		(width 0.127)
		(layer "In5.Cu")
		(net "XM_ADDR_6")
	)
	(segment
		(start 137.648188 -56.397906)
		(end 126.161038 -56.397906)
		(width 0.127)
		(layer "In5.Cu")
		(net "XM_ADDR_6")
	)
	(segment
		(start 142.741396 -54.240684)
		(end 142.487396 -54.240684)
		(width 0.127)
		(layer "In5.Cu")
		(net "XM_ADDR_6")
	)
	(segment
		(start 114.146076 -58.7883)
		(end 113.193576 -57.8358)
		(width 0.127)
		(layer "In5.Cu")
		(net "XM_ADDR_6")
	)
	(segment
		(start 113.193576 -57.8358)
		(end 112.959388 -57.8358)
		(width 0.127)
		(layer "In5.Cu")
		(net "XM_ADDR_6")
	)
	(segment
		(start 142.995396 -55.868062)
		(end 142.868396 -55.741062)
		(width 0.127)
		(layer "In5.Cu")
		(net "XM_ADDR_6")
	)
	(segment
		(start 142.868396 -54.367684)
		(end 142.741396 -54.240684)
		(width 0.127)
		(layer "In5.Cu")
		(net "XM_ADDR_6")
	)
	(segment
		(start 148.16455 -52.959)
		(end 147.818602 -52.959)
		(width 0.127)
		(layer "In5.Cu")
		(net "XM_ADDR_6")
	)
	(segment
		(start 116.2177 -58.7883)
		(end 114.146076 -58.7883)
		(width 0.127)
		(layer "In5.Cu")
		(net "XM_ADDR_6")
	)
	(segment
		(start 142.868396 -55.741062)
		(end 142.868396 -54.367684)
		(width 0.127)
		(layer "In5.Cu")
		(net "XM_ADDR_6")
	)
	(segment
		(start 126.161038 -56.397906)
		(end 125.060456 -57.498488)
		(width 0.127)
		(layer "In5.Cu")
		(net "XM_ADDR_6")
	)
	(segment
		(start 142.360396 -54.367684)
		(end 142.360396 -55.741062)
		(width 0.127)
		(layer "In5.Cu")
		(net "XM_ADDR_6")
	)
	(segment
		(start 138.178794 -55.868062)
		(end 137.648188 -56.397906)
		(width 0.127)
		(layer "In5.Cu")
		(net "XM_ADDR_6")
	)
	(segment
		(start 142.360396 -55.741062)
		(end 142.233396 -55.868062)
		(width 0.127)
		(layer "In5.Cu")
		(net "XM_ADDR_6")
	)
	(segment
		(start 85.86216 -33.625282)
		(end 85.775546 -33.538668)
		(width 0.1016)
		(layer "F.Cu")
		(net "SAS3008_RAID_TX_P0")
	)
	(segment
		(start 85.23986 -33.538414)
		(end 84.9884 -33.789874)
		(width 0.1016)
		(layer "F.Cu")
		(net "SAS3008_RAID_TX_P0")
	)
	(segment
		(start 123.752356 -82.234786)
		(end 123.807982 -82.290412)
		(width 0.1016)
		(layer "F.Cu")
		(net "SAS3008_RAID_TX_P0")
	)
	(segment
		(start 86.21776 -33.655)
		(end 85.934042 -33.655)
		(width 0.1016)
		(layer "F.Cu")
		(net "SAS3008_RAID_TX_P0")
	)
	(segment
		(start 85.521546 -33.508696)
		(end 85.311742 -33.508696)
		(width 0.1016)
		(layer "F.Cu")
		(net "SAS3008_RAID_TX_P0")
	)
	(segment
		(start 123.752356 -81.777586)
		(end 123.752356 -81.798414)
		(width 0.1016)
		(layer "F.Cu")
		(net "SAS3008_RAID_TX_P0")
	)
	(segment
		(start 85.5218 -33.50895)
		(end 85.521546 -33.508696)
		(width 0.1016)
		(layer "F.Cu")
		(net "SAS3008_RAID_TX_P0")
	)
	(segment
		(start 123.73737 -81.7626)
		(end 123.752356 -81.777586)
		(width 0.1016)
		(layer "F.Cu")
		(net "SAS3008_RAID_TX_P0")
	)
	(segment
		(start 123.951492 -82.349848)
		(end 124.350018 -82.349848)
		(width 0.1016)
		(layer "F.Cu")
		(net "SAS3008_RAID_TX_P0")
	)
	(segment
		(start 85.703664 -33.50895)
		(end 85.5218 -33.50895)
		(width 0.1016)
		(layer "F.Cu")
		(net "SAS3008_RAID_TX_P0")
	)
	(segment
		(start 123.69292 -81.941924)
		(end 123.69292 -82.091276)
		(width 0.1016)
		(layer "F.Cu")
		(net "SAS3008_RAID_TX_P0")
	)
	(via
		(at 77.133958 -36.659312)
		(size 0.5588)
		(drill 0.3048)
		(layers "F.Cu" "B.Cu")
		(net "SAS3008_RAID_TX_P0")
	)
	(via
		(at 123.853448 -80.925924)
		(size 0.5588)
		(drill 0.3048)
		(layers "F.Cu" "B.Cu")
		(net "SAS3008_RAID_TX_P0")
	)
	(via
		(at 123.73737 -81.7626)
		(size 0.508)
		(drill 0.254)
		(layers "F.Cu" "B.Cu")
		(net "SAS3008_RAID_TX_P0")
	)
	(via
		(at 84.9884 -33.789874)
		(size 0.5588)
		(drill 0.3048)
		(layers "F.Cu" "B.Cu")
		(net "SAS3008_RAID_TX_P0")
	)
	(arc
		(start 85.934042 -33.655)
		(mid 85.895147 -33.647281)
		(end 85.86216 -33.625282)
		(width 0.1016)
		(layer "F.Cu")
		(net "SAS3008_RAID_TX_P0")
	)
	(arc
		(start 85.311742 -33.508696)
		(mid 85.272847 -33.516415)
		(end 85.23986 -33.538414)
		(width 0.1016)
		(layer "F.Cu")
		(net "SAS3008_RAID_TX_P0")
	)
	(arc
		(start 85.775546 -33.538668)
		(mid 85.742552 -33.516685)
		(end 85.703664 -33.50895)
		(width 0.1016)
		(layer "F.Cu")
		(net "SAS3008_RAID_TX_P0")
	)
	(arc
		(start 123.752356 -81.798414)
		(mid 123.708361 -81.864257)
		(end 123.69292 -81.941924)
		(width 0.1016)
		(layer "F.Cu")
		(net "SAS3008_RAID_TX_P0")
	)
	(arc
		(start 123.69292 -82.091276)
		(mid 123.708368 -82.16894)
		(end 123.752356 -82.234786)
		(width 0.1016)
		(layer "F.Cu")
		(net "SAS3008_RAID_TX_P0")
	)
	(arc
		(start 123.807982 -82.290412)
		(mid 123.873825 -82.334407)
		(end 123.951492 -82.349848)
		(width 0.1016)
		(layer "F.Cu")
		(net "SAS3008_RAID_TX_P0")
	)
	(segment
		(start 123.758452 -80.925924)
		(end 123.853448 -80.925924)
		(width 0.1016)
		(layer "B.Cu")
		(net "SAS3008_RAID_TX_P0")
	)
	(segment
		(start 123.58497 -81.632552)
		(end 123.58497 -81.099406)
		(width 0.1016)
		(layer "B.Cu")
		(net "SAS3008_RAID_TX_P0")
	)
	(segment
		(start 123.73737 -81.7626)
		(end 123.715018 -81.7626)
		(width 0.1016)
		(layer "B.Cu")
		(net "SAS3008_RAID_TX_P0")
	)
	(segment
		(start 84.233512 -33.4772)
		(end 78.747366 -33.4772)
		(width 0.1016)
		(layer "B.Cu")
		(net "SAS3008_RAID_TX_P0")
	)
	(segment
		(start 76.876402 -36.559236)
		(end 76.917042 -36.599876)
		(width 0.1016)
		(layer "B.Cu")
		(net "SAS3008_RAID_TX_P0")
	)
	(segment
		(start 77.060552 -36.659312)
		(end 77.133958 -36.659312)
		(width 0.1016)
		(layer "B.Cu")
		(net "SAS3008_RAID_TX_P0")
	)
	(segment
		(start 76.816966 -35.433)
		(end 76.816966 -36.415726)
		(width 0.1016)
		(layer "B.Cu")
		(net "SAS3008_RAID_TX_P0")
	)
	(segment
		(start 78.328266 -33.6677)
		(end 76.996544 -34.999422)
		(width 0.1016)
		(layer "B.Cu")
		(net "SAS3008_RAID_TX_P0")
	)
	(segment
		(start 78.356968 -33.638744)
		(end 78.328266 -33.6677)
		(width 0.1016)
		(layer "B.Cu")
		(net "SAS3008_RAID_TX_P0")
	)
	(arc
		(start 76.917042 -36.599876)
		(mid 76.982885 -36.643871)
		(end 77.060552 -36.659312)
		(width 0.1016)
		(layer "B.Cu")
		(net "SAS3008_RAID_TX_P0")
	)
	(arc
		(start 123.58497 -81.099406)
		(mid 123.598176 -81.033017)
		(end 123.63577 -80.976724)
		(width 0.1016)
		(layer "B.Cu")
		(net "SAS3008_RAID_TX_P0")
	)
	(arc
		(start 123.62307 -81.7245)
		(mid 123.594882 -81.682314)
		(end 123.58497 -81.632552)
		(width 0.1016)
		(layer "B.Cu")
		(net "SAS3008_RAID_TX_P0")
	)
	(arc
		(start 123.63577 -80.976724)
		(mid 123.692057 -80.939114)
		(end 123.758452 -80.925924)
		(width 0.1016)
		(layer "B.Cu")
		(net "SAS3008_RAID_TX_P0")
	)
	(arc
		(start 76.816966 -36.415726)
		(mid 76.832414 -36.49339)
		(end 76.876402 -36.559236)
		(width 0.1016)
		(layer "B.Cu")
		(net "SAS3008_RAID_TX_P0")
	)
	(arc
		(start 76.996544 -34.999422)
		(mid 76.863625 -35.198349)
		(end 76.816966 -35.433)
		(width 0.1016)
		(layer "B.Cu")
		(net "SAS3008_RAID_TX_P0")
	)
	(arc
		(start 78.747366 -33.4772)
		(mid 78.536093 -33.519131)
		(end 78.356968 -33.638744)
		(width 0.1016)
		(layer "B.Cu")
		(net "SAS3008_RAID_TX_P0")
	)
	(arc
		(start 84.9884 -33.789874)
		(mid 84.642054 -33.558453)
		(end 84.233512 -33.4772)
		(width 0.1016)
		(layer "B.Cu")
		(net "SAS3008_RAID_TX_P0")
	)
	(arc
		(start 123.715018 -81.7626)
		(mid 123.665251 -81.752701)
		(end 123.62307 -81.7245)
		(width 0.1016)
		(layer "B.Cu")
		(net "SAS3008_RAID_TX_P0")
	)
	(segment
		(start 76.800202 -49.20869)
		(end 76.800456 -49.20869)
		(width 0.1016)
		(layer "In2.Cu")
		(net "SAS3008_RAID_TX_P0")
	)
	(segment
		(start 85.917278 -58.349642)
		(end 89.158064 -61.590428)
		(width 0.1016)
		(layer "In2.Cu")
		(net "SAS3008_RAID_TX_P0")
	)
	(segment
		(start 118.339616 -79.696056)
		(end 118.33987 -79.696056)
		(width 0.1016)
		(layer "In2.Cu")
		(net "SAS3008_RAID_TX_P0")
	)
	(segment
		(start 119.685054 -80.4926)
		(end 123.449842 -80.4926)
		(width 0.1016)
		(layer "In2.Cu")
		(net "SAS3008_RAID_TX_P0")
	)
	(segment
		(start 76.800456 -49.20869)
		(end 83.638136 -56.064404)
		(width 0.1016)
		(layer "In2.Cu")
		(net "SAS3008_RAID_TX_P0")
	)
	(segment
		(start 77.045058 -36.696142)
		(end 76.7588 -36.9824)
		(width 0.1016)
		(layer "In2.Cu")
		(net "SAS3008_RAID_TX_P0")
	)
	(segment
		(start 89.662 -62.807088)
		(end 89.662 -63.486538)
		(width 0.1016)
		(layer "In2.Cu")
		(net "SAS3008_RAID_TX_P0")
	)
	(segment
		(start 90.149426 -64.66332)
		(end 100.690426 -75.20432)
		(width 0.1016)
		(layer "In2.Cu")
		(net "SAS3008_RAID_TX_P0")
	)
	(segment
		(start 123.853448 -80.895698)
		(end 123.853448 -80.925924)
		(width 0.1016)
		(layer "In2.Cu")
		(net "SAS3008_RAID_TX_P0")
	)
	(segment
		(start 112.2934 -75.5142)
		(end 112.2934 -75.513946)
		(width 0.1016)
		(layer "In2.Cu")
		(net "SAS3008_RAID_TX_P0")
	)
	(segment
		(start 123.593352 -80.552036)
		(end 123.793758 -80.751934)
		(width 0.1016)
		(layer "In2.Cu")
		(net "SAS3008_RAID_TX_P0")
	)
	(segment
		(start 101.438456 -75.5142)
		(end 112.2934 -75.5142)
		(width 0.1016)
		(layer "In2.Cu")
		(net "SAS3008_RAID_TX_P0")
	)
	(segment
		(start 118.33987 -79.696056)
		(end 118.748302 -80.104488)
		(width 0.1016)
		(layer "In2.Cu")
		(net "SAS3008_RAID_TX_P0")
	)
	(segment
		(start 76.740766 -37.025834)
		(end 76.740766 -49.06518)
		(width 0.1016)
		(layer "In2.Cu")
		(net "SAS3008_RAID_TX_P0")
	)
	(segment
		(start 115.75288 -77.10932)
		(end 118.339616 -79.696056)
		(width 0.1016)
		(layer "In2.Cu")
		(net "SAS3008_RAID_TX_P0")
	)
	(segment
		(start 115.475766 -76.831952)
		(end 115.75288 -77.10932)
		(width 0.1016)
		(layer "In2.Cu")
		(net "SAS3008_RAID_TX_P0")
	)
	(segment
		(start 83.638136 -56.064404)
		(end 85.917278 -58.349642)
		(width 0.1016)
		(layer "In2.Cu")
		(net "SAS3008_RAID_TX_P0")
	)
	(arc
		(start 100.690426 -75.20432)
		(mid 101.033625 -75.433638)
		(end 101.438456 -75.5142)
		(width 0.1016)
		(layer "In2.Cu")
		(net "SAS3008_RAID_TX_P0")
	)
	(arc
		(start 112.2934 -75.513946)
		(mid 114.015672 -75.856433)
		(end 115.475766 -76.831952)
		(width 0.1016)
		(layer "In2.Cu")
		(net "SAS3008_RAID_TX_P0")
	)
	(arc
		(start 89.662 -63.486538)
		(mid 89.78868 -64.123403)
		(end 90.149426 -64.66332)
		(width 0.1016)
		(layer "In2.Cu")
		(net "SAS3008_RAID_TX_P0")
	)
	(arc
		(start 89.158064 -61.590428)
		(mid 89.531101 -62.148622)
		(end 89.662 -62.807088)
		(width 0.1016)
		(layer "In2.Cu")
		(net "SAS3008_RAID_TX_P0")
	)
	(arc
		(start 76.740766 -49.06518)
		(mid 76.756199 -49.142858)
		(end 76.800202 -49.20869)
		(width 0.1016)
		(layer "In2.Cu")
		(net "SAS3008_RAID_TX_P0")
	)
	(arc
		(start 118.748302 -80.104488)
		(mid 119.178073 -80.391715)
		(end 119.685054 -80.4926)
		(width 0.1016)
		(layer "In2.Cu")
		(net "SAS3008_RAID_TX_P0")
	)
	(arc
		(start 123.793758 -80.751934)
		(mid 123.837938 -80.817865)
		(end 123.853448 -80.895698)
		(width 0.1016)
		(layer "In2.Cu")
		(net "SAS3008_RAID_TX_P0")
	)
	(arc
		(start 76.7588 -36.9824)
		(mid 76.745485 -37.002328)
		(end 76.740766 -37.025834)
		(width 0.1016)
		(layer "In2.Cu")
		(net "SAS3008_RAID_TX_P0")
	)
	(arc
		(start 77.133958 -36.659312)
		(mid 77.085843 -36.668883)
		(end 77.045058 -36.696142)
		(width 0.1016)
		(layer "In2.Cu")
		(net "SAS3008_RAID_TX_P0")
	)
	(arc
		(start 123.449842 -80.4926)
		(mid 123.527506 -80.508048)
		(end 123.593352 -80.552036)
		(width 0.1016)
		(layer "In2.Cu")
		(net "SAS3008_RAID_TX_P0")
	)
	(segment
		(start 167.503348 -120.304052)
		(end 167.503348 -120.777)
		(width 0.254)
		(layer "F.Cu")
		(net "P0V9_E_RF")
	)
	(segment
		(start 167.503348 -120.777)
		(end 167.503348 -122.101356)
		(width 0.254)
		(layer "F.Cu")
		(net "P0V9_E_RF")
	)
	(segment
		(start 167.503348 -122.101356)
		(end 166.360348 -122.101356)
		(width 0.254)
		(layer "F.Cu")
		(net "P0V9_E_RF")
	)
	(segment
		(start 168.432226 -118.391178)
		(end 168.432226 -119.375174)
		(width 0.254)
		(layer "F.Cu")
		(net "P0V9_E_RF")
	)
	(segment
		(start 168.432226 -119.375174)
		(end 167.503348 -120.304052)
		(width 0.254)
		(layer "F.Cu")
		(net "P0V9_E_RF")
	)
	(via
		(at 167.503348 -120.777)
		(size 0.7112)
		(drill 0.3556)
		(layers "F.Cu" "B.Cu")
		(net "P0V9_E_RF")
	)
	(segment
		(start 71.80199 -131.173982)
		(end 71.80199 -131.21132)
		(width 0.1143)
		(layer "F.Cu")
		(net "XM_DATA9")
	)
	(segment
		(start 71.80199 -131.21132)
		(end 71.787004 -131.226306)
		(width 0.1143)
		(layer "F.Cu")
		(net "XM_DATA9")
	)
	(segment
		(start 75.786742 -130.892042)
		(end 72.08393 -130.892042)
		(width 0.1143)
		(layer "F.Cu")
		(net "XM_DATA9")
	)
	(segment
		(start 108.349796 -91.34983)
		(end 107.84967 -90.849704)
		(width 0.1143)
		(layer "F.Cu")
		(net "XM_DATA9")
	)
	(segment
		(start 72.08393 -130.892042)
		(end 71.80199 -131.173982)
		(width 0.1143)
		(layer "F.Cu")
		(net "XM_DATA9")
	)
	(via
		(at 71.501 -132.969)
		(size 0.7112)
		(drill 0.3556)
		(layers "F.Cu" "B.Cu")
		(net "XM_DATA9")
	)
	(via
		(at 107.84967 -90.849704)
		(size 0.508)
		(drill 0.254)
		(layers "F.Cu" "B.Cu")
		(net "XM_DATA9")
	)
	(via
		(at 71.787004 -131.226306)
		(size 0.5588)
		(drill 0.3048)
		(layers "F.Cu" "B.Cu")
		(net "XM_DATA9")
	)
	(segment
		(start 74.836274 -94.848172)
		(end 74.410062 -94.42196)
		(width 0.1143)
		(layer "B.Cu")
		(net "XM_DATA9")
	)
	(segment
		(start 107.478322 -90.849704)
		(end 107.033822 -90.405204)
		(width 0.1143)
		(layer "B.Cu")
		(net "XM_DATA9")
	)
	(segment
		(start 72.793352 -95.877126)
		(end 72.793352 -96.03867)
		(width 0.1143)
		(layer "B.Cu")
		(net "XM_DATA9")
	)
	(segment
		(start 76.452984 -93.231462)
		(end 76.452984 -93.393006)
		(width 0.1143)
		(layer "B.Cu")
		(net "XM_DATA9")
	)
	(segment
		(start 75.380088 -93.451934)
		(end 75.8063 -93.878146)
		(width 0.1143)
		(layer "B.Cu")
		(net "XM_DATA9")
	)
	(segment
		(start 75.482958 -94.201488)
		(end 75.056746 -93.775276)
		(width 0.1143)
		(layer "B.Cu")
		(net "XM_DATA9")
	)
	(segment
		(start 75.8063 -94.03969)
		(end 75.644502 -94.201488)
		(width 0.1143)
		(layer "B.Cu")
		(net "XM_DATA9")
	)
	(segment
		(start 87.614506 -89.929208)
		(end 87.208614 -90.3351)
		(width 0.1143)
		(layer "B.Cu")
		(net "XM_DATA9")
	)
	(segment
		(start 73.219564 -96.626426)
		(end 70.593966 -99.252024)
		(width 0.1143)
		(layer "B.Cu")
		(net "XM_DATA9")
	)
	(segment
		(start 75.8063 -93.878146)
		(end 75.8063 -94.03969)
		(width 0.1143)
		(layer "B.Cu")
		(net "XM_DATA9")
	)
	(segment
		(start 76.291186 -93.554804)
		(end 76.129642 -93.554804)
		(width 0.1143)
		(layer "B.Cu")
		(net "XM_DATA9")
	)
	(segment
		(start 87.208614 -90.3351)
		(end 87.20836 -90.3351)
		(width 0.1143)
		(layer "B.Cu")
		(net "XM_DATA9")
	)
	(segment
		(start 101.955854 -89.195656)
		(end 101.222302 -89.929208)
		(width 0.1143)
		(layer "B.Cu")
		(net "XM_DATA9")
	)
	(segment
		(start 73.866248 -95.818198)
		(end 73.866248 -95.979742)
		(width 0.1143)
		(layer "B.Cu")
		(net "XM_DATA9")
	)
	(segment
		(start 73.440036 -95.391986)
		(end 73.866248 -95.818198)
		(width 0.1143)
		(layer "B.Cu")
		(net "XM_DATA9")
	)
	(segment
		(start 74.733404 -94.098618)
		(end 75.159616 -94.52483)
		(width 0.1143)
		(layer "B.Cu")
		(net "XM_DATA9")
	)
	(segment
		(start 71.374 -131.63931)
		(end 71.787004 -131.226306)
		(width 0.1143)
		(layer "B.Cu")
		(net "XM_DATA9")
	)
	(segment
		(start 73.440036 -95.230442)
		(end 73.440036 -95.391986)
		(width 0.1143)
		(layer "B.Cu")
		(net "XM_DATA9")
	)
	(segment
		(start 76.776326 -92.90812)
		(end 76.350114 -92.481908)
		(width 0.1143)
		(layer "B.Cu")
		(net "XM_DATA9")
	)
	(segment
		(start 76.93787 -92.90812)
		(end 76.776326 -92.90812)
		(width 0.1143)
		(layer "B.Cu")
		(net "XM_DATA9")
	)
	(segment
		(start 74.895202 -93.775276)
		(end 74.733404 -93.937074)
		(width 0.1143)
		(layer "B.Cu")
		(net "XM_DATA9")
	)
	(segment
		(start 74.248518 -94.42196)
		(end 74.08672 -94.583758)
		(width 0.1143)
		(layer "B.Cu")
		(net "XM_DATA9")
	)
	(segment
		(start 106.294174 -89.71026)
		(end 105.98912 -89.405206)
		(width 0.1143)
		(layer "B.Cu")
		(net "XM_DATA9")
	)
	(segment
		(start 87.20836 -90.3351)
		(end 86.40064 -91.14282)
		(width 0.1143)
		(layer "B.Cu")
		(net "XM_DATA9")
	)
	(segment
		(start 73.763378 -95.068644)
		(end 73.601834 -95.068644)
		(width 0.1143)
		(layer "B.Cu")
		(net "XM_DATA9")
	)
	(segment
		(start 73.601834 -95.068644)
		(end 73.440036 -95.230442)
		(width 0.1143)
		(layer "B.Cu")
		(net "XM_DATA9")
	)
	(segment
		(start 74.08672 -94.745302)
		(end 74.512932 -95.171514)
		(width 0.1143)
		(layer "B.Cu")
		(net "XM_DATA9")
	)
	(segment
		(start 71.374 -132.842)
		(end 71.374 -131.63931)
		(width 0.1143)
		(layer "B.Cu")
		(net "XM_DATA9")
	)
	(segment
		(start 76.026772 -92.643706)
		(end 76.026772 -92.80525)
		(width 0.1143)
		(layer "B.Cu")
		(net "XM_DATA9")
	)
	(segment
		(start 75.159616 -94.52483)
		(end 75.159616 -94.686374)
		(width 0.1143)
		(layer "B.Cu")
		(net "XM_DATA9")
	)
	(segment
		(start 86.40064 -91.14282)
		(end 77.91831 -91.14282)
		(width 0.1143)
		(layer "B.Cu")
		(net "XM_DATA9")
	)
	(segment
		(start 71.774304 -131.213606)
		(end 71.787004 -131.226306)
		(width 0.1143)
		(layer "B.Cu")
		(net "XM_DATA9")
	)
	(segment
		(start 73.866248 -95.979742)
		(end 73.70445 -96.14154)
		(width 0.1143)
		(layer "B.Cu")
		(net "XM_DATA9")
	)
	(segment
		(start 106.821224 -90.405204)
		(end 106.294174 -89.878154)
		(width 0.1143)
		(layer "B.Cu")
		(net "XM_DATA9")
	)
	(segment
		(start 70.37832 -129.118106)
		(end 71.774304 -130.51409)
		(width 0.1143)
		(layer "B.Cu")
		(net "XM_DATA9")
	)
	(segment
		(start 75.644502 -94.201488)
		(end 75.482958 -94.201488)
		(width 0.1143)
		(layer "B.Cu")
		(net "XM_DATA9")
	)
	(segment
		(start 74.997818 -94.848172)
		(end 74.836274 -94.848172)
		(width 0.1143)
		(layer "B.Cu")
		(net "XM_DATA9")
	)
	(segment
		(start 107.84967 -90.849704)
		(end 107.478322 -90.849704)
		(width 0.1143)
		(layer "B.Cu")
		(net "XM_DATA9")
	)
	(segment
		(start 107.033822 -90.405204)
		(end 106.821224 -90.405204)
		(width 0.1143)
		(layer "B.Cu")
		(net "XM_DATA9")
	)
	(segment
		(start 74.351134 -95.494856)
		(end 74.18959 -95.494856)
		(width 0.1143)
		(layer "B.Cu")
		(net "XM_DATA9")
	)
	(segment
		(start 72.95515 -95.715328)
		(end 72.793352 -95.877126)
		(width 0.1143)
		(layer "B.Cu")
		(net "XM_DATA9")
	)
	(segment
		(start 76.129642 -93.554804)
		(end 75.70343 -93.128592)
		(width 0.1143)
		(layer "B.Cu")
		(net "XM_DATA9")
	)
	(segment
		(start 70.37832 -99.467416)
		(end 70.37832 -129.118106)
		(width 0.1143)
		(layer "B.Cu")
		(net "XM_DATA9")
	)
	(segment
		(start 71.501 -132.969)
		(end 71.374 -132.842)
		(width 0.1143)
		(layer "B.Cu")
		(net "XM_DATA9")
	)
	(segment
		(start 104.322626 -89.195656)
		(end 101.955854 -89.195656)
		(width 0.1143)
		(layer "B.Cu")
		(net "XM_DATA9")
	)
	(segment
		(start 72.793352 -96.03867)
		(end 73.219564 -96.464882)
		(width 0.1143)
		(layer "B.Cu")
		(net "XM_DATA9")
	)
	(segment
		(start 101.222302 -89.929208)
		(end 87.614506 -89.929208)
		(width 0.1143)
		(layer "B.Cu")
		(net "XM_DATA9")
	)
	(segment
		(start 70.593966 -99.252024)
		(end 70.593712 -99.252024)
		(width 0.1143)
		(layer "B.Cu")
		(net "XM_DATA9")
	)
	(segment
		(start 73.542906 -96.14154)
		(end 73.116694 -95.715328)
		(width 0.1143)
		(layer "B.Cu")
		(net "XM_DATA9")
	)
	(segment
		(start 74.410062 -94.42196)
		(end 74.248518 -94.42196)
		(width 0.1143)
		(layer "B.Cu")
		(net "XM_DATA9")
	)
	(segment
		(start 73.219564 -96.464882)
		(end 73.219564 -96.626426)
		(width 0.1143)
		(layer "B.Cu")
		(net "XM_DATA9")
	)
	(segment
		(start 75.056746 -93.775276)
		(end 74.895202 -93.775276)
		(width 0.1143)
		(layer "B.Cu")
		(net "XM_DATA9")
	)
	(segment
		(start 77.42174 -91.63939)
		(end 77.42174 -92.42425)
		(width 0.1143)
		(layer "B.Cu")
		(net "XM_DATA9")
	)
	(segment
		(start 74.733404 -93.937074)
		(end 74.733404 -94.098618)
		(width 0.1143)
		(layer "B.Cu")
		(net "XM_DATA9")
	)
	(segment
		(start 70.593712 -99.252024)
		(end 70.37832 -99.467416)
		(width 0.1143)
		(layer "B.Cu")
		(net "XM_DATA9")
	)
	(segment
		(start 73.116694 -95.715328)
		(end 72.95515 -95.715328)
		(width 0.1143)
		(layer "B.Cu")
		(net "XM_DATA9")
	)
	(segment
		(start 76.18857 -92.481908)
		(end 76.026772 -92.643706)
		(width 0.1143)
		(layer "B.Cu")
		(net "XM_DATA9")
	)
	(segment
		(start 74.512932 -95.333058)
		(end 74.351134 -95.494856)
		(width 0.1143)
		(layer "B.Cu")
		(net "XM_DATA9")
	)
	(segment
		(start 76.026772 -92.80525)
		(end 76.452984 -93.231462)
		(width 0.1143)
		(layer "B.Cu")
		(net "XM_DATA9")
	)
	(segment
		(start 74.08672 -94.583758)
		(end 74.08672 -94.745302)
		(width 0.1143)
		(layer "B.Cu")
		(net "XM_DATA9")
	)
	(segment
		(start 75.380088 -93.29039)
		(end 75.380088 -93.451934)
		(width 0.1143)
		(layer "B.Cu")
		(net "XM_DATA9")
	)
	(segment
		(start 75.70343 -93.128592)
		(end 75.541886 -93.128592)
		(width 0.1143)
		(layer "B.Cu")
		(net "XM_DATA9")
	)
	(segment
		(start 77.42174 -92.42425)
		(end 76.93787 -92.90812)
		(width 0.1143)
		(layer "B.Cu")
		(net "XM_DATA9")
	)
	(segment
		(start 104.532176 -89.405206)
		(end 104.322626 -89.195656)
		(width 0.1143)
		(layer "B.Cu")
		(net "XM_DATA9")
	)
	(segment
		(start 74.512932 -95.171514)
		(end 74.512932 -95.333058)
		(width 0.1143)
		(layer "B.Cu")
		(net "XM_DATA9")
	)
	(segment
		(start 71.774304 -130.51409)
		(end 71.774304 -131.213606)
		(width 0.1143)
		(layer "B.Cu")
		(net "XM_DATA9")
	)
	(segment
		(start 75.541886 -93.128592)
		(end 75.380088 -93.29039)
		(width 0.1143)
		(layer "B.Cu")
		(net "XM_DATA9")
	)
	(segment
		(start 75.159616 -94.686374)
		(end 74.997818 -94.848172)
		(width 0.1143)
		(layer "B.Cu")
		(net "XM_DATA9")
	)
	(segment
		(start 76.452984 -93.393006)
		(end 76.291186 -93.554804)
		(width 0.1143)
		(layer "B.Cu")
		(net "XM_DATA9")
	)
	(segment
		(start 76.350114 -92.481908)
		(end 76.18857 -92.481908)
		(width 0.1143)
		(layer "B.Cu")
		(net "XM_DATA9")
	)
	(segment
		(start 106.294174 -89.878154)
		(end 106.294174 -89.71026)
		(width 0.1143)
		(layer "B.Cu")
		(net "XM_DATA9")
	)
	(segment
		(start 73.70445 -96.14154)
		(end 73.542906 -96.14154)
		(width 0.1143)
		(layer "B.Cu")
		(net "XM_DATA9")
	)
	(segment
		(start 77.91831 -91.14282)
		(end 77.42174 -91.63939)
		(width 0.1143)
		(layer "B.Cu")
		(net "XM_DATA9")
	)
	(segment
		(start 74.18959 -95.494856)
		(end 73.763378 -95.068644)
		(width 0.1143)
		(layer "B.Cu")
		(net "XM_DATA9")
	)
	(segment
		(start 105.98912 -89.405206)
		(end 104.532176 -89.405206)
		(width 0.1143)
		(layer "B.Cu")
		(net "XM_DATA9")
	)
	(segment
		(start 127.58166 -83.94954)
		(end 126.86157 -83.94954)
		(width 0.0889)
		(layer "F.Cu")
		(net "SAS_HDD_TX13_P")
	)
	(segment
		(start 126.671832 -84.02828)
		(end 126.350014 -84.349844)
		(width 0.0889)
		(layer "F.Cu")
		(net "SAS_HDD_TX13_P")
	)
	(segment
		(start 128.669288 -83.203542)
		(end 128.2319 -83.64093)
		(width 0.1016)
		(layer "F.Cu")
		(net "SAS_HDD_TX13_P")
	)
	(segment
		(start 128.04013 -83.67776)
		(end 127.90043 -83.81746)
		(width 0.0889)
		(layer "F.Cu")
		(net "SAS_HDD_TX13_P")
	)
	(segment
		(start 131.75996 -83.058)
		(end 129.02057 -83.058)
		(width 0.1016)
		(layer "F.Cu")
		(net "SAS_HDD_TX13_P")
	)
	(segment
		(start 128.143 -83.67776)
		(end 128.04013 -83.67776)
		(width 0.0889)
		(layer "F.Cu")
		(net "SAS_HDD_TX13_P")
	)
	(arc
		(start 127.90043 -83.81746)
		(mid 127.754177 -83.915183)
		(end 127.58166 -83.94954)
		(width 0.0889)
		(layer "F.Cu")
		(net "SAS_HDD_TX13_P")
	)
	(arc
		(start 129.02057 -83.058)
		(mid 128.830444 -83.095818)
		(end 128.669288 -83.203542)
		(width 0.1016)
		(layer "F.Cu")
		(net "SAS_HDD_TX13_P")
	)
	(arc
		(start 126.86157 -83.94954)
		(mid 126.758882 -83.97006)
		(end 126.671832 -84.02828)
		(width 0.0889)
		(layer "F.Cu")
		(net "SAS_HDD_TX13_P")
	)
	(arc
		(start 128.2319 -83.64093)
		(mid 128.191112 -83.668183)
		(end 128.143 -83.67776)
		(width 0.0889)
		(layer "F.Cu")
		(net "SAS_HDD_TX13_P")
	)
	(arc
		(start 131.933442 -83.129882)
		(mid 131.853848 -83.076699)
		(end 131.75996 -83.058)
		(width 0.1016)
		(layer "F.Cu")
		(net "SAS_HDD_TX13_P")
	)
	(segment
		(start 146.385026 -47.127414)
		(end 147.1676 -47.127414)
		(width 0.1143)
		(layer "F.Cu")
		(net "XM_ADDR_7")
	)
	(segment
		(start 147.1676 -48.956214)
		(end 147.2819 -49.070514)
		(width 0.1143)
		(layer "F.Cu")
		(net "XM_ADDR_7")
	)
	(segment
		(start 146.33829 -48.041814)
		(end 147.1676 -48.041814)
		(width 0.1143)
		(layer "F.Cu")
		(net "XM_ADDR_7")
	)
	(segment
		(start 146.78025 -49.413414)
		(end 146.66595 -49.527714)
		(width 0.1143)
		(layer "F.Cu")
		(net "XM_ADDR_7")
	)
	(segment
		(start 150.495 -56.642)
		(end 151.5745 -56.642)
		(width 0.1143)
		(layer "F.Cu")
		(net "XM_ADDR_7")
	)
	(segment
		(start 147.2819 -47.470314)
		(end 147.1676 -47.584614)
		(width 0.1143)
		(layer "F.Cu")
		(net "XM_ADDR_7")
	)
	(segment
		(start 146.66595 -49.756314)
		(end 146.78025 -49.870614)
		(width 0.1143)
		(layer "F.Cu")
		(net "XM_ADDR_7")
	)
	(segment
		(start 147.066 -54.229)
		(end 149.479 -56.642)
		(width 0.1143)
		(layer "F.Cu")
		(net "XM_ADDR_7")
	)
	(segment
		(start 147.1676 -48.499014)
		(end 146.431508 -48.499014)
		(width 0.1143)
		(layer "F.Cu")
		(net "XM_ADDR_7")
	)
	(segment
		(start 147.2819 -47.241714)
		(end 147.2819 -47.470314)
		(width 0.1143)
		(layer "F.Cu")
		(net "XM_ADDR_7")
	)
	(segment
		(start 147.2819 -49.984914)
		(end 147.2819 -50.213514)
		(width 0.1143)
		(layer "F.Cu")
		(net "XM_ADDR_7")
	)
	(segment
		(start 146.258026 -47.000414)
		(end 146.385026 -47.127414)
		(width 0.1143)
		(layer "F.Cu")
		(net "XM_ADDR_7")
	)
	(segment
		(start 147.1676 -49.870614)
		(end 147.2819 -49.984914)
		(width 0.1143)
		(layer "F.Cu")
		(net "XM_ADDR_7")
	)
	(segment
		(start 147.2819 -49.070514)
		(end 147.2819 -49.299114)
		(width 0.1143)
		(layer "F.Cu")
		(net "XM_ADDR_7")
	)
	(segment
		(start 146.304508 -48.829214)
		(end 146.431508 -48.956214)
		(width 0.1143)
		(layer "F.Cu")
		(net "XM_ADDR_7")
	)
	(segment
		(start 146.66595 -49.527714)
		(end 146.66595 -49.756314)
		(width 0.1143)
		(layer "F.Cu")
		(net "XM_ADDR_7")
	)
	(segment
		(start 146.33829 -47.584614)
		(end 146.2151 -47.707804)
		(width 0.1143)
		(layer "F.Cu")
		(net "XM_ADDR_7")
	)
	(segment
		(start 146.385026 -46.670214)
		(end 146.258026 -46.797214)
		(width 0.1143)
		(layer "F.Cu")
		(net "XM_ADDR_7")
	)
	(segment
		(start 147.1676 -47.584614)
		(end 146.33829 -47.584614)
		(width 0.1143)
		(layer "F.Cu")
		(net "XM_ADDR_7")
	)
	(segment
		(start 147.2819 -50.213514)
		(end 147.1676 -50.327814)
		(width 0.1143)
		(layer "F.Cu")
		(net "XM_ADDR_7")
	)
	(segment
		(start 146.4691 -51.943)
		(end 147.066 -52.5399)
		(width 0.1143)
		(layer "F.Cu")
		(net "XM_ADDR_7")
	)
	(segment
		(start 149.479 -56.642)
		(end 150.495 -56.642)
		(width 0.1143)
		(layer "F.Cu")
		(net "XM_ADDR_7")
	)
	(segment
		(start 146.78025 -50.327814)
		(end 146.66595 -50.442114)
		(width 0.1143)
		(layer "F.Cu")
		(net "XM_ADDR_7")
	)
	(segment
		(start 147.1676 -46.670214)
		(end 146.385026 -46.670214)
		(width 0.1143)
		(layer "F.Cu")
		(net "XM_ADDR_7")
	)
	(segment
		(start 146.78025 -46.213014)
		(end 147.1676 -46.213014)
		(width 0.1143)
		(layer "F.Cu")
		(net "XM_ADDR_7")
	)
	(segment
		(start 147.066 -52.5399)
		(end 147.066 -54.229)
		(width 0.1143)
		(layer "F.Cu")
		(net "XM_ADDR_7")
	)
	(segment
		(start 147.2819 -48.156114)
		(end 147.2819 -48.384714)
		(width 0.1143)
		(layer "F.Cu")
		(net "XM_ADDR_7")
	)
	(segment
		(start 146.2151 -47.707804)
		(end 146.2151 -47.918624)
		(width 0.1143)
		(layer "F.Cu")
		(net "XM_ADDR_7")
	)
	(segment
		(start 113.949988 -56.056022)
		(end 115.678966 -57.785)
		(width 0.1143)
		(layer "F.Cu")
		(net "XM_ADDR_7")
	)
	(segment
		(start 147.1676 -50.327814)
		(end 146.78025 -50.327814)
		(width 0.1143)
		(layer "F.Cu")
		(net "XM_ADDR_7")
	)
	(segment
		(start 147.2819 -48.384714)
		(end 147.1676 -48.499014)
		(width 0.1143)
		(layer "F.Cu")
		(net "XM_ADDR_7")
	)
	(segment
		(start 145.598896 -42.7101)
		(end 145.598896 -45.03166)
		(width 0.1143)
		(layer "F.Cu")
		(net "XM_ADDR_7")
	)
	(segment
		(start 146.431508 -48.956214)
		(end 147.1676 -48.956214)
		(width 0.1143)
		(layer "F.Cu")
		(net "XM_ADDR_7")
	)
	(segment
		(start 146.78025 -49.870614)
		(end 147.1676 -49.870614)
		(width 0.1143)
		(layer "F.Cu")
		(net "XM_ADDR_7")
	)
	(segment
		(start 147.2819 -46.327314)
		(end 147.2819 -46.555914)
		(width 0.1143)
		(layer "F.Cu")
		(net "XM_ADDR_7")
	)
	(segment
		(start 147.2819 -46.555914)
		(end 147.1676 -46.670214)
		(width 0.1143)
		(layer "F.Cu")
		(net "XM_ADDR_7")
	)
	(segment
		(start 147.1676 -49.413414)
		(end 146.78025 -49.413414)
		(width 0.1143)
		(layer "F.Cu")
		(net "XM_ADDR_7")
	)
	(segment
		(start 146.304508 -48.626014)
		(end 146.304508 -48.829214)
		(width 0.1143)
		(layer "F.Cu")
		(net "XM_ADDR_7")
	)
	(segment
		(start 146.66595 -51.74615)
		(end 146.4691 -51.943)
		(width 0.1143)
		(layer "F.Cu")
		(net "XM_ADDR_7")
	)
	(segment
		(start 146.258026 -46.797214)
		(end 146.258026 -47.000414)
		(width 0.1143)
		(layer "F.Cu")
		(net "XM_ADDR_7")
	)
	(segment
		(start 113.949988 -55.79999)
		(end 113.949988 -56.056022)
		(width 0.1143)
		(layer "F.Cu")
		(net "XM_ADDR_7")
	)
	(segment
		(start 147.1676 -47.127414)
		(end 147.2819 -47.241714)
		(width 0.1143)
		(layer "F.Cu")
		(net "XM_ADDR_7")
	)
	(segment
		(start 145.598896 -45.03166)
		(end 146.78025 -46.213014)
		(width 0.1143)
		(layer "F.Cu")
		(net "XM_ADDR_7")
	)
	(segment
		(start 147.1676 -48.041814)
		(end 147.2819 -48.156114)
		(width 0.1143)
		(layer "F.Cu")
		(net "XM_ADDR_7")
	)
	(segment
		(start 146.66595 -50.442114)
		(end 146.66595 -51.74615)
		(width 0.1143)
		(layer "F.Cu")
		(net "XM_ADDR_7")
	)
	(segment
		(start 146.431508 -48.499014)
		(end 146.304508 -48.626014)
		(width 0.1143)
		(layer "F.Cu")
		(net "XM_ADDR_7")
	)
	(segment
		(start 146.2151 -47.918624)
		(end 146.33829 -48.041814)
		(width 0.1143)
		(layer "F.Cu")
		(net "XM_ADDR_7")
	)
	(segment
		(start 147.1676 -46.213014)
		(end 147.2819 -46.327314)
		(width 0.1143)
		(layer "F.Cu")
		(net "XM_ADDR_7")
	)
	(segment
		(start 147.2819 -49.299114)
		(end 147.1676 -49.413414)
		(width 0.1143)
		(layer "F.Cu")
		(net "XM_ADDR_7")
	)
	(via
		(at 115.678966 -57.785)
		(size 0.508)
		(drill 0.254)
		(layers "F.Cu" "B.Cu")
		(net "XM_ADDR_7")
	)
	(via
		(at 150.495 -56.642)
		(size 0.7112)
		(drill 0.3556)
		(layers "F.Cu" "B.Cu")
		(net "XM_ADDR_7")
	)
	(via
		(at 146.4691 -51.943)
		(size 0.5588)
		(drill 0.3048)
		(layers "F.Cu" "B.Cu")
		(net "XM_ADDR_7")
	)
	(segment
		(start 147.215352 -52.325778)
		(end 147.215352 -52.0065)
		(width 0.127)
		(layer "In5.Cu")
		(net "XM_ADDR_7")
	)
	(segment
		(start 140.109956 -52.714398)
		(end 140.109956 -52.702206)
		(width 0.127)
		(layer "In5.Cu")
		(net "XM_ADDR_7")
	)
	(segment
		(start 144.503902 -51.835812)
		(end 144.898872 -52.230782)
		(width 0.127)
		(layer "In5.Cu")
		(net "XM_ADDR_7")
	)
	(segment
		(start 125.802898 -55.534306)
		(end 137.290048 -55.534306)
		(width 0.127)
		(layer "In5.Cu")
		(net "XM_ADDR_7")
	)
	(segment
		(start 144.898872 -52.230782)
		(end 145.078704 -52.230782)
		(width 0.127)
		(layer "In5.Cu")
		(net "XM_ADDR_7")
	)
	(segment
		(start 145.70964 -52.318412)
		(end 145.70964 -53.059076)
		(width 0.127)
		(layer "In5.Cu")
		(net "XM_ADDR_7")
	)
	(segment
		(start 115.940078 -57.785)
		(end 117.103652 -56.621426)
		(width 0.127)
		(layer "In5.Cu")
		(net "XM_ADDR_7")
	)
	(segment
		(start 145.078704 -52.230782)
		(end 145.399506 -51.910234)
		(width 0.127)
		(layer "In5.Cu")
		(net "XM_ADDR_7")
	)
	(segment
		(start 124.715778 -56.621426)
		(end 125.802898 -55.534306)
		(width 0.127)
		(layer "In5.Cu")
		(net "XM_ADDR_7")
	)
	(segment
		(start 147.215352 -52.0065)
		(end 147.088352 -51.8795)
		(width 0.127)
		(layer "In5.Cu")
		(net "XM_ADDR_7")
	)
	(segment
		(start 145.758662 -52.26939)
		(end 145.70964 -52.318412)
		(width 0.127)
		(layer "In5.Cu")
		(net "XM_ADDR_7")
	)
	(segment
		(start 140.109956 -52.702206)
		(end 140.97635 -51.835812)
		(width 0.127)
		(layer "In5.Cu")
		(net "XM_ADDR_7")
	)
	(segment
		(start 147.088352 -51.8795)
		(end 146.5326 -51.8795)
		(width 0.127)
		(layer "In5.Cu")
		(net "XM_ADDR_7")
	)
	(segment
		(start 117.103652 -56.621426)
		(end 124.715778 -56.621426)
		(width 0.127)
		(layer "In5.Cu")
		(net "XM_ADDR_7")
	)
	(segment
		(start 137.290048 -55.534306)
		(end 140.109956 -52.714398)
		(width 0.127)
		(layer "In5.Cu")
		(net "XM_ADDR_7")
	)
	(segment
		(start 145.83664 -53.186076)
		(end 146.355054 -53.186076)
		(width 0.127)
		(layer "In5.Cu")
		(net "XM_ADDR_7")
	)
	(segment
		(start 145.758662 -52.090066)
		(end 145.758662 -52.26939)
		(width 0.127)
		(layer "In5.Cu")
		(net "XM_ADDR_7")
	)
	(segment
		(start 146.5326 -51.8795)
		(end 146.4691 -51.943)
		(width 0.127)
		(layer "In5.Cu")
		(net "XM_ADDR_7")
	)
	(segment
		(start 145.399506 -51.910234)
		(end 145.57883 -51.910234)
		(width 0.127)
		(layer "In5.Cu")
		(net "XM_ADDR_7")
	)
	(segment
		(start 146.355054 -53.186076)
		(end 147.215352 -52.325778)
		(width 0.127)
		(layer "In5.Cu")
		(net "XM_ADDR_7")
	)
	(segment
		(start 145.70964 -53.059076)
		(end 145.83664 -53.186076)
		(width 0.127)
		(layer "In5.Cu")
		(net "XM_ADDR_7")
	)
	(segment
		(start 140.97635 -51.835812)
		(end 144.503902 -51.835812)
		(width 0.127)
		(layer "In5.Cu")
		(net "XM_ADDR_7")
	)
	(segment
		(start 115.678966 -57.785)
		(end 115.940078 -57.785)
		(width 0.127)
		(layer "In5.Cu")
		(net "XM_ADDR_7")
	)
	(segment
		(start 145.57883 -51.910234)
		(end 145.758662 -52.090066)
		(width 0.127)
		(layer "In5.Cu")
		(net "XM_ADDR_7")
	)
	(segment
		(start 83.427062 -35.175444)
		(end 83.208876 -35.265614)
		(width 0.1016)
		(layer "F.Cu")
		(net "SAS3008_RAID_TX_P1")
	)
	(segment
		(start 85.825838 -35.23996)
		(end 85.811868 -35.22599)
		(width 0.1016)
		(layer "F.Cu")
		(net "SAS3008_RAID_TX_P1")
	)
	(segment
		(start 83.0834 -35.453574)
		(end 83.0834 -35.523678)
		(width 0.1016)
		(layer "F.Cu")
		(net "SAS3008_RAID_TX_P1")
	)
	(segment
		(start 86.21776 -35.306)
		(end 85.985096 -35.306)
		(width 0.1016)
		(layer "F.Cu")
		(net "SAS3008_RAID_TX_P1")
	)
	(segment
		(start 123.35002 -83.349846)
		(end 123.850146 -82.84972)
		(width 0.1016)
		(layer "F.Cu")
		(net "SAS3008_RAID_TX_P1")
	)
	(segment
		(start 85.65261 -35.15995)
		(end 83.504786 -35.15995)
		(width 0.1016)
		(layer "F.Cu")
		(net "SAS3008_RAID_TX_P1")
	)
	(via
		(at 123.850146 -82.84972)
		(size 0.508)
		(drill 0.254)
		(layers "F.Cu" "B.Cu")
		(net "SAS3008_RAID_TX_P1")
	)
	(via
		(at 83.0834 -35.523678)
		(size 0.5588)
		(drill 0.3048)
		(layers "F.Cu" "B.Cu")
		(net "SAS3008_RAID_TX_P1")
	)
	(via
		(at 78.663292 -41.6052)
		(size 0.5588)
		(drill 0.3048)
		(layers "F.Cu" "B.Cu")
		(net "SAS3008_RAID_TX_P1")
	)
	(via
		(at 125.756162 -80.251808)
		(size 0.5588)
		(drill 0.3048)
		(layers "F.Cu" "B.Cu")
		(net "SAS3008_RAID_TX_P1")
	)
	(arc
		(start 83.504786 -35.15995)
		(mid 83.465156 -35.163852)
		(end 83.427062 -35.175444)
		(width 0.1016)
		(layer "F.Cu")
		(net "SAS3008_RAID_TX_P1")
	)
	(arc
		(start 85.811868 -35.22599)
		(mid 85.738814 -35.177114)
		(end 85.65261 -35.15995)
		(width 0.1016)
		(layer "F.Cu")
		(net "SAS3008_RAID_TX_P1")
	)
	(arc
		(start 83.208876 -35.265614)
		(mid 83.117614 -35.340545)
		(end 83.0834 -35.453574)
		(width 0.1016)
		(layer "F.Cu")
		(net "SAS3008_RAID_TX_P1")
	)
	(arc
		(start 85.985096 -35.306)
		(mid 85.898892 -35.288835)
		(end 85.825838 -35.23996)
		(width 0.1016)
		(layer "F.Cu")
		(net "SAS3008_RAID_TX_P1")
	)
	(segment
		(start 82.760058 -35.2425)
		(end 79.653892 -35.2425)
		(width 0.1016)
		(layer "B.Cu")
		(net "SAS3008_RAID_TX_P1")
	)
	(segment
		(start 124.513086 -82.510884)
		(end 124.476002 -82.548222)
		(width 0.1016)
		(layer "B.Cu")
		(net "SAS3008_RAID_TX_P1")
	)
	(segment
		(start 78.346554 -38.16858)
		(end 78.3463 -41.246044)
		(width 0.1016)
		(layer "B.Cu")
		(net "SAS3008_RAID_TX_P1")
	)
	(segment
		(start 125.43917 -80.899)
		(end 125.43917 -81.2292)
		(width 0.1016)
		(layer "B.Cu")
		(net "SAS3008_RAID_TX_P1")
	)
	(segment
		(start 83.0834 -35.523678)
		(end 82.83194 -35.272218)
		(width 0.1016)
		(layer "B.Cu")
		(net "SAS3008_RAID_TX_P1")
	)
	(segment
		(start 125.756162 -80.251808)
		(end 125.672596 -80.335374)
		(width 0.1016)
		(layer "B.Cu")
		(net "SAS3008_RAID_TX_P1")
	)
	(segment
		(start 125.187964 -81.836006)
		(end 124.513086 -82.510884)
		(width 0.1016)
		(layer "B.Cu")
		(net "SAS3008_RAID_TX_P1")
	)
	(segment
		(start 79.242666 -35.41268)
		(end 79.1718 -35.4838)
		(width 0.1016)
		(layer "B.Cu")
		(net "SAS3008_RAID_TX_P1")
	)
	(segment
		(start 78.376018 -41.317926)
		(end 78.663292 -41.6052)
		(width 0.1016)
		(layer "B.Cu")
		(net "SAS3008_RAID_TX_P1")
	)
	(segment
		(start 79.0194 -35.851846)
		(end 79.0194 -36.54425)
		(width 0.1016)
		(layer "B.Cu")
		(net "SAS3008_RAID_TX_P1")
	)
	(segment
		(start 123.908312 -82.791554)
		(end 123.850146 -82.84972)
		(width 0.1016)
		(layer "B.Cu")
		(net "SAS3008_RAID_TX_P1")
	)
	(arc
		(start 124.476002 -82.548222)
		(mid 124.290112 -82.672337)
		(end 124.070872 -82.715862)
		(width 0.1016)
		(layer "B.Cu")
		(net "SAS3008_RAID_TX_P1")
	)
	(arc
		(start 79.1718 -35.4838)
		(mid 79.058971 -35.652661)
		(end 79.0194 -35.851846)
		(width 0.1016)
		(layer "B.Cu")
		(net "SAS3008_RAID_TX_P1")
	)
	(arc
		(start 79.0194 -36.54425)
		(mid 78.957549 -36.855198)
		(end 78.781402 -37.118798)
		(width 0.1016)
		(layer "B.Cu")
		(net "SAS3008_RAID_TX_P1")
	)
	(arc
		(start 82.83194 -35.272218)
		(mid 82.798946 -35.250235)
		(end 82.760058 -35.2425)
		(width 0.1016)
		(layer "B.Cu")
		(net "SAS3008_RAID_TX_P1")
	)
	(arc
		(start 78.3463 -41.246044)
		(mid 78.354019 -41.284939)
		(end 78.376018 -41.317926)
		(width 0.1016)
		(layer "B.Cu")
		(net "SAS3008_RAID_TX_P1")
	)
	(arc
		(start 125.672596 -80.335374)
		(mid 125.499809 -80.593968)
		(end 125.43917 -80.899)
		(width 0.1016)
		(layer "B.Cu")
		(net "SAS3008_RAID_TX_P1")
	)
	(arc
		(start 125.43917 -81.2292)
		(mid 125.373941 -81.557601)
		(end 125.187964 -81.836006)
		(width 0.1016)
		(layer "B.Cu")
		(net "SAS3008_RAID_TX_P1")
	)
	(arc
		(start 123.983242 -82.738976)
		(mid 123.943444 -82.761943)
		(end 123.908312 -82.791554)
		(width 0.1016)
		(layer "B.Cu")
		(net "SAS3008_RAID_TX_P1")
	)
	(arc
		(start 124.070872 -82.715862)
		(mid 124.026049 -82.723596)
		(end 123.983242 -82.738976)
		(width 0.1016)
		(layer "B.Cu")
		(net "SAS3008_RAID_TX_P1")
	)
	(arc
		(start 79.653892 -35.2425)
		(mid 79.431344 -35.286674)
		(end 79.242666 -35.41268)
		(width 0.1016)
		(layer "B.Cu")
		(net "SAS3008_RAID_TX_P1")
	)
	(arc
		(start 78.781402 -37.118798)
		(mid 78.459578 -37.600442)
		(end 78.346554 -38.16858)
		(width 0.1016)
		(layer "B.Cu")
		(net "SAS3008_RAID_TX_P1")
	)
	(segment
		(start 101.520498 -71.185532)
		(end 102.276656 -71.94169)
		(width 0.1016)
		(layer "In2.Cu")
		(net "SAS3008_RAID_TX_P1")
	)
	(segment
		(start 88.068658 -57.733692)
		(end 88.28405 -57.949084)
		(width 0.1016)
		(layer "In2.Cu")
		(net "SAS3008_RAID_TX_P1")
	)
	(segment
		(start 88.763602 -58.109104)
		(end 88.979248 -58.324496)
		(width 0.1016)
		(layer "In2.Cu")
		(net "SAS3008_RAID_TX_P1")
	)
	(segment
		(start 89.139014 -58.804048)
		(end 90.687652 -60.352686)
		(width 0.1016)
		(layer "In2.Cu")
		(net "SAS3008_RAID_TX_P1")
	)
	(segment
		(start 79.801466 -49.4665)
		(end 86.143338 -55.808372)
		(width 0.1016)
		(layer "In2.Cu")
		(net "SAS3008_RAID_TX_P1")
	)
	(segment
		(start 93.307916 -62.653418)
		(end 93.523562 -62.86881)
		(width 0.1016)
		(layer "In2.Cu")
		(net "SAS3008_RAID_TX_P1")
	)
	(segment
		(start 91.542616 -61.20765)
		(end 91.758008 -61.423042)
		(width 0.1016)
		(layer "In2.Cu")
		(net "SAS3008_RAID_TX_P1")
	)
	(segment
		(start 98.230944 -67.576446)
		(end 98.44659 -67.791838)
		(width 0.1016)
		(layer "In2.Cu")
		(net "SAS3008_RAID_TX_P1")
	)
	(segment
		(start 79.801212 -49.4665)
		(end 79.801466 -49.4665)
		(width 0.1016)
		(layer "In2.Cu")
		(net "SAS3008_RAID_TX_P1")
	)
	(segment
		(start 121.483628 -79.375)
		(end 124.44984 -79.375)
		(width 0.1016)
		(layer "In2.Cu")
		(net "SAS3008_RAID_TX_P1")
	)
	(segment
		(start 96.465644 -66.130678)
		(end 96.681036 -66.34607)
		(width 0.1016)
		(layer "In2.Cu")
		(net "SAS3008_RAID_TX_P1")
	)
	(segment
		(start 124.89815 -79.56042)
		(end 125.471682 -80.133952)
		(width 0.1016)
		(layer "In2.Cu")
		(net "SAS3008_RAID_TX_P1")
	)
	(segment
		(start 78.4606 -42.094658)
		(end 78.4606 -47.79264)
		(width 0.1016)
		(layer "In2.Cu")
		(net "SAS3008_RAID_TX_P1")
	)
	(segment
		(start 115.01247 -73.71207)
		(end 120.1039 -78.8035)
		(width 0.1016)
		(layer "In2.Cu")
		(net "SAS3008_RAID_TX_P1")
	)
	(segment
		(start 93.683328 -63.348362)
		(end 95.61068 -65.275714)
		(width 0.1016)
		(layer "In2.Cu")
		(net "SAS3008_RAID_TX_P1")
	)
	(segment
		(start 100.074476 -69.419978)
		(end 100.290122 -69.63537)
		(width 0.1016)
		(layer "In2.Cu")
		(net "SAS3008_RAID_TX_P1")
	)
	(segment
		(start 87.693246 -57.038494)
		(end 87.908892 -57.25414)
		(width 0.1016)
		(layer "In2.Cu")
		(net "SAS3008_RAID_TX_P1")
	)
	(segment
		(start 97.536 -67.201034)
		(end 97.751392 -67.416426)
		(width 0.1016)
		(layer "In2.Cu")
		(net "SAS3008_RAID_TX_P1")
	)
	(segment
		(start 86.998302 -56.663336)
		(end 87.213694 -56.878728)
		(width 0.1016)
		(layer "In2.Cu")
		(net "SAS3008_RAID_TX_P1")
	)
	(segment
		(start 86.62289 -55.968138)
		(end 86.838282 -56.183784)
		(width 0.1016)
		(layer "In2.Cu")
		(net "SAS3008_RAID_TX_P1")
	)
	(segment
		(start 101.145086 -70.490334)
		(end 101.360478 -70.70598)
		(width 0.1016)
		(layer "In2.Cu")
		(net "SAS3008_RAID_TX_P1")
	)
	(segment
		(start 78.696312 -48.3616)
		(end 79.801212 -49.4665)
		(width 0.1016)
		(layer "In2.Cu")
		(net "SAS3008_RAID_TX_P1")
	)
	(segment
		(start 92.23756 -61.582808)
		(end 92.453206 -61.798454)
		(width 0.1016)
		(layer "In2.Cu")
		(net "SAS3008_RAID_TX_P1")
	)
	(segment
		(start 100.449888 -70.114922)
		(end 100.665534 -70.330568)
		(width 0.1016)
		(layer "In2.Cu")
		(net "SAS3008_RAID_TX_P1")
	)
	(segment
		(start 96.090232 -65.43548)
		(end 96.305624 -65.651126)
		(width 0.1016)
		(layer "In2.Cu")
		(net "SAS3008_RAID_TX_P1")
	)
	(segment
		(start 97.160588 -66.505836)
		(end 97.376234 -66.721482)
		(width 0.1016)
		(layer "In2.Cu")
		(net "SAS3008_RAID_TX_P1")
	)
	(segment
		(start 98.606356 -68.27139)
		(end 99.595178 -69.260212)
		(width 0.1016)
		(layer "In2.Cu")
		(net "SAS3008_RAID_TX_P1")
	)
	(segment
		(start 105.382568 -73.2282)
		(end 113.84407 -73.2282)
		(width 0.1016)
		(layer "In2.Cu")
		(net "SAS3008_RAID_TX_P1")
	)
	(segment
		(start 91.167204 -60.512452)
		(end 91.382596 -60.728098)
		(width 0.1016)
		(layer "In2.Cu")
		(net "SAS3008_RAID_TX_P1")
	)
	(segment
		(start 92.612972 -62.278006)
		(end 92.828364 -62.493398)
		(width 0.1016)
		(layer "In2.Cu")
		(net "SAS3008_RAID_TX_P1")
	)
	(arc
		(start 90.687652 -60.352686)
		(mid 90.797907 -60.421522)
		(end 90.927428 -60.432442)
		(width 0.1016)
		(layer "In2.Cu")
		(net "SAS3008_RAID_TX_P1")
	)
	(arc
		(start 100.370132 -69.875146)
		(mid 100.380599 -70.003303)
		(end 100.447856 -70.11289)
		(width 0.1016)
		(layer "In2.Cu")
		(net "SAS3008_RAID_TX_P1")
	)
	(arc
		(start 124.44984 -79.375)
		(mid 124.692426 -79.423142)
		(end 124.89815 -79.56042)
		(width 0.1016)
		(layer "In2.Cu")
		(net "SAS3008_RAID_TX_P1")
	)
	(arc
		(start 86.838282 -56.183784)
		(mid 86.907279 -56.294003)
		(end 86.918292 -56.42356)
		(width 0.1016)
		(layer "In2.Cu")
		(net "SAS3008_RAID_TX_P1")
	)
	(arc
		(start 91.462606 -60.967874)
		(mid 91.473656 -61.097419)
		(end 91.542616 -61.20765)
		(width 0.1016)
		(layer "In2.Cu")
		(net "SAS3008_RAID_TX_P1")
	)
	(arc
		(start 88.523826 -58.029094)
		(mid 88.653371 -58.040144)
		(end 88.763602 -58.109104)
		(width 0.1016)
		(layer "In2.Cu")
		(net "SAS3008_RAID_TX_P1")
	)
	(arc
		(start 101.360478 -70.70598)
		(mid 101.429475 -70.816199)
		(end 101.440488 -70.945756)
		(width 0.1016)
		(layer "In2.Cu")
		(net "SAS3008_RAID_TX_P1")
	)
	(arc
		(start 100.665534 -70.330568)
		(mid 100.775764 -70.399502)
		(end 100.90531 -70.410578)
		(width 0.1016)
		(layer "In2.Cu")
		(net "SAS3008_RAID_TX_P1")
	)
	(arc
		(start 98.5266 -68.031614)
		(mid 98.537517 -68.161136)
		(end 98.606356 -68.27139)
		(width 0.1016)
		(layer "In2.Cu")
		(net "SAS3008_RAID_TX_P1")
	)
	(arc
		(start 90.927428 -60.432442)
		(mid 91.056985 -60.443485)
		(end 91.167204 -60.512452)
		(width 0.1016)
		(layer "In2.Cu")
		(net "SAS3008_RAID_TX_P1")
	)
	(arc
		(start 93.523562 -62.86881)
		(mid 93.592496 -62.97904)
		(end 93.603572 -63.108586)
		(width 0.1016)
		(layer "In2.Cu")
		(net "SAS3008_RAID_TX_P1")
	)
	(arc
		(start 87.45347 -56.958738)
		(mid 87.582992 -56.969655)
		(end 87.693246 -57.038494)
		(width 0.1016)
		(layer "In2.Cu")
		(net "SAS3008_RAID_TX_P1")
	)
	(arc
		(start 93.603572 -63.108586)
		(mid 93.614489 -63.238108)
		(end 93.683328 -63.348362)
		(width 0.1016)
		(layer "In2.Cu")
		(net "SAS3008_RAID_TX_P1")
	)
	(arc
		(start 91.758008 -61.423042)
		(mid 91.868238 -61.491976)
		(end 91.997784 -61.503052)
		(width 0.1016)
		(layer "In2.Cu")
		(net "SAS3008_RAID_TX_P1")
	)
	(arc
		(start 88.28405 -57.949084)
		(mid 88.394269 -58.018081)
		(end 88.523826 -58.029094)
		(width 0.1016)
		(layer "In2.Cu")
		(net "SAS3008_RAID_TX_P1")
	)
	(arc
		(start 95.850456 -65.35547)
		(mid 95.980013 -65.366513)
		(end 96.090232 -65.43548)
		(width 0.1016)
		(layer "In2.Cu")
		(net "SAS3008_RAID_TX_P1")
	)
	(arc
		(start 97.751392 -67.416426)
		(mid 97.861611 -67.485423)
		(end 97.991168 -67.496436)
		(width 0.1016)
		(layer "In2.Cu")
		(net "SAS3008_RAID_TX_P1")
	)
	(arc
		(start 113.84407 -73.2282)
		(mid 114.476381 -73.353957)
		(end 115.01247 -73.71207)
		(width 0.1016)
		(layer "In2.Cu")
		(net "SAS3008_RAID_TX_P1")
	)
	(arc
		(start 96.305624 -65.651126)
		(mid 96.374621 -65.761345)
		(end 96.385634 -65.890902)
		(width 0.1016)
		(layer "In2.Cu")
		(net "SAS3008_RAID_TX_P1")
	)
	(arc
		(start 120.1039 -78.8035)
		(mid 120.736925 -79.226474)
		(end 121.483628 -79.375)
		(width 0.1016)
		(layer "In2.Cu")
		(net "SAS3008_RAID_TX_P1")
	)
	(arc
		(start 92.453206 -61.798454)
		(mid 92.522042 -61.908709)
		(end 92.532962 -62.03823)
		(width 0.1016)
		(layer "In2.Cu")
		(net "SAS3008_RAID_TX_P1")
	)
	(arc
		(start 91.997784 -61.503052)
		(mid 92.127306 -61.513969)
		(end 92.23756 -61.582808)
		(width 0.1016)
		(layer "In2.Cu")
		(net "SAS3008_RAID_TX_P1")
	)
	(arc
		(start 102.276656 -71.94169)
		(mid 103.701661 -72.893848)
		(end 105.382568 -73.2282)
		(width 0.1016)
		(layer "In2.Cu")
		(net "SAS3008_RAID_TX_P1")
	)
	(arc
		(start 96.681036 -66.34607)
		(mid 96.791266 -66.415004)
		(end 96.920812 -66.42608)
		(width 0.1016)
		(layer "In2.Cu")
		(net "SAS3008_RAID_TX_P1")
	)
	(arc
		(start 86.918292 -56.42356)
		(mid 86.929342 -56.553105)
		(end 86.998302 -56.663336)
		(width 0.1016)
		(layer "In2.Cu")
		(net "SAS3008_RAID_TX_P1")
	)
	(arc
		(start 99.595178 -69.260212)
		(mid 99.705314 -69.329008)
		(end 99.8347 -69.339968)
		(width 0.1016)
		(layer "In2.Cu")
		(net "SAS3008_RAID_TX_P1")
	)
	(arc
		(start 88.979248 -58.324496)
		(mid 89.048182 -58.434726)
		(end 89.059258 -58.564272)
		(width 0.1016)
		(layer "In2.Cu")
		(net "SAS3008_RAID_TX_P1")
	)
	(arc
		(start 93.06814 -62.573408)
		(mid 93.197685 -62.584458)
		(end 93.307916 -62.653418)
		(width 0.1016)
		(layer "In2.Cu")
		(net "SAS3008_RAID_TX_P1")
	)
	(arc
		(start 87.213694 -56.878728)
		(mid 87.323924 -56.947662)
		(end 87.45347 -56.958738)
		(width 0.1016)
		(layer "In2.Cu")
		(net "SAS3008_RAID_TX_P1")
	)
	(arc
		(start 100.90531 -70.410578)
		(mid 101.034832 -70.421495)
		(end 101.145086 -70.490334)
		(width 0.1016)
		(layer "In2.Cu")
		(net "SAS3008_RAID_TX_P1")
	)
	(arc
		(start 99.8347 -69.339968)
		(mid 99.964245 -69.351018)
		(end 100.074476 -69.419978)
		(width 0.1016)
		(layer "In2.Cu")
		(net "SAS3008_RAID_TX_P1")
	)
	(arc
		(start 97.45599 -66.961258)
		(mid 97.467033 -67.090815)
		(end 97.536 -67.201034)
		(width 0.1016)
		(layer "In2.Cu")
		(net "SAS3008_RAID_TX_P1")
	)
	(arc
		(start 100.290122 -69.63537)
		(mid 100.359056 -69.7456)
		(end 100.370132 -69.875146)
		(width 0.1016)
		(layer "In2.Cu")
		(net "SAS3008_RAID_TX_P1")
	)
	(arc
		(start 91.382596 -60.728098)
		(mid 91.451593 -60.838317)
		(end 91.462606 -60.967874)
		(width 0.1016)
		(layer "In2.Cu")
		(net "SAS3008_RAID_TX_P1")
	)
	(arc
		(start 96.920812 -66.42608)
		(mid 97.050334 -66.436997)
		(end 97.160588 -66.505836)
		(width 0.1016)
		(layer "In2.Cu")
		(net "SAS3008_RAID_TX_P1")
	)
	(arc
		(start 87.988648 -57.493916)
		(mid 87.999691 -57.623473)
		(end 88.068658 -57.733692)
		(width 0.1016)
		(layer "In2.Cu")
		(net "SAS3008_RAID_TX_P1")
	)
	(arc
		(start 92.828364 -62.493398)
		(mid 92.938583 -62.562395)
		(end 93.06814 -62.573408)
		(width 0.1016)
		(layer "In2.Cu")
		(net "SAS3008_RAID_TX_P1")
	)
	(arc
		(start 86.383114 -55.888128)
		(mid 86.512671 -55.899171)
		(end 86.62289 -55.968138)
		(width 0.1016)
		(layer "In2.Cu")
		(net "SAS3008_RAID_TX_P1")
	)
	(arc
		(start 100.447856 -70.11289)
		(mid 100.448869 -70.113909)
		(end 100.449888 -70.114922)
		(width 0.1016)
		(layer "In2.Cu")
		(net "SAS3008_RAID_TX_P1")
	)
	(arc
		(start 78.663292 -41.6052)
		(mid 78.513242 -41.829765)
		(end 78.4606 -42.094658)
		(width 0.1016)
		(layer "In2.Cu")
		(net "SAS3008_RAID_TX_P1")
	)
	(arc
		(start 97.376234 -66.721482)
		(mid 97.44507 -66.831737)
		(end 97.45599 -66.961258)
		(width 0.1016)
		(layer "In2.Cu")
		(net "SAS3008_RAID_TX_P1")
	)
	(arc
		(start 97.991168 -67.496436)
		(mid 98.120713 -67.507486)
		(end 98.230944 -67.576446)
		(width 0.1016)
		(layer "In2.Cu")
		(net "SAS3008_RAID_TX_P1")
	)
	(arc
		(start 92.532962 -62.03823)
		(mid 92.544005 -62.167787)
		(end 92.612972 -62.278006)
		(width 0.1016)
		(layer "In2.Cu")
		(net "SAS3008_RAID_TX_P1")
	)
	(arc
		(start 98.44659 -67.791838)
		(mid 98.515524 -67.902068)
		(end 98.5266 -68.031614)
		(width 0.1016)
		(layer "In2.Cu")
		(net "SAS3008_RAID_TX_P1")
	)
	(arc
		(start 101.440488 -70.945756)
		(mid 101.451538 -71.075301)
		(end 101.520498 -71.185532)
		(width 0.1016)
		(layer "In2.Cu")
		(net "SAS3008_RAID_TX_P1")
	)
	(arc
		(start 89.059258 -58.564272)
		(mid 89.070175 -58.693794)
		(end 89.139014 -58.804048)
		(width 0.1016)
		(layer "In2.Cu")
		(net "SAS3008_RAID_TX_P1")
	)
	(arc
		(start 87.908892 -57.25414)
		(mid 87.977728 -57.364395)
		(end 87.988648 -57.493916)
		(width 0.1016)
		(layer "In2.Cu")
		(net "SAS3008_RAID_TX_P1")
	)
	(arc
		(start 95.61068 -65.275714)
		(mid 95.720935 -65.34455)
		(end 95.850456 -65.35547)
		(width 0.1016)
		(layer "In2.Cu")
		(net "SAS3008_RAID_TX_P1")
	)
	(arc
		(start 78.4606 -47.79264)
		(mid 78.521852 -48.100575)
		(end 78.696312 -48.3616)
		(width 0.1016)
		(layer "In2.Cu")
		(net "SAS3008_RAID_TX_P1")
	)
	(arc
		(start 125.471682 -80.133952)
		(mid 125.602203 -80.221163)
		(end 125.756162 -80.251808)
		(width 0.1016)
		(layer "In2.Cu")
		(net "SAS3008_RAID_TX_P1")
	)
	(arc
		(start 86.143338 -55.808372)
		(mid 86.253593 -55.877208)
		(end 86.383114 -55.888128)
		(width 0.1016)
		(layer "In2.Cu")
		(net "SAS3008_RAID_TX_P1")
	)
	(arc
		(start 96.385634 -65.890902)
		(mid 96.396684 -66.020447)
		(end 96.465644 -66.130678)
		(width 0.1016)
		(layer "In2.Cu")
		(net "SAS3008_RAID_TX_P1")
	)
	(segment
		(start 102.891844 -88.891872)
		(end 101.961442 -88.891872)
		(width 0.1143)
		(layer "F.Cu")
		(net "XM_DATA15")
	)
	(segment
		(start 74.464672 -137.391902)
		(end 74.41057 -137.3378)
		(width 0.1143)
		(layer "F.Cu")
		(net "XM_DATA15")
	)
	(segment
		(start 101.961442 -88.891872)
		(end 101.632004 -88.562434)
		(width 0.1143)
		(layer "F.Cu")
		(net "XM_DATA15")
	)
	(segment
		(start 100.934774 -88.562434)
		(end 100.470208 -89.027)
		(width 0.1143)
		(layer "F.Cu")
		(net "XM_DATA15")
	)
	(segment
		(start 100.470208 -89.027)
		(end 100.01377 -89.027)
		(width 0.1143)
		(layer "F.Cu")
		(net "XM_DATA15")
	)
	(segment
		(start 75.786742 -137.391902)
		(end 74.464672 -137.391902)
		(width 0.1143)
		(layer "F.Cu")
		(net "XM_DATA15")
	)
	(segment
		(start 101.632004 -88.562434)
		(end 100.934774 -88.562434)
		(width 0.1143)
		(layer "F.Cu")
		(net "XM_DATA15")
	)
	(segment
		(start 103.349806 -89.349834)
		(end 102.891844 -88.891872)
		(width 0.1143)
		(layer "F.Cu")
		(net "XM_DATA15")
	)
	(segment
		(start 74.41057 -137.3378)
		(end 71.76897 -137.3378)
		(width 0.1143)
		(layer "F.Cu")
		(net "XM_DATA15")
	)
	(via
		(at 95.6564 -88.97874)
		(size 0.7112)
		(drill 0.3556)
		(layers "F.Cu" "B.Cu")
		(net "XM_DATA15")
	)
	(via
		(at 100.01377 -89.027)
		(size 0.508)
		(drill 0.254)
		(layers "F.Cu" "B.Cu")
		(net "XM_DATA15")
	)
	(via
		(at 71.76897 -137.3378)
		(size 0.5588)
		(drill 0.3048)
		(layers "F.Cu" "B.Cu")
		(net "XM_DATA15")
	)
	(segment
		(start 71.681086 -94.565724)
		(end 75.84059 -90.40622)
		(width 0.1143)
		(layer "B.Cu")
		(net "XM_DATA15")
	)
	(segment
		(start 71.85406 -95.546926)
		(end 72.015604 -95.546926)
		(width 0.1143)
		(layer "B.Cu")
		(net "XM_DATA15")
	)
	(segment
		(start 70.387718 -96.020636)
		(end 70.387718 -95.859092)
		(width 0.1143)
		(layer "B.Cu")
		(net "XM_DATA15")
	)
	(segment
		(start 70.87997 -131.05384)
		(end 69.64172 -129.81559)
		(width 0.1143)
		(layer "B.Cu")
		(net "XM_DATA15")
	)
	(segment
		(start 70.884034 -96.678496)
		(end 70.884034 -96.516952)
		(width 0.1143)
		(layer "B.Cu")
		(net "XM_DATA15")
	)
	(segment
		(start 94.872302 -89.192608)
		(end 95.08617 -88.97874)
		(width 0.1143)
		(layer "B.Cu")
		(net "XM_DATA15")
	)
	(segment
		(start 70.87997 -133.154674)
		(end 70.87997 -131.05384)
		(width 0.1143)
		(layer "B.Cu")
		(net "XM_DATA15")
	)
	(segment
		(start 99.848162 -89.192608)
		(end 100.01377 -89.027)
		(width 0.1143)
		(layer "B.Cu")
		(net "XM_DATA15")
	)
	(segment
		(start 71.034402 -95.373952)
		(end 71.034402 -95.212408)
		(width 0.1143)
		(layer "B.Cu")
		(net "XM_DATA15")
	)
	(segment
		(start 75.84059 -90.40622)
		(end 86.095332 -90.40622)
		(width 0.1143)
		(layer "B.Cu")
		(net "XM_DATA15")
	)
	(segment
		(start 69.64172 -96.60509)
		(end 69.902832 -96.343978)
		(width 0.1143)
		(layer "B.Cu")
		(net "XM_DATA15")
	)
	(segment
		(start 70.387718 -95.859092)
		(end 70.549516 -95.697294)
		(width 0.1143)
		(layer "B.Cu")
		(net "XM_DATA15")
	)
	(segment
		(start 97.258378 -89.192608)
		(end 99.848162 -89.192608)
		(width 0.1143)
		(layer "B.Cu")
		(net "XM_DATA15")
	)
	(segment
		(start 69.902832 -96.343978)
		(end 70.064376 -96.343978)
		(width 0.1143)
		(layer "B.Cu")
		(net "XM_DATA15")
	)
	(segment
		(start 69.64172 -129.81559)
		(end 69.64172 -96.60509)
		(width 0.1143)
		(layer "B.Cu")
		(net "XM_DATA15")
	)
	(segment
		(start 71.76897 -137.3378)
		(end 72.380602 -136.726168)
		(width 0.1143)
		(layer "B.Cu")
		(net "XM_DATA15")
	)
	(segment
		(start 70.722236 -96.840294)
		(end 70.884034 -96.678496)
		(width 0.1143)
		(layer "B.Cu")
		(net "XM_DATA15")
	)
	(segment
		(start 72.177402 -95.385128)
		(end 72.177402 -95.223584)
		(width 0.1143)
		(layer "B.Cu")
		(net "XM_DATA15")
	)
	(segment
		(start 87.309198 -89.192608)
		(end 94.872302 -89.192608)
		(width 0.1143)
		(layer "B.Cu")
		(net "XM_DATA15")
	)
	(segment
		(start 72.015604 -95.546926)
		(end 72.177402 -95.385128)
		(width 0.1143)
		(layer "B.Cu")
		(net "XM_DATA15")
	)
	(segment
		(start 95.6564 -88.97874)
		(end 97.04451 -88.97874)
		(width 0.1143)
		(layer "B.Cu")
		(net "XM_DATA15")
	)
	(segment
		(start 70.064376 -96.343978)
		(end 70.560692 -96.840294)
		(width 0.1143)
		(layer "B.Cu")
		(net "XM_DATA15")
	)
	(segment
		(start 71.530718 -96.031812)
		(end 71.530718 -95.870268)
		(width 0.1143)
		(layer "B.Cu")
		(net "XM_DATA15")
	)
	(segment
		(start 71.1962 -95.05061)
		(end 71.357744 -95.05061)
		(width 0.1143)
		(layer "B.Cu")
		(net "XM_DATA15")
	)
	(segment
		(start 70.549516 -95.697294)
		(end 70.71106 -95.697294)
		(width 0.1143)
		(layer "B.Cu")
		(net "XM_DATA15")
	)
	(segment
		(start 70.71106 -95.697294)
		(end 71.207376 -96.19361)
		(width 0.1143)
		(layer "B.Cu")
		(net "XM_DATA15")
	)
	(segment
		(start 95.08617 -88.97874)
		(end 95.6564 -88.97874)
		(width 0.1143)
		(layer "B.Cu")
		(net "XM_DATA15")
	)
	(segment
		(start 72.380602 -134.655306)
		(end 70.87997 -133.154674)
		(width 0.1143)
		(layer "B.Cu")
		(net "XM_DATA15")
	)
	(segment
		(start 86.903052 -89.5985)
		(end 86.903306 -89.5985)
		(width 0.1143)
		(layer "B.Cu")
		(net "XM_DATA15")
	)
	(segment
		(start 71.207376 -96.19361)
		(end 71.36892 -96.19361)
		(width 0.1143)
		(layer "B.Cu")
		(net "XM_DATA15")
	)
	(segment
		(start 71.034402 -95.212408)
		(end 71.1962 -95.05061)
		(width 0.1143)
		(layer "B.Cu")
		(net "XM_DATA15")
	)
	(segment
		(start 72.177402 -95.223584)
		(end 71.681086 -94.727268)
		(width 0.1143)
		(layer "B.Cu")
		(net "XM_DATA15")
	)
	(segment
		(start 72.380602 -136.726168)
		(end 72.380602 -134.655306)
		(width 0.1143)
		(layer "B.Cu")
		(net "XM_DATA15")
	)
	(segment
		(start 86.095332 -90.40622)
		(end 86.903052 -89.5985)
		(width 0.1143)
		(layer "B.Cu")
		(net "XM_DATA15")
	)
	(segment
		(start 70.560692 -96.840294)
		(end 70.722236 -96.840294)
		(width 0.1143)
		(layer "B.Cu")
		(net "XM_DATA15")
	)
	(segment
		(start 71.530718 -95.870268)
		(end 71.034402 -95.373952)
		(width 0.1143)
		(layer "B.Cu")
		(net "XM_DATA15")
	)
	(segment
		(start 71.681086 -94.727268)
		(end 71.681086 -94.565724)
		(width 0.1143)
		(layer "B.Cu")
		(net "XM_DATA15")
	)
	(segment
		(start 86.903306 -89.5985)
		(end 87.309198 -89.192608)
		(width 0.1143)
		(layer "B.Cu")
		(net "XM_DATA15")
	)
	(segment
		(start 71.357744 -95.05061)
		(end 71.85406 -95.546926)
		(width 0.1143)
		(layer "B.Cu")
		(net "XM_DATA15")
	)
	(segment
		(start 70.884034 -96.516952)
		(end 70.387718 -96.020636)
		(width 0.1143)
		(layer "B.Cu")
		(net "XM_DATA15")
	)
	(segment
		(start 71.36892 -96.19361)
		(end 71.530718 -96.031812)
		(width 0.1143)
		(layer "B.Cu")
		(net "XM_DATA15")
	)
	(segment
		(start 97.04451 -88.97874)
		(end 97.258378 -89.192608)
		(width 0.1143)
		(layer "B.Cu")
		(net "XM_DATA15")
	)
	(segment
		(start 107.086654 -56.972962)
		(end 107.086654 -56.13654)
		(width 0.1143)
		(layer "F.Cu")
		(net "XM_NAND_CS_N")
	)
	(segment
		(start 107.086654 -56.13654)
		(end 106.750104 -55.79999)
		(width 0.1143)
		(layer "F.Cu")
		(net "XM_NAND_CS_N")
	)
	(segment
		(start 106.861356 -57.19826)
		(end 107.086654 -56.972962)
		(width 0.1143)
		(layer "F.Cu")
		(net "XM_NAND_CS_N")
	)
	(via
		(at 105.791 -58.293)
		(size 0.7112)
		(drill 0.3556)
		(layers "F.Cu" "B.Cu")
		(net "XM_NAND_CS_N")
	)
	(via
		(at 106.861356 -57.19826)
		(size 0.508)
		(drill 0.254)
		(layers "F.Cu" "B.Cu")
		(net "XM_NAND_CS_N")
	)
	(segment
		(start 105.791 -57.2135)
		(end 105.791 -58.293)
		(width 0.1143)
		(layer "B.Cu")
		(net "XM_NAND_CS_N")
	)
	(segment
		(start 105.8545 -57.15)
		(end 105.791 -57.2135)
		(width 0.1143)
		(layer "B.Cu")
		(net "XM_NAND_CS_N")
	)
	(segment
		(start 106.861356 -57.19826)
		(end 106.813096 -57.15)
		(width 0.1143)
		(layer "B.Cu")
		(net "XM_NAND_CS_N")
	)
	(segment
		(start 106.813096 -57.15)
		(end 105.8545 -57.15)
		(width 0.1143)
		(layer "B.Cu")
		(net "XM_NAND_CS_N")
	)
	(segment
		(start 123.1519 -81.8769)
		(end 123.2408 -81.9658)
		(width 0.1016)
		(layer "F.Cu")
		(net "SAS3008_RAID_TX_N0")
	)
	(segment
		(start 85.86216 -33.049718)
		(end 85.775546 -33.136332)
		(width 0.1016)
		(layer "F.Cu")
		(net "SAS3008_RAID_TX_N0")
	)
	(segment
		(start 85.66404 -33.16605)
		(end 85.663786 -33.165796)
		(width 0.1016)
		(layer "F.Cu")
		(net "SAS3008_RAID_TX_N0")
	)
	(segment
		(start 85.703664 -33.16605)
		(end 85.66404 -33.16605)
		(width 0.1016)
		(layer "F.Cu")
		(net "SAS3008_RAID_TX_N0")
	)
	(segment
		(start 86.21776 -33.02)
		(end 85.934042 -33.02)
		(width 0.1016)
		(layer "F.Cu")
		(net "SAS3008_RAID_TX_N0")
	)
	(segment
		(start 123.35002 -82.229452)
		(end 123.35002 -82.349848)
		(width 0.1016)
		(layer "F.Cu")
		(net "SAS3008_RAID_TX_N0")
	)
	(segment
		(start 85.663786 -33.165796)
		(end 85.311488 -33.165796)
		(width 0.1016)
		(layer "F.Cu")
		(net "SAS3008_RAID_TX_N0")
	)
	(segment
		(start 122.936 -81.788)
		(end 122.93727 -81.788)
		(width 0.1016)
		(layer "F.Cu")
		(net "SAS3008_RAID_TX_N0")
	)
	(segment
		(start 85.239606 -33.136078)
		(end 84.9884 -32.884872)
		(width 0.1016)
		(layer "F.Cu")
		(net "SAS3008_RAID_TX_N0")
	)
	(via
		(at 122.92457 -80.9244)
		(size 0.508)
		(drill 0.254)
		(layers "F.Cu" "B.Cu")
		(net "SAS3008_RAID_TX_N0")
	)
	(via
		(at 84.9884 -32.884872)
		(size 0.5588)
		(drill 0.3048)
		(layers "F.Cu" "B.Cu")
		(net "SAS3008_RAID_TX_N0")
	)
	(via
		(at 76.157074 -36.659312)
		(size 0.5588)
		(drill 0.3048)
		(layers "F.Cu" "B.Cu")
		(net "SAS3008_RAID_TX_N0")
	)
	(via
		(at 122.936 -81.788)
		(size 0.508)
		(drill 0.254)
		(layers "F.Cu" "B.Cu")
		(net "SAS3008_RAID_TX_N0")
	)
	(arc
		(start 122.93727 -81.788)
		(mid 123.053426 -81.811105)
		(end 123.1519 -81.8769)
		(width 0.1016)
		(layer "F.Cu")
		(net "SAS3008_RAID_TX_N0")
	)
	(arc
		(start 85.311488 -33.165796)
		(mid 85.272593 -33.158077)
		(end 85.239606 -33.136078)
		(width 0.1016)
		(layer "F.Cu")
		(net "SAS3008_RAID_TX_N0")
	)
	(arc
		(start 123.2408 -81.9658)
		(mid 123.321626 -82.086765)
		(end 123.35002 -82.229452)
		(width 0.1016)
		(layer "F.Cu")
		(net "SAS3008_RAID_TX_N0")
	)
	(arc
		(start 85.934042 -33.02)
		(mid 85.895147 -33.027719)
		(end 85.86216 -33.049718)
		(width 0.1016)
		(layer "F.Cu")
		(net "SAS3008_RAID_TX_N0")
	)
	(arc
		(start 85.775546 -33.136332)
		(mid 85.742552 -33.158315)
		(end 85.703664 -33.16605)
		(width 0.1016)
		(layer "F.Cu")
		(net "SAS3008_RAID_TX_N0")
	)
	(segment
		(start 78.747366 -33.1343)
		(end 78.747366 -33.134046)
		(width 0.1016)
		(layer "B.Cu")
		(net "SAS3008_RAID_TX_N0")
	)
	(segment
		(start 84.406486 -33.1343)
		(end 78.747366 -33.1343)
		(width 0.1016)
		(layer "B.Cu")
		(net "SAS3008_RAID_TX_N0")
	)
	(segment
		(start 76.458826 -36.266628)
		(end 76.410312 -36.38423)
		(width 0.1016)
		(layer "B.Cu")
		(net "SAS3008_RAID_TX_N0")
	)
	(segment
		(start 84.9884 -32.884872)
		(end 84.974176 -32.899096)
		(width 0.1016)
		(layer "B.Cu")
		(net "SAS3008_RAID_TX_N0")
	)
	(segment
		(start 122.936 -81.788)
		(end 122.936 -80.952086)
		(width 0.1016)
		(layer "B.Cu")
		(net "SAS3008_RAID_TX_N0")
	)
	(segment
		(start 78.113636 -33.396682)
		(end 78.08468 -33.426146)
		(width 0.1016)
		(layer "B.Cu")
		(net "SAS3008_RAID_TX_N0")
	)
	(segment
		(start 76.366116 -36.450524)
		(end 76.157074 -36.659312)
		(width 0.1016)
		(layer "B.Cu")
		(net "SAS3008_RAID_TX_N0")
	)
	(segment
		(start 78.08468 -33.426146)
		(end 76.753974 -34.756852)
		(width 0.1016)
		(layer "B.Cu")
		(net "SAS3008_RAID_TX_N0")
	)
	(segment
		(start 76.474066 -35.433)
		(end 76.474066 -36.189412)
		(width 0.1016)
		(layer "B.Cu")
		(net "SAS3008_RAID_TX_N0")
	)
	(arc
		(start 78.747366 -33.134046)
		(mid 78.404359 -33.20227)
		(end 78.113636 -33.396682)
		(width 0.1016)
		(layer "B.Cu")
		(net "SAS3008_RAID_TX_N0")
	)
	(arc
		(start 76.410312 -36.38423)
		(mid 76.391488 -36.419559)
		(end 76.366116 -36.450524)
		(width 0.1016)
		(layer "B.Cu")
		(net "SAS3008_RAID_TX_N0")
	)
	(arc
		(start 84.974176 -32.899096)
		(mid 84.713732 -33.073182)
		(end 84.406486 -33.1343)
		(width 0.1016)
		(layer "B.Cu")
		(net "SAS3008_RAID_TX_N0")
	)
	(arc
		(start 76.474066 -36.189412)
		(mid 76.470219 -36.228765)
		(end 76.458826 -36.266628)
		(width 0.1016)
		(layer "B.Cu")
		(net "SAS3008_RAID_TX_N0")
	)
	(arc
		(start 76.753974 -34.756852)
		(mid 76.546829 -35.067101)
		(end 76.474066 -35.433)
		(width 0.1016)
		(layer "B.Cu")
		(net "SAS3008_RAID_TX_N0")
	)
	(arc
		(start 122.936 -80.952086)
		(mid 122.933022 -80.937117)
		(end 122.92457 -80.9244)
		(width 0.1016)
		(layer "B.Cu")
		(net "SAS3008_RAID_TX_N0")
	)
	(segment
		(start 101.438202 -75.8444)
		(end 112.2934 -75.8444)
		(width 0.1016)
		(layer "In2.Cu")
		(net "SAS3008_RAID_TX_N0")
	)
	(segment
		(start 119.6848 -80.8228)
		(end 122.679206 -80.8228)
		(width 0.1016)
		(layer "In2.Cu")
		(net "SAS3008_RAID_TX_N0")
	)
	(segment
		(start 76.566522 -49.442116)
		(end 85.683598 -58.583068)
		(width 0.1016)
		(layer "In2.Cu")
		(net "SAS3008_RAID_TX_N0")
	)
	(segment
		(start 115.242086 -77.065632)
		(end 115.5192 -77.343)
		(width 0.1016)
		(layer "In2.Cu")
		(net "SAS3008_RAID_TX_N0")
	)
	(segment
		(start 89.916 -64.897)
		(end 100.457 -75.438)
		(width 0.1016)
		(layer "In2.Cu")
		(net "SAS3008_RAID_TX_N0")
	)
	(segment
		(start 76.157074 -36.659312)
		(end 76.163678 -36.66617)
		(width 0.1016)
		(layer "In2.Cu")
		(net "SAS3008_RAID_TX_N0")
	)
	(segment
		(start 76.410566 -37.2618)
		(end 76.410566 -49.064926)
		(width 0.1016)
		(layer "In2.Cu")
		(net "SAS3008_RAID_TX_N0")
	)
	(segment
		(start 118.205504 -80.02905)
		(end 118.514622 -80.338168)
		(width 0.1016)
		(layer "In2.Cu")
		(net "SAS3008_RAID_TX_N0")
	)
	(segment
		(start 115.5192 -77.343)
		(end 118.205504 -80.02905)
		(width 0.1016)
		(layer "In2.Cu")
		(net "SAS3008_RAID_TX_N0")
	)
	(segment
		(start 85.683598 -58.583068)
		(end 88.924638 -61.824108)
		(width 0.1016)
		(layer "In2.Cu")
		(net "SAS3008_RAID_TX_N0")
	)
	(segment
		(start 89.3318 -62.807088)
		(end 89.3318 -63.486538)
		(width 0.1016)
		(layer "In2.Cu")
		(net "SAS3008_RAID_TX_N0")
	)
	(arc
		(start 122.679206 -80.8228)
		(mid 122.811983 -80.849211)
		(end 122.92457 -80.9244)
		(width 0.1016)
		(layer "In2.Cu")
		(net "SAS3008_RAID_TX_N0")
	)
	(arc
		(start 112.2934 -75.8444)
		(mid 113.889212 -76.161733)
		(end 115.242086 -77.065632)
		(width 0.1016)
		(layer "In2.Cu")
		(net "SAS3008_RAID_TX_N0")
	)
	(arc
		(start 76.163678 -36.66617)
		(mid 76.346359 -36.939432)
		(end 76.410566 -37.2618)
		(width 0.1016)
		(layer "In2.Cu")
		(net "SAS3008_RAID_TX_N0")
	)
	(arc
		(start 118.514622 -80.338168)
		(mid 119.051518 -80.696848)
		(end 119.6848 -80.8228)
		(width 0.1016)
		(layer "In2.Cu")
		(net "SAS3008_RAID_TX_N0")
	)
	(arc
		(start 100.457 -75.438)
		(mid 100.907193 -75.738776)
		(end 101.438202 -75.8444)
		(width 0.1016)
		(layer "In2.Cu")
		(net "SAS3008_RAID_TX_N0")
	)
	(arc
		(start 88.924638 -61.824108)
		(mid 89.225983 -62.275103)
		(end 89.3318 -62.807088)
		(width 0.1016)
		(layer "In2.Cu")
		(net "SAS3008_RAID_TX_N0")
	)
	(arc
		(start 76.410566 -49.064926)
		(mid 76.451051 -49.26902)
		(end 76.566522 -49.442116)
		(width 0.1016)
		(layer "In2.Cu")
		(net "SAS3008_RAID_TX_N0")
	)
	(arc
		(start 89.3318 -63.486538)
		(mid 89.483567 -64.249902)
		(end 89.916 -64.897)
		(width 0.1016)
		(layer "In2.Cu")
		(net "SAS3008_RAID_TX_N0")
	)
	(segment
		(start 102.18928 -95.962724)
		(end 102.04323 -96.108774)
		(width 0.1143)
		(layer "F.Cu")
		(net "EXP_XM_ADDR_1")
	)
	(segment
		(start 103.349806 -96.350074)
		(end 102.968044 -96.350074)
		(width 0.1143)
		(layer "F.Cu")
		(net "EXP_XM_ADDR_1")
	)
	(segment
		(start 75.786742 -127.391922)
		(end 75.003152 -127.391922)
		(width 0.1143)
		(layer "F.Cu")
		(net "EXP_XM_ADDR_1")
	)
	(segment
		(start 99.383342 -97.7646)
		(end 99.36861 -97.7646)
		(width 0.1143)
		(layer "F.Cu")
		(net "EXP_XM_ADDR_1")
	)
	(segment
		(start 102.04323 -96.108774)
		(end 101.668834 -96.108774)
		(width 0.1143)
		(layer "F.Cu")
		(net "EXP_XM_ADDR_1")
	)
	(segment
		(start 102.968044 -96.350074)
		(end 102.580694 -95.962724)
		(width 0.1143)
		(layer "F.Cu")
		(net "EXP_XM_ADDR_1")
	)
	(segment
		(start 101.668834 -96.108774)
		(end 100.593398 -97.18421)
		(width 0.1143)
		(layer "F.Cu")
		(net "EXP_XM_ADDR_1")
	)
	(segment
		(start 102.580694 -95.962724)
		(end 102.18928 -95.962724)
		(width 0.1143)
		(layer "F.Cu")
		(net "EXP_XM_ADDR_1")
	)
	(segment
		(start 100.593398 -97.18421)
		(end 99.963732 -97.18421)
		(width 0.1143)
		(layer "F.Cu")
		(net "EXP_XM_ADDR_1")
	)
	(segment
		(start 75.003152 -127.391922)
		(end 74.30135 -126.69012)
		(width 0.1143)
		(layer "F.Cu")
		(net "EXP_XM_ADDR_1")
	)
	(segment
		(start 99.963732 -97.18421)
		(end 99.383342 -97.7646)
		(width 0.1143)
		(layer "F.Cu")
		(net "EXP_XM_ADDR_1")
	)
	(via
		(at 74.54773 -125.5522)
		(size 0.7112)
		(drill 0.3556)
		(layers "F.Cu" "B.Cu")
		(net "EXP_XM_ADDR_1")
	)
	(via
		(at 99.36861 -97.7646)
		(size 0.508)
		(drill 0.254)
		(layers "F.Cu" "B.Cu")
		(net "EXP_XM_ADDR_1")
	)
	(via
		(at 74.30135 -126.69012)
		(size 0.5588)
		(drill 0.3048)
		(layers "F.Cu" "B.Cu")
		(net "EXP_XM_ADDR_1")
	)
	(segment
		(start 74.54773 -126.44374)
		(end 74.30135 -126.69012)
		(width 0.1143)
		(layer "B.Cu")
		(net "EXP_XM_ADDR_1")
	)
	(segment
		(start 74.54773 -125.5522)
		(end 74.54773 -126.44374)
		(width 0.1143)
		(layer "B.Cu")
		(net "EXP_XM_ADDR_1")
	)
	(segment
		(start 74.909172 -120.271794)
		(end 74.729594 -120.451372)
		(width 0.127)
		(layer "In2.Cu")
		(net "EXP_XM_ADDR_1")
	)
	(segment
		(start 74.698606 -118.263924)
		(end 74.698606 -118.443756)
		(width 0.127)
		(layer "In2.Cu")
		(net "EXP_XM_ADDR_1")
	)
	(segment
		(start 96.665542 -99.83978)
		(end 96.48571 -99.83978)
		(width 0.127)
		(layer "In2.Cu")
		(net "EXP_XM_ADDR_1")
	)
	(segment
		(start 72.46239 -125.19914)
		(end 74.43089 -125.19914)
		(width 0.127)
		(layer "In2.Cu")
		(net "EXP_XM_ADDR_1")
	)
	(segment
		(start 97.024952 -99.300538)
		(end 97.024952 -99.48037)
		(width 0.127)
		(layer "In2.Cu")
		(net "EXP_XM_ADDR_1")
	)
	(segment
		(start 72.46239 -121.13514)
		(end 73.086976 -121.13514)
		(width 0.127)
		(layer "In2.Cu")
		(net "EXP_XM_ADDR_1")
	)
	(segment
		(start 96.057466 -100.669344)
		(end 95.946722 -100.5586)
		(width 0.127)
		(layer "In2.Cu")
		(net "EXP_XM_ADDR_1")
	)
	(segment
		(start 76.855066 -116.287296)
		(end 77.784452 -117.216682)
		(width 0.127)
		(layer "In2.Cu")
		(net "EXP_XM_ADDR_1")
	)
	(segment
		(start 72.33539 -123.04014)
		(end 72.46239 -123.16714)
		(width 0.127)
		(layer "In2.Cu")
		(net "EXP_XM_ADDR_1")
	)
	(segment
		(start 75.417426 -117.724936)
		(end 76.346812 -118.654322)
		(width 0.127)
		(layer "In2.Cu")
		(net "EXP_XM_ADDR_1")
	)
	(segment
		(start 77.604874 -117.576092)
		(end 77.425042 -117.576092)
		(width 0.127)
		(layer "In2.Cu")
		(net "EXP_XM_ADDR_1")
	)
	(segment
		(start 72.76973 -126.69012)
		(end 74.30135 -126.69012)
		(width 0.127)
		(layer "In2.Cu")
		(net "EXP_XM_ADDR_1")
	)
	(segment
		(start 74.159364 -118.803166)
		(end 73.979786 -118.982744)
		(width 0.127)
		(layer "In2.Cu")
		(net "EXP_XM_ADDR_1")
	)
	(segment
		(start 73.440544 -119.521986)
		(end 72.33539 -120.62714)
		(width 0.127)
		(layer "In2.Cu")
		(net "EXP_XM_ADDR_1")
	)
	(segment
		(start 95.946722 -100.5586)
		(end 95.76689 -100.5586)
		(width 0.127)
		(layer "In2.Cu")
		(net "EXP_XM_ADDR_1")
	)
	(segment
		(start 76.136246 -116.826284)
		(end 76.136246 -117.006116)
		(width 0.127)
		(layer "In2.Cu")
		(net "EXP_XM_ADDR_1")
	)
	(segment
		(start 74.55789 -123.29414)
		(end 74.55789 -123.54814)
		(width 0.127)
		(layer "In2.Cu")
		(net "EXP_XM_ADDR_1")
	)
	(segment
		(start 73.086976 -121.13514)
		(end 73.213976 -121.00814)
		(width 0.127)
		(layer "In2.Cu")
		(net "EXP_XM_ADDR_1")
	)
	(segment
		(start 75.597004 -117.365526)
		(end 75.417426 -117.545104)
		(width 0.127)
		(layer "In2.Cu")
		(net "EXP_XM_ADDR_1")
	)
	(segment
		(start 72.46239 -121.64314)
		(end 72.33539 -121.77014)
		(width 0.127)
		(layer "In2.Cu")
		(net "EXP_XM_ADDR_1")
	)
	(segment
		(start 75.448414 -119.732552)
		(end 75.268582 -119.732552)
		(width 0.127)
		(layer "In2.Cu")
		(net "EXP_XM_ADDR_1")
	)
	(segment
		(start 99.36861 -97.7646)
		(end 99.30511 -97.8281)
		(width 0.127)
		(layer "In2.Cu")
		(net "EXP_XM_ADDR_1")
	)
	(segment
		(start 75.417426 -117.545104)
		(end 75.417426 -117.724936)
		(width 0.127)
		(layer "In2.Cu")
		(net "EXP_XM_ADDR_1")
	)
	(segment
		(start 74.55789 -125.58014)
		(end 74.43089 -125.70714)
		(width 0.127)
		(layer "In2.Cu")
		(net "EXP_XM_ADDR_1")
	)
	(segment
		(start 77.065632 -118.115334)
		(end 76.886054 -118.294912)
		(width 0.127)
		(layer "In2.Cu")
		(net "EXP_XM_ADDR_1")
	)
	(segment
		(start 96.23679 -100.669344)
		(end 96.057466 -100.669344)
		(width 0.127)
		(layer "In2.Cu")
		(net "EXP_XM_ADDR_1")
	)
	(segment
		(start 72.46239 -124.18314)
		(end 74.43089 -124.18314)
		(width 0.127)
		(layer "In2.Cu")
		(net "EXP_XM_ADDR_1")
	)
	(segment
		(start 72.46239 -123.16714)
		(end 74.43089 -123.16714)
		(width 0.127)
		(layer "In2.Cu")
		(net "EXP_XM_ADDR_1")
	)
	(segment
		(start 73.721976 -120.541542)
		(end 73.721976 -121.00814)
		(width 0.127)
		(layer "In2.Cu")
		(net "EXP_XM_ADDR_1")
	)
	(segment
		(start 76.495656 -116.646706)
		(end 76.315824 -116.646706)
		(width 0.127)
		(layer "In2.Cu")
		(net "EXP_XM_ADDR_1")
	)
	(segment
		(start 74.43089 -121.64314)
		(end 72.46239 -121.64314)
		(width 0.127)
		(layer "In2.Cu")
		(net "EXP_XM_ADDR_1")
	)
	(segment
		(start 73.848976 -121.13514)
		(end 74.43089 -121.13514)
		(width 0.127)
		(layer "In2.Cu")
		(net "EXP_XM_ADDR_1")
	)
	(segment
		(start 72.33539 -125.07214)
		(end 72.46239 -125.19914)
		(width 0.127)
		(layer "In2.Cu")
		(net "EXP_XM_ADDR_1")
	)
	(segment
		(start 75.776836 -117.365526)
		(end 75.597004 -117.365526)
		(width 0.127)
		(layer "In2.Cu")
		(net "EXP_XM_ADDR_1")
	)
	(segment
		(start 72.33539 -121.00814)
		(end 72.46239 -121.13514)
		(width 0.127)
		(layer "In2.Cu")
		(net "EXP_XM_ADDR_1")
	)
	(segment
		(start 97.20453 -99.12096)
		(end 97.024952 -99.300538)
		(width 0.127)
		(layer "In2.Cu")
		(net "EXP_XM_ADDR_1")
	)
	(segment
		(start 96.306132 -100.19919)
		(end 96.416876 -100.309934)
		(width 0.127)
		(layer "In2.Cu")
		(net "EXP_XM_ADDR_1")
	)
	(segment
		(start 73.594976 -120.414542)
		(end 73.721976 -120.541542)
		(width 0.127)
		(layer "In2.Cu")
		(net "EXP_XM_ADDR_1")
	)
	(segment
		(start 97.135696 -99.770438)
		(end 96.95561 -99.950524)
		(width 0.127)
		(layer "In2.Cu")
		(net "EXP_XM_ADDR_1")
	)
	(segment
		(start 74.909172 -120.091962)
		(end 74.909172 -120.271794)
		(width 0.127)
		(layer "In2.Cu")
		(net "EXP_XM_ADDR_1")
	)
	(segment
		(start 74.55789 -124.31014)
		(end 74.55789 -124.56414)
		(width 0.127)
		(layer "In2.Cu")
		(net "EXP_XM_ADDR_1")
	)
	(segment
		(start 74.43089 -122.15114)
		(end 74.55789 -122.27814)
		(width 0.127)
		(layer "In2.Cu")
		(net "EXP_XM_ADDR_1")
	)
	(segment
		(start 93.643958 -101.537008)
		(end 89.22893 -105.952036)
		(width 0.127)
		(layer "In2.Cu")
		(net "EXP_XM_ADDR_1")
	)
	(segment
		(start 74.55789 -123.54814)
		(end 74.43089 -123.67514)
		(width 0.127)
		(layer "In2.Cu")
		(net "EXP_XM_ADDR_1")
	)
	(segment
		(start 74.43089 -125.19914)
		(end 74.55789 -125.32614)
		(width 0.127)
		(layer "In2.Cu")
		(net "EXP_XM_ADDR_1")
	)
	(segment
		(start 77.425042 -117.576092)
		(end 76.495656 -116.646706)
		(width 0.127)
		(layer "In2.Cu")
		(net "EXP_XM_ADDR_1")
	)
	(segment
		(start 72.33539 -124.05614)
		(end 72.46239 -124.18314)
		(width 0.127)
		(layer "In2.Cu")
		(net "EXP_XM_ADDR_1")
	)
	(segment
		(start 74.339196 -118.803166)
		(end 74.159364 -118.803166)
		(width 0.127)
		(layer "In2.Cu")
		(net "EXP_XM_ADDR_1")
	)
	(segment
		(start 73.620376 -119.521986)
		(end 73.440544 -119.521986)
		(width 0.127)
		(layer "In2.Cu")
		(net "EXP_XM_ADDR_1")
	)
	(segment
		(start 97.384362 -99.12096)
		(end 97.20453 -99.12096)
		(width 0.127)
		(layer "In2.Cu")
		(net "EXP_XM_ADDR_1")
	)
	(segment
		(start 96.95561 -99.950524)
		(end 96.776286 -99.950524)
		(width 0.127)
		(layer "In2.Cu")
		(net "EXP_XM_ADDR_1")
	)
	(segment
		(start 74.55789 -121.51614)
		(end 74.43089 -121.64314)
		(width 0.127)
		(layer "In2.Cu")
		(net "EXP_XM_ADDR_1")
	)
	(segment
		(start 76.346812 -118.654322)
		(end 76.346812 -118.834154)
		(width 0.127)
		(layer "In2.Cu")
		(net "EXP_XM_ADDR_1")
	)
	(segment
		(start 72.33539 -122.02414)
		(end 72.46239 -122.15114)
		(width 0.127)
		(layer "In2.Cu")
		(net "EXP_XM_ADDR_1")
	)
	(segment
		(start 76.136246 -117.006116)
		(end 77.065632 -117.935502)
		(width 0.127)
		(layer "In2.Cu")
		(net "EXP_XM_ADDR_1")
	)
	(segment
		(start 99.30511 -97.8281)
		(end 99.294188 -97.8281)
		(width 0.127)
		(layer "In2.Cu")
		(net "EXP_XM_ADDR_1")
	)
	(segment
		(start 76.706222 -118.294912)
		(end 75.776836 -117.365526)
		(width 0.127)
		(layer "In2.Cu")
		(net "EXP_XM_ADDR_1")
	)
	(segment
		(start 75.627992 -119.373142)
		(end 75.627992 -119.552974)
		(width 0.127)
		(layer "In2.Cu")
		(net "EXP_XM_ADDR_1")
	)
	(segment
		(start 74.549762 -120.451372)
		(end 73.620376 -119.521986)
		(width 0.127)
		(layer "In2.Cu")
		(net "EXP_XM_ADDR_1")
	)
	(segment
		(start 95.698056 -101.208078)
		(end 95.36938 -101.537008)
		(width 0.127)
		(layer "In2.Cu")
		(net "EXP_XM_ADDR_1")
	)
	(segment
		(start 95.76689 -100.5586)
		(end 95.587312 -100.738178)
		(width 0.127)
		(layer "In2.Cu")
		(net "EXP_XM_ADDR_1")
	)
	(segment
		(start 89.22893 -105.952544)
		(end 86.398354 -108.78312)
		(width 0.127)
		(layer "In2.Cu")
		(net "EXP_XM_ADDR_1")
	)
	(segment
		(start 74.55789 -125.32614)
		(end 74.55789 -125.58014)
		(width 0.127)
		(layer "In2.Cu")
		(net "EXP_XM_ADDR_1")
	)
	(segment
		(start 73.213976 -121.00814)
		(end 73.213976 -120.541542)
		(width 0.127)
		(layer "In2.Cu")
		(net "EXP_XM_ADDR_1")
	)
	(segment
		(start 74.43089 -123.16714)
		(end 74.55789 -123.29414)
		(width 0.127)
		(layer "In2.Cu")
		(net "EXP_XM_ADDR_1")
	)
	(segment
		(start 97.495106 -99.231704)
		(end 97.384362 -99.12096)
		(width 0.127)
		(layer "In2.Cu")
		(net "EXP_XM_ADDR_1")
	)
	(segment
		(start 97.135696 -99.591114)
		(end 97.135696 -99.770438)
		(width 0.127)
		(layer "In2.Cu")
		(net "EXP_XM_ADDR_1")
	)
	(segment
		(start 77.784452 -117.216682)
		(end 77.784452 -117.396514)
		(width 0.127)
		(layer "In2.Cu")
		(net "EXP_XM_ADDR_1")
	)
	(segment
		(start 75.058016 -118.084346)
		(end 74.878184 -118.084346)
		(width 0.127)
		(layer "In2.Cu")
		(net "EXP_XM_ADDR_1")
	)
	(segment
		(start 74.55789 -122.27814)
		(end 74.55789 -122.53214)
		(width 0.127)
		(layer "In2.Cu")
		(net "EXP_XM_ADDR_1")
	)
	(segment
		(start 76.315824 -116.646706)
		(end 76.136246 -116.826284)
		(width 0.127)
		(layer "In2.Cu")
		(net "EXP_XM_ADDR_1")
	)
	(segment
		(start 98.784664 -98.12147)
		(end 97.67443 -99.231704)
		(width 0.127)
		(layer "In2.Cu")
		(net "EXP_XM_ADDR_1")
	)
	(segment
		(start 74.878184 -118.084346)
		(end 74.698606 -118.263924)
		(width 0.127)
		(layer "In2.Cu")
		(net "EXP_XM_ADDR_1")
	)
	(segment
		(start 97.67443 -99.231704)
		(end 97.495106 -99.231704)
		(width 0.127)
		(layer "In2.Cu")
		(net "EXP_XM_ADDR_1")
	)
	(segment
		(start 84.17941 -108.78312)
		(end 76.855066 -116.107464)
		(width 0.127)
		(layer "In2.Cu")
		(net "EXP_XM_ADDR_1")
	)
	(segment
		(start 97.024952 -99.48037)
		(end 97.135696 -99.591114)
		(width 0.127)
		(layer "In2.Cu")
		(net "EXP_XM_ADDR_1")
	)
	(segment
		(start 74.698606 -118.443756)
		(end 75.627992 -119.373142)
		(width 0.127)
		(layer "In2.Cu")
		(net "EXP_XM_ADDR_1")
	)
	(segment
		(start 96.416876 -100.489258)
		(end 96.23679 -100.669344)
		(width 0.127)
		(layer "In2.Cu")
		(net "EXP_XM_ADDR_1")
	)
	(segment
		(start 76.855066 -116.107464)
		(end 76.855066 -116.287296)
		(width 0.127)
		(layer "In2.Cu")
		(net "EXP_XM_ADDR_1")
	)
	(segment
		(start 99.294188 -97.8281)
		(end 99.268788 -97.8535)
		(width 0.127)
		(layer "In2.Cu")
		(net "EXP_XM_ADDR_1")
	)
	(segment
		(start 73.979786 -118.982744)
		(end 73.979786 -119.162576)
		(width 0.127)
		(layer "In2.Cu")
		(net "EXP_XM_ADDR_1")
	)
	(segment
		(start 72.46239 -122.65914)
		(end 72.33539 -122.78614)
		(width 0.127)
		(layer "In2.Cu")
		(net "EXP_XM_ADDR_1")
	)
	(segment
		(start 73.721976 -121.00814)
		(end 73.848976 -121.13514)
		(width 0.127)
		(layer "In2.Cu")
		(net "EXP_XM_ADDR_1")
	)
	(segment
		(start 96.306132 -100.019358)
		(end 96.306132 -100.19919)
		(width 0.127)
		(layer "In2.Cu")
		(net "EXP_XM_ADDR_1")
	)
	(segment
		(start 74.43089 -125.70714)
		(end 72.46239 -125.70714)
		(width 0.127)
		(layer "In2.Cu")
		(net "EXP_XM_ADDR_1")
	)
	(segment
		(start 72.46239 -125.70714)
		(end 72.33539 -125.83414)
		(width 0.127)
		(layer "In2.Cu")
		(net "EXP_XM_ADDR_1")
	)
	(segment
		(start 75.627992 -119.552974)
		(end 75.448414 -119.732552)
		(width 0.127)
		(layer "In2.Cu")
		(net "EXP_XM_ADDR_1")
	)
	(segment
		(start 72.33539 -126.25578)
		(end 72.76973 -126.69012)
		(width 0.127)
		(layer "In2.Cu")
		(net "EXP_XM_ADDR_1")
	)
	(segment
		(start 72.46239 -124.69114)
		(end 72.33539 -124.81814)
		(width 0.127)
		(layer "In2.Cu")
		(net "EXP_XM_ADDR_1")
	)
	(segment
		(start 72.33539 -124.81814)
		(end 72.33539 -125.07214)
		(width 0.127)
		(layer "In2.Cu")
		(net "EXP_XM_ADDR_1")
	)
	(segment
		(start 86.398354 -108.78312)
		(end 84.17941 -108.78312)
		(width 0.127)
		(layer "In2.Cu")
		(net "EXP_XM_ADDR_1")
	)
	(segment
		(start 74.43089 -121.13514)
		(end 74.55789 -121.26214)
		(width 0.127)
		(layer "In2.Cu")
		(net "EXP_XM_ADDR_1")
	)
	(segment
		(start 72.33539 -123.80214)
		(end 72.33539 -124.05614)
		(width 0.127)
		(layer "In2.Cu")
		(net "EXP_XM_ADDR_1")
	)
	(segment
		(start 74.55789 -124.56414)
		(end 74.43089 -124.69114)
		(width 0.127)
		(layer "In2.Cu")
		(net "EXP_XM_ADDR_1")
	)
	(segment
		(start 95.36938 -101.537008)
		(end 93.643958 -101.537008)
		(width 0.127)
		(layer "In2.Cu")
		(net "EXP_XM_ADDR_1")
	)
	(segment
		(start 75.987402 -119.013732)
		(end 75.058016 -118.084346)
		(width 0.127)
		(layer "In2.Cu")
		(net "EXP_XM_ADDR_1")
	)
	(segment
		(start 74.43089 -124.69114)
		(end 72.46239 -124.69114)
		(width 0.127)
		(layer "In2.Cu")
		(net "EXP_XM_ADDR_1")
	)
	(segment
		(start 96.416876 -100.309934)
		(end 96.416876 -100.489258)
		(width 0.127)
		(layer "In2.Cu")
		(net "EXP_XM_ADDR_1")
	)
	(segment
		(start 99.051618 -97.8535)
		(end 98.784664 -98.12147)
		(width 0.127)
		(layer "In2.Cu")
		(net "EXP_XM_ADDR_1")
	)
	(segment
		(start 77.784452 -117.396514)
		(end 77.604874 -117.576092)
		(width 0.127)
		(layer "In2.Cu")
		(net "EXP_XM_ADDR_1")
	)
	(segment
		(start 96.48571 -99.83978)
		(end 96.306132 -100.019358)
		(width 0.127)
		(layer "In2.Cu")
		(net "EXP_XM_ADDR_1")
	)
	(segment
		(start 74.43089 -123.67514)
		(end 72.46239 -123.67514)
		(width 0.127)
		(layer "In2.Cu")
		(net "EXP_XM_ADDR_1")
	)
	(segment
		(start 74.55789 -121.26214)
		(end 74.55789 -121.51614)
		(width 0.127)
		(layer "In2.Cu")
		(net "EXP_XM_ADDR_1")
	)
	(segment
		(start 77.065632 -117.935502)
		(end 77.065632 -118.115334)
		(width 0.127)
		(layer "In2.Cu")
		(net "EXP_XM_ADDR_1")
	)
	(segment
		(start 99.268788 -97.8535)
		(end 99.051618 -97.8535)
		(width 0.127)
		(layer "In2.Cu")
		(net "EXP_XM_ADDR_1")
	)
	(segment
		(start 72.33539 -125.83414)
		(end 72.33539 -126.25578)
		(width 0.127)
		(layer "In2.Cu")
		(net "EXP_XM_ADDR_1")
	)
	(segment
		(start 95.698056 -101.028754)
		(end 95.698056 -101.208078)
		(width 0.127)
		(layer "In2.Cu")
		(net "EXP_XM_ADDR_1")
	)
	(segment
		(start 76.346812 -118.834154)
		(end 76.167234 -119.013732)
		(width 0.127)
		(layer "In2.Cu")
		(net "EXP_XM_ADDR_1")
	)
	(segment
		(start 96.776286 -99.950524)
		(end 96.665542 -99.83978)
		(width 0.127)
		(layer "In2.Cu")
		(net "EXP_XM_ADDR_1")
	)
	(segment
		(start 73.340976 -120.414542)
		(end 73.594976 -120.414542)
		(width 0.127)
		(layer "In2.Cu")
		(net "EXP_XM_ADDR_1")
	)
	(segment
		(start 72.33539 -121.77014)
		(end 72.33539 -122.02414)
		(width 0.127)
		(layer "In2.Cu")
		(net "EXP_XM_ADDR_1")
	)
	(segment
		(start 95.587312 -100.91801)
		(end 95.698056 -101.028754)
		(width 0.127)
		(layer "In2.Cu")
		(net "EXP_XM_ADDR_1")
	)
	(segment
		(start 76.167234 -119.013732)
		(end 75.987402 -119.013732)
		(width 0.127)
		(layer "In2.Cu")
		(net "EXP_XM_ADDR_1")
	)
	(segment
		(start 95.587312 -100.738178)
		(end 95.587312 -100.91801)
		(width 0.127)
		(layer "In2.Cu")
		(net "EXP_XM_ADDR_1")
	)
	(segment
		(start 73.979786 -119.162576)
		(end 74.909172 -120.091962)
		(width 0.127)
		(layer "In2.Cu")
		(net "EXP_XM_ADDR_1")
	)
	(segment
		(start 76.886054 -118.294912)
		(end 76.706222 -118.294912)
		(width 0.127)
		(layer "In2.Cu")
		(net "EXP_XM_ADDR_1")
	)
	(segment
		(start 74.729594 -120.451372)
		(end 74.549762 -120.451372)
		(width 0.127)
		(layer "In2.Cu")
		(net "EXP_XM_ADDR_1")
	)
	(segment
		(start 75.268582 -119.732552)
		(end 74.339196 -118.803166)
		(width 0.127)
		(layer "In2.Cu")
		(net "EXP_XM_ADDR_1")
	)
	(segment
		(start 74.43089 -124.18314)
		(end 74.55789 -124.31014)
		(width 0.127)
		(layer "In2.Cu")
		(net "EXP_XM_ADDR_1")
	)
	(segment
		(start 74.43089 -122.65914)
		(end 72.46239 -122.65914)
		(width 0.127)
		(layer "In2.Cu")
		(net "EXP_XM_ADDR_1")
	)
	(segment
		(start 89.22893 -105.952036)
		(end 89.22893 -105.952544)
		(width 0.127)
		(layer "In2.Cu")
		(net "EXP_XM_ADDR_1")
	)
	(segment
		(start 72.46239 -123.67514)
		(end 72.33539 -123.80214)
		(width 0.127)
		(layer "In2.Cu")
		(net "EXP_XM_ADDR_1")
	)
	(segment
		(start 73.213976 -120.541542)
		(end 73.340976 -120.414542)
		(width 0.127)
		(layer "In2.Cu")
		(net "EXP_XM_ADDR_1")
	)
	(segment
		(start 72.46239 -122.15114)
		(end 74.43089 -122.15114)
		(width 0.127)
		(layer "In2.Cu")
		(net "EXP_XM_ADDR_1")
	)
	(segment
		(start 72.33539 -122.78614)
		(end 72.33539 -123.04014)
		(width 0.127)
		(layer "In2.Cu")
		(net "EXP_XM_ADDR_1")
	)
	(segment
		(start 72.33539 -120.62714)
		(end 72.33539 -121.00814)
		(width 0.127)
		(layer "In2.Cu")
		(net "EXP_XM_ADDR_1")
	)
	(segment
		(start 74.55789 -122.53214)
		(end 74.43089 -122.65914)
		(width 0.127)
		(layer "In2.Cu")
		(net "EXP_XM_ADDR_1")
	)
	(segment
		(start 126.774194 -82.681064)
		(end 126.739904 -82.715354)
		(width 0.1016)
		(layer "F.Cu")
		(net "SAS_HDD_TX12_N")
	)
	(segment
		(start 127.089662 -82.366104)
		(end 126.93523 -82.520536)
		(width 0.1016)
		(layer "F.Cu")
		(net "SAS_HDD_TX12_N")
	)
	(segment
		(start 126.786132 -82.669634)
		(end 126.774194 -82.681064)
		(width 0.1016)
		(layer "F.Cu")
		(net "SAS_HDD_TX12_N")
	)
	(segment
		(start 126.739904 -82.715354)
		(end 126.727712 -82.7278)
		(width 0.1016)
		(layer "F.Cu")
		(net "SAS_HDD_TX12_N")
	)
	(segment
		(start 126.93523 -82.520536)
		(end 126.800864 -82.654648)
		(width 0.1016)
		(layer "F.Cu")
		(net "SAS_HDD_TX12_N")
	)
	(segment
		(start 130.836416 -82.078068)
		(end 127.785114 -82.078068)
		(width 0.1016)
		(layer "F.Cu")
		(net "SAS_HDD_TX12_N")
	)
	(segment
		(start 126.727204 -82.728054)
		(end 126.52248 -82.93354)
		(width 0.1016)
		(layer "F.Cu")
		(net "SAS_HDD_TX12_N")
	)
	(segment
		(start 131.135882 -81.426558)
		(end 131.280916 -81.571846)
		(width 0.1016)
		(layer "F.Cu")
		(net "SAS_HDD_TX12_N")
	)
	(segment
		(start 126.800864 -82.654648)
		(end 126.786132 -82.669634)
		(width 0.1016)
		(layer "F.Cu")
		(net "SAS_HDD_TX12_N")
	)
	(segment
		(start 131.212082 -81.916778)
		(end 131.20243 -81.92643)
		(width 0.1016)
		(layer "F.Cu")
		(net "SAS_HDD_TX12_N")
	)
	(segment
		(start 126.727712 -82.7278)
		(end 126.727204 -82.728054)
		(width 0.1016)
		(layer "F.Cu")
		(net "SAS_HDD_TX12_N")
	)
	(arc
		(start 131.280916 -81.571846)
		(mid 131.30833 -81.612735)
		(end 131.318 -81.661)
		(width 0.1016)
		(layer "F.Cu")
		(net "SAS_HDD_TX12_N")
	)
	(arc
		(start 131.20243 -81.92643)
		(mid 131.034501 -82.038636)
		(end 130.836416 -82.078068)
		(width 0.1016)
		(layer "F.Cu")
		(net "SAS_HDD_TX12_N")
	)
	(arc
		(start 127.785114 -82.078068)
		(mid 127.408735 -82.152917)
		(end 127.089662 -82.366104)
		(width 0.1016)
		(layer "F.Cu")
		(net "SAS_HDD_TX12_N")
	)
	(arc
		(start 126.52248 -82.93354)
		(mid 126.394856 -83.124543)
		(end 126.350014 -83.349846)
		(width 0.1016)
		(layer "F.Cu")
		(net "SAS_HDD_TX12_N")
	)
	(arc
		(start 131.318 -81.661)
		(mid 131.290468 -81.799415)
		(end 131.212082 -81.916778)
		(width 0.1016)
		(layer "F.Cu")
		(net "SAS_HDD_TX12_N")
	)
	(segment
		(start 108.331 -57.056782)
		(end 108.00715 -56.732932)
		(width 0.1143)
		(layer "F.Cu")
		(net "XM_OE_N")
	)
	(segment
		(start 146.588226 -59.258962)
		(end 146.588226 -59.217306)
		(width 0.1143)
		(layer "F.Cu")
		(net "XM_OE_N")
	)
	(segment
		(start 108.00715 -56.463184)
		(end 107.54995 -56.005984)
		(width 0.1143)
		(layer "F.Cu")
		(net "XM_OE_N")
	)
	(segment
		(start 108.331 -57.727342)
		(end 108.332016 -57.726326)
		(width 0.1143)
		(layer "F.Cu")
		(net "XM_OE_N")
	)
	(segment
		(start 108.331 -57.131712)
		(end 108.331 -57.056782)
		(width 0.1143)
		(layer "F.Cu")
		(net "XM_OE_N")
	)
	(segment
		(start 108.00715 -56.732932)
		(end 108.00715 -56.463184)
		(width 0.1143)
		(layer "F.Cu")
		(net "XM_OE_N")
	)
	(segment
		(start 107.54995 -56.005984)
		(end 107.54995 -55.79999)
		(width 0.1143)
		(layer "F.Cu")
		(net "XM_OE_N")
	)
	(segment
		(start 108.332016 -57.132728)
		(end 108.331 -57.131712)
		(width 0.1143)
		(layer "F.Cu")
		(net "XM_OE_N")
	)
	(segment
		(start 146.598386 -61.9379)
		(end 146.598386 -59.269122)
		(width 0.1143)
		(layer "F.Cu")
		(net "XM_OE_N")
	)
	(segment
		(start 108.331 -58.579766)
		(end 108.331 -57.727342)
		(width 0.1143)
		(layer "F.Cu")
		(net "XM_OE_N")
	)
	(segment
		(start 146.598386 -59.269122)
		(end 146.588226 -59.258962)
		(width 0.1143)
		(layer "F.Cu")
		(net "XM_OE_N")
	)
	(segment
		(start 108.241338 -58.669428)
		(end 108.331 -58.579766)
		(width 0.1143)
		(layer "F.Cu")
		(net "XM_OE_N")
	)
	(segment
		(start 108.332016 -57.726326)
		(end 108.332016 -57.132728)
		(width 0.1143)
		(layer "F.Cu")
		(net "XM_OE_N")
	)
	(via
		(at 108.241338 -58.669428)
		(size 0.508)
		(drill 0.254)
		(layers "F.Cu" "B.Cu")
		(net "XM_OE_N")
	)
	(via
		(at 146.588226 -59.217306)
		(size 0.5588)
		(drill 0.3048)
		(layers "F.Cu" "B.Cu")
		(net "XM_OE_N")
	)
	(via
		(at 128.524 -60.833)
		(size 0.7112)
		(drill 0.3556)
		(layers "F.Cu" "B.Cu")
		(net "XM_OE_N")
	)
	(segment
		(start 128.524 -60.833)
		(end 128.651 -60.96)
		(width 0.1143)
		(layer "B.Cu")
		(net "XM_OE_N")
	)
	(segment
		(start 128.524 -60.833)
		(end 127.937768 -60.246768)
		(width 0.1143)
		(layer "B.Cu")
		(net "XM_OE_N")
	)
	(segment
		(start 128.651 -60.96)
		(end 135.89 -60.96)
		(width 0.1143)
		(layer "B.Cu")
		(net "XM_OE_N")
	)
	(segment
		(start 146.54657 -59.571382)
		(end 146.54657 -59.258962)
		(width 0.1143)
		(layer "B.Cu")
		(net "XM_OE_N")
	)
	(segment
		(start 146.54657 -59.258962)
		(end 146.588226 -59.217306)
		(width 0.1143)
		(layer "B.Cu")
		(net "XM_OE_N")
	)
	(segment
		(start 136.271 -61.341)
		(end 144.776952 -61.341)
		(width 0.1143)
		(layer "B.Cu")
		(net "XM_OE_N")
	)
	(segment
		(start 135.89 -60.96)
		(end 136.271 -61.341)
		(width 0.1143)
		(layer "B.Cu")
		(net "XM_OE_N")
	)
	(segment
		(start 127.937768 -60.246768)
		(end 109.818678 -60.246768)
		(width 0.1143)
		(layer "B.Cu")
		(net "XM_OE_N")
	)
	(segment
		(start 109.818678 -60.246768)
		(end 108.241338 -58.669428)
		(width 0.1143)
		(layer "B.Cu")
		(net "XM_OE_N")
	)
	(segment
		(start 144.776952 -61.341)
		(end 146.54657 -59.571382)
		(width 0.1143)
		(layer "B.Cu")
		(net "XM_OE_N")
	)
	(segment
		(start 100.726494 -98.425508)
		(end 100.726494 -98.685604)
		(width 0.1143)
		(layer "F.Cu")
		(net "EXP_XM_ADDR_0")
	)
	(segment
		(start 100.726494 -98.685604)
		(end 100.70846 -98.703638)
		(width 0.1143)
		(layer "F.Cu")
		(net "EXP_XM_ADDR_0")
	)
	(segment
		(start 102.19563 -96.956372)
		(end 100.726494 -98.425508)
		(width 0.1143)
		(layer "F.Cu")
		(net "EXP_XM_ADDR_0")
	)
	(segment
		(start 104.349804 -96.350074)
		(end 103.743252 -96.956372)
		(width 0.1143)
		(layer "F.Cu")
		(net "EXP_XM_ADDR_0")
	)
	(segment
		(start 103.743252 -96.956372)
		(end 102.19563 -96.956372)
		(width 0.1143)
		(layer "F.Cu")
		(net "EXP_XM_ADDR_0")
	)
	(via
		(at 100.70846 -98.703638)
		(size 0.508)
		(drill 0.254)
		(layers "F.Cu" "B.Cu")
		(net "EXP_XM_ADDR_0")
	)
	(segment
		(start 100.556822 -98.552)
		(end 100.70846 -98.703638)
		(width 0.1143)
		(layer "B.Cu")
		(net "EXP_XM_ADDR_0")
	)
	(segment
		(start 99.7966 -98.552)
		(end 100.556822 -98.552)
		(width 0.1143)
		(layer "B.Cu")
		(net "EXP_XM_ADDR_0")
	)
	(segment
		(start 127.265176 -82.675984)
		(end 127.178054 -82.763106)
		(width 0.1016)
		(layer "F.Cu")
		(net "SAS_HDD_TX12_P")
	)
	(segment
		(start 127.14097 -82.852768)
		(end 127.14097 -83.132422)
		(width 0.1016)
		(layer "F.Cu")
		(net "SAS_HDD_TX12_P")
	)
	(segment
		(start 130.83667 -82.420968)
		(end 127.785368 -82.420968)
		(width 0.1016)
		(layer "F.Cu")
		(net "SAS_HDD_TX12_P")
	)
	(segment
		(start 127.178054 -83.222084)
		(end 127.274574 -83.318604)
		(width 0.1016)
		(layer "F.Cu")
		(net "SAS_HDD_TX12_P")
	)
	(segment
		(start 127.332232 -82.608674)
		(end 127.265176 -82.675984)
		(width 0.1016)
		(layer "F.Cu")
		(net "SAS_HDD_TX12_P")
	)
	(segment
		(start 131.454652 -82.159348)
		(end 131.445 -82.169)
		(width 0.1016)
		(layer "F.Cu")
		(net "SAS_HDD_TX12_P")
	)
	(arc
		(start 127.178054 -82.763106)
		(mid 127.150621 -82.804257)
		(end 127.14097 -82.852768)
		(width 0.1016)
		(layer "F.Cu")
		(net "SAS_HDD_TX12_P")
	)
	(arc
		(start 131.445 -82.169)
		(mid 131.165882 -82.355438)
		(end 130.83667 -82.420968)
		(width 0.1016)
		(layer "F.Cu")
		(net "SAS_HDD_TX12_P")
	)
	(arc
		(start 127.274574 -83.318604)
		(mid 127.309185 -83.34173)
		(end 127.350012 -83.349846)
		(width 0.1016)
		(layer "F.Cu")
		(net "SAS_HDD_TX12_P")
	)
	(arc
		(start 131.6609 -81.66354)
		(mid 131.606881 -81.93188)
		(end 131.454652 -82.159348)
		(width 0.1016)
		(layer "F.Cu")
		(net "SAS_HDD_TX12_P")
	)
	(arc
		(start 127.14097 -83.132422)
		(mid 127.150603 -83.18094)
		(end 127.178054 -83.222084)
		(width 0.1016)
		(layer "F.Cu")
		(net "SAS_HDD_TX12_P")
	)
	(arc
		(start 127.785368 -82.420968)
		(mid 127.540128 -82.469749)
		(end 127.332232 -82.608674)
		(width 0.1016)
		(layer "F.Cu")
		(net "SAS_HDD_TX12_P")
	)
	(arc
		(start 131.897882 -81.426558)
		(mid 131.73031 -81.495968)
		(end 131.6609 -81.66354)
		(width 0.1016)
		(layer "F.Cu")
		(net "SAS_HDD_TX12_P")
	)
	(segment
		(start 145.098516 -45.530516)
		(end 145.796 -46.228)
		(width 0.1143)
		(layer "F.Cu")
		(net "XM_ADDR_8")
	)
	(segment
		(start 113.150142 -55.79999)
		(end 113.150142 -56.068976)
		(width 0.1143)
		(layer "F.Cu")
		(net "XM_ADDR_8")
	)
	(segment
		(start 113.519966 -56.4388)
		(end 113.519966 -56.861456)
		(width 0.1143)
		(layer "F.Cu")
		(net "XM_ADDR_8")
	)
	(segment
		(start 145.098516 -41.337484)
		(end 145.098516 -42.7101)
		(width 0.1143)
		(layer "F.Cu")
		(net "XM_ADDR_8")
	)
	(segment
		(start 145.034 -39.3065)
		(end 145.447766 -39.720266)
		(width 0.1143)
		(layer "F.Cu")
		(net "XM_ADDR_8")
	)
	(segment
		(start 146.177 -49.315624)
		(end 146.177 -50.3936)
		(width 0.1143)
		(layer "F.Cu")
		(net "XM_ADDR_8")
	)
	(segment
		(start 113.150142 -56.068976)
		(end 113.519966 -56.4388)
		(width 0.1143)
		(layer "F.Cu")
		(net "XM_ADDR_8")
	)
	(segment
		(start 145.447766 -39.720266)
		(end 145.447766 -40.513)
		(width 0.1143)
		(layer "F.Cu")
		(net "XM_ADDR_8")
	)
	(segment
		(start 145.796 -48.934624)
		(end 146.177 -49.315624)
		(width 0.1143)
		(layer "F.Cu")
		(net "XM_ADDR_8")
	)
	(segment
		(start 113.519966 -56.861456)
		(end 114.00536 -57.34685)
		(width 0.1143)
		(layer "F.Cu")
		(net "XM_ADDR_8")
	)
	(segment
		(start 145.447766 -40.513)
		(end 145.447766 -40.988234)
		(width 0.1143)
		(layer "F.Cu")
		(net "XM_ADDR_8")
	)
	(segment
		(start 145.098516 -42.7101)
		(end 145.098516 -45.530516)
		(width 0.1143)
		(layer "F.Cu")
		(net "XM_ADDR_8")
	)
	(segment
		(start 145.447766 -40.988234)
		(end 145.098516 -41.337484)
		(width 0.1143)
		(layer "F.Cu")
		(net "XM_ADDR_8")
	)
	(segment
		(start 145.796 -46.228)
		(end 145.796 -48.934624)
		(width 0.1143)
		(layer "F.Cu")
		(net "XM_ADDR_8")
	)
	(via
		(at 114.00536 -57.34685)
		(size 0.508)
		(drill 0.254)
		(layers "F.Cu" "B.Cu")
		(net "XM_ADDR_8")
	)
	(via
		(at 146.177 -50.3936)
		(size 0.5588)
		(drill 0.3048)
		(layers "F.Cu" "B.Cu")
		(net "XM_ADDR_8")
	)
	(via
		(at 145.447766 -40.513)
		(size 0.7112)
		(drill 0.3556)
		(layers "F.Cu" "B.Cu")
		(net "XM_ADDR_8")
	)
	(segment
		(start 144.574768 -51.0667)
		(end 145.104358 -51.0667)
		(width 0.127)
		(layer "In5.Cu")
		(net "XM_ADDR_8")
	)
	(segment
		(start 145.645632 -50.3936)
		(end 146.177 -50.3936)
		(width 0.127)
		(layer "In5.Cu")
		(net "XM_ADDR_8")
	)
	(segment
		(start 133.765544 -54.63413)
		(end 134.285736 -54.63413)
		(width 0.127)
		(layer "In5.Cu")
		(net "XM_ADDR_8")
	)
	(segment
		(start 139.312904 -51.312826)
		(end 144.328642 -51.312826)
		(width 0.127)
		(layer "In5.Cu")
		(net "XM_ADDR_8")
	)
	(segment
		(start 134.793736 -54.263036)
		(end 134.920736 -54.390036)
		(width 0.127)
		(layer "In5.Cu")
		(net "XM_ADDR_8")
	)
	(segment
		(start 115.154202 -57.184798)
		(end 115.813332 -56.525668)
		(width 0.127)
		(layer "In5.Cu")
		(net "XM_ADDR_8")
	)
	(segment
		(start 133.638544 -54.50713)
		(end 133.765544 -54.63413)
		(width 0.127)
		(layer "In5.Cu")
		(net "XM_ADDR_8")
	)
	(segment
		(start 133.511544 -53.9496)
		(end 133.638544 -54.0766)
		(width 0.127)
		(layer "In5.Cu")
		(net "XM_ADDR_8")
	)
	(segment
		(start 134.539736 -54.263036)
		(end 134.793736 -54.263036)
		(width 0.127)
		(layer "In5.Cu")
		(net "XM_ADDR_8")
	)
	(segment
		(start 139.185904 -51.439826)
		(end 139.312904 -51.312826)
		(width 0.127)
		(layer "In5.Cu")
		(net "XM_ADDR_8")
	)
	(segment
		(start 115.813332 -56.346344)
		(end 115.600988 -56.133492)
		(width 0.127)
		(layer "In5.Cu")
		(net "XM_ADDR_8")
	)
	(segment
		(start 134.920736 -54.50713)
		(end 135.047736 -54.63413)
		(width 0.127)
		(layer "In5.Cu")
		(net "XM_ADDR_8")
	)
	(segment
		(start 146.876516 -49.445926)
		(end 146.749516 -49.318926)
		(width 0.127)
		(layer "In5.Cu")
		(net "XM_ADDR_8")
	)
	(segment
		(start 139.185904 -52.41671)
		(end 139.185904 -51.439826)
		(width 0.127)
		(layer "In5.Cu")
		(net "XM_ADDR_8")
	)
	(segment
		(start 124.131578 -55.626254)
		(end 124.48921 -55.626254)
		(width 0.127)
		(layer "In5.Cu")
		(net "XM_ADDR_8")
	)
	(segment
		(start 146.262344 -51.449224)
		(end 146.263868 -51.4477)
		(width 0.127)
		(layer "In5.Cu")
		(net "XM_ADDR_8")
	)
	(segment
		(start 118.369334 -55.757826)
		(end 118.50116 -55.626)
		(width 0.127)
		(layer "In5.Cu")
		(net "XM_ADDR_8")
	)
	(segment
		(start 134.920736 -54.390036)
		(end 134.920736 -54.50713)
		(width 0.127)
		(layer "In5.Cu")
		(net "XM_ADDR_8")
	)
	(segment
		(start 134.412736 -54.390036)
		(end 134.539736 -54.263036)
		(width 0.127)
		(layer "In5.Cu")
		(net "XM_ADDR_8")
	)
	(segment
		(start 144.328642 -51.312826)
		(end 144.574768 -51.0667)
		(width 0.127)
		(layer "In5.Cu")
		(net "XM_ADDR_8")
	)
	(segment
		(start 115.78082 -55.774336)
		(end 115.960652 -55.774336)
		(width 0.127)
		(layer "In5.Cu")
		(net "XM_ADDR_8")
	)
	(segment
		(start 134.412736 -54.50713)
		(end 134.412736 -54.390036)
		(width 0.127)
		(layer "In5.Cu")
		(net "XM_ADDR_8")
	)
	(segment
		(start 136.968484 -54.63413)
		(end 139.185904 -52.41671)
		(width 0.127)
		(layer "In5.Cu")
		(net "XM_ADDR_8")
	)
	(segment
		(start 145.104358 -51.0667)
		(end 145.231358 -51.1937)
		(width 0.127)
		(layer "In5.Cu")
		(net "XM_ADDR_8")
	)
	(segment
		(start 115.813332 -56.525668)
		(end 115.813332 -56.346344)
		(width 0.127)
		(layer "In5.Cu")
		(net "XM_ADDR_8")
	)
	(segment
		(start 116.581174 -55.757826)
		(end 118.369334 -55.757826)
		(width 0.127)
		(layer "In5.Cu")
		(net "XM_ADDR_8")
	)
	(segment
		(start 118.50116 -55.626)
		(end 124.131324 -55.626)
		(width 0.127)
		(layer "In5.Cu")
		(net "XM_ADDR_8")
	)
	(segment
		(start 116.172742 -55.986934)
		(end 116.352066 -55.986934)
		(width 0.127)
		(layer "In5.Cu")
		(net "XM_ADDR_8")
	)
	(segment
		(start 124.131324 -55.626)
		(end 124.131578 -55.626254)
		(width 0.127)
		(layer "In5.Cu")
		(net "XM_ADDR_8")
	)
	(segment
		(start 133.638544 -54.0766)
		(end 133.638544 -54.50713)
		(width 0.127)
		(layer "In5.Cu")
		(net "XM_ADDR_8")
	)
	(segment
		(start 114.00536 -57.34685)
		(end 113.811812 -57.540398)
		(width 0.127)
		(layer "In5.Cu")
		(net "XM_ADDR_8")
	)
	(segment
		(start 145.547588 -50.295556)
		(end 145.645632 -50.3936)
		(width 0.127)
		(layer "In5.Cu")
		(net "XM_ADDR_8")
	)
	(segment
		(start 116.352066 -55.986934)
		(end 116.581174 -55.757826)
		(width 0.127)
		(layer "In5.Cu")
		(net "XM_ADDR_8")
	)
	(segment
		(start 113.938812 -57.944004)
		(end 115.027202 -57.944004)
		(width 0.127)
		(layer "In5.Cu")
		(net "XM_ADDR_8")
	)
	(segment
		(start 113.811812 -57.540398)
		(end 113.811812 -57.817004)
		(width 0.127)
		(layer "In5.Cu")
		(net "XM_ADDR_8")
	)
	(segment
		(start 115.154202 -57.817004)
		(end 115.154202 -57.184798)
		(width 0.127)
		(layer "In5.Cu")
		(net "XM_ADDR_8")
	)
	(segment
		(start 146.263868 -51.4477)
		(end 146.75104 -51.4477)
		(width 0.127)
		(layer "In5.Cu")
		(net "XM_ADDR_8")
	)
	(segment
		(start 135.047736 -54.63413)
		(end 136.968484 -54.63413)
		(width 0.127)
		(layer "In5.Cu")
		(net "XM_ADDR_8")
	)
	(segment
		(start 146.876516 -51.322224)
		(end 146.876516 -49.445926)
		(width 0.127)
		(layer "In5.Cu")
		(net "XM_ADDR_8")
	)
	(segment
		(start 145.231358 -51.322224)
		(end 145.358358 -51.449224)
		(width 0.127)
		(layer "In5.Cu")
		(net "XM_ADDR_8")
	)
	(segment
		(start 145.358358 -51.449224)
		(end 146.262344 -51.449224)
		(width 0.127)
		(layer "In5.Cu")
		(net "XM_ADDR_8")
	)
	(segment
		(start 146.75104 -51.4477)
		(end 146.876516 -51.322224)
		(width 0.127)
		(layer "In5.Cu")
		(net "XM_ADDR_8")
	)
	(segment
		(start 115.600988 -55.95366)
		(end 115.78082 -55.774336)
		(width 0.127)
		(layer "In5.Cu")
		(net "XM_ADDR_8")
	)
	(segment
		(start 134.285736 -54.63413)
		(end 134.412736 -54.50713)
		(width 0.127)
		(layer "In5.Cu")
		(net "XM_ADDR_8")
	)
	(segment
		(start 113.811812 -57.817004)
		(end 113.938812 -57.944004)
		(width 0.127)
		(layer "In5.Cu")
		(net "XM_ADDR_8")
	)
	(segment
		(start 146.749516 -49.318926)
		(end 145.645632 -49.318926)
		(width 0.127)
		(layer "In5.Cu")
		(net "XM_ADDR_8")
	)
	(segment
		(start 115.960652 -55.774336)
		(end 116.172742 -55.986934)
		(width 0.127)
		(layer "In5.Cu")
		(net "XM_ADDR_8")
	)
	(segment
		(start 145.231358 -51.1937)
		(end 145.231358 -51.322224)
		(width 0.127)
		(layer "In5.Cu")
		(net "XM_ADDR_8")
	)
	(segment
		(start 126.165864 -53.9496)
		(end 133.511544 -53.9496)
		(width 0.127)
		(layer "In5.Cu")
		(net "XM_ADDR_8")
	)
	(segment
		(start 145.645632 -49.318926)
		(end 145.547588 -49.41697)
		(width 0.127)
		(layer "In5.Cu")
		(net "XM_ADDR_8")
	)
	(segment
		(start 115.027202 -57.944004)
		(end 115.154202 -57.817004)
		(width 0.127)
		(layer "In5.Cu")
		(net "XM_ADDR_8")
	)
	(segment
		(start 115.600988 -56.133492)
		(end 115.600988 -55.95366)
		(width 0.127)
		(layer "In5.Cu")
		(net "XM_ADDR_8")
	)
	(segment
		(start 124.48921 -55.626254)
		(end 126.165864 -53.9496)
		(width 0.127)
		(layer "In5.Cu")
		(net "XM_ADDR_8")
	)
	(segment
		(start 145.547588 -49.41697)
		(end 145.547588 -50.295556)
		(width 0.127)
		(layer "In5.Cu")
		(net "XM_ADDR_8")
	)
	(segment
		(start 122.350022 -83.349846)
		(end 122.850148 -82.84972)
		(width 0.1016)
		(layer "F.Cu")
		(net "SAS3008_RAID_TX_N1")
	)
	(segment
		(start 85.825838 -34.73704)
		(end 85.811868 -34.75101)
		(width 0.1016)
		(layer "F.Cu")
		(net "SAS3008_RAID_TX_N1")
	)
	(segment
		(start 85.65261 -34.81705)
		(end 83.562444 -34.81705)
		(width 0.1016)
		(layer "F.Cu")
		(net "SAS3008_RAID_TX_N1")
	)
	(segment
		(start 86.21776 -34.671)
		(end 85.985096 -34.671)
		(width 0.1016)
		(layer "F.Cu")
		(net "SAS3008_RAID_TX_N1")
	)
	(via
		(at 124.779278 -80.251808)
		(size 0.5588)
		(drill 0.3048)
		(layers "F.Cu" "B.Cu")
		(net "SAS3008_RAID_TX_N1")
	)
	(via
		(at 83.0834 -34.618676)
		(size 0.5588)
		(drill 0.3048)
		(layers "F.Cu" "B.Cu")
		(net "SAS3008_RAID_TX_N1")
	)
	(via
		(at 122.850148 -82.84972)
		(size 0.508)
		(drill 0.254)
		(layers "F.Cu" "B.Cu")
		(net "SAS3008_RAID_TX_N1")
	)
	(via
		(at 77.686408 -41.6052)
		(size 0.5588)
		(drill 0.3048)
		(layers "F.Cu" "B.Cu")
		(net "SAS3008_RAID_TX_N1")
	)
	(arc
		(start 85.811868 -34.75101)
		(mid 85.738814 -34.799886)
		(end 85.65261 -34.81705)
		(width 0.1016)
		(layer "F.Cu")
		(net "SAS3008_RAID_TX_N1")
	)
	(arc
		(start 85.985096 -34.671)
		(mid 85.898892 -34.688165)
		(end 85.825838 -34.73704)
		(width 0.1016)
		(layer "F.Cu")
		(net "SAS3008_RAID_TX_N1")
	)
	(arc
		(start 83.562444 -34.81705)
		(mid 83.303207 -34.765485)
		(end 83.0834 -34.618676)
		(width 0.1016)
		(layer "F.Cu")
		(net "SAS3008_RAID_TX_N1")
	)
	(segment
		(start 83.0834 -34.618676)
		(end 82.832194 -34.869882)
		(width 0.1016)
		(layer "B.Cu")
		(net "SAS3008_RAID_TX_N1")
	)
	(segment
		(start 124.2695 -82.26933)
		(end 124.254768 -82.284316)
		(width 0.1016)
		(layer "B.Cu")
		(net "SAS3008_RAID_TX_N1")
	)
	(segment
		(start 78.999842 -35.17011)
		(end 78.928976 -35.241484)
		(width 0.1016)
		(layer "B.Cu")
		(net "SAS3008_RAID_TX_N1")
	)
	(segment
		(start 124.945394 -81.593436)
		(end 124.2695 -82.26933)
		(width 0.1016)
		(layer "B.Cu")
		(net "SAS3008_RAID_TX_N1")
	)
	(segment
		(start 77.973682 -41.317926)
		(end 77.686408 -41.6052)
		(width 0.1016)
		(layer "B.Cu")
		(net "SAS3008_RAID_TX_N1")
	)
	(segment
		(start 124.04217 -82.3722)
		(end 123.81357 -82.3722)
		(width 0.1016)
		(layer "B.Cu")
		(net "SAS3008_RAID_TX_N1")
	)
	(segment
		(start 122.98426 -82.715862)
		(end 122.850148 -82.84972)
		(width 0.1016)
		(layer "B.Cu")
		(net "SAS3008_RAID_TX_N1")
	)
	(segment
		(start 125.09627 -80.899)
		(end 125.09627 -81.2292)
		(width 0.1016)
		(layer "B.Cu")
		(net "SAS3008_RAID_TX_N1")
	)
	(segment
		(start 78.0034 -38.16858)
		(end 78.0034 -41.246044)
		(width 0.1016)
		(layer "B.Cu")
		(net "SAS3008_RAID_TX_N1")
	)
	(segment
		(start 124.779278 -80.251808)
		(end 124.862844 -80.335374)
		(width 0.1016)
		(layer "B.Cu")
		(net "SAS3008_RAID_TX_N1")
	)
	(segment
		(start 78.6765 -35.851846)
		(end 78.6765 -36.543996)
		(width 0.1016)
		(layer "B.Cu")
		(net "SAS3008_RAID_TX_N1")
	)
	(segment
		(start 82.760312 -34.8996)
		(end 79.653638 -34.8996)
		(width 0.1016)
		(layer "B.Cu")
		(net "SAS3008_RAID_TX_N1")
	)
	(arc
		(start 123.81357 -82.3722)
		(mid 123.364747 -82.46157)
		(end 122.98426 -82.715862)
		(width 0.1016)
		(layer "B.Cu")
		(net "SAS3008_RAID_TX_N1")
	)
	(arc
		(start 78.928976 -35.241484)
		(mid 78.742052 -35.521564)
		(end 78.6765 -35.851846)
		(width 0.1016)
		(layer "B.Cu")
		(net "SAS3008_RAID_TX_N1")
	)
	(arc
		(start 125.09627 -81.2292)
		(mid 125.057059 -81.426325)
		(end 124.945394 -81.593436)
		(width 0.1016)
		(layer "B.Cu")
		(net "SAS3008_RAID_TX_N1")
	)
	(arc
		(start 82.832194 -34.869882)
		(mid 82.7992 -34.891865)
		(end 82.760312 -34.8996)
		(width 0.1016)
		(layer "B.Cu")
		(net "SAS3008_RAID_TX_N1")
	)
	(arc
		(start 78.0034 -41.246044)
		(mid 77.995681 -41.284939)
		(end 77.973682 -41.317926)
		(width 0.1016)
		(layer "B.Cu")
		(net "SAS3008_RAID_TX_N1")
	)
	(arc
		(start 78.6765 -36.543996)
		(mid 78.640716 -36.723805)
		(end 78.538832 -36.876228)
		(width 0.1016)
		(layer "B.Cu")
		(net "SAS3008_RAID_TX_N1")
	)
	(arc
		(start 124.254768 -82.284316)
		(mid 124.157212 -82.349408)
		(end 124.04217 -82.3722)
		(width 0.1016)
		(layer "B.Cu")
		(net "SAS3008_RAID_TX_N1")
	)
	(arc
		(start 79.653638 -34.8996)
		(mid 79.299853 -34.969861)
		(end 78.999842 -35.17011)
		(width 0.1016)
		(layer "B.Cu")
		(net "SAS3008_RAID_TX_N1")
	)
	(arc
		(start 124.862844 -80.335374)
		(mid 125.035631 -80.593968)
		(end 125.09627 -80.899)
		(width 0.1016)
		(layer "B.Cu")
		(net "SAS3008_RAID_TX_N1")
	)
	(arc
		(start 78.538832 -36.876228)
		(mid 78.142645 -37.469164)
		(end 78.0034 -38.16858)
		(width 0.1016)
		(layer "B.Cu")
		(net "SAS3008_RAID_TX_N1")
	)
	(segment
		(start 114.77879 -73.94575)
		(end 119.87022 -79.03718)
		(width 0.1016)
		(layer "In2.Cu")
		(net "SAS3008_RAID_TX_N1")
	)
	(segment
		(start 124.66447 -79.7941)
		(end 124.67717 -79.8068)
		(width 0.1016)
		(layer "In2.Cu")
		(net "SAS3008_RAID_TX_N1")
	)
	(segment
		(start 78.462632 -48.59528)
		(end 79.634588 -49.766982)
		(width 0.1016)
		(layer "In2.Cu")
		(net "SAS3008_RAID_TX_N1")
	)
	(segment
		(start 85.909658 -56.041798)
		(end 85.909658 -56.042052)
		(width 0.1016)
		(layer "In2.Cu")
		(net "SAS3008_RAID_TX_N1")
	)
	(segment
		(start 77.686408 -41.6052)
		(end 77.92339 -41.842436)
		(width 0.1016)
		(layer "In2.Cu")
		(net "SAS3008_RAID_TX_N1")
	)
	(segment
		(start 79.664306 -49.7967)
		(end 79.66456 -49.7967)
		(width 0.1016)
		(layer "In2.Cu")
		(net "SAS3008_RAID_TX_N1")
	)
	(segment
		(start 79.634588 -49.766982)
		(end 79.664306 -49.7967)
		(width 0.1016)
		(layer "In2.Cu")
		(net "SAS3008_RAID_TX_N1")
	)
	(segment
		(start 79.66456 -49.7967)
		(end 85.909658 -56.041798)
		(width 0.1016)
		(layer "In2.Cu")
		(net "SAS3008_RAID_TX_N1")
	)
	(segment
		(start 78.1304 -42.3418)
		(end 78.1304 -47.792894)
		(width 0.1016)
		(layer "In2.Cu")
		(net "SAS3008_RAID_TX_N1")
	)
	(segment
		(start 105.382822 -73.5584)
		(end 113.844324 -73.5584)
		(width 0.1016)
		(layer "In2.Cu")
		(net "SAS3008_RAID_TX_N1")
	)
	(segment
		(start 101.287834 -71.420228)
		(end 102.042976 -72.175116)
		(width 0.1016)
		(layer "In2.Cu")
		(net "SAS3008_RAID_TX_N1")
	)
	(segment
		(start 121.483882 -79.7052)
		(end 124.450094 -79.7052)
		(width 0.1016)
		(layer "In2.Cu")
		(net "SAS3008_RAID_TX_N1")
	)
	(segment
		(start 85.909658 -56.042052)
		(end 101.287834 -71.420228)
		(width 0.1016)
		(layer "In2.Cu")
		(net "SAS3008_RAID_TX_N1")
	)
	(segment
		(start 124.779278 -80.053434)
		(end 124.779278 -80.251808)
		(width 0.1016)
		(layer "In2.Cu")
		(net "SAS3008_RAID_TX_N1")
	)
	(arc
		(start 78.1304 -47.792894)
		(mid 78.216738 -48.227122)
		(end 78.462632 -48.59528)
		(width 0.1016)
		(layer "In2.Cu")
		(net "SAS3008_RAID_TX_N1")
	)
	(arc
		(start 113.844324 -73.5584)
		(mid 114.350068 -73.659168)
		(end 114.77879 -73.94575)
		(width 0.1016)
		(layer "In2.Cu")
		(net "SAS3008_RAID_TX_N1")
	)
	(arc
		(start 124.450094 -79.7052)
		(mid 124.566113 -79.728353)
		(end 124.66447 -79.7941)
		(width 0.1016)
		(layer "In2.Cu")
		(net "SAS3008_RAID_TX_N1")
	)
	(arc
		(start 124.67717 -79.8068)
		(mid 124.752779 -79.919957)
		(end 124.779278 -80.053434)
		(width 0.1016)
		(layer "In2.Cu")
		(net "SAS3008_RAID_TX_N1")
	)
	(arc
		(start 102.042976 -72.175116)
		(mid 103.575297 -73.199014)
		(end 105.382822 -73.5584)
		(width 0.1016)
		(layer "In2.Cu")
		(net "SAS3008_RAID_TX_N1")
	)
	(arc
		(start 77.92339 -41.842436)
		(mid 78.076559 -42.071531)
		(end 78.1304 -42.3418)
		(width 0.1016)
		(layer "In2.Cu")
		(net "SAS3008_RAID_TX_N1")
	)
	(arc
		(start 119.87022 -79.03718)
		(mid 120.610604 -79.531703)
		(end 121.483882 -79.7052)
		(width 0.1016)
		(layer "In2.Cu")
		(net "SAS3008_RAID_TX_N1")
	)
	(segment
		(start 102.875334 -89.87536)
		(end 102.85349 -89.87536)
		(width 0.1143)
		(layer "F.Cu")
		(net "XM_DATA10")
	)
	(segment
		(start 103.349806 -90.349832)
		(end 102.875334 -89.87536)
		(width 0.1143)
		(layer "F.Cu")
		(net "XM_DATA10")
	)
	(segment
		(start 73.834498 -131.90347)
		(end 72.793352 -131.90347)
		(width 0.1143)
		(layer "F.Cu")
		(net "XM_DATA10")
	)
	(segment
		(start 75.786742 -131.892802)
		(end 73.845166 -131.892802)
		(width 0.1143)
		(layer "F.Cu")
		(net "XM_DATA10")
	)
	(segment
		(start 73.845166 -131.892802)
		(end 73.834498 -131.90347)
		(width 0.1143)
		(layer "F.Cu")
		(net "XM_DATA10")
	)
	(via
		(at 78.352396 -94.75724)
		(size 0.7112)
		(drill 0.3556)
		(layers "F.Cu" "B.Cu")
		(net "XM_DATA10")
	)
	(via
		(at 72.793352 -131.90347)
		(size 0.5588)
		(drill 0.3048)
		(layers "F.Cu" "B.Cu")
		(net "XM_DATA10")
	)
	(via
		(at 102.85349 -89.87536)
		(size 0.508)
		(drill 0.254)
		(layers "F.Cu" "B.Cu")
		(net "XM_DATA10")
	)
	(segment
		(start 72.91578 -97.972626)
		(end 72.753982 -98.134424)
		(width 0.1143)
		(layer "B.Cu")
		(net "XM_DATA10")
	)
	(segment
		(start 74.81951 -98.2599)
		(end 74.657966 -98.2599)
		(width 0.1143)
		(layer "B.Cu")
		(net "XM_DATA10")
	)
	(segment
		(start 74.011282 -98.906584)
		(end 73.077324 -97.972626)
		(width 0.1143)
		(layer "B.Cu")
		(net "XM_DATA10")
	)
	(segment
		(start 87.513668 -91.0717)
		(end 87.513922 -91.0717)
		(width 0.1143)
		(layer "B.Cu")
		(net "XM_DATA10")
	)
	(segment
		(start 75.987402 -95.062548)
		(end 76.92136 -95.996506)
		(width 0.1143)
		(layer "B.Cu")
		(net "XM_DATA10")
	)
	(segment
		(start 74.981308 -97.936558)
		(end 74.981308 -98.098102)
		(width 0.1143)
		(layer "B.Cu")
		(net "XM_DATA10")
	)
	(segment
		(start 74.334624 -98.744786)
		(end 74.172826 -98.906584)
		(width 0.1143)
		(layer "B.Cu")
		(net "XM_DATA10")
	)
	(segment
		(start 75.627992 -97.289874)
		(end 75.627992 -97.451418)
		(width 0.1143)
		(layer "B.Cu")
		(net "XM_DATA10")
	)
	(segment
		(start 75.017376 -96.032574)
		(end 74.855832 -96.032574)
		(width 0.1143)
		(layer "B.Cu")
		(net "XM_DATA10")
	)
	(segment
		(start 73.400666 -97.649284)
		(end 74.334624 -98.583242)
		(width 0.1143)
		(layer "B.Cu")
		(net "XM_DATA10")
	)
	(segment
		(start 75.66406 -95.38589)
		(end 75.502516 -95.38589)
		(width 0.1143)
		(layer "B.Cu")
		(net "XM_DATA10")
	)
	(segment
		(start 73.077324 -97.972626)
		(end 72.91578 -97.972626)
		(width 0.1143)
		(layer "B.Cu")
		(net "XM_DATA10")
	)
	(segment
		(start 81.23047 -91.87942)
		(end 86.705948 -91.87942)
		(width 0.1143)
		(layer "B.Cu")
		(net "XM_DATA10")
	)
	(segment
		(start 72.529192 -130.226308)
		(end 72.529192 -130.227324)
		(width 0.1143)
		(layer "B.Cu")
		(net "XM_DATA10")
	)
	(segment
		(start 71.11492 -101.96449)
		(end 71.11492 -128.812036)
		(width 0.1143)
		(layer "B.Cu")
		(net "XM_DATA10")
	)
	(segment
		(start 78.352396 -94.75724)
		(end 78.744064 -94.365572)
		(width 0.1143)
		(layer "B.Cu")
		(net "XM_DATA10")
	)
	(segment
		(start 75.627992 -97.451418)
		(end 75.466194 -97.613216)
		(width 0.1143)
		(layer "B.Cu")
		(net "XM_DATA10")
	)
	(segment
		(start 72.753982 -98.295968)
		(end 73.68794 -99.229926)
		(width 0.1143)
		(layer "B.Cu")
		(net "XM_DATA10")
	)
	(segment
		(start 74.04735 -96.841056)
		(end 74.04735 -97.0026)
		(width 0.1143)
		(layer "B.Cu")
		(net "XM_DATA10")
	)
	(segment
		(start 77.728318 -95.381318)
		(end 77.728318 -95.381572)
		(width 0.1143)
		(layer "B.Cu")
		(net "XM_DATA10")
	)
	(segment
		(start 72.529192 -130.227324)
		(end 72.78497 -130.483102)
		(width 0.1143)
		(layer "B.Cu")
		(net "XM_DATA10")
	)
	(segment
		(start 102.00132 -90.72753)
		(end 102.85349 -89.87536)
		(width 0.1143)
		(layer "B.Cu")
		(net "XM_DATA10")
	)
	(segment
		(start 74.694034 -96.355916)
		(end 75.627992 -97.289874)
		(width 0.1143)
		(layer "B.Cu")
		(net "XM_DATA10")
	)
	(segment
		(start 87.513922 -91.0717)
		(end 87.900764 -90.684858)
		(width 0.1143)
		(layer "B.Cu")
		(net "XM_DATA10")
	)
	(segment
		(start 73.562464 -97.325942)
		(end 73.400666 -97.48774)
		(width 0.1143)
		(layer "B.Cu")
		(net "XM_DATA10")
	)
	(segment
		(start 76.274676 -96.64319)
		(end 76.274676 -96.804734)
		(width 0.1143)
		(layer "B.Cu")
		(net "XM_DATA10")
	)
	(segment
		(start 72.78497 -131.895088)
		(end 72.793352 -131.90347)
		(width 0.1143)
		(layer "B.Cu")
		(net "XM_DATA10")
	)
	(segment
		(start 76.598018 -96.319848)
		(end 75.66406 -95.38589)
		(width 0.1143)
		(layer "B.Cu")
		(net "XM_DATA10")
	)
	(segment
		(start 76.92136 -95.996506)
		(end 76.92136 -96.15805)
		(width 0.1143)
		(layer "B.Cu")
		(net "XM_DATA10")
	)
	(segment
		(start 78.744318 -94.365572)
		(end 81.23047 -91.87942)
		(width 0.1143)
		(layer "B.Cu")
		(net "XM_DATA10")
	)
	(segment
		(start 77.728318 -95.381572)
		(end 77.436726 -95.673164)
		(width 0.1143)
		(layer "B.Cu")
		(net "XM_DATA10")
	)
	(segment
		(start 77.244702 -95.673164)
		(end 76.310744 -94.739206)
		(width 0.1143)
		(layer "B.Cu")
		(net "XM_DATA10")
	)
	(segment
		(start 74.694034 -96.194372)
		(end 74.694034 -96.355916)
		(width 0.1143)
		(layer "B.Cu")
		(net "XM_DATA10")
	)
	(segment
		(start 74.172826 -98.906584)
		(end 74.011282 -98.906584)
		(width 0.1143)
		(layer "B.Cu")
		(net "XM_DATA10")
	)
	(segment
		(start 75.340718 -95.709232)
		(end 76.274676 -96.64319)
		(width 0.1143)
		(layer "B.Cu")
		(net "XM_DATA10")
	)
	(segment
		(start 75.466194 -97.613216)
		(end 75.30465 -97.613216)
		(width 0.1143)
		(layer "B.Cu")
		(net "XM_DATA10")
	)
	(segment
		(start 75.340718 -95.547688)
		(end 75.340718 -95.709232)
		(width 0.1143)
		(layer "B.Cu")
		(net "XM_DATA10")
	)
	(segment
		(start 78.744064 -94.365572)
		(end 78.744318 -94.365572)
		(width 0.1143)
		(layer "B.Cu")
		(net "XM_DATA10")
	)
	(segment
		(start 76.274676 -96.804734)
		(end 76.112878 -96.966532)
		(width 0.1143)
		(layer "B.Cu")
		(net "XM_DATA10")
	)
	(segment
		(start 71.11492 -128.812036)
		(end 72.529192 -130.226308)
		(width 0.1143)
		(layer "B.Cu")
		(net "XM_DATA10")
	)
	(segment
		(start 87.900764 -90.684858)
		(end 99.66579 -90.684858)
		(width 0.1143)
		(layer "B.Cu")
		(net "XM_DATA10")
	)
	(segment
		(start 75.502516 -95.38589)
		(end 75.340718 -95.547688)
		(width 0.1143)
		(layer "B.Cu")
		(net "XM_DATA10")
	)
	(segment
		(start 74.370692 -96.679258)
		(end 74.209148 -96.679258)
		(width 0.1143)
		(layer "B.Cu")
		(net "XM_DATA10")
	)
	(segment
		(start 74.855832 -96.032574)
		(end 74.694034 -96.194372)
		(width 0.1143)
		(layer "B.Cu")
		(net "XM_DATA10")
	)
	(segment
		(start 74.981308 -98.098102)
		(end 74.81951 -98.2599)
		(width 0.1143)
		(layer "B.Cu")
		(net "XM_DATA10")
	)
	(segment
		(start 77.436726 -95.673164)
		(end 77.244702 -95.673164)
		(width 0.1143)
		(layer "B.Cu")
		(net "XM_DATA10")
	)
	(segment
		(start 99.66579 -90.684858)
		(end 99.708462 -90.72753)
		(width 0.1143)
		(layer "B.Cu")
		(net "XM_DATA10")
	)
	(segment
		(start 73.400666 -97.48774)
		(end 73.400666 -97.649284)
		(width 0.1143)
		(layer "B.Cu")
		(net "XM_DATA10")
	)
	(segment
		(start 74.334624 -98.583242)
		(end 74.334624 -98.744786)
		(width 0.1143)
		(layer "B.Cu")
		(net "XM_DATA10")
	)
	(segment
		(start 78.352396 -94.75724)
		(end 77.728318 -95.381318)
		(width 0.1143)
		(layer "B.Cu")
		(net "XM_DATA10")
	)
	(segment
		(start 73.724008 -97.325942)
		(end 73.562464 -97.325942)
		(width 0.1143)
		(layer "B.Cu")
		(net "XM_DATA10")
	)
	(segment
		(start 99.708462 -90.72753)
		(end 102.00132 -90.72753)
		(width 0.1143)
		(layer "B.Cu")
		(net "XM_DATA10")
	)
	(segment
		(start 72.78497 -130.483102)
		(end 72.78497 -131.895088)
		(width 0.1143)
		(layer "B.Cu")
		(net "XM_DATA10")
	)
	(segment
		(start 76.1492 -94.739206)
		(end 75.987402 -94.901004)
		(width 0.1143)
		(layer "B.Cu")
		(net "XM_DATA10")
	)
	(segment
		(start 75.30465 -97.613216)
		(end 74.370692 -96.679258)
		(width 0.1143)
		(layer "B.Cu")
		(net "XM_DATA10")
	)
	(segment
		(start 74.209148 -96.679258)
		(end 74.04735 -96.841056)
		(width 0.1143)
		(layer "B.Cu")
		(net "XM_DATA10")
	)
	(segment
		(start 75.987402 -94.901004)
		(end 75.987402 -95.062548)
		(width 0.1143)
		(layer "B.Cu")
		(net "XM_DATA10")
	)
	(segment
		(start 72.753982 -98.134424)
		(end 72.753982 -98.295968)
		(width 0.1143)
		(layer "B.Cu")
		(net "XM_DATA10")
	)
	(segment
		(start 86.705948 -91.87942)
		(end 87.513668 -91.0717)
		(width 0.1143)
		(layer "B.Cu")
		(net "XM_DATA10")
	)
	(segment
		(start 74.04735 -97.0026)
		(end 74.981308 -97.936558)
		(width 0.1143)
		(layer "B.Cu")
		(net "XM_DATA10")
	)
	(segment
		(start 73.68794 -99.229926)
		(end 73.68794 -99.39147)
		(width 0.1143)
		(layer "B.Cu")
		(net "XM_DATA10")
	)
	(segment
		(start 76.92136 -96.15805)
		(end 76.759562 -96.319848)
		(width 0.1143)
		(layer "B.Cu")
		(net "XM_DATA10")
	)
	(segment
		(start 76.310744 -94.739206)
		(end 76.1492 -94.739206)
		(width 0.1143)
		(layer "B.Cu")
		(net "XM_DATA10")
	)
	(segment
		(start 75.951334 -96.966532)
		(end 75.017376 -96.032574)
		(width 0.1143)
		(layer "B.Cu")
		(net "XM_DATA10")
	)
	(segment
		(start 74.657966 -98.2599)
		(end 73.724008 -97.325942)
		(width 0.1143)
		(layer "B.Cu")
		(net "XM_DATA10")
	)
	(segment
		(start 76.759562 -96.319848)
		(end 76.598018 -96.319848)
		(width 0.1143)
		(layer "B.Cu")
		(net "XM_DATA10")
	)
	(segment
		(start 73.68794 -99.39147)
		(end 71.11492 -101.96449)
		(width 0.1143)
		(layer "B.Cu")
		(net "XM_DATA10")
	)
	(segment
		(start 76.112878 -96.966532)
		(end 75.951334 -96.966532)
		(width 0.1143)
		(layer "B.Cu")
		(net "XM_DATA10")
	)
	(segment
		(start 107.349798 -106.53014)
		(end 107.349798 -106.350054)
		(width 0.1016)
		(layer "F.Cu")
		(net "SAS_HDD_TX11_N")
	)
	(segment
		(start 105.899712 -108.512864)
		(end 106.815636 -107.597194)
		(width 0.1016)
		(layer "F.Cu")
		(net "SAS_HDD_TX11_N")
	)
	(segment
		(start 107.093512 -106.966258)
		(end 107.222544 -106.837226)
		(width 0.1016)
		(layer "F.Cu")
		(net "SAS_HDD_TX11_N")
	)
	(segment
		(start 102.988364 -111.423704)
		(end 103.10749 -111.304832)
		(width 0.1016)
		(layer "F.Cu")
		(net "SAS_HDD_TX11_N")
	)
	(segment
		(start 101.814122 -113.62182)
		(end 101.844348 -113.591594)
		(width 0.1016)
		(layer "F.Cu")
		(net "SAS_HDD_TX11_N")
	)
	(segment
		(start 101.88702 -113.488216)
		(end 101.88702 -113.182146)
		(width 0.1016)
		(layer "F.Cu")
		(net "SAS_HDD_TX11_N")
	)
	(segment
		(start 105.188512 -109.223556)
		(end 105.668826 -108.743496)
		(width 0.1016)
		(layer "F.Cu")
		(net "SAS_HDD_TX11_N")
	)
	(segment
		(start 102.67188 -111.740188)
		(end 102.988364 -111.423704)
		(width 0.1016)
		(layer "F.Cu")
		(net "SAS_HDD_TX11_N")
	)
	(segment
		(start 105.668826 -108.743496)
		(end 105.899712 -108.512864)
		(width 0.1016)
		(layer "F.Cu")
		(net "SAS_HDD_TX11_N")
	)
	(segment
		(start 103.97236 -110.439454)
		(end 105.188512 -109.223556)
		(width 0.1016)
		(layer "F.Cu")
		(net "SAS_HDD_TX11_N")
	)
	(segment
		(start 103.10749 -111.304832)
		(end 103.97236 -110.439454)
		(width 0.1016)
		(layer "F.Cu")
		(net "SAS_HDD_TX11_N")
	)
	(segment
		(start 101.74097 -114.0206)
		(end 101.74097 -113.798096)
		(width 0.1016)
		(layer "F.Cu")
		(net "SAS_HDD_TX11_N")
	)
	(segment
		(start 102.351078 -112.061752)
		(end 102.67188 -111.740188)
		(width 0.1016)
		(layer "F.Cu")
		(net "SAS_HDD_TX11_N")
	)
	(arc
		(start 107.222544 -106.837226)
		(mid 107.316685 -106.696334)
		(end 107.349798 -106.53014)
		(width 0.1016)
		(layer "F.Cu")
		(net "SAS_HDD_TX11_N")
	)
	(arc
		(start 101.74097 -113.798096)
		(mid 101.759987 -113.702673)
		(end 101.814122 -113.62182)
		(width 0.1016)
		(layer "F.Cu")
		(net "SAS_HDD_TX11_N")
	)
	(arc
		(start 106.851704 -107.54995)
		(mid 106.936757 -107.419705)
		(end 106.968798 -107.267502)
		(width 0.1016)
		(layer "F.Cu")
		(net "SAS_HDD_TX11_N")
	)
	(arc
		(start 106.968798 -107.267502)
		(mid 107.001207 -107.104481)
		(end 107.093512 -106.966258)
		(width 0.1016)
		(layer "F.Cu")
		(net "SAS_HDD_TX11_N")
	)
	(arc
		(start 106.820462 -107.592114)
		(mid 106.823184 -107.589243)
		(end 106.825796 -107.586272)
		(width 0.1016)
		(layer "F.Cu")
		(net "SAS_HDD_TX11_N")
	)
	(arc
		(start 101.844348 -113.591594)
		(mid 101.875933 -113.544135)
		(end 101.88702 -113.488216)
		(width 0.1016)
		(layer "F.Cu")
		(net "SAS_HDD_TX11_N")
	)
	(arc
		(start 106.835448 -107.574334)
		(mid 106.84446 -107.562732)
		(end 106.851704 -107.54995)
		(width 0.1016)
		(layer "F.Cu")
		(net "SAS_HDD_TX11_N")
	)
	(arc
		(start 106.825796 -107.586272)
		(mid 106.830846 -107.580484)
		(end 106.835448 -107.574334)
		(width 0.1016)
		(layer "F.Cu")
		(net "SAS_HDD_TX11_N")
	)
	(arc
		(start 106.815636 -107.597194)
		(mid 106.816917 -107.595935)
		(end 106.818176 -107.594654)
		(width 0.1016)
		(layer "F.Cu")
		(net "SAS_HDD_TX11_N")
	)
	(arc
		(start 106.818176 -107.594654)
		(mid 106.81933 -107.593394)
		(end 106.820462 -107.592114)
		(width 0.1016)
		(layer "F.Cu")
		(net "SAS_HDD_TX11_N")
	)
	(arc
		(start 101.88702 -113.182146)
		(mid 102.007614 -112.575788)
		(end 102.351078 -112.061752)
		(width 0.1016)
		(layer "F.Cu")
		(net "SAS_HDD_TX11_N")
	)
	(segment
		(start 140.10005 -55.222902)
		(end 139.71905 -54.841902)
		(width 0.1143)
		(layer "F.Cu")
		(net "XM_DATA_13")
	)
	(segment
		(start 140.10005 -59.050428)
		(end 140.10005 -55.222902)
		(width 0.1143)
		(layer "F.Cu")
		(net "XM_DATA_13")
	)
	(segment
		(start 115.039394 -51.799998)
		(end 115.043966 -51.795426)
		(width 0.1143)
		(layer "F.Cu")
		(net "XM_DATA_13")
	)
	(segment
		(start 140.098526 -61.9379)
		(end 140.098526 -59.051952)
		(width 0.1143)
		(layer "F.Cu")
		(net "XM_DATA_13")
	)
	(segment
		(start 115.043966 -51.795426)
		(end 115.043966 -51.7906)
		(width 0.1143)
		(layer "F.Cu")
		(net "XM_DATA_13")
	)
	(segment
		(start 113.949988 -51.799998)
		(end 115.039394 -51.799998)
		(width 0.1143)
		(layer "F.Cu")
		(net "XM_DATA_13")
	)
	(segment
		(start 140.098526 -59.051952)
		(end 140.10005 -59.050428)
		(width 0.1143)
		(layer "F.Cu")
		(net "XM_DATA_13")
	)
	(via
		(at 115.043966 -51.7906)
		(size 0.508)
		(drill 0.254)
		(layers "F.Cu" "B.Cu")
		(net "XM_DATA_13")
	)
	(via
		(at 139.71905 -54.841902)
		(size 0.5588)
		(drill 0.3048)
		(layers "F.Cu" "B.Cu")
		(net "XM_DATA_13")
	)
	(via
		(at 139.71905 -53.975)
		(size 0.7112)
		(drill 0.3556)
		(layers "F.Cu" "B.Cu")
		(net "XM_DATA_13")
	)
	(segment
		(start 134.32536 -53.2003)
		(end 134.21106 -53.086)
		(width 0.1143)
		(layer "B.Cu")
		(net "XM_DATA_13")
	)
	(segment
		(start 133.86816 -53.2003)
		(end 133.86816 -54.0766)
		(width 0.1143)
		(layer "B.Cu")
		(net "XM_DATA_13")
	)
	(segment
		(start 113.411 -51.7906)
		(end 115.043966 -51.7906)
		(width 0.1143)
		(layer "B.Cu")
		(net "XM_DATA_13")
	)
	(segment
		(start 134.43966 -54.1909)
		(end 134.32536 -54.0766)
		(width 0.1143)
		(layer "B.Cu")
		(net "XM_DATA_13")
	)
	(segment
		(start 138.60145 -53.0733)
		(end 138.48715 -52.959)
		(width 0.1143)
		(layer "B.Cu")
		(net "XM_DATA_13")
	)
	(segment
		(start 139.71905 -53.975)
		(end 139.71905 -53.086)
		(width 0.1143)
		(layer "B.Cu")
		(net "XM_DATA_13")
	)
	(segment
		(start 113.411 -52.487576)
		(end 113.284 -52.360576)
		(width 0.1143)
		(layer "B.Cu")
		(net "XM_DATA_13")
	)
	(segment
		(start 138.48715 -52.959)
		(end 137.033 -52.959)
		(width 0.1143)
		(layer "B.Cu")
		(net "XM_DATA_13")
	)
	(segment
		(start 133.98246 -53.086)
		(end 133.86816 -53.2003)
		(width 0.1143)
		(layer "B.Cu")
		(net "XM_DATA_13")
	)
	(segment
		(start 116.675916 -52.360576)
		(end 116.675916 -52.356004)
		(width 0.1143)
		(layer "B.Cu")
		(net "XM_DATA_13")
	)
	(segment
		(start 139.05865 -53.0733)
		(end 139.05865 -53.467)
		(width 0.1143)
		(layer "B.Cu")
		(net "XM_DATA_13")
	)
	(segment
		(start 133.41096 -54.0766)
		(end 133.41096 -53.2003)
		(width 0.1143)
		(layer "B.Cu")
		(net "XM_DATA_13")
	)
	(segment
		(start 138.60145 -53.467)
		(end 138.60145 -53.0733)
		(width 0.1143)
		(layer "B.Cu")
		(net "XM_DATA_13")
	)
	(segment
		(start 134.78256 -53.2003)
		(end 134.78256 -54.0766)
		(width 0.1143)
		(layer "B.Cu")
		(net "XM_DATA_13")
	)
	(segment
		(start 134.32536 -54.0766)
		(end 134.32536 -53.2003)
		(width 0.1143)
		(layer "B.Cu")
		(net "XM_DATA_13")
	)
	(segment
		(start 139.71905 -54.841902)
		(end 139.71905 -53.975)
		(width 0.1143)
		(layer "B.Cu")
		(net "XM_DATA_13")
	)
	(segment
		(start 115.850416 -52.360576)
		(end 115.723416 -52.487576)
		(width 0.1143)
		(layer "B.Cu")
		(net "XM_DATA_13")
	)
	(segment
		(start 136.906 -53.086)
		(end 134.89686 -53.086)
		(width 0.1143)
		(layer "B.Cu")
		(net "XM_DATA_13")
	)
	(segment
		(start 134.78256 -54.0766)
		(end 134.66826 -54.1909)
		(width 0.1143)
		(layer "B.Cu")
		(net "XM_DATA_13")
	)
	(segment
		(start 138.72845 -53.594)
		(end 138.60145 -53.467)
		(width 0.1143)
		(layer "B.Cu")
		(net "XM_DATA_13")
	)
	(segment
		(start 134.66826 -54.1909)
		(end 134.43966 -54.1909)
		(width 0.1143)
		(layer "B.Cu")
		(net "XM_DATA_13")
	)
	(segment
		(start 133.29666 -53.086)
		(end 119.507 -53.086)
		(width 0.1143)
		(layer "B.Cu")
		(net "XM_DATA_13")
	)
	(segment
		(start 116.09197 -52.11445)
		(end 115.850416 -52.356004)
		(width 0.1143)
		(layer "B.Cu")
		(net "XM_DATA_13")
	)
	(segment
		(start 133.86816 -54.0766)
		(end 133.75386 -54.1909)
		(width 0.1143)
		(layer "B.Cu")
		(net "XM_DATA_13")
	)
	(segment
		(start 139.17295 -52.959)
		(end 139.05865 -53.0733)
		(width 0.1143)
		(layer "B.Cu")
		(net "XM_DATA_13")
	)
	(segment
		(start 134.89686 -53.086)
		(end 134.78256 -53.2003)
		(width 0.1143)
		(layer "B.Cu")
		(net "XM_DATA_13")
	)
	(segment
		(start 133.52526 -54.1909)
		(end 133.41096 -54.0766)
		(width 0.1143)
		(layer "B.Cu")
		(net "XM_DATA_13")
	)
	(segment
		(start 119.507 -53.086)
		(end 118.908576 -52.487576)
		(width 0.1143)
		(layer "B.Cu")
		(net "XM_DATA_13")
	)
	(segment
		(start 115.850416 -52.356004)
		(end 115.850416 -52.360576)
		(width 0.1143)
		(layer "B.Cu")
		(net "XM_DATA_13")
	)
	(segment
		(start 113.284 -51.9176)
		(end 113.411 -51.7906)
		(width 0.1143)
		(layer "B.Cu")
		(net "XM_DATA_13")
	)
	(segment
		(start 139.05865 -53.467)
		(end 138.93165 -53.594)
		(width 0.1143)
		(layer "B.Cu")
		(net "XM_DATA_13")
	)
	(segment
		(start 133.41096 -53.2003)
		(end 133.29666 -53.086)
		(width 0.1143)
		(layer "B.Cu")
		(net "XM_DATA_13")
	)
	(segment
		(start 137.033 -52.959)
		(end 136.906 -53.086)
		(width 0.1143)
		(layer "B.Cu")
		(net "XM_DATA_13")
	)
	(segment
		(start 118.908576 -52.487576)
		(end 116.802916 -52.487576)
		(width 0.1143)
		(layer "B.Cu")
		(net "XM_DATA_13")
	)
	(segment
		(start 138.93165 -53.594)
		(end 138.72845 -53.594)
		(width 0.1143)
		(layer "B.Cu")
		(net "XM_DATA_13")
	)
	(segment
		(start 134.21106 -53.086)
		(end 133.98246 -53.086)
		(width 0.1143)
		(layer "B.Cu")
		(net "XM_DATA_13")
	)
	(segment
		(start 116.675916 -52.356004)
		(end 116.434362 -52.11445)
		(width 0.1143)
		(layer "B.Cu")
		(net "XM_DATA_13")
	)
	(segment
		(start 139.71905 -53.086)
		(end 139.59205 -52.959)
		(width 0.1143)
		(layer "B.Cu")
		(net "XM_DATA_13")
	)
	(segment
		(start 116.802916 -52.487576)
		(end 116.675916 -52.360576)
		(width 0.1143)
		(layer "B.Cu")
		(net "XM_DATA_13")
	)
	(segment
		(start 113.284 -52.360576)
		(end 113.284 -51.9176)
		(width 0.1143)
		(layer "B.Cu")
		(net "XM_DATA_13")
	)
	(segment
		(start 133.75386 -54.1909)
		(end 133.52526 -54.1909)
		(width 0.1143)
		(layer "B.Cu")
		(net "XM_DATA_13")
	)
	(segment
		(start 116.434362 -52.11445)
		(end 116.09197 -52.11445)
		(width 0.1143)
		(layer "B.Cu")
		(net "XM_DATA_13")
	)
	(segment
		(start 115.723416 -52.487576)
		(end 113.411 -52.487576)
		(width 0.1143)
		(layer "B.Cu")
		(net "XM_DATA_13")
	)
	(segment
		(start 139.59205 -52.959)
		(end 139.17295 -52.959)
		(width 0.1143)
		(layer "B.Cu")
		(net "XM_DATA_13")
	)
	(segment
		(start 85.703664 -36.81095)
		(end 82.353404 -36.81095)
		(width 0.1016)
		(layer "F.Cu")
		(net "SAS3008_RAID_TX_P2")
	)
	(segment
		(start 86.21776 -36.957)
		(end 85.934042 -36.957)
		(width 0.1016)
		(layer "F.Cu")
		(net "SAS3008_RAID_TX_P2")
	)
	(segment
		(start 82.281776 -36.840668)
		(end 82.156554 -36.965382)
		(width 0.1016)
		(layer "F.Cu")
		(net "SAS3008_RAID_TX_P2")
	)
	(segment
		(start 85.86216 -36.927282)
		(end 85.775546 -36.840668)
		(width 0.1016)
		(layer "F.Cu")
		(net "SAS3008_RAID_TX_P2")
	)
	(segment
		(start 81.516474 -37.024818)
		(end 81.2292 -37.312092)
		(width 0.1016)
		(layer "F.Cu")
		(net "SAS3008_RAID_TX_P2")
	)
	(segment
		(start 82.084926 -36.9951)
		(end 81.588356 -36.9951)
		(width 0.1016)
		(layer "F.Cu")
		(net "SAS3008_RAID_TX_P2")
	)
	(segment
		(start 123.35002 -84.349844)
		(end 123.850146 -83.849718)
		(width 0.1016)
		(layer "F.Cu")
		(net "SAS3008_RAID_TX_P2")
	)
	(via
		(at 81.2292 -37.312092)
		(size 0.5588)
		(drill 0.3048)
		(layers "F.Cu" "B.Cu")
		(net "SAS3008_RAID_TX_P2")
	)
	(via
		(at 123.850146 -83.849718)
		(size 0.508)
		(drill 0.254)
		(layers "F.Cu" "B.Cu")
		(net "SAS3008_RAID_TX_P2")
	)
	(via
		(at 80.580992 -39.624)
		(size 0.5588)
		(drill 0.254)
		(layers "F.Cu" "B.Cu")
		(net "SAS3008_RAID_TX_P2")
	)
	(via
		(at 128.131062 -79.8068)
		(size 0.5588)
		(drill 0.3048)
		(layers "F.Cu" "B.Cu")
		(net "SAS3008_RAID_TX_P2")
	)
	(arc
		(start 85.934042 -36.957)
		(mid 85.895147 -36.949281)
		(end 85.86216 -36.927282)
		(width 0.1016)
		(layer "F.Cu")
		(net "SAS3008_RAID_TX_P2")
	)
	(arc
		(start 81.588356 -36.9951)
		(mid 81.549461 -37.002819)
		(end 81.516474 -37.024818)
		(width 0.1016)
		(layer "F.Cu")
		(net "SAS3008_RAID_TX_P2")
	)
	(arc
		(start 82.156554 -36.965382)
		(mid 82.123692 -36.98737)
		(end 82.084926 -36.9951)
		(width 0.1016)
		(layer "F.Cu")
		(net "SAS3008_RAID_TX_P2")
	)
	(arc
		(start 82.353404 -36.81095)
		(mid 82.31466 -36.818732)
		(end 82.281776 -36.840668)
		(width 0.1016)
		(layer "F.Cu")
		(net "SAS3008_RAID_TX_P2")
	)
	(arc
		(start 85.775546 -36.840668)
		(mid 85.742552 -36.818685)
		(end 85.703664 -36.81095)
		(width 0.1016)
		(layer "F.Cu")
		(net "SAS3008_RAID_TX_P2")
	)
	(segment
		(start 125.332236 -82.761074)
		(end 125.702568 -82.6008)
		(width 0.1016)
		(layer "B.Cu")
		(net "SAS3008_RAID_TX_P2")
	)
	(segment
		(start 127.7874 -82.042)
		(end 127.7874 -80.2132)
		(width 0.1016)
		(layer "B.Cu")
		(net "SAS3008_RAID_TX_P2")
	)
	(segment
		(start 80.941926 -37.024818)
		(end 81.2292 -37.312092)
		(width 0.1016)
		(layer "B.Cu")
		(net "SAS3008_RAID_TX_P2")
	)
	(segment
		(start 123.850146 -83.849718)
		(end 124.005594 -83.693762)
		(width 0.1016)
		(layer "B.Cu")
		(net "SAS3008_RAID_TX_P2")
	)
	(segment
		(start 124.06757 -83.6676)
		(end 124.118624 -83.6676)
		(width 0.1016)
		(layer "B.Cu")
		(net "SAS3008_RAID_TX_P2")
	)
	(segment
		(start 124.641102 -83.452208)
		(end 125.332236 -82.761074)
		(width 0.1016)
		(layer "B.Cu")
		(net "SAS3008_RAID_TX_P2")
	)
	(segment
		(start 80.580992 -39.624)
		(end 80.258412 -39.30142)
		(width 0.1016)
		(layer "B.Cu")
		(net "SAS3008_RAID_TX_P2")
	)
	(segment
		(start 80.2132 -39.1922)
		(end 80.2132 -37.2491)
		(width 0.1016)
		(layer "B.Cu")
		(net "SAS3008_RAID_TX_P2")
	)
	(segment
		(start 124.005594 -83.693762)
		(end 124.007118 -83.692492)
		(width 0.1016)
		(layer "B.Cu")
		(net "SAS3008_RAID_TX_P2")
	)
	(segment
		(start 125.702568 -82.6008)
		(end 127.2286 -82.6008)
		(width 0.1016)
		(layer "B.Cu")
		(net "SAS3008_RAID_TX_P2")
	)
	(segment
		(start 80.4672 -36.9951)
		(end 80.870044 -36.9951)
		(width 0.1016)
		(layer "B.Cu")
		(net "SAS3008_RAID_TX_P2")
	)
	(arc
		(start 124.118624 -83.6676)
		(mid 124.401193 -83.611642)
		(end 124.641102 -83.452208)
		(width 0.1016)
		(layer "B.Cu")
		(net "SAS3008_RAID_TX_P2")
	)
	(arc
		(start 80.870044 -36.9951)
		(mid 80.908939 -37.002819)
		(end 80.941926 -37.024818)
		(width 0.1016)
		(layer "B.Cu")
		(net "SAS3008_RAID_TX_P2")
	)
	(arc
		(start 80.258412 -39.30142)
		(mid 80.224929 -39.251309)
		(end 80.2132 -39.1922)
		(width 0.1016)
		(layer "B.Cu")
		(net "SAS3008_RAID_TX_P2")
	)
	(arc
		(start 80.2132 -37.2491)
		(mid 80.287595 -37.069495)
		(end 80.4672 -36.9951)
		(width 0.1016)
		(layer "B.Cu")
		(net "SAS3008_RAID_TX_P2")
	)
	(arc
		(start 124.007118 -83.692492)
		(mid 124.034869 -83.674043)
		(end 124.06757 -83.6676)
		(width 0.1016)
		(layer "B.Cu")
		(net "SAS3008_RAID_TX_P2")
	)
	(arc
		(start 127.7874 -80.2132)
		(mid 127.884823 -79.947056)
		(end 128.131062 -79.8068)
		(width 0.1016)
		(layer "B.Cu")
		(net "SAS3008_RAID_TX_P2")
	)
	(arc
		(start 127.2286 -82.6008)
		(mid 127.623731 -82.437131)
		(end 127.7874 -82.042)
		(width 0.1016)
		(layer "B.Cu")
		(net "SAS3008_RAID_TX_P2")
	)
	(segment
		(start 92.715842 -59.459876)
		(end 95.081852 -61.825886)
		(width 0.1016)
		(layer "In2.Cu")
		(net "SAS3008_RAID_TX_P2")
	)
	(segment
		(start 98.077528 -64.821562)
		(end 98.390456 -65.13449)
		(width 0.1016)
		(layer "In2.Cu")
		(net "SAS3008_RAID_TX_P2")
	)
	(segment
		(start 102.848156 -67.564)
		(end 104.14 -67.564)
		(width 0.1016)
		(layer "In2.Cu")
		(net "SAS3008_RAID_TX_P2")
	)
	(segment
		(start 91.270074 -57.694322)
		(end 91.48572 -57.909968)
		(width 0.1016)
		(layer "In2.Cu")
		(net "SAS3008_RAID_TX_P2")
	)
	(segment
		(start 108.965746 -70.6374)
		(end 115.951 -70.6374)
		(width 0.1016)
		(layer "In2.Cu")
		(net "SAS3008_RAID_TX_P2")
	)
	(segment
		(start 91.645486 -58.38952)
		(end 91.860878 -58.604912)
		(width 0.1016)
		(layer "In2.Cu")
		(net "SAS3008_RAID_TX_P2")
	)
	(segment
		(start 127.80137 -75.655424)
		(end 127.80137 -76.105766)
		(width 0.1016)
		(layer "In2.Cu")
		(net "SAS3008_RAID_TX_P2")
	)
	(segment
		(start 100.804218 -65.879218)
		(end 102.235 -67.31)
		(width 0.1016)
		(layer "In2.Cu")
		(net "SAS3008_RAID_TX_P2")
	)
	(segment
		(start 82.505042 -48.92929)
		(end 82.720688 -49.144936)
		(width 0.1016)
		(layer "In2.Cu")
		(net "SAS3008_RAID_TX_P2")
	)
	(segment
		(start 128.02743 -76.557886)
		(end 128.02743 -76.862686)
		(width 0.1016)
		(layer "In2.Cu")
		(net "SAS3008_RAID_TX_P2")
	)
	(segment
		(start 97.702116 -64.126618)
		(end 97.917762 -64.34201)
		(width 0.1016)
		(layer "In2.Cu")
		(net "SAS3008_RAID_TX_P2")
	)
	(segment
		(start 80.305402 -47.04969)
		(end 82.025236 -48.769524)
		(width 0.1016)
		(layer "In2.Cu")
		(net "SAS3008_RAID_TX_P2")
	)
	(segment
		(start 119.409464 -72.7456)
		(end 124.784104 -72.7456)
		(width 0.1016)
		(layer "In2.Cu")
		(net "SAS3008_RAID_TX_P2")
	)
	(segment
		(start 116.81587 -70.995794)
		(end 117.969538 -72.148954)
		(width 0.1016)
		(layer "In2.Cu")
		(net "SAS3008_RAID_TX_P2")
	)
	(segment
		(start 90.57513 -57.319164)
		(end 90.790522 -57.534556)
		(width 0.1016)
		(layer "In2.Cu")
		(net "SAS3008_RAID_TX_P2")
	)
	(segment
		(start 80.245966 -44.501816)
		(end 80.245966 -44.806616)
		(width 0.1016)
		(layer "In2.Cu")
		(net "SAS3008_RAID_TX_P2")
	)
	(segment
		(start 83.95081 -50.694844)
		(end 84.166456 -50.91049)
		(width 0.1016)
		(layer "In2.Cu")
		(net "SAS3008_RAID_TX_P2")
	)
	(segment
		(start 97.007172 -63.751206)
		(end 97.222564 -63.966598)
		(width 0.1016)
		(layer "In2.Cu")
		(net "SAS3008_RAID_TX_P2")
	)
	(segment
		(start 82.025236 -48.769524)
		(end 82.02549 -48.769524)
		(width 0.1016)
		(layer "In2.Cu")
		(net "SAS3008_RAID_TX_P2")
	)
	(segment
		(start 96.63176 -63.056008)
		(end 96.847406 -63.271654)
		(width 0.1016)
		(layer "In2.Cu")
		(net "SAS3008_RAID_TX_P2")
	)
	(segment
		(start 85.02142 -51.765454)
		(end 89.720166 -56.4642)
		(width 0.1016)
		(layer "In2.Cu")
		(net "SAS3008_RAID_TX_P2")
	)
	(segment
		(start 80.472026 -42.231056)
		(end 80.472026 -42.535856)
		(width 0.1016)
		(layer "In2.Cu")
		(net "SAS3008_RAID_TX_P2")
	)
	(segment
		(start 80.245966 -42.987976)
		(end 80.245966 -43.292776)
		(width 0.1016)
		(layer "In2.Cu")
		(net "SAS3008_RAID_TX_P2")
	)
	(segment
		(start 98.675698 -65.2526)
		(end 99.291394 -65.2526)
		(width 0.1016)
		(layer "In2.Cu")
		(net "SAS3008_RAID_TX_P2")
	)
	(segment
		(start 92.34043 -58.764932)
		(end 92.556076 -58.980324)
		(width 0.1016)
		(layer "In2.Cu")
		(net "SAS3008_RAID_TX_P2")
	)
	(segment
		(start 127.945388 -79.621126)
		(end 128.131062 -79.8068)
		(width 0.1016)
		(layer "In2.Cu")
		(net "SAS3008_RAID_TX_P2")
	)
	(segment
		(start 80.472026 -43.744896)
		(end 80.472026 -44.049696)
		(width 0.1016)
		(layer "In2.Cu")
		(net "SAS3008_RAID_TX_P2")
	)
	(segment
		(start 80.245966 -40.132)
		(end 80.245966 -41.778936)
		(width 0.1016)
		(layer "In2.Cu")
		(net "SAS3008_RAID_TX_P2")
	)
	(segment
		(start 80.580992 -39.624)
		(end 80.368394 -39.836852)
		(width 0.1016)
		(layer "In2.Cu")
		(net "SAS3008_RAID_TX_P2")
	)
	(segment
		(start 82.880454 -49.624488)
		(end 83.0961 -49.840134)
		(width 0.1016)
		(layer "In2.Cu")
		(net "SAS3008_RAID_TX_P2")
	)
	(segment
		(start 127.80137 -77.314806)
		(end 127.80137 -79.2734)
		(width 0.1016)
		(layer "In2.Cu")
		(net "SAS3008_RAID_TX_P2")
	)
	(segment
		(start 83.575398 -49.9999)
		(end 83.791044 -50.215292)
		(width 0.1016)
		(layer "In2.Cu")
		(net "SAS3008_RAID_TX_P2")
	)
	(segment
		(start 90.199718 -56.623966)
		(end 90.41511 -56.839612)
		(width 0.1016)
		(layer "In2.Cu")
		(net "SAS3008_RAID_TX_P2")
	)
	(segment
		(start 125.642116 -73.100946)
		(end 127.52197 -74.9808)
		(width 0.1016)
		(layer "In2.Cu")
		(net "SAS3008_RAID_TX_P2")
	)
	(segment
		(start 105.224072 -68.013072)
		(end 107.057952 -69.846952)
		(width 0.1016)
		(layer "In2.Cu")
		(net "SAS3008_RAID_TX_P2")
	)
	(segment
		(start 80.245966 -46.015656)
		(end 80.245966 -46.90618)
		(width 0.1016)
		(layer "In2.Cu")
		(net "SAS3008_RAID_TX_P2")
	)
	(segment
		(start 95.936816 -62.68085)
		(end 96.152208 -62.896242)
		(width 0.1016)
		(layer "In2.Cu")
		(net "SAS3008_RAID_TX_P2")
	)
	(segment
		(start 80.472026 -45.258736)
		(end 80.472026 -45.563536)
		(width 0.1016)
		(layer "In2.Cu")
		(net "SAS3008_RAID_TX_P2")
	)
	(segment
		(start 95.561404 -61.985652)
		(end 95.776796 -62.201298)
		(width 0.1016)
		(layer "In2.Cu")
		(net "SAS3008_RAID_TX_P2")
	)
	(segment
		(start 84.646008 -51.070256)
		(end 84.8614 -51.285902)
		(width 0.1016)
		(layer "In2.Cu")
		(net "SAS3008_RAID_TX_P2")
	)
	(arc
		(start 127.80137 -79.2734)
		(mid 127.838802 -79.461582)
		(end 127.945388 -79.621126)
		(width 0.1016)
		(layer "In2.Cu")
		(net "SAS3008_RAID_TX_P2")
	)
	(arc
		(start 107.057952 -69.846952)
		(mid 107.933239 -70.431923)
		(end 108.965746 -70.6374)
		(width 0.1016)
		(layer "In2.Cu")
		(net "SAS3008_RAID_TX_P2")
	)
	(arc
		(start 82.095848 -48.821594)
		(mid 82.178337 -48.849007)
		(end 82.265266 -48.849534)
		(width 0.1016)
		(layer "In2.Cu")
		(net "SAS3008_RAID_TX_P2")
	)
	(arc
		(start 82.800444 -49.384712)
		(mid 82.811487 -49.514269)
		(end 82.880454 -49.624488)
		(width 0.1016)
		(layer "In2.Cu")
		(net "SAS3008_RAID_TX_P2")
	)
	(arc
		(start 80.358996 -43.518836)
		(mid 80.442833 -43.618212)
		(end 80.472026 -43.744896)
		(width 0.1016)
		(layer "In2.Cu")
		(net "SAS3008_RAID_TX_P2")
	)
	(arc
		(start 97.917762 -64.34201)
		(mid 97.986696 -64.45224)
		(end 97.997772 -64.581786)
		(width 0.1016)
		(layer "In2.Cu")
		(net "SAS3008_RAID_TX_P2")
	)
	(arc
		(start 92.556076 -58.980324)
		(mid 92.62501 -59.090554)
		(end 92.636086 -59.2201)
		(width 0.1016)
		(layer "In2.Cu")
		(net "SAS3008_RAID_TX_P2")
	)
	(arc
		(start 82.265266 -48.849534)
		(mid 82.394788 -48.860451)
		(end 82.505042 -48.92929)
		(width 0.1016)
		(layer "In2.Cu")
		(net "SAS3008_RAID_TX_P2")
	)
	(arc
		(start 80.358996 -44.275756)
		(mid 80.275159 -44.375132)
		(end 80.245966 -44.501816)
		(width 0.1016)
		(layer "In2.Cu")
		(net "SAS3008_RAID_TX_P2")
	)
	(arc
		(start 97.997772 -64.581786)
		(mid 98.008519 -64.710796)
		(end 98.076766 -64.8208)
		(width 0.1016)
		(layer "In2.Cu")
		(net "SAS3008_RAID_TX_P2")
	)
	(arc
		(start 80.358996 -42.761916)
		(mid 80.275159 -42.861292)
		(end 80.245966 -42.987976)
		(width 0.1016)
		(layer "In2.Cu")
		(net "SAS3008_RAID_TX_P2")
	)
	(arc
		(start 80.472026 -42.535856)
		(mid 80.442787 -42.662517)
		(end 80.358996 -42.761916)
		(width 0.1016)
		(layer "In2.Cu")
		(net "SAS3008_RAID_TX_P2")
	)
	(arc
		(start 83.871054 -50.455068)
		(mid 83.881971 -50.58459)
		(end 83.95081 -50.694844)
		(width 0.1016)
		(layer "In2.Cu")
		(net "SAS3008_RAID_TX_P2")
	)
	(arc
		(start 92.636086 -59.2201)
		(mid 92.647003 -59.349622)
		(end 92.715842 -59.459876)
		(width 0.1016)
		(layer "In2.Cu")
		(net "SAS3008_RAID_TX_P2")
	)
	(arc
		(start 99.291394 -65.2526)
		(mid 100.110123 -65.415455)
		(end 100.804218 -65.879218)
		(width 0.1016)
		(layer "In2.Cu")
		(net "SAS3008_RAID_TX_P2")
	)
	(arc
		(start 91.565476 -58.149744)
		(mid 91.576519 -58.279301)
		(end 91.645486 -58.38952)
		(width 0.1016)
		(layer "In2.Cu")
		(net "SAS3008_RAID_TX_P2")
	)
	(arc
		(start 82.02549 -48.769524)
		(mid 82.0586 -48.798355)
		(end 82.095848 -48.821594)
		(width 0.1016)
		(layer "In2.Cu")
		(net "SAS3008_RAID_TX_P2")
	)
	(arc
		(start 128.02743 -76.862686)
		(mid 127.998191 -76.989347)
		(end 127.9144 -77.088746)
		(width 0.1016)
		(layer "In2.Cu")
		(net "SAS3008_RAID_TX_P2")
	)
	(arc
		(start 90.49512 -57.079388)
		(mid 90.50617 -57.208933)
		(end 90.57513 -57.319164)
		(width 0.1016)
		(layer "In2.Cu")
		(net "SAS3008_RAID_TX_P2")
	)
	(arc
		(start 80.472026 -45.563536)
		(mid 80.442787 -45.690197)
		(end 80.358996 -45.789596)
		(width 0.1016)
		(layer "In2.Cu")
		(net "SAS3008_RAID_TX_P2")
	)
	(arc
		(start 91.48572 -57.909968)
		(mid 91.554556 -58.020223)
		(end 91.565476 -58.149744)
		(width 0.1016)
		(layer "In2.Cu")
		(net "SAS3008_RAID_TX_P2")
	)
	(arc
		(start 80.245966 -43.292776)
		(mid 80.275205 -43.419437)
		(end 80.358996 -43.518836)
		(width 0.1016)
		(layer "In2.Cu")
		(net "SAS3008_RAID_TX_P2")
	)
	(arc
		(start 80.358996 -42.004996)
		(mid 80.442833 -42.104372)
		(end 80.472026 -42.231056)
		(width 0.1016)
		(layer "In2.Cu")
		(net "SAS3008_RAID_TX_P2")
	)
	(arc
		(start 95.321628 -61.905642)
		(mid 95.451185 -61.916685)
		(end 95.561404 -61.985652)
		(width 0.1016)
		(layer "In2.Cu")
		(net "SAS3008_RAID_TX_P2")
	)
	(arc
		(start 95.776796 -62.201298)
		(mid 95.845793 -62.311517)
		(end 95.856806 -62.441074)
		(width 0.1016)
		(layer "In2.Cu")
		(net "SAS3008_RAID_TX_P2")
	)
	(arc
		(start 80.245966 -41.778936)
		(mid 80.275205 -41.905597)
		(end 80.358996 -42.004996)
		(width 0.1016)
		(layer "In2.Cu")
		(net "SAS3008_RAID_TX_P2")
	)
	(arc
		(start 80.245966 -46.90618)
		(mid 80.261414 -46.983844)
		(end 80.305402 -47.04969)
		(width 0.1016)
		(layer "In2.Cu")
		(net "SAS3008_RAID_TX_P2")
	)
	(arc
		(start 97.46234 -64.046608)
		(mid 97.591885 -64.057658)
		(end 97.702116 -64.126618)
		(width 0.1016)
		(layer "In2.Cu")
		(net "SAS3008_RAID_TX_P2")
	)
	(arc
		(start 80.368394 -39.836852)
		(mid 80.27783 -39.972252)
		(end 80.245966 -40.132)
		(width 0.1016)
		(layer "In2.Cu")
		(net "SAS3008_RAID_TX_P2")
	)
	(arc
		(start 96.847406 -63.271654)
		(mid 96.916242 -63.381909)
		(end 96.927162 -63.51143)
		(width 0.1016)
		(layer "In2.Cu")
		(net "SAS3008_RAID_TX_P2")
	)
	(arc
		(start 96.391984 -62.976252)
		(mid 96.521506 -62.987169)
		(end 96.63176 -63.056008)
		(width 0.1016)
		(layer "In2.Cu")
		(net "SAS3008_RAID_TX_P2")
	)
	(arc
		(start 97.222564 -63.966598)
		(mid 97.332783 -64.035595)
		(end 97.46234 -64.046608)
		(width 0.1016)
		(layer "In2.Cu")
		(net "SAS3008_RAID_TX_P2")
	)
	(arc
		(start 117.969538 -72.148954)
		(mid 118.630138 -72.590572)
		(end 119.409464 -72.7456)
		(width 0.1016)
		(layer "In2.Cu")
		(net "SAS3008_RAID_TX_P2")
	)
	(arc
		(start 82.720688 -49.144936)
		(mid 82.789524 -49.255191)
		(end 82.800444 -49.384712)
		(width 0.1016)
		(layer "In2.Cu")
		(net "SAS3008_RAID_TX_P2")
	)
	(arc
		(start 89.720166 -56.4642)
		(mid 89.830421 -56.533036)
		(end 89.959942 -56.543956)
		(width 0.1016)
		(layer "In2.Cu")
		(net "SAS3008_RAID_TX_P2")
	)
	(arc
		(start 96.927162 -63.51143)
		(mid 96.938205 -63.640987)
		(end 97.007172 -63.751206)
		(width 0.1016)
		(layer "In2.Cu")
		(net "SAS3008_RAID_TX_P2")
	)
	(arc
		(start 84.8614 -51.285902)
		(mid 84.930397 -51.396121)
		(end 84.94141 -51.525678)
		(width 0.1016)
		(layer "In2.Cu")
		(net "SAS3008_RAID_TX_P2")
	)
	(arc
		(start 127.52197 -74.9808)
		(mid 127.72876 -75.290334)
		(end 127.80137 -75.655424)
		(width 0.1016)
		(layer "In2.Cu")
		(net "SAS3008_RAID_TX_P2")
	)
	(arc
		(start 83.0961 -49.840134)
		(mid 83.206236 -49.90893)
		(end 83.335622 -49.91989)
		(width 0.1016)
		(layer "In2.Cu")
		(net "SAS3008_RAID_TX_P2")
	)
	(arc
		(start 83.791044 -50.215292)
		(mid 83.859978 -50.325522)
		(end 83.871054 -50.455068)
		(width 0.1016)
		(layer "In2.Cu")
		(net "SAS3008_RAID_TX_P2")
	)
	(arc
		(start 90.790522 -57.534556)
		(mid 90.900752 -57.60349)
		(end 91.030298 -57.614566)
		(width 0.1016)
		(layer "In2.Cu")
		(net "SAS3008_RAID_TX_P2")
	)
	(arc
		(start 84.166456 -50.91049)
		(mid 84.276686 -50.979424)
		(end 84.406232 -50.9905)
		(width 0.1016)
		(layer "In2.Cu")
		(net "SAS3008_RAID_TX_P2")
	)
	(arc
		(start 84.94141 -51.525678)
		(mid 84.95246 -51.655223)
		(end 85.02142 -51.765454)
		(width 0.1016)
		(layer "In2.Cu")
		(net "SAS3008_RAID_TX_P2")
	)
	(arc
		(start 98.390456 -65.13449)
		(mid 98.521326 -65.221935)
		(end 98.675698 -65.2526)
		(width 0.1016)
		(layer "In2.Cu")
		(net "SAS3008_RAID_TX_P2")
	)
	(arc
		(start 95.081852 -61.825886)
		(mid 95.192107 -61.894722)
		(end 95.321628 -61.905642)
		(width 0.1016)
		(layer "In2.Cu")
		(net "SAS3008_RAID_TX_P2")
	)
	(arc
		(start 80.245966 -44.806616)
		(mid 80.275205 -44.933277)
		(end 80.358996 -45.032676)
		(width 0.1016)
		(layer "In2.Cu")
		(net "SAS3008_RAID_TX_P2")
	)
	(arc
		(start 91.030298 -57.614566)
		(mid 91.15982 -57.625483)
		(end 91.270074 -57.694322)
		(width 0.1016)
		(layer "In2.Cu")
		(net "SAS3008_RAID_TX_P2")
	)
	(arc
		(start 95.856806 -62.441074)
		(mid 95.867856 -62.570619)
		(end 95.936816 -62.68085)
		(width 0.1016)
		(layer "In2.Cu")
		(net "SAS3008_RAID_TX_P2")
	)
	(arc
		(start 102.235 -67.31)
		(mid 102.516318 -67.497971)
		(end 102.848156 -67.564)
		(width 0.1016)
		(layer "In2.Cu")
		(net "SAS3008_RAID_TX_P2")
	)
	(arc
		(start 127.9144 -77.088746)
		(mid 127.830563 -77.188122)
		(end 127.80137 -77.314806)
		(width 0.1016)
		(layer "In2.Cu")
		(net "SAS3008_RAID_TX_P2")
	)
	(arc
		(start 89.959942 -56.543956)
		(mid 90.089499 -56.554999)
		(end 90.199718 -56.623966)
		(width 0.1016)
		(layer "In2.Cu")
		(net "SAS3008_RAID_TX_P2")
	)
	(arc
		(start 115.951 -70.6374)
		(mid 116.419069 -70.730598)
		(end 116.81587 -70.995794)
		(width 0.1016)
		(layer "In2.Cu")
		(net "SAS3008_RAID_TX_P2")
	)
	(arc
		(start 124.784104 -72.7456)
		(mid 125.248411 -72.838014)
		(end 125.642116 -73.100946)
		(width 0.1016)
		(layer "In2.Cu")
		(net "SAS3008_RAID_TX_P2")
	)
	(arc
		(start 104.14 -67.564)
		(mid 104.726709 -67.680704)
		(end 105.224072 -68.013072)
		(width 0.1016)
		(layer "In2.Cu")
		(net "SAS3008_RAID_TX_P2")
	)
	(arc
		(start 80.358996 -45.032676)
		(mid 80.442833 -45.132052)
		(end 80.472026 -45.258736)
		(width 0.1016)
		(layer "In2.Cu")
		(net "SAS3008_RAID_TX_P2")
	)
	(arc
		(start 84.406232 -50.9905)
		(mid 84.535754 -51.001417)
		(end 84.646008 -51.070256)
		(width 0.1016)
		(layer "In2.Cu")
		(net "SAS3008_RAID_TX_P2")
	)
	(arc
		(start 127.9144 -76.331826)
		(mid 127.998237 -76.431202)
		(end 128.02743 -76.557886)
		(width 0.1016)
		(layer "In2.Cu")
		(net "SAS3008_RAID_TX_P2")
	)
	(arc
		(start 98.076766 -64.8208)
		(mid 98.077147 -64.821181)
		(end 98.077528 -64.821562)
		(width 0.1016)
		(layer "In2.Cu")
		(net "SAS3008_RAID_TX_P2")
	)
	(arc
		(start 83.335622 -49.91989)
		(mid 83.465167 -49.93094)
		(end 83.575398 -49.9999)
		(width 0.1016)
		(layer "In2.Cu")
		(net "SAS3008_RAID_TX_P2")
	)
	(arc
		(start 127.80137 -76.105766)
		(mid 127.830609 -76.232427)
		(end 127.9144 -76.331826)
		(width 0.1016)
		(layer "In2.Cu")
		(net "SAS3008_RAID_TX_P2")
	)
	(arc
		(start 91.860878 -58.604912)
		(mid 91.971097 -58.673909)
		(end 92.100654 -58.684922)
		(width 0.1016)
		(layer "In2.Cu")
		(net "SAS3008_RAID_TX_P2")
	)
	(arc
		(start 80.472026 -44.049696)
		(mid 80.442787 -44.176357)
		(end 80.358996 -44.275756)
		(width 0.1016)
		(layer "In2.Cu")
		(net "SAS3008_RAID_TX_P2")
	)
	(arc
		(start 80.358996 -45.789596)
		(mid 80.275159 -45.888972)
		(end 80.245966 -46.015656)
		(width 0.1016)
		(layer "In2.Cu")
		(net "SAS3008_RAID_TX_P2")
	)
	(arc
		(start 96.152208 -62.896242)
		(mid 96.262438 -62.965176)
		(end 96.391984 -62.976252)
		(width 0.1016)
		(layer "In2.Cu")
		(net "SAS3008_RAID_TX_P2")
	)
	(arc
		(start 92.100654 -58.684922)
		(mid 92.230199 -58.695972)
		(end 92.34043 -58.764932)
		(width 0.1016)
		(layer "In2.Cu")
		(net "SAS3008_RAID_TX_P2")
	)
	(arc
		(start 90.41511 -56.839612)
		(mid 90.484107 -56.949831)
		(end 90.49512 -57.079388)
		(width 0.1016)
		(layer "In2.Cu")
		(net "SAS3008_RAID_TX_P2")
	)
	(segment
		(start 107.302554 -107.386628)
		(end 107.349798 -107.350052)
		(width 0.1016)
		(layer "F.Cu")
		(net "SAS_HDD_TX11_P")
	)
	(segment
		(start 102.22992 -113.487962)
		(end 102.22992 -113.1824)
		(width 0.1016)
		(layer "F.Cu")
		(net "SAS_HDD_TX11_P")
	)
	(segment
		(start 105.32237 -109.575854)
		(end 107.086908 -107.811316)
		(width 0.1016)
		(layer "F.Cu")
		(net "SAS_HDD_TX11_P")
	)
	(segment
		(start 105.322116 -109.575854)
		(end 105.32237 -109.575854)
		(width 0.1016)
		(layer "F.Cu")
		(net "SAS_HDD_TX11_P")
	)
	(segment
		(start 102.37597 -114.0206)
		(end 102.37597 -113.798096)
		(width 0.1016)
		(layer "F.Cu")
		(net "SAS_HDD_TX11_P")
	)
	(segment
		(start 102.593648 -112.304322)
		(end 105.322116 -109.575854)
		(width 0.1016)
		(layer "F.Cu")
		(net "SAS_HDD_TX11_P")
	)
	(segment
		(start 102.303072 -113.62182)
		(end 102.272846 -113.591594)
		(width 0.1016)
		(layer "F.Cu")
		(net "SAS_HDD_TX11_P")
	)
	(arc
		(start 102.37597 -113.798096)
		(mid 102.357033 -113.702713)
		(end 102.303072 -113.62182)
		(width 0.1016)
		(layer "F.Cu")
		(net "SAS_HDD_TX11_P")
	)
	(arc
		(start 107.086908 -107.811316)
		(mid 107.232873 -107.617568)
		(end 107.311698 -107.388152)
		(width 0.1016)
		(layer "F.Cu")
		(net "SAS_HDD_TX11_P")
	)
	(arc
		(start 102.22992 -113.1824)
		(mid 102.324447 -112.707181)
		(end 102.593648 -112.304322)
		(width 0.1016)
		(layer "F.Cu")
		(net "SAS_HDD_TX11_P")
	)
	(arc
		(start 107.311698 -107.388152)
		(mid 107.307152 -107.387238)
		(end 107.302554 -107.386628)
		(width 0.1016)
		(layer "F.Cu")
		(net "SAS_HDD_TX11_P")
	)
	(arc
		(start 102.272846 -113.591594)
		(mid 102.241076 -113.544047)
		(end 102.22992 -113.487962)
		(width 0.1016)
		(layer "F.Cu")
		(net "SAS_HDD_TX11_P")
	)
	(segment
		(start 110.320836 -57.604406)
		(end 110.320836 -57.560464)
		(width 0.1143)
		(layer "F.Cu")
		(net "XM_ALE")
	)
	(segment
		(start 110.369096 -56.23687)
		(end 110.750096 -55.85587)
		(width 0.1143)
		(layer "F.Cu")
		(net "XM_ALE")
	)
	(segment
		(start 110.369096 -57.512204)
		(end 110.369096 -56.23687)
		(width 0.1143)
		(layer "F.Cu")
		(net "XM_ALE")
	)
	(segment
		(start 110.750096 -55.85587)
		(end 110.750096 -55.79999)
		(width 0.1143)
		(layer "F.Cu")
		(net "XM_ALE")
	)
	(segment
		(start 110.320836 -57.560464)
		(end 110.369096 -57.512204)
		(width 0.1143)
		(layer "F.Cu")
		(net "XM_ALE")
	)
	(via
		(at 110.320836 -57.604406)
		(size 0.508)
		(drill 0.254)
		(layers "F.Cu" "B.Cu")
		(net "XM_ALE")
	)
	(segment
		(start 111.429546 -57.632346)
		(end 110.348776 -57.632346)
		(width 0.1143)
		(layer "B.Cu")
		(net "XM_ALE")
	)
	(segment
		(start 111.762286 -57.299606)
		(end 111.429546 -57.632346)
		(width 0.1143)
		(layer "B.Cu")
		(net "XM_ALE")
	)
	(segment
		(start 110.348776 -57.632346)
		(end 110.320836 -57.604406)
		(width 0.1143)
		(layer "B.Cu")
		(net "XM_ALE")
	)
	(segment
		(start 85.865208 -38.11905)
		(end 84.690966 -38.11905)
		(width 0.1016)
		(layer "F.Cu")
		(net "SAS3008_RAID_TX_N3")
	)
	(segment
		(start 122.795284 -84.849716)
		(end 122.350022 -85.294978)
		(width 0.1016)
		(layer "F.Cu")
		(net "SAS3008_RAID_TX_N3")
	)
	(segment
		(start 84.246466 -37.9349)
		(end 84.055966 -37.7444)
		(width 0.1016)
		(layer "F.Cu")
		(net "SAS3008_RAID_TX_N3")
	)
	(segment
		(start 122.850148 -84.849716)
		(end 122.795284 -84.849716)
		(width 0.1016)
		(layer "F.Cu")
		(net "SAS3008_RAID_TX_N3")
	)
	(segment
		(start 122.350022 -85.294978)
		(end 122.350022 -85.349842)
		(width 0.1016)
		(layer "F.Cu")
		(net "SAS3008_RAID_TX_N3")
	)
	(via
		(at 129.159 -81.28)
		(size 0.5588)
		(drill 0.3048)
		(layers "F.Cu" "B.Cu")
		(net "SAS3008_RAID_TX_N3")
	)
	(via
		(at 84.055966 -37.7444)
		(size 0.508)
		(drill 0.254)
		(layers "F.Cu" "B.Cu")
		(net "SAS3008_RAID_TX_N3")
	)
	(via
		(at 122.850148 -84.849716)
		(size 0.508)
		(drill 0.254)
		(layers "F.Cu" "B.Cu")
		(net "SAS3008_RAID_TX_N3")
	)
	(via
		(at 82.911188 -37.831776)
		(size 0.5588)
		(drill 0.3048)
		(layers "F.Cu" "B.Cu")
		(net "SAS3008_RAID_TX_N3")
	)
	(arc
		(start 84.690966 -38.11905)
		(mid 84.450392 -38.071197)
		(end 84.246466 -37.9349)
		(width 0.1016)
		(layer "F.Cu")
		(net "SAS3008_RAID_TX_N3")
	)
	(arc
		(start 86.21776 -37.973)
		(mid 86.056008 -38.081079)
		(end 85.865208 -38.11905)
		(width 0.1016)
		(layer "F.Cu")
		(net "SAS3008_RAID_TX_N3")
	)
	(segment
		(start 129.41427 -81.53527)
		(end 129.159 -81.28)
		(width 0.1016)
		(layer "B.Cu")
		(net "SAS3008_RAID_TX_N3")
	)
	(segment
		(start 83.852766 -38.1127)
		(end 83.175856 -38.1127)
		(width 0.1016)
		(layer "B.Cu")
		(net "SAS3008_RAID_TX_N3")
	)
	(segment
		(start 129.41427 -82.9056)
		(end 129.41427 -81.53527)
		(width 0.1016)
		(layer "B.Cu")
		(net "SAS3008_RAID_TX_N3")
	)
	(segment
		(start 82.911188 -37.848032)
		(end 82.911188 -37.831776)
		(width 0.1016)
		(layer "B.Cu")
		(net "SAS3008_RAID_TX_N3")
	)
	(segment
		(start 125.872494 -83.3501)
		(end 128.96977 -83.3501)
		(width 0.1016)
		(layer "B.Cu")
		(net "SAS3008_RAID_TX_N3")
	)
	(segment
		(start 123.996958 -84.297012)
		(end 124.113036 -84.180934)
		(width 0.1016)
		(layer "B.Cu")
		(net "SAS3008_RAID_TX_N3")
	)
	(segment
		(start 124.52477 -84.0105)
		(end 124.67717 -84.0105)
		(width 0.1016)
		(layer "B.Cu")
		(net "SAS3008_RAID_TX_N3")
	)
	(segment
		(start 84.055966 -37.7444)
		(end 84.055966 -37.9095)
		(width 0.1016)
		(layer "B.Cu")
		(net "SAS3008_RAID_TX_N3")
	)
	(segment
		(start 123.698 -84.328)
		(end 123.922028 -84.328)
		(width 0.1016)
		(layer "B.Cu")
		(net "SAS3008_RAID_TX_N3")
	)
	(segment
		(start 122.850148 -84.849716)
		(end 123.141232 -84.558632)
		(width 0.1016)
		(layer "B.Cu")
		(net "SAS3008_RAID_TX_N3")
	)
	(segment
		(start 125.041406 -83.859624)
		(end 125.3236 -83.57743)
		(width 0.1016)
		(layer "B.Cu")
		(net "SAS3008_RAID_TX_N3")
	)
	(arc
		(start 84.055966 -37.9095)
		(mid 83.99645 -38.053184)
		(end 83.852766 -38.1127)
		(width 0.1016)
		(layer "B.Cu")
		(net "SAS3008_RAID_TX_N3")
	)
	(arc
		(start 123.922028 -84.328)
		(mid 123.962561 -84.319937)
		(end 123.996958 -84.297012)
		(width 0.1016)
		(layer "B.Cu")
		(net "SAS3008_RAID_TX_N3")
	)
	(arc
		(start 124.67717 -84.0105)
		(mid 124.874295 -83.971289)
		(end 125.041406 -83.859624)
		(width 0.1016)
		(layer "B.Cu")
		(net "SAS3008_RAID_TX_N3")
	)
	(arc
		(start 83.175856 -38.1127)
		(mid 82.988707 -38.035181)
		(end 82.911188 -37.848032)
		(width 0.1016)
		(layer "B.Cu")
		(net "SAS3008_RAID_TX_N3")
	)
	(arc
		(start 123.141232 -84.558632)
		(mid 123.396679 -84.387948)
		(end 123.698 -84.328)
		(width 0.1016)
		(layer "B.Cu")
		(net "SAS3008_RAID_TX_N3")
	)
	(arc
		(start 125.3236 -83.57743)
		(mid 125.575449 -83.409213)
		(end 125.872494 -83.3501)
		(width 0.1016)
		(layer "B.Cu")
		(net "SAS3008_RAID_TX_N3")
	)
	(arc
		(start 128.96977 -83.3501)
		(mid 129.284079 -83.219909)
		(end 129.41427 -82.9056)
		(width 0.1016)
		(layer "B.Cu")
		(net "SAS3008_RAID_TX_N3")
	)
	(arc
		(start 124.113036 -84.180934)
		(mid 124.301956 -84.054795)
		(end 124.52477 -84.0105)
		(width 0.1016)
		(layer "B.Cu")
		(net "SAS3008_RAID_TX_N3")
	)
	(segment
		(start 81.998312 -40.944546)
		(end 81.909412 -40.855646)
		(width 0.1016)
		(layer "In2.Cu")
		(net "SAS3008_RAID_TX_N3")
	)
	(segment
		(start 108.251244 -68.95338)
		(end 103.641906 -64.344042)
		(width 0.1016)
		(layer "In2.Cu")
		(net "SAS3008_RAID_TX_N3")
	)
	(segment
		(start 84.513166 -41.17848)
		(end 82.563462 -41.17848)
		(width 0.1016)
		(layer "In2.Cu")
		(net "SAS3008_RAID_TX_N3")
	)
	(segment
		(start 82.911188 -37.891974)
		(end 82.911188 -37.831776)
		(width 0.1016)
		(layer "In2.Cu")
		(net "SAS3008_RAID_TX_N3")
	)
	(segment
		(start 81.642966 -40.212264)
		(end 81.642966 -38.893242)
		(width 0.1016)
		(layer "In2.Cu")
		(net "SAS3008_RAID_TX_N3")
	)
	(segment
		(start 99.96043 -63.615824)
		(end 99.83343 -63.488824)
		(width 0.1016)
		(layer "In2.Cu")
		(net "SAS3008_RAID_TX_N3")
	)
	(segment
		(start 81.815686 -38.476174)
		(end 81.815432 -38.476174)
		(width 0.1016)
		(layer "In2.Cu")
		(net "SAS3008_RAID_TX_N3")
	)
	(segment
		(start 129.45237 -80.772)
		(end 129.45237 -74.6252)
		(width 0.1016)
		(layer "In2.Cu")
		(net "SAS3008_RAID_TX_N3")
	)
	(segment
		(start 82.614516 -38.153594)
		(end 82.754978 -38.168326)
		(width 0.1016)
		(layer "In2.Cu")
		(net "SAS3008_RAID_TX_N3")
	)
	(segment
		(start 98.462084 -62.117986)
		(end 86.064598 -49.719992)
		(width 0.1016)
		(layer "In2.Cu")
		(net "SAS3008_RAID_TX_N3")
	)
	(segment
		(start 126.480062 -71.2724)
		(end 120.692164 -71.2724)
		(width 0.1016)
		(layer "In2.Cu")
		(net "SAS3008_RAID_TX_N3")
	)
	(segment
		(start 102.707948 -63.9572)
		(end 100.78466 -63.9572)
		(width 0.1016)
		(layer "In2.Cu")
		(net "SAS3008_RAID_TX_N3")
	)
	(segment
		(start 99.833176 -63.488824)
		(end 98.46818 -62.123828)
		(width 0.1016)
		(layer "In2.Cu")
		(net "SAS3008_RAID_TX_N3")
	)
	(segment
		(start 128.96723 -73.45426)
		(end 127.00127 -71.4883)
		(width 0.1016)
		(layer "In2.Cu")
		(net "SAS3008_RAID_TX_N3")
	)
	(segment
		(start 85.249512 -47.752)
		(end 85.249766 -47.752)
		(width 0.1016)
		(layer "In2.Cu")
		(net "SAS3008_RAID_TX_N3")
	)
	(segment
		(start 81.815432 -38.476174)
		(end 81.846674 -38.444932)
		(width 0.1016)
		(layer "In2.Cu")
		(net "SAS3008_RAID_TX_N3")
	)
	(segment
		(start 117.84711 -69.1642)
		(end 108.76026 -69.1642)
		(width 0.1016)
		(layer "In2.Cu")
		(net "SAS3008_RAID_TX_N3")
	)
	(segment
		(start 85.249766 -47.752)
		(end 85.249766 -41.91508)
		(width 0.1016)
		(layer "In2.Cu")
		(net "SAS3008_RAID_TX_N3")
	)
	(segment
		(start 129.159 -81.28)
		(end 129.300478 -81.138268)
		(width 0.1016)
		(layer "In2.Cu")
		(net "SAS3008_RAID_TX_N3")
	)
	(segment
		(start 99.83343 -63.488824)
		(end 99.833176 -63.488824)
		(width 0.1016)
		(layer "In2.Cu")
		(net "SAS3008_RAID_TX_N3")
	)
	(segment
		(start 119.863616 -70.929246)
		(end 118.27637 -69.342)
		(width 0.1016)
		(layer "In2.Cu")
		(net "SAS3008_RAID_TX_N3")
	)
	(arc
		(start 82.557874 -38.150546)
		(mid 82.586233 -38.151357)
		(end 82.614516 -38.153594)
		(width 0.1016)
		(layer "In2.Cu")
		(net "SAS3008_RAID_TX_N3")
	)
	(arc
		(start 118.27637 -69.342)
		(mid 118.079424 -69.210405)
		(end 117.84711 -69.1642)
		(width 0.1016)
		(layer "In2.Cu")
		(net "SAS3008_RAID_TX_N3")
	)
	(arc
		(start 120.692164 -71.2724)
		(mid 120.243734 -71.183277)
		(end 119.863616 -70.929246)
		(width 0.1016)
		(layer "In2.Cu")
		(net "SAS3008_RAID_TX_N3")
	)
	(arc
		(start 82.804 -38.1508)
		(mid 82.883346 -38.03205)
		(end 82.911188 -37.891974)
		(width 0.1016)
		(layer "In2.Cu")
		(net "SAS3008_RAID_TX_N3")
	)
	(arc
		(start 82.754978 -38.168326)
		(mid 82.781464 -38.165095)
		(end 82.804 -38.1508)
		(width 0.1016)
		(layer "In2.Cu")
		(net "SAS3008_RAID_TX_N3")
	)
	(arc
		(start 108.76026 -69.1642)
		(mid 108.484816 -69.109353)
		(end 108.251244 -68.95338)
		(width 0.1016)
		(layer "In2.Cu")
		(net "SAS3008_RAID_TX_N3")
	)
	(arc
		(start 81.642966 -38.893242)
		(mid 81.687914 -38.667565)
		(end 81.815686 -38.476174)
		(width 0.1016)
		(layer "In2.Cu")
		(net "SAS3008_RAID_TX_N3")
	)
	(arc
		(start 100.78466 -63.9572)
		(mid 100.338627 -63.868421)
		(end 99.96043 -63.615824)
		(width 0.1016)
		(layer "In2.Cu")
		(net "SAS3008_RAID_TX_N3")
	)
	(arc
		(start 129.300478 -81.138268)
		(mid 129.412845 -80.970238)
		(end 129.45237 -80.772)
		(width 0.1016)
		(layer "In2.Cu")
		(net "SAS3008_RAID_TX_N3")
	)
	(arc
		(start 103.641906 -64.344042)
		(mid 103.213402 -64.057725)
		(end 102.707948 -63.9572)
		(width 0.1016)
		(layer "In2.Cu")
		(net "SAS3008_RAID_TX_N3")
	)
	(arc
		(start 127.00127 -71.4883)
		(mid 126.762138 -71.328517)
		(end 126.480062 -71.2724)
		(width 0.1016)
		(layer "In2.Cu")
		(net "SAS3008_RAID_TX_N3")
	)
	(arc
		(start 86.064598 -49.719992)
		(mid 85.461338 -48.817055)
		(end 85.249512 -47.752)
		(width 0.1016)
		(layer "In2.Cu")
		(net "SAS3008_RAID_TX_N3")
	)
	(arc
		(start 85.249766 -41.91508)
		(mid 85.034021 -41.394225)
		(end 84.513166 -41.17848)
		(width 0.1016)
		(layer "In2.Cu")
		(net "SAS3008_RAID_TX_N3")
	)
	(arc
		(start 98.46818 -62.123828)
		(mid 98.465122 -62.120917)
		(end 98.462084 -62.117986)
		(width 0.1016)
		(layer "In2.Cu")
		(net "SAS3008_RAID_TX_N3")
	)
	(arc
		(start 81.846674 -38.444932)
		(mid 82.172977 -38.226963)
		(end 82.557874 -38.150546)
		(width 0.1016)
		(layer "In2.Cu")
		(net "SAS3008_RAID_TX_N3")
	)
	(arc
		(start 81.909412 -40.855646)
		(mid 81.712199 -40.560446)
		(end 81.642966 -40.212264)
		(width 0.1016)
		(layer "In2.Cu")
		(net "SAS3008_RAID_TX_N3")
	)
	(arc
		(start 129.45237 -74.6252)
		(mid 129.32624 -73.991485)
		(end 128.96723 -73.45426)
		(width 0.1016)
		(layer "In2.Cu")
		(net "SAS3008_RAID_TX_N3")
	)
	(arc
		(start 82.563462 -41.17848)
		(mid 82.257587 -41.117789)
		(end 81.998312 -40.944546)
		(width 0.1016)
		(layer "In2.Cu")
		(net "SAS3008_RAID_TX_N3")
	)
	(segment
		(start 60.71997 -132.08)
		(end 60.84697 -131.953)
		(width 0.1143)
		(layer "F.Cu")
		(net "EXP_XM_BUSY_N")
	)
	(segment
		(start 60.100972 -131.892802)
		(end 60.28817 -132.08)
		(width 0.1143)
		(layer "F.Cu")
		(net "EXP_XM_BUSY_N")
	)
	(segment
		(start 99.32797 -89.94648)
		(end 101.82479 -89.94648)
		(width 0.1143)
		(layer "F.Cu")
		(net "EXP_XM_BUSY_N")
	)
	(segment
		(start 97.32645 -91.948)
		(end 99.32797 -89.94648)
		(width 0.1143)
		(layer "F.Cu")
		(net "EXP_XM_BUSY_N")
	)
	(segment
		(start 102.349808 -90.349832)
		(end 102.228142 -90.349832)
		(width 0.1143)
		(layer "F.Cu")
		(net "EXP_XM_BUSY_N")
	)
	(segment
		(start 56.558942 -131.892802)
		(end 60.100972 -131.892802)
		(width 0.1143)
		(layer "F.Cu")
		(net "EXP_XM_BUSY_N")
	)
	(segment
		(start 60.28817 -132.08)
		(end 60.71997 -132.08)
		(width 0.1143)
		(layer "F.Cu")
		(net "EXP_XM_BUSY_N")
	)
	(segment
		(start 102.228142 -90.349832)
		(end 101.82479 -89.94648)
		(width 0.1143)
		(layer "F.Cu")
		(net "EXP_XM_BUSY_N")
	)
	(segment
		(start 96.34347 -91.948)
		(end 97.32645 -91.948)
		(width 0.1143)
		(layer "F.Cu")
		(net "EXP_XM_BUSY_N")
	)
	(via
		(at 61.3664 -132.715)
		(size 0.7112)
		(drill 0.3556)
		(layers "F.Cu" "B.Cu")
		(net "EXP_XM_BUSY_N")
	)
	(via
		(at 101.82479 -89.94648)
		(size 0.508)
		(drill 0.254)
		(layers "F.Cu" "B.Cu")
		(net "EXP_XM_BUSY_N")
	)
	(via
		(at 60.84697 -131.953)
		(size 0.5588)
		(drill 0.3048)
		(layers "F.Cu" "B.Cu")
		(net "EXP_XM_BUSY_N")
	)
	(segment
		(start 60.8584 -132.207)
		(end 60.8584 -131.98983)
		(width 0.1143)
		(layer "B.Cu")
		(net "EXP_XM_BUSY_N")
	)
	(segment
		(start 60.8584 -131.98983)
		(end 60.84697 -131.9784)
		(width 0.1143)
		(layer "B.Cu")
		(net "EXP_XM_BUSY_N")
	)
	(segment
		(start 61.3664 -132.715)
		(end 60.8584 -132.207)
		(width 0.1143)
		(layer "B.Cu")
		(net "EXP_XM_BUSY_N")
	)
	(segment
		(start 60.84697 -131.9784)
		(end 60.84697 -131.953)
		(width 0.1143)
		(layer "B.Cu")
		(net "EXP_XM_BUSY_N")
	)
	(segment
		(start 92.445078 -87.8967)
		(end 92.445078 -89.02446)
		(width 0.127)
		(layer "In2.Cu")
		(net "EXP_XM_BUSY_N")
	)
	(segment
		(start 93.588078 -89.15146)
		(end 94.87027 -89.15146)
		(width 0.127)
		(layer "In2.Cu")
		(net "EXP_XM_BUSY_N")
	)
	(segment
		(start 60.70727 -131.8133)
		(end 60.70727 -130.223768)
		(width 0.127)
		(layer "In2.Cu")
		(net "EXP_XM_BUSY_N")
	)
	(segment
		(start 91.048078 -87.7697)
		(end 91.302078 -87.7697)
		(width 0.127)
		(layer "In2.Cu")
		(net "EXP_XM_BUSY_N")
	)
	(segment
		(start 95.63227 -89.15146)
		(end 95.88627 -89.15146)
		(width 0.127)
		(layer "In2.Cu")
		(net "EXP_XM_BUSY_N")
	)
	(segment
		(start 91.302078 -87.7697)
		(end 91.429078 -87.8967)
		(width 0.127)
		(layer "In2.Cu")
		(net "EXP_XM_BUSY_N")
	)
	(segment
		(start 60.70727 -130.223768)
		(end 60.592462 -130.10896)
		(width 0.127)
		(layer "In2.Cu")
		(net "EXP_XM_BUSY_N")
	)
	(segment
		(start 101.39299 -89.51468)
		(end 101.82479 -89.94648)
		(width 0.127)
		(layer "In2.Cu")
		(net "EXP_XM_BUSY_N")
	)
	(segment
		(start 96.52127 -87.8967)
		(end 96.52127 -89.02446)
		(width 0.127)
		(layer "In2.Cu")
		(net "EXP_XM_BUSY_N")
	)
	(segment
		(start 97.15627 -87.7697)
		(end 97.41027 -87.7697)
		(width 0.127)
		(layer "In2.Cu")
		(net "EXP_XM_BUSY_N")
	)
	(segment
		(start 100.48367 -88.94572)
		(end 101.05263 -89.51468)
		(width 0.127)
		(layer "In2.Cu")
		(net "EXP_XM_BUSY_N")
	)
	(segment
		(start 91.429078 -87.8967)
		(end 91.429078 -89.02446)
		(width 0.127)
		(layer "In2.Cu")
		(net "EXP_XM_BUSY_N")
	)
	(segment
		(start 100.208588 -88.5571)
		(end 100.48367 -88.832182)
		(width 0.127)
		(layer "In2.Cu")
		(net "EXP_XM_BUSY_N")
	)
	(segment
		(start 100.48367 -88.832182)
		(end 100.48367 -88.94572)
		(width 0.127)
		(layer "In2.Cu")
		(net "EXP_XM_BUSY_N")
	)
	(segment
		(start 90.921078 -87.8967)
		(end 91.048078 -87.7697)
		(width 0.127)
		(layer "In2.Cu")
		(net "EXP_XM_BUSY_N")
	)
	(segment
		(start 96.52127 -89.02446)
		(end 96.64827 -89.15146)
		(width 0.127)
		(layer "In2.Cu")
		(net "EXP_XM_BUSY_N")
	)
	(segment
		(start 60.592462 -130.10896)
		(end 60.592462 -117.06225)
		(width 0.127)
		(layer "In2.Cu")
		(net "EXP_XM_BUSY_N")
	)
	(segment
		(start 97.66427 -89.15146)
		(end 98.50755 -89.15146)
		(width 0.127)
		(layer "In2.Cu")
		(net "EXP_XM_BUSY_N")
	)
	(segment
		(start 96.14027 -87.7697)
		(end 96.39427 -87.7697)
		(width 0.127)
		(layer "In2.Cu")
		(net "EXP_XM_BUSY_N")
	)
	(segment
		(start 101.05263 -89.51468)
		(end 101.39299 -89.51468)
		(width 0.127)
		(layer "In2.Cu")
		(net "EXP_XM_BUSY_N")
	)
	(segment
		(start 95.37827 -87.7697)
		(end 95.50527 -87.8967)
		(width 0.127)
		(layer "In2.Cu")
		(net "EXP_XM_BUSY_N")
	)
	(segment
		(start 96.01327 -89.02446)
		(end 96.01327 -87.8967)
		(width 0.127)
		(layer "In2.Cu")
		(net "EXP_XM_BUSY_N")
	)
	(segment
		(start 92.826078 -89.15146)
		(end 92.953078 -89.02446)
		(width 0.127)
		(layer "In2.Cu")
		(net "EXP_XM_BUSY_N")
	)
	(segment
		(start 96.01327 -87.8967)
		(end 96.14027 -87.7697)
		(width 0.127)
		(layer "In2.Cu")
		(net "EXP_XM_BUSY_N")
	)
	(segment
		(start 97.53727 -87.8967)
		(end 97.53727 -89.02446)
		(width 0.127)
		(layer "In2.Cu")
		(net "EXP_XM_BUSY_N")
	)
	(segment
		(start 95.12427 -87.7697)
		(end 95.37827 -87.7697)
		(width 0.127)
		(layer "In2.Cu")
		(net "EXP_XM_BUSY_N")
	)
	(segment
		(start 94.99727 -89.02446)
		(end 94.99727 -87.8967)
		(width 0.127)
		(layer "In2.Cu")
		(net "EXP_XM_BUSY_N")
	)
	(segment
		(start 91.429078 -89.02446)
		(end 91.556078 -89.15146)
		(width 0.127)
		(layer "In2.Cu")
		(net "EXP_XM_BUSY_N")
	)
	(segment
		(start 94.87027 -89.15146)
		(end 94.99727 -89.02446)
		(width 0.127)
		(layer "In2.Cu")
		(net "EXP_XM_BUSY_N")
	)
	(segment
		(start 95.50527 -87.8967)
		(end 95.50527 -89.02446)
		(width 0.127)
		(layer "In2.Cu")
		(net "EXP_XM_BUSY_N")
	)
	(segment
		(start 97.02927 -87.8967)
		(end 97.15627 -87.7697)
		(width 0.127)
		(layer "In2.Cu")
		(net "EXP_XM_BUSY_N")
	)
	(segment
		(start 96.90227 -89.15146)
		(end 97.02927 -89.02446)
		(width 0.127)
		(layer "In2.Cu")
		(net "EXP_XM_BUSY_N")
	)
	(segment
		(start 95.88627 -89.15146)
		(end 96.01327 -89.02446)
		(width 0.127)
		(layer "In2.Cu")
		(net "EXP_XM_BUSY_N")
	)
	(segment
		(start 99.61118 -88.5571)
		(end 100.208588 -88.5571)
		(width 0.127)
		(layer "In2.Cu")
		(net "EXP_XM_BUSY_N")
	)
	(segment
		(start 85.474556 -92.180156)
		(end 85.891116 -92.180156)
		(width 0.127)
		(layer "In2.Cu")
		(net "EXP_XM_BUSY_N")
	)
	(segment
		(start 85.891116 -92.180156)
		(end 88.535764 -89.535508)
		(width 0.127)
		(layer "In2.Cu")
		(net "EXP_XM_BUSY_N")
	)
	(segment
		(start 92.445078 -89.02446)
		(end 92.572078 -89.15146)
		(width 0.127)
		(layer "In2.Cu")
		(net "EXP_XM_BUSY_N")
	)
	(segment
		(start 92.572078 -89.15146)
		(end 92.826078 -89.15146)
		(width 0.127)
		(layer "In2.Cu")
		(net "EXP_XM_BUSY_N")
	)
	(segment
		(start 98.64852 -89.010236)
		(end 98.64852 -88.53424)
		(width 0.127)
		(layer "In2.Cu")
		(net "EXP_XM_BUSY_N")
	)
	(segment
		(start 90.41003 -89.535508)
		(end 90.921078 -89.02446)
		(width 0.127)
		(layer "In2.Cu")
		(net "EXP_XM_BUSY_N")
	)
	(segment
		(start 92.953078 -89.02446)
		(end 92.953078 -87.8967)
		(width 0.127)
		(layer "In2.Cu")
		(net "EXP_XM_BUSY_N")
	)
	(segment
		(start 92.318078 -87.7697)
		(end 92.445078 -87.8967)
		(width 0.127)
		(layer "In2.Cu")
		(net "EXP_XM_BUSY_N")
	)
	(segment
		(start 97.41027 -87.7697)
		(end 97.53727 -87.8967)
		(width 0.127)
		(layer "In2.Cu")
		(net "EXP_XM_BUSY_N")
	)
	(segment
		(start 88.535764 -89.535508)
		(end 90.41003 -89.535508)
		(width 0.127)
		(layer "In2.Cu")
		(net "EXP_XM_BUSY_N")
	)
	(segment
		(start 90.921078 -89.02446)
		(end 90.921078 -87.8967)
		(width 0.127)
		(layer "In2.Cu")
		(net "EXP_XM_BUSY_N")
	)
	(segment
		(start 98.923602 -88.259158)
		(end 99.313238 -88.259158)
		(width 0.127)
		(layer "In2.Cu")
		(net "EXP_XM_BUSY_N")
	)
	(segment
		(start 92.953078 -87.8967)
		(end 93.080078 -87.7697)
		(width 0.127)
		(layer "In2.Cu")
		(net "EXP_XM_BUSY_N")
	)
	(segment
		(start 96.64827 -89.15146)
		(end 96.90227 -89.15146)
		(width 0.127)
		(layer "In2.Cu")
		(net "EXP_XM_BUSY_N")
	)
	(segment
		(start 91.556078 -89.15146)
		(end 91.810078 -89.15146)
		(width 0.127)
		(layer "In2.Cu")
		(net "EXP_XM_BUSY_N")
	)
	(segment
		(start 93.080078 -87.7697)
		(end 93.334078 -87.7697)
		(width 0.127)
		(layer "In2.Cu")
		(net "EXP_XM_BUSY_N")
	)
	(segment
		(start 94.99727 -87.8967)
		(end 95.12427 -87.7697)
		(width 0.127)
		(layer "In2.Cu")
		(net "EXP_XM_BUSY_N")
	)
	(segment
		(start 96.39427 -87.7697)
		(end 96.52127 -87.8967)
		(width 0.127)
		(layer "In2.Cu")
		(net "EXP_XM_BUSY_N")
	)
	(segment
		(start 97.53727 -89.02446)
		(end 97.66427 -89.15146)
		(width 0.127)
		(layer "In2.Cu")
		(net "EXP_XM_BUSY_N")
	)
	(segment
		(start 60.592462 -117.06225)
		(end 85.474556 -92.180156)
		(width 0.127)
		(layer "In2.Cu")
		(net "EXP_XM_BUSY_N")
	)
	(segment
		(start 91.937078 -87.8967)
		(end 92.064078 -87.7697)
		(width 0.127)
		(layer "In2.Cu")
		(net "EXP_XM_BUSY_N")
	)
	(segment
		(start 91.810078 -89.15146)
		(end 91.937078 -89.02446)
		(width 0.127)
		(layer "In2.Cu")
		(net "EXP_XM_BUSY_N")
	)
	(segment
		(start 97.02927 -89.02446)
		(end 97.02927 -87.8967)
		(width 0.127)
		(layer "In2.Cu")
		(net "EXP_XM_BUSY_N")
	)
	(segment
		(start 98.50755 -89.15146)
		(end 98.64852 -89.010236)
		(width 0.127)
		(layer "In2.Cu")
		(net "EXP_XM_BUSY_N")
	)
	(segment
		(start 93.461078 -87.8967)
		(end 93.461078 -89.02446)
		(width 0.127)
		(layer "In2.Cu")
		(net "EXP_XM_BUSY_N")
	)
	(segment
		(start 93.334078 -87.7697)
		(end 93.461078 -87.8967)
		(width 0.127)
		(layer "In2.Cu")
		(net "EXP_XM_BUSY_N")
	)
	(segment
		(start 93.461078 -89.02446)
		(end 93.588078 -89.15146)
		(width 0.127)
		(layer "In2.Cu")
		(net "EXP_XM_BUSY_N")
	)
	(segment
		(start 60.84697 -131.953)
		(end 60.70727 -131.8133)
		(width 0.127)
		(layer "In2.Cu")
		(net "EXP_XM_BUSY_N")
	)
	(segment
		(start 98.64852 -88.53424)
		(end 98.923602 -88.259158)
		(width 0.127)
		(layer "In2.Cu")
		(net "EXP_XM_BUSY_N")
	)
	(segment
		(start 92.064078 -87.7697)
		(end 92.318078 -87.7697)
		(width 0.127)
		(layer "In2.Cu")
		(net "EXP_XM_BUSY_N")
	)
	(segment
		(start 95.50527 -89.02446)
		(end 95.63227 -89.15146)
		(width 0.127)
		(layer "In2.Cu")
		(net "EXP_XM_BUSY_N")
	)
	(segment
		(start 91.937078 -89.02446)
		(end 91.937078 -87.8967)
		(width 0.127)
		(layer "In2.Cu")
		(net "EXP_XM_BUSY_N")
	)
	(segment
		(start 99.313238 -88.259158)
		(end 99.61118 -88.5571)
		(width 0.127)
		(layer "In2.Cu")
		(net "EXP_XM_BUSY_N")
	)
	(segment
		(start 139.298934 -48.575976)
		(end 139.413234 -48.690276)
		(width 0.1143)
		(layer "F.Cu")
		(net "XM_ADDR_12")
	)
	(segment
		(start 138.91895 -49.147476)
		(end 138.91895 -49.376076)
		(width 0.1143)
		(layer "F.Cu")
		(net "XM_ADDR_12")
	)
	(segment
		(start 139.413234 -48.690276)
		(end 139.413234 -48.918876)
		(width 0.1143)
		(layer "F.Cu")
		(net "XM_ADDR_12")
	)
	(segment
		(start 139.89685 -47.82185)
		(end 139.827 -47.752)
		(width 0.1143)
		(layer "F.Cu")
		(net "XM_ADDR_12")
	)
	(segment
		(start 139.04595 -50.607976)
		(end 139.76985 -50.607976)
		(width 0.1143)
		(layer "F.Cu")
		(net "XM_ADDR_12")
	)
	(segment
		(start 139.76985 -50.607976)
		(end 139.89685 -50.480976)
		(width 0.1143)
		(layer "F.Cu")
		(net "XM_ADDR_12")
	)
	(segment
		(start 138.518646 -43.94073)
		(end 138.518646 -45.92828)
		(width 0.1143)
		(layer "F.Cu")
		(net "XM_ADDR_12")
	)
	(segment
		(start 139.03325 -48.575976)
		(end 139.298934 -48.575976)
		(width 0.1143)
		(layer "F.Cu")
		(net "XM_ADDR_12")
	)
	(segment
		(start 139.298934 -49.033176)
		(end 139.03325 -49.033176)
		(width 0.1143)
		(layer "F.Cu")
		(net "XM_ADDR_12")
	)
	(segment
		(start 138.518646 -45.92828)
		(end 138.91895 -46.328584)
		(width 0.1143)
		(layer "F.Cu")
		(net "XM_ADDR_12")
	)
	(segment
		(start 138.91895 -46.328584)
		(end 138.91895 -48.461676)
		(width 0.1143)
		(layer "F.Cu")
		(net "XM_ADDR_12")
	)
	(segment
		(start 138.91895 -50.480976)
		(end 139.04595 -50.607976)
		(width 0.1143)
		(layer "F.Cu")
		(net "XM_ADDR_12")
	)
	(segment
		(start 112.350042 -53.399944)
		(end 112.749838 -53.000148)
		(width 0.1143)
		(layer "F.Cu")
		(net "XM_ADDR_12")
	)
	(segment
		(start 139.413234 -49.833276)
		(end 139.298934 -49.947576)
		(width 0.1143)
		(layer "F.Cu")
		(net "XM_ADDR_12")
	)
	(segment
		(start 139.298934 -49.490376)
		(end 139.413234 -49.604676)
		(width 0.1143)
		(layer "F.Cu")
		(net "XM_ADDR_12")
	)
	(segment
		(start 138.598656 -43.86072)
		(end 138.518646 -43.94073)
		(width 0.1143)
		(layer "F.Cu")
		(net "XM_ADDR_12")
	)
	(segment
		(start 139.03325 -49.490376)
		(end 139.298934 -49.490376)
		(width 0.1143)
		(layer "F.Cu")
		(net "XM_ADDR_12")
	)
	(segment
		(start 139.03325 -49.947576)
		(end 138.91895 -50.061876)
		(width 0.1143)
		(layer "F.Cu")
		(net "XM_ADDR_12")
	)
	(segment
		(start 139.413234 -49.604676)
		(end 139.413234 -49.833276)
		(width 0.1143)
		(layer "F.Cu")
		(net "XM_ADDR_12")
	)
	(segment
		(start 138.91895 -49.376076)
		(end 139.03325 -49.490376)
		(width 0.1143)
		(layer "F.Cu")
		(net "XM_ADDR_12")
	)
	(segment
		(start 138.91895 -48.461676)
		(end 139.03325 -48.575976)
		(width 0.1143)
		(layer "F.Cu")
		(net "XM_ADDR_12")
	)
	(segment
		(start 139.03325 -49.033176)
		(end 138.91895 -49.147476)
		(width 0.1143)
		(layer "F.Cu")
		(net "XM_ADDR_12")
	)
	(segment
		(start 138.598656 -42.7101)
		(end 138.598656 -43.86072)
		(width 0.1143)
		(layer "F.Cu")
		(net "XM_ADDR_12")
	)
	(segment
		(start 139.413234 -48.918876)
		(end 139.298934 -49.033176)
		(width 0.1143)
		(layer "F.Cu")
		(net "XM_ADDR_12")
	)
	(segment
		(start 139.298934 -49.947576)
		(end 139.03325 -49.947576)
		(width 0.1143)
		(layer "F.Cu")
		(net "XM_ADDR_12")
	)
	(segment
		(start 138.91895 -50.061876)
		(end 138.91895 -50.480976)
		(width 0.1143)
		(layer "F.Cu")
		(net "XM_ADDR_12")
	)
	(segment
		(start 139.89685 -50.480976)
		(end 139.89685 -47.82185)
		(width 0.1143)
		(layer "F.Cu")
		(net "XM_ADDR_12")
	)
	(via
		(at 139.827 -47.752)
		(size 0.5588)
		(drill 0.3048)
		(layers "F.Cu" "B.Cu")
		(net "XM_ADDR_12")
	)
	(via
		(at 112.749838 -53.000148)
		(size 0.508)
		(drill 0.254)
		(layers "F.Cu" "B.Cu")
		(net "XM_ADDR_12")
	)
	(via
		(at 139.827 -46.863)
		(size 0.7112)
		(drill 0.3556)
		(layers "F.Cu" "B.Cu")
		(net "XM_ADDR_12")
	)
	(segment
		(start 139.827 -46.863)
		(end 139.827 -47.752)
		(width 0.1143)
		(layer "B.Cu")
		(net "XM_ADDR_12")
	)
	(segment
		(start 115.611402 -52.8193)
		(end 115.611402 -52.5907)
		(width 0.127)
		(layer "In5.Cu")
		(net "XM_ADDR_12")
	)
	(segment
		(start 129.11709 -49.258728)
		(end 128.86309 -49.258728)
		(width 0.127)
		(layer "In5.Cu")
		(net "XM_ADDR_12")
	)
	(segment
		(start 115.484402 -52.4637)
		(end 115.230402 -52.4637)
		(width 0.127)
		(layer "In5.Cu")
		(net "XM_ADDR_12")
	)
	(segment
		(start 113.597944 -53.34762)
		(end 113.597944 -52.581048)
		(width 0.127)
		(layer "In5.Cu")
		(net "XM_ADDR_12")
	)
	(segment
		(start 113.960402 -53.47462)
		(end 113.724944 -53.47462)
		(width 0.127)
		(layer "In5.Cu")
		(net "XM_ADDR_12")
	)
	(segment
		(start 114.595402 -52.5907)
		(end 114.468402 -52.4637)
		(width 0.127)
		(layer "In5.Cu")
		(net "XM_ADDR_12")
	)
	(segment
		(start 118.098062 -52.499006)
		(end 117.971062 -52.372006)
		(width 0.127)
		(layer "In5.Cu")
		(net "XM_ADDR_12")
	)
	(segment
		(start 125.597158 -49.258728)
		(end 122.35688 -52.499006)
		(width 0.127)
		(layer "In5.Cu")
		(net "XM_ADDR_12")
	)
	(segment
		(start 131.14909 -49.258728)
		(end 130.89509 -49.258728)
		(width 0.127)
		(layer "In5.Cu")
		(net "XM_ADDR_12")
	)
	(segment
		(start 114.976402 -52.9463)
		(end 114.722402 -52.9463)
		(width 0.127)
		(layer "In5.Cu")
		(net "XM_ADDR_12")
	)
	(segment
		(start 113.470944 -52.454048)
		(end 113.11382 -52.454048)
		(width 0.127)
		(layer "In5.Cu")
		(net "XM_ADDR_12")
	)
	(segment
		(start 129.24409 -49.385728)
		(end 129.11709 -49.258728)
		(width 0.127)
		(layer "In5.Cu")
		(net "XM_ADDR_12")
	)
	(segment
		(start 130.13309 -49.258728)
		(end 129.87909 -49.258728)
		(width 0.127)
		(layer "In5.Cu")
		(net "XM_ADDR_12")
	)
	(segment
		(start 119.495062 -52.245514)
		(end 119.495062 -52.372006)
		(width 0.127)
		(layer "In5.Cu")
		(net "XM_ADDR_12")
	)
	(segment
		(start 131.65709 -50.009806)
		(end 131.40309 -50.009806)
		(width 0.127)
		(layer "In5.Cu")
		(net "XM_ADDR_12")
	)
	(segment
		(start 126.19609 -49.385728)
		(end 126.06909 -49.258728)
		(width 0.127)
		(layer "In5.Cu")
		(net "XM_ADDR_12")
	)
	(segment
		(start 139.0777 -47.5107)
		(end 139.0777 -48.0441)
		(width 0.127)
		(layer "In5.Cu")
		(net "XM_ADDR_12")
	)
	(segment
		(start 114.087402 -53.34762)
		(end 113.960402 -53.47462)
		(width 0.127)
		(layer "In5.Cu")
		(net "XM_ADDR_12")
	)
	(segment
		(start 120.892062 -52.118514)
		(end 120.638062 -52.118514)
		(width 0.127)
		(layer "In5.Cu")
		(net "XM_ADDR_12")
	)
	(segment
		(start 131.91109 -49.258728)
		(end 131.78409 -49.385728)
		(width 0.127)
		(layer "In5.Cu")
		(net "XM_ADDR_12")
	)
	(segment
		(start 127.21209 -49.385728)
		(end 127.08509 -49.258728)
		(width 0.127)
		(layer "In5.Cu")
		(net "XM_ADDR_12")
	)
	(segment
		(start 126.57709 -50.009806)
		(end 126.32309 -50.009806)
		(width 0.127)
		(layer "In5.Cu")
		(net "XM_ADDR_12")
	)
	(segment
		(start 127.33909 -50.009806)
		(end 127.21209 -49.882806)
		(width 0.127)
		(layer "In5.Cu")
		(net "XM_ADDR_12")
	)
	(segment
		(start 126.70409 -49.882806)
		(end 126.57709 -50.009806)
		(width 0.127)
		(layer "In5.Cu")
		(net "XM_ADDR_12")
	)
	(segment
		(start 113.597944 -52.581048)
		(end 113.470944 -52.454048)
		(width 0.127)
		(layer "In5.Cu")
		(net "XM_ADDR_12")
	)
	(segment
		(start 126.70409 -49.385728)
		(end 126.70409 -49.882806)
		(width 0.127)
		(layer "In5.Cu")
		(net "XM_ADDR_12")
	)
	(segment
		(start 126.06909 -49.258728)
		(end 125.597158 -49.258728)
		(width 0.127)
		(layer "In5.Cu")
		(net "XM_ADDR_12")
	)
	(segment
		(start 121.019062 -52.245514)
		(end 120.892062 -52.118514)
		(width 0.127)
		(layer "In5.Cu")
		(net "XM_ADDR_12")
	)
	(segment
		(start 117.971062 -52.372006)
		(end 117.971062 -52.245514)
		(width 0.127)
		(layer "In5.Cu")
		(net "XM_ADDR_12")
	)
	(segment
		(start 130.38709 -50.009806)
		(end 130.26009 -49.882806)
		(width 0.127)
		(layer "In5.Cu")
		(net "XM_ADDR_12")
	)
	(segment
		(start 114.468402 -52.4637)
		(end 114.214402 -52.4637)
		(width 0.127)
		(layer "In5.Cu")
		(net "XM_ADDR_12")
	)
	(segment
		(start 115.738402 -52.9463)
		(end 115.611402 -52.8193)
		(width 0.127)
		(layer "In5.Cu")
		(net "XM_ADDR_12")
	)
	(segment
		(start 139.827 -47.5742)
		(end 139.6365 -47.3837)
		(width 0.127)
		(layer "In5.Cu")
		(net "XM_ADDR_12")
	)
	(segment
		(start 118.987062 -52.372006)
		(end 118.987062 -52.245514)
		(width 0.127)
		(layer "In5.Cu")
		(net "XM_ADDR_12")
	)
	(segment
		(start 119.495062 -52.372006)
		(end 119.368062 -52.499006)
		(width 0.127)
		(layer "In5.Cu")
		(net "XM_ADDR_12")
	)
	(segment
		(start 127.08509 -49.258728)
		(end 126.83109 -49.258728)
		(width 0.127)
		(layer "In5.Cu")
		(net "XM_ADDR_12")
	)
	(segment
		(start 127.72009 -49.385728)
		(end 127.72009 -49.882806)
		(width 0.127)
		(layer "In5.Cu")
		(net "XM_ADDR_12")
	)
	(segment
		(start 126.19609 -49.882806)
		(end 126.19609 -49.385728)
		(width 0.127)
		(layer "In5.Cu")
		(net "XM_ADDR_12")
	)
	(segment
		(start 113.11382 -52.454048)
		(end 112.749838 -52.81803)
		(width 0.127)
		(layer "In5.Cu")
		(net "XM_ADDR_12")
	)
	(segment
		(start 134.9883 -47.3837)
		(end 133.113272 -49.258728)
		(width 0.127)
		(layer "In5.Cu")
		(net "XM_ADDR_12")
	)
	(segment
		(start 129.62509 -50.009806)
		(end 129.37109 -50.009806)
		(width 0.127)
		(layer "In5.Cu")
		(net "XM_ADDR_12")
	)
	(segment
		(start 128.22809 -49.882806)
		(end 128.22809 -49.385728)
		(width 0.127)
		(layer "In5.Cu")
		(net "XM_ADDR_12")
	)
	(segment
		(start 138.5697 -47.5107)
		(end 138.4427 -47.3837)
		(width 0.127)
		(layer "In5.Cu")
		(net "XM_ADDR_12")
	)
	(segment
		(start 138.6967 -48.1711)
		(end 138.5697 -48.0441)
		(width 0.127)
		(layer "In5.Cu")
		(net "XM_ADDR_12")
	)
	(segment
		(start 128.35509 -50.009806)
		(end 128.22809 -49.882806)
		(width 0.127)
		(layer "In5.Cu")
		(net "XM_ADDR_12")
	)
	(segment
		(start 119.114062 -52.499006)
		(end 118.987062 -52.372006)
		(width 0.127)
		(layer "In5.Cu")
		(net "XM_ADDR_12")
	)
	(segment
		(start 128.86309 -49.258728)
		(end 128.73609 -49.385728)
		(width 0.127)
		(layer "In5.Cu")
		(net "XM_ADDR_12")
	)
	(segment
		(start 131.40309 -50.009806)
		(end 131.27609 -49.882806)
		(width 0.127)
		(layer "In5.Cu")
		(net "XM_ADDR_12")
	)
	(segment
		(start 138.9507 -48.1711)
		(end 138.6967 -48.1711)
		(width 0.127)
		(layer "In5.Cu")
		(net "XM_ADDR_12")
	)
	(segment
		(start 130.76809 -49.882806)
		(end 130.64109 -50.009806)
		(width 0.127)
		(layer "In5.Cu")
		(net "XM_ADDR_12")
	)
	(segment
		(start 139.827 -47.752)
		(end 139.827 -47.5742)
		(width 0.127)
		(layer "In5.Cu")
		(net "XM_ADDR_12")
	)
	(segment
		(start 112.749838 -52.81803)
		(end 112.749838 -53.000148)
		(width 0.127)
		(layer "In5.Cu")
		(net "XM_ADDR_12")
	)
	(segment
		(start 128.73609 -49.385728)
		(end 128.73609 -49.882806)
		(width 0.127)
		(layer "In5.Cu")
		(net "XM_ADDR_12")
	)
	(segment
		(start 139.0777 -48.0441)
		(end 138.9507 -48.1711)
		(width 0.127)
		(layer "In5.Cu")
		(net "XM_ADDR_12")
	)
	(segment
		(start 120.511062 -52.245514)
		(end 120.511062 -52.372006)
		(width 0.127)
		(layer "In5.Cu")
		(net "XM_ADDR_12")
	)
	(segment
		(start 118.479062 -52.245514)
		(end 118.479062 -52.372006)
		(width 0.127)
		(layer "In5.Cu")
		(net "XM_ADDR_12")
	)
	(segment
		(start 126.83109 -49.258728)
		(end 126.70409 -49.385728)
		(width 0.127)
		(layer "In5.Cu")
		(net "XM_ADDR_12")
	)
	(segment
		(start 133.113272 -49.258728)
		(end 131.91109 -49.258728)
		(width 0.127)
		(layer "In5.Cu")
		(net "XM_ADDR_12")
	)
	(segment
		(start 139.2047 -47.3837)
		(end 139.0777 -47.5107)
		(width 0.127)
		(layer "In5.Cu")
		(net "XM_ADDR_12")
	)
	(segment
		(start 120.130062 -52.499006)
		(end 120.003062 -52.372006)
		(width 0.127)
		(layer "In5.Cu")
		(net "XM_ADDR_12")
	)
	(segment
		(start 128.22809 -49.385728)
		(end 128.10109 -49.258728)
		(width 0.127)
		(layer "In5.Cu")
		(net "XM_ADDR_12")
	)
	(segment
		(start 117.971062 -52.245514)
		(end 117.844062 -52.118514)
		(width 0.127)
		(layer "In5.Cu")
		(net "XM_ADDR_12")
	)
	(segment
		(start 138.4427 -47.3837)
		(end 134.9883 -47.3837)
		(width 0.127)
		(layer "In5.Cu")
		(net "XM_ADDR_12")
	)
	(segment
		(start 139.6365 -47.3837)
		(end 139.2047 -47.3837)
		(width 0.127)
		(layer "In5.Cu")
		(net "XM_ADDR_12")
	)
	(segment
		(start 117.844062 -52.118514)
		(end 117.408198 -52.118514)
		(width 0.127)
		(layer "In5.Cu")
		(net "XM_ADDR_12")
	)
	(segment
		(start 114.595402 -52.8193)
		(end 114.595402 -52.5907)
		(width 0.127)
		(layer "In5.Cu")
		(net "XM_ADDR_12")
	)
	(segment
		(start 115.611402 -52.5907)
		(end 115.484402 -52.4637)
		(width 0.127)
		(layer "In5.Cu")
		(net "XM_ADDR_12")
	)
	(segment
		(start 115.103402 -52.5907)
		(end 115.103402 -52.8193)
		(width 0.127)
		(layer "In5.Cu")
		(net "XM_ADDR_12")
	)
	(segment
		(start 129.75209 -49.385728)
		(end 129.75209 -49.882806)
		(width 0.127)
		(layer "In5.Cu")
		(net "XM_ADDR_12")
	)
	(segment
		(start 114.722402 -52.9463)
		(end 114.595402 -52.8193)
		(width 0.127)
		(layer "In5.Cu")
		(net "XM_ADDR_12")
	)
	(segment
		(start 116.4717 -52.9463)
		(end 115.738402 -52.9463)
		(width 0.127)
		(layer "In5.Cu")
		(net "XM_ADDR_12")
	)
	(segment
		(start 130.64109 -50.009806)
		(end 130.38709 -50.009806)
		(width 0.127)
		(layer "In5.Cu")
		(net "XM_ADDR_12")
	)
	(segment
		(start 131.78409 -49.882806)
		(end 131.65709 -50.009806)
		(width 0.127)
		(layer "In5.Cu")
		(net "XM_ADDR_12")
	)
	(segment
		(start 117.12575 -52.400962)
		(end 117.017038 -52.400962)
		(width 0.127)
		(layer "In5.Cu")
		(net "XM_ADDR_12")
	)
	(segment
		(start 118.860062 -52.118514)
		(end 118.606062 -52.118514)
		(width 0.127)
		(layer "In5.Cu")
		(net "XM_ADDR_12")
	)
	(segment
		(start 129.75209 -49.882806)
		(end 129.62509 -50.009806)
		(width 0.127)
		(layer "In5.Cu")
		(net "XM_ADDR_12")
	)
	(segment
		(start 130.76809 -49.385728)
		(end 130.76809 -49.882806)
		(width 0.127)
		(layer "In5.Cu")
		(net "XM_ADDR_12")
	)
	(segment
		(start 120.384062 -52.499006)
		(end 120.130062 -52.499006)
		(width 0.127)
		(layer "In5.Cu")
		(net "XM_ADDR_12")
	)
	(segment
		(start 118.352062 -52.499006)
		(end 118.098062 -52.499006)
		(width 0.127)
		(layer "In5.Cu")
		(net "XM_ADDR_12")
	)
	(segment
		(start 130.89509 -49.258728)
		(end 130.76809 -49.385728)
		(width 0.127)
		(layer "In5.Cu")
		(net "XM_ADDR_12")
	)
	(segment
		(start 129.24409 -49.882806)
		(end 129.24409 -49.385728)
		(width 0.127)
		(layer "In5.Cu")
		(net "XM_ADDR_12")
	)
	(segment
		(start 120.638062 -52.118514)
		(end 120.511062 -52.245514)
		(width 0.127)
		(layer "In5.Cu")
		(net "XM_ADDR_12")
	)
	(segment
		(start 130.26009 -49.882806)
		(end 130.26009 -49.385728)
		(width 0.127)
		(layer "In5.Cu")
		(net "XM_ADDR_12")
	)
	(segment
		(start 113.724944 -53.47462)
		(end 113.597944 -53.34762)
		(width 0.127)
		(layer "In5.Cu")
		(net "XM_ADDR_12")
	)
	(segment
		(start 131.27609 -49.385728)
		(end 131.14909 -49.258728)
		(width 0.127)
		(layer "In5.Cu")
		(net "XM_ADDR_12")
	)
	(segment
		(start 127.21209 -49.882806)
		(end 127.21209 -49.385728)
		(width 0.127)
		(layer "In5.Cu")
		(net "XM_ADDR_12")
	)
	(segment
		(start 128.73609 -49.882806)
		(end 128.60909 -50.009806)
		(width 0.127)
		(layer "In5.Cu")
		(net "XM_ADDR_12")
	)
	(segment
		(start 119.622062 -52.118514)
		(end 119.495062 -52.245514)
		(width 0.127)
		(layer "In5.Cu")
		(net "XM_ADDR_12")
	)
	(segment
		(start 129.87909 -49.258728)
		(end 129.75209 -49.385728)
		(width 0.127)
		(layer "In5.Cu")
		(net "XM_ADDR_12")
	)
	(segment
		(start 131.27609 -49.882806)
		(end 131.27609 -49.385728)
		(width 0.127)
		(layer "In5.Cu")
		(net "XM_ADDR_12")
	)
	(segment
		(start 122.35688 -52.499006)
		(end 121.146062 -52.499006)
		(width 0.127)
		(layer "In5.Cu")
		(net "XM_ADDR_12")
	)
	(segment
		(start 127.59309 -50.009806)
		(end 127.33909 -50.009806)
		(width 0.127)
		(layer "In5.Cu")
		(net "XM_ADDR_12")
	)
	(segment
		(start 120.003062 -52.245514)
		(end 119.876062 -52.118514)
		(width 0.127)
		(layer "In5.Cu")
		(net "XM_ADDR_12")
	)
	(segment
		(start 131.78409 -49.385728)
		(end 131.78409 -49.882806)
		(width 0.127)
		(layer "In5.Cu")
		(net "XM_ADDR_12")
	)
	(segment
		(start 117.017038 -52.400962)
		(end 116.4717 -52.9463)
		(width 0.127)
		(layer "In5.Cu")
		(net "XM_ADDR_12")
	)
	(segment
		(start 118.479062 -52.372006)
		(end 118.352062 -52.499006)
		(width 0.127)
		(layer "In5.Cu")
		(net "XM_ADDR_12")
	)
	(segment
		(start 118.606062 -52.118514)
		(end 118.479062 -52.245514)
		(width 0.127)
		(layer "In5.Cu")
		(net "XM_ADDR_12")
	)
	(segment
		(start 115.230402 -52.4637)
		(end 115.103402 -52.5907)
		(width 0.127)
		(layer "In5.Cu")
		(net "XM_ADDR_12")
	)
	(segment
		(start 114.087402 -52.5907)
		(end 114.087402 -53.34762)
		(width 0.127)
		(layer "In5.Cu")
		(net "XM_ADDR_12")
	)
	(segment
		(start 121.146062 -52.499006)
		(end 121.019062 -52.372006)
		(width 0.127)
		(layer "In5.Cu")
		(net "XM_ADDR_12")
	)
	(segment
		(start 118.987062 -52.245514)
		(end 118.860062 -52.118514)
		(width 0.127)
		(layer "In5.Cu")
		(net "XM_ADDR_12")
	)
	(segment
		(start 117.408198 -52.118514)
		(end 117.12575 -52.400962)
		(width 0.127)
		(layer "In5.Cu")
		(net "XM_ADDR_12")
	)
	(segment
		(start 138.5697 -48.0441)
		(end 138.5697 -47.5107)
		(width 0.127)
		(layer "In5.Cu")
		(net "XM_ADDR_12")
	)
	(segment
		(start 127.72009 -49.882806)
		(end 127.59309 -50.009806)
		(width 0.127)
		(layer "In5.Cu")
		(net "XM_ADDR_12")
	)
	(segment
		(start 120.003062 -52.372006)
		(end 120.003062 -52.245514)
		(width 0.127)
		(layer "In5.Cu")
		(net "XM_ADDR_12")
	)
	(segment
		(start 128.10109 -49.258728)
		(end 127.84709 -49.258728)
		(width 0.127)
		(layer "In5.Cu")
		(net "XM_ADDR_12")
	)
	(segment
		(start 120.511062 -52.372006)
		(end 120.384062 -52.499006)
		(width 0.127)
		(layer "In5.Cu")
		(net "XM_ADDR_12")
	)
	(segment
		(start 128.60909 -50.009806)
		(end 128.35509 -50.009806)
		(width 0.127)
		(layer "In5.Cu")
		(net "XM_ADDR_12")
	)
	(segment
		(start 114.214402 -52.4637)
		(end 114.087402 -52.5907)
		(width 0.127)
		(layer "In5.Cu")
		(net "XM_ADDR_12")
	)
	(segment
		(start 127.84709 -49.258728)
		(end 127.72009 -49.385728)
		(width 0.127)
		(layer "In5.Cu")
		(net "XM_ADDR_12")
	)
	(segment
		(start 126.32309 -50.009806)
		(end 126.19609 -49.882806)
		(width 0.127)
		(layer "In5.Cu")
		(net "XM_ADDR_12")
	)
	(segment
		(start 115.103402 -52.8193)
		(end 114.976402 -52.9463)
		(width 0.127)
		(layer "In5.Cu")
		(net "XM_ADDR_12")
	)
	(segment
		(start 119.368062 -52.499006)
		(end 119.114062 -52.499006)
		(width 0.127)
		(layer "In5.Cu")
		(net "XM_ADDR_12")
	)
	(segment
		(start 121.019062 -52.372006)
		(end 121.019062 -52.245514)
		(width 0.127)
		(layer "In5.Cu")
		(net "XM_ADDR_12")
	)
	(segment
		(start 130.26009 -49.385728)
		(end 130.13309 -49.258728)
		(width 0.127)
		(layer "In5.Cu")
		(net "XM_ADDR_12")
	)
	(segment
		(start 129.37109 -50.009806)
		(end 129.24409 -49.882806)
		(width 0.127)
		(layer "In5.Cu")
		(net "XM_ADDR_12")
	)
	(segment
		(start 119.876062 -52.118514)
		(end 119.622062 -52.118514)
		(width 0.127)
		(layer "In5.Cu")
		(net "XM_ADDR_12")
	)
	(segment
		(start 123.825 -84.836)
		(end 123.825 -84.793582)
		(width 0.1016)
		(layer "F.Cu")
		(net "SAS3008_RAID_TX_P3")
	)
	(segment
		(start 84.272628 -38.571932)
		(end 84.08416 -38.760654)
		(width 0.1016)
		(layer "F.Cu")
		(net "SAS3008_RAID_TX_P3")
	)
	(segment
		(start 123.35002 -85.349842)
		(end 123.35002 -85.31098)
		(width 0.1016)
		(layer "F.Cu")
		(net "SAS3008_RAID_TX_P3")
	)
	(segment
		(start 123.35002 -85.31098)
		(end 123.825 -84.836)
		(width 0.1016)
		(layer "F.Cu")
		(net "SAS3008_RAID_TX_P3")
	)
	(segment
		(start 85.865208 -38.46195)
		(end 84.538566 -38.46195)
		(width 0.1016)
		(layer "F.Cu")
		(net "SAS3008_RAID_TX_P3")
	)
	(via
		(at 130.048 -81.28)
		(size 0.5588)
		(drill 0.3048)
		(layers "F.Cu" "B.Cu")
		(net "SAS3008_RAID_TX_P3")
	)
	(via
		(at 82.911188 -38.736778)
		(size 0.5588)
		(drill 0.3048)
		(layers "F.Cu" "B.Cu")
		(net "SAS3008_RAID_TX_P3")
	)
	(via
		(at 84.08416 -38.760654)
		(size 0.508)
		(drill 0.254)
		(layers "F.Cu" "B.Cu")
		(net "SAS3008_RAID_TX_P3")
	)
	(via
		(at 123.825 -84.793582)
		(size 0.508)
		(drill 0.254)
		(layers "F.Cu" "B.Cu")
		(net "SAS3008_RAID_TX_P3")
	)
	(arc
		(start 84.538566 -38.46195)
		(mid 84.394654 -38.490482)
		(end 84.272628 -38.571932)
		(width 0.1016)
		(layer "F.Cu")
		(net "SAS3008_RAID_TX_P3")
	)
	(arc
		(start 86.21776 -38.608)
		(mid 86.056008 -38.499921)
		(end 85.865208 -38.46195)
		(width 0.1016)
		(layer "F.Cu")
		(net "SAS3008_RAID_TX_P3")
	)
	(segment
		(start 129.75717 -82.9056)
		(end 129.75717 -81.57083)
		(width 0.1016)
		(layer "B.Cu")
		(net "SAS3008_RAID_TX_P3")
	)
	(segment
		(start 125.872748 -83.693)
		(end 128.96977 -83.693)
		(width 0.1016)
		(layer "B.Cu")
		(net "SAS3008_RAID_TX_P3")
	)
	(segment
		(start 125.283976 -84.102194)
		(end 125.56617 -83.82)
		(width 0.1016)
		(layer "B.Cu")
		(net "SAS3008_RAID_TX_P3")
	)
	(segment
		(start 84.08416 -38.760654)
		(end 84.08416 -38.650926)
		(width 0.1016)
		(layer "B.Cu")
		(net "SAS3008_RAID_TX_P3")
	)
	(segment
		(start 124.099066 -84.680044)
		(end 124.355606 -84.423504)
		(width 0.1016)
		(layer "B.Cu")
		(net "SAS3008_RAID_TX_P3")
	)
	(segment
		(start 83.888834 -38.4556)
		(end 83.166966 -38.4556)
		(width 0.1016)
		(layer "B.Cu")
		(net "SAS3008_RAID_TX_P3")
	)
	(segment
		(start 124.52477 -84.3534)
		(end 124.67717 -84.3534)
		(width 0.1016)
		(layer "B.Cu")
		(net "SAS3008_RAID_TX_P3")
	)
	(segment
		(start 129.75717 -81.57083)
		(end 130.048 -81.28)
		(width 0.1016)
		(layer "B.Cu")
		(net "SAS3008_RAID_TX_P3")
	)
	(segment
		(start 82.911188 -38.711378)
		(end 82.911188 -38.736778)
		(width 0.1016)
		(layer "B.Cu")
		(net "SAS3008_RAID_TX_P3")
	)
	(arc
		(start 123.825 -84.793582)
		(mid 123.97333 -84.764077)
		(end 124.099066 -84.680044)
		(width 0.1016)
		(layer "B.Cu")
		(net "SAS3008_RAID_TX_P3")
	)
	(arc
		(start 128.96977 -83.693)
		(mid 129.526546 -83.462376)
		(end 129.75717 -82.9056)
		(width 0.1016)
		(layer "B.Cu")
		(net "SAS3008_RAID_TX_P3")
	)
	(arc
		(start 125.56617 -83.82)
		(mid 125.706829 -83.726015)
		(end 125.872748 -83.693)
		(width 0.1016)
		(layer "B.Cu")
		(net "SAS3008_RAID_TX_P3")
	)
	(arc
		(start 83.166966 -38.4556)
		(mid 82.986104 -38.530516)
		(end 82.911188 -38.711378)
		(width 0.1016)
		(layer "B.Cu")
		(net "SAS3008_RAID_TX_P3")
	)
	(arc
		(start 84.08416 -38.650926)
		(mid 84.02695 -38.51281)
		(end 83.888834 -38.4556)
		(width 0.1016)
		(layer "B.Cu")
		(net "SAS3008_RAID_TX_P3")
	)
	(arc
		(start 124.355606 -84.423504)
		(mid 124.433219 -84.371645)
		(end 124.52477 -84.3534)
		(width 0.1016)
		(layer "B.Cu")
		(net "SAS3008_RAID_TX_P3")
	)
	(arc
		(start 124.67717 -84.3534)
		(mid 125.005571 -84.288171)
		(end 125.283976 -84.102194)
		(width 0.1016)
		(layer "B.Cu")
		(net "SAS3008_RAID_TX_P3")
	)
	(segment
		(start 89.516458 -52.384706)
		(end 89.300812 -52.169314)
		(width 0.1016)
		(layer "In2.Cu")
		(net "SAS3008_RAID_TX_P3")
	)
	(segment
		(start 97.84588 -61.034168)
		(end 97.630488 -60.818522)
		(width 0.1016)
		(layer "In2.Cu")
		(net "SAS3008_RAID_TX_P3")
	)
	(segment
		(start 81.973166 -40.21201)
		(end 81.973166 -38.893496)
		(width 0.1016)
		(layer "In2.Cu")
		(net "SAS3008_RAID_TX_P3")
	)
	(segment
		(start 91.945968 -55.134002)
		(end 91.730322 -54.918356)
		(width 0.1016)
		(layer "In2.Cu")
		(net "SAS3008_RAID_TX_P3")
	)
	(segment
		(start 98.541078 -61.40958)
		(end 98.325432 -61.193934)
		(width 0.1016)
		(layer "In2.Cu")
		(net "SAS3008_RAID_TX_P3")
	)
	(segment
		(start 103.893112 -64.127888)
		(end 103.875586 -64.110362)
		(width 0.1016)
		(layer "In2.Cu")
		(net "SAS3008_RAID_TX_P3")
	)
	(segment
		(start 91.570556 -54.438804)
		(end 91.35491 -54.223412)
		(width 0.1016)
		(layer "In2.Cu")
		(net "SAS3008_RAID_TX_P3")
	)
	(segment
		(start 110.80877 -68.60794)
		(end 110.50397 -68.60794)
		(width 0.1016)
		(layer "In2.Cu")
		(net "SAS3008_RAID_TX_P3")
	)
	(segment
		(start 82.231992 -40.71112)
		(end 82.143092 -40.62222)
		(width 0.1016)
		(layer "In2.Cu")
		(net "SAS3008_RAID_TX_P3")
	)
	(segment
		(start 112.32261 -68.60794)
		(end 112.01781 -68.60794)
		(width 0.1016)
		(layer "In2.Cu")
		(net "SAS3008_RAID_TX_P3")
	)
	(segment
		(start 83.624928 -40.62222)
		(end 83.320128 -40.62222)
		(width 0.1016)
		(layer "In2.Cu")
		(net "SAS3008_RAID_TX_P3")
	)
	(segment
		(start 108.48467 -68.7197)
		(end 107.274614 -67.509644)
		(width 0.1016)
		(layer "In2.Cu")
		(net "SAS3008_RAID_TX_P3")
	)
	(segment
		(start 111.56569 -68.834)
		(end 111.26089 -68.834)
		(width 0.1016)
		(layer "In2.Cu")
		(net "SAS3008_RAID_TX_P3")
	)
	(segment
		(start 103.892858 -64.127888)
		(end 103.893112 -64.127888)
		(width 0.1016)
		(layer "In2.Cu")
		(net "SAS3008_RAID_TX_P3")
	)
	(segment
		(start 82.049366 -38.7096)
		(end 82.080354 -38.678612)
		(width 0.1016)
		(layer "In2.Cu")
		(net "SAS3008_RAID_TX_P3")
	)
	(segment
		(start 87.750904 -50.938938)
		(end 86.298278 -49.486312)
		(width 0.1016)
		(layer "In2.Cu")
		(net "SAS3008_RAID_TX_P3")
	)
	(segment
		(start 96.775524 -59.963558)
		(end 96.559878 -59.748166)
		(width 0.1016)
		(layer "In2.Cu")
		(net "SAS3008_RAID_TX_P3")
	)
	(segment
		(start 126.480316 -70.9422)
		(end 120.692164 -70.9422)
		(width 0.1016)
		(layer "In2.Cu")
		(net "SAS3008_RAID_TX_P3")
	)
	(segment
		(start 82.868008 -40.84828)
		(end 82.563208 -40.84828)
		(width 0.1016)
		(layer "In2.Cu")
		(net "SAS3008_RAID_TX_P3")
	)
	(segment
		(start 93.711522 -56.57977)
		(end 93.495876 -56.364378)
		(width 0.1016)
		(layer "In2.Cu")
		(net "SAS3008_RAID_TX_P3")
	)
	(segment
		(start 85.579966 -43.596814)
		(end 85.579966 -41.91508)
		(width 0.1016)
		(layer "In2.Cu")
		(net "SAS3008_RAID_TX_P3")
	)
	(segment
		(start 88.82126 -52.009294)
		(end 88.605868 -51.793902)
		(width 0.1016)
		(layer "In2.Cu")
		(net "SAS3008_RAID_TX_P3")
	)
	(segment
		(start 95.705168 -58.893202)
		(end 93.871288 -57.059322)
		(width 0.1016)
		(layer "In2.Cu")
		(net "SAS3008_RAID_TX_P3")
	)
	(segment
		(start 85.579966 -47.752)
		(end 85.579966 -46.319694)
		(width 0.1016)
		(layer "In2.Cu")
		(net "SAS3008_RAID_TX_P3")
	)
	(segment
		(start 90.875612 -54.063646)
		(end 89.676224 -52.864258)
		(width 0.1016)
		(layer "In2.Cu")
		(net "SAS3008_RAID_TX_P3")
	)
	(segment
		(start 85.806026 -45.867574)
		(end 85.806026 -45.562774)
		(width 0.1016)
		(layer "In2.Cu")
		(net "SAS3008_RAID_TX_P3")
	)
	(segment
		(start 82.724752 -38.550342)
		(end 82.911188 -38.736778)
		(width 0.1016)
		(layer "In2.Cu")
		(net "SAS3008_RAID_TX_P3")
	)
	(segment
		(start 92.640912 -55.509414)
		(end 92.42552 -55.293768)
		(width 0.1016)
		(layer "In2.Cu")
		(net "SAS3008_RAID_TX_P3")
	)
	(segment
		(start 129.20091 -73.22058)
		(end 127.234696 -71.25462)
		(width 0.1016)
		(layer "In2.Cu")
		(net "SAS3008_RAID_TX_P3")
	)
	(segment
		(start 107.114594 -67.030092)
		(end 106.899202 -66.814446)
		(width 0.1016)
		(layer "In2.Cu")
		(net "SAS3008_RAID_TX_P3")
	)
	(segment
		(start 106.044238 -65.959482)
		(end 105.828592 -65.74409)
		(width 0.1016)
		(layer "In2.Cu")
		(net "SAS3008_RAID_TX_P3")
	)
	(segment
		(start 100.193856 -63.382144)
		(end 98.700844 -61.889132)
		(width 0.1016)
		(layer "In2.Cu")
		(net "SAS3008_RAID_TX_P3")
	)
	(segment
		(start 85.579966 -45.110654)
		(end 85.579966 -44.805854)
		(width 0.1016)
		(layer "In2.Cu")
		(net "SAS3008_RAID_TX_P3")
	)
	(segment
		(start 105.34904 -65.58407)
		(end 103.892858 -64.127888)
		(width 0.1016)
		(layer "In2.Cu")
		(net "SAS3008_RAID_TX_P3")
	)
	(segment
		(start 102.707694 -63.627)
		(end 100.784914 -63.627)
		(width 0.1016)
		(layer "In2.Cu")
		(net "SAS3008_RAID_TX_P3")
	)
	(segment
		(start 84.513166 -40.84828)
		(end 84.077048 -40.84828)
		(width 0.1016)
		(layer "In2.Cu")
		(net "SAS3008_RAID_TX_P3")
	)
	(segment
		(start 117.846856 -68.834)
		(end 112.77473 -68.834)
		(width 0.1016)
		(layer "In2.Cu")
		(net "SAS3008_RAID_TX_P3")
	)
	(segment
		(start 130.048 -81.28)
		(end 129.95402 -81.186274)
		(width 0.1016)
		(layer "In2.Cu")
		(net "SAS3008_RAID_TX_P3")
	)
	(segment
		(start 110.05185 -68.834)
		(end 108.760514 -68.834)
		(width 0.1016)
		(layer "In2.Cu")
		(net "SAS3008_RAID_TX_P3")
	)
	(segment
		(start 93.016324 -56.204358)
		(end 92.800932 -55.988966)
		(width 0.1016)
		(layer "In2.Cu")
		(net "SAS3008_RAID_TX_P3")
	)
	(segment
		(start 106.41965 -66.65468)
		(end 106.204004 -66.439034)
		(width 0.1016)
		(layer "In2.Cu")
		(net "SAS3008_RAID_TX_P3")
	)
	(segment
		(start 120.097296 -70.69582)
		(end 118.509796 -69.10832)
		(width 0.1016)
		(layer "In2.Cu")
		(net "SAS3008_RAID_TX_P3")
	)
	(segment
		(start 97.470468 -60.33897)
		(end 97.255076 -60.123578)
		(width 0.1016)
		(layer "In2.Cu")
		(net "SAS3008_RAID_TX_P3")
	)
	(segment
		(start 88.446102 -51.31435)
		(end 88.230456 -51.098704)
		(width 0.1016)
		(layer "In2.Cu")
		(net "SAS3008_RAID_TX_P3")
	)
	(segment
		(start 129.78257 -80.772)
		(end 129.78257 -74.624946)
		(width 0.1016)
		(layer "In2.Cu")
		(net "SAS3008_RAID_TX_P3")
	)
	(segment
		(start 85.806026 -44.353734)
		(end 85.806026 -44.048934)
		(width 0.1016)
		(layer "In2.Cu")
		(net "SAS3008_RAID_TX_P3")
	)
	(segment
		(start 96.400112 -59.268614)
		(end 96.18472 -59.052968)
		(width 0.1016)
		(layer "In2.Cu")
		(net "SAS3008_RAID_TX_P3")
	)
	(arc
		(start 83.320128 -40.62222)
		(mid 83.193467 -40.651459)
		(end 83.094068 -40.73525)
		(width 0.1016)
		(layer "In2.Cu")
		(net "SAS3008_RAID_TX_P3")
	)
	(arc
		(start 96.559878 -59.748166)
		(mid 96.491042 -59.637911)
		(end 96.480122 -59.50839)
		(width 0.1016)
		(layer "In2.Cu")
		(net "SAS3008_RAID_TX_P3")
	)
	(arc
		(start 106.659426 -66.734436)
		(mid 106.529904 -66.723519)
		(end 106.41965 -66.65468)
		(width 0.1016)
		(layer "In2.Cu")
		(net "SAS3008_RAID_TX_P3")
	)
	(arc
		(start 92.185744 -55.214012)
		(mid 92.056187 -55.202969)
		(end 91.945968 -55.134002)
		(width 0.1016)
		(layer "In2.Cu")
		(net "SAS3008_RAID_TX_P3")
	)
	(arc
		(start 127.234696 -71.25462)
		(mid 126.88857 -71.023379)
		(end 126.480316 -70.9422)
		(width 0.1016)
		(layer "In2.Cu")
		(net "SAS3008_RAID_TX_P3")
	)
	(arc
		(start 110.50397 -68.60794)
		(mid 110.377309 -68.637179)
		(end 110.27791 -68.72097)
		(width 0.1016)
		(layer "In2.Cu")
		(net "SAS3008_RAID_TX_P3")
	)
	(arc
		(start 120.692164 -70.9422)
		(mid 120.370232 -70.878164)
		(end 120.097296 -70.69582)
		(width 0.1016)
		(layer "In2.Cu")
		(net "SAS3008_RAID_TX_P3")
	)
	(arc
		(start 93.495876 -56.364378)
		(mid 93.385657 -56.295381)
		(end 93.2561 -56.284368)
		(width 0.1016)
		(layer "In2.Cu")
		(net "SAS3008_RAID_TX_P3")
	)
	(arc
		(start 89.676224 -52.864258)
		(mid 89.607388 -52.754003)
		(end 89.596468 -52.624482)
		(width 0.1016)
		(layer "In2.Cu")
		(net "SAS3008_RAID_TX_P3")
	)
	(arc
		(start 97.0153 -60.043568)
		(mid 96.885755 -60.032518)
		(end 96.775524 -59.963558)
		(width 0.1016)
		(layer "In2.Cu")
		(net "SAS3008_RAID_TX_P3")
	)
	(arc
		(start 85.692996 -43.822874)
		(mid 85.609159 -43.723498)
		(end 85.579966 -43.596814)
		(width 0.1016)
		(layer "In2.Cu")
		(net "SAS3008_RAID_TX_P3")
	)
	(arc
		(start 83.850988 -40.73525)
		(mid 83.751612 -40.651413)
		(end 83.624928 -40.62222)
		(width 0.1016)
		(layer "In2.Cu")
		(net "SAS3008_RAID_TX_P3")
	)
	(arc
		(start 85.579966 -46.319694)
		(mid 85.609205 -46.193033)
		(end 85.692996 -46.093634)
		(width 0.1016)
		(layer "In2.Cu")
		(net "SAS3008_RAID_TX_P3")
	)
	(arc
		(start 106.124248 -66.199258)
		(mid 106.113205 -66.069701)
		(end 106.044238 -65.959482)
		(width 0.1016)
		(layer "In2.Cu")
		(net "SAS3008_RAID_TX_P3")
	)
	(arc
		(start 87.99068 -51.018948)
		(mid 87.861123 -51.007905)
		(end 87.750904 -50.938938)
		(width 0.1016)
		(layer "In2.Cu")
		(net "SAS3008_RAID_TX_P3")
	)
	(arc
		(start 82.080354 -38.678612)
		(mid 82.299209 -38.532378)
		(end 82.557366 -38.481)
		(width 0.1016)
		(layer "In2.Cu")
		(net "SAS3008_RAID_TX_P3")
	)
	(arc
		(start 129.78257 -74.624946)
		(mid 129.631355 -73.864938)
		(end 129.20091 -73.22058)
		(width 0.1016)
		(layer "In2.Cu")
		(net "SAS3008_RAID_TX_P3")
	)
	(arc
		(start 111.79175 -68.72097)
		(mid 111.692374 -68.804807)
		(end 111.56569 -68.834)
		(width 0.1016)
		(layer "In2.Cu")
		(net "SAS3008_RAID_TX_P3")
	)
	(arc
		(start 91.115134 -54.143402)
		(mid 90.985759 -54.132409)
		(end 90.875612 -54.063646)
		(width 0.1016)
		(layer "In2.Cu")
		(net "SAS3008_RAID_TX_P3")
	)
	(arc
		(start 93.871288 -57.059322)
		(mid 93.802291 -56.949103)
		(end 93.791278 -56.819546)
		(width 0.1016)
		(layer "In2.Cu")
		(net "SAS3008_RAID_TX_P3")
	)
	(arc
		(start 82.563208 -40.84828)
		(mid 82.383968 -40.812627)
		(end 82.231992 -40.71112)
		(width 0.1016)
		(layer "In2.Cu")
		(net "SAS3008_RAID_TX_P3")
	)
	(arc
		(start 105.588816 -65.66408)
		(mid 105.459271 -65.65303)
		(end 105.34904 -65.58407)
		(width 0.1016)
		(layer "In2.Cu")
		(net "SAS3008_RAID_TX_P3")
	)
	(arc
		(start 97.550478 -60.578746)
		(mid 97.539428 -60.449201)
		(end 97.470468 -60.33897)
		(width 0.1016)
		(layer "In2.Cu")
		(net "SAS3008_RAID_TX_P3")
	)
	(arc
		(start 98.325432 -61.193934)
		(mid 98.215202 -61.125)
		(end 98.085656 -61.113924)
		(width 0.1016)
		(layer "In2.Cu")
		(net "SAS3008_RAID_TX_P3")
	)
	(arc
		(start 84.077048 -40.84828)
		(mid 83.950387 -40.819041)
		(end 83.850988 -40.73525)
		(width 0.1016)
		(layer "In2.Cu")
		(net "SAS3008_RAID_TX_P3")
	)
	(arc
		(start 85.692996 -46.093634)
		(mid 85.776833 -45.994258)
		(end 85.806026 -45.867574)
		(width 0.1016)
		(layer "In2.Cu")
		(net "SAS3008_RAID_TX_P3")
	)
	(arc
		(start 93.791278 -56.819546)
		(mid 93.780361 -56.690024)
		(end 93.711522 -56.57977)
		(width 0.1016)
		(layer "In2.Cu")
		(net "SAS3008_RAID_TX_P3")
	)
	(arc
		(start 92.720922 -55.74919)
		(mid 92.709872 -55.619645)
		(end 92.640912 -55.509414)
		(width 0.1016)
		(layer "In2.Cu")
		(net "SAS3008_RAID_TX_P3")
	)
	(arc
		(start 88.605868 -51.793902)
		(mid 88.536934 -51.683672)
		(end 88.525858 -51.554126)
		(width 0.1016)
		(layer "In2.Cu")
		(net "SAS3008_RAID_TX_P3")
	)
	(arc
		(start 89.300812 -52.169314)
		(mid 89.190593 -52.100317)
		(end 89.061036 -52.089304)
		(width 0.1016)
		(layer "In2.Cu")
		(net "SAS3008_RAID_TX_P3")
	)
	(arc
		(start 105.828592 -65.74409)
		(mid 105.718373 -65.675093)
		(end 105.588816 -65.66408)
		(width 0.1016)
		(layer "In2.Cu")
		(net "SAS3008_RAID_TX_P3")
	)
	(arc
		(start 85.806026 -44.048934)
		(mid 85.776787 -43.922273)
		(end 85.692996 -43.822874)
		(width 0.1016)
		(layer "In2.Cu")
		(net "SAS3008_RAID_TX_P3")
	)
	(arc
		(start 82.557366 -38.481)
		(mid 82.569193 -38.481334)
		(end 82.580988 -38.48227)
		(width 0.1016)
		(layer "In2.Cu")
		(net "SAS3008_RAID_TX_P3")
	)
	(arc
		(start 96.480122 -59.50839)
		(mid 96.469079 -59.378833)
		(end 96.400112 -59.268614)
		(width 0.1016)
		(layer "In2.Cu")
		(net "SAS3008_RAID_TX_P3")
	)
	(arc
		(start 89.596468 -52.624482)
		(mid 89.585425 -52.494925)
		(end 89.516458 -52.384706)
		(width 0.1016)
		(layer "In2.Cu")
		(net "SAS3008_RAID_TX_P3")
	)
	(arc
		(start 112.54867 -68.72097)
		(mid 112.449294 -68.637133)
		(end 112.32261 -68.60794)
		(width 0.1016)
		(layer "In2.Cu")
		(net "SAS3008_RAID_TX_P3")
	)
	(arc
		(start 82.143092 -40.62222)
		(mid 82.017337 -40.434014)
		(end 81.973166 -40.21201)
		(width 0.1016)
		(layer "In2.Cu")
		(net "SAS3008_RAID_TX_P3")
	)
	(arc
		(start 98.700844 -61.889132)
		(mid 98.63191 -61.778902)
		(end 98.620834 -61.649356)
		(width 0.1016)
		(layer "In2.Cu")
		(net "SAS3008_RAID_TX_P3")
	)
	(arc
		(start 85.692996 -45.336714)
		(mid 85.609159 -45.237338)
		(end 85.579966 -45.110654)
		(width 0.1016)
		(layer "In2.Cu")
		(net "SAS3008_RAID_TX_P3")
	)
	(arc
		(start 112.01781 -68.60794)
		(mid 111.891149 -68.637179)
		(end 111.79175 -68.72097)
		(width 0.1016)
		(layer "In2.Cu")
		(net "SAS3008_RAID_TX_P3")
	)
	(arc
		(start 91.730322 -54.918356)
		(mid 91.661486 -54.808101)
		(end 91.650566 -54.67858)
		(width 0.1016)
		(layer "In2.Cu")
		(net "SAS3008_RAID_TX_P3")
	)
	(arc
		(start 106.899202 -66.814446)
		(mid 106.788972 -66.745512)
		(end 106.659426 -66.734436)
		(width 0.1016)
		(layer "In2.Cu")
		(net "SAS3008_RAID_TX_P3")
	)
	(arc
		(start 97.255076 -60.123578)
		(mid 97.144857 -60.054581)
		(end 97.0153 -60.043568)
		(width 0.1016)
		(layer "In2.Cu")
		(net "SAS3008_RAID_TX_P3")
	)
	(arc
		(start 98.085656 -61.113924)
		(mid 97.956134 -61.103007)
		(end 97.84588 -61.034168)
		(width 0.1016)
		(layer "In2.Cu")
		(net "SAS3008_RAID_TX_P3")
	)
	(arc
		(start 85.579966 -41.91508)
		(mid 85.267508 -41.160738)
		(end 84.513166 -40.84828)
		(width 0.1016)
		(layer "In2.Cu")
		(net "SAS3008_RAID_TX_P3")
	)
	(arc
		(start 111.03483 -68.72097)
		(mid 110.935454 -68.637133)
		(end 110.80877 -68.60794)
		(width 0.1016)
		(layer "In2.Cu")
		(net "SAS3008_RAID_TX_P3")
	)
	(arc
		(start 89.061036 -52.089304)
		(mid 88.931491 -52.078254)
		(end 88.82126 -52.009294)
		(width 0.1016)
		(layer "In2.Cu")
		(net "SAS3008_RAID_TX_P3")
	)
	(arc
		(start 91.35491 -54.223412)
		(mid 91.244691 -54.154415)
		(end 91.115134 -54.143402)
		(width 0.1016)
		(layer "In2.Cu")
		(net "SAS3008_RAID_TX_P3")
	)
	(arc
		(start 85.806026 -45.562774)
		(mid 85.776787 -45.436113)
		(end 85.692996 -45.336714)
		(width 0.1016)
		(layer "In2.Cu")
		(net "SAS3008_RAID_TX_P3")
	)
	(arc
		(start 83.094068 -40.73525)
		(mid 82.994692 -40.819087)
		(end 82.868008 -40.84828)
		(width 0.1016)
		(layer "In2.Cu")
		(net "SAS3008_RAID_TX_P3")
	)
	(arc
		(start 88.525858 -51.554126)
		(mid 88.514941 -51.424604)
		(end 88.446102 -51.31435)
		(width 0.1016)
		(layer "In2.Cu")
		(net "SAS3008_RAID_TX_P3")
	)
	(arc
		(start 112.77473 -68.834)
		(mid 112.648069 -68.804761)
		(end 112.54867 -68.72097)
		(width 0.1016)
		(layer "In2.Cu")
		(net "SAS3008_RAID_TX_P3")
	)
	(arc
		(start 88.230456 -51.098704)
		(mid 88.120201 -51.029868)
		(end 87.99068 -51.018948)
		(width 0.1016)
		(layer "In2.Cu")
		(net "SAS3008_RAID_TX_P3")
	)
	(arc
		(start 81.973166 -38.893496)
		(mid 81.992965 -38.793962)
		(end 82.049366 -38.7096)
		(width 0.1016)
		(layer "In2.Cu")
		(net "SAS3008_RAID_TX_P3")
	)
	(arc
		(start 92.42552 -55.293768)
		(mid 92.315265 -55.224932)
		(end 92.185744 -55.214012)
		(width 0.1016)
		(layer "In2.Cu")
		(net "SAS3008_RAID_TX_P3")
	)
	(arc
		(start 110.27791 -68.72097)
		(mid 110.178534 -68.804807)
		(end 110.05185 -68.834)
		(width 0.1016)
		(layer "In2.Cu")
		(net "SAS3008_RAID_TX_P3")
	)
	(arc
		(start 111.26089 -68.834)
		(mid 111.134229 -68.804761)
		(end 111.03483 -68.72097)
		(width 0.1016)
		(layer "In2.Cu")
		(net "SAS3008_RAID_TX_P3")
	)
	(arc
		(start 106.204004 -66.439034)
		(mid 106.135168 -66.328779)
		(end 106.124248 -66.199258)
		(width 0.1016)
		(layer "In2.Cu")
		(net "SAS3008_RAID_TX_P3")
	)
	(arc
		(start 107.194604 -67.269868)
		(mid 107.183554 -67.140323)
		(end 107.114594 -67.030092)
		(width 0.1016)
		(layer "In2.Cu")
		(net "SAS3008_RAID_TX_P3")
	)
	(arc
		(start 108.760514 -68.834)
		(mid 108.611212 -68.804302)
		(end 108.48467 -68.7197)
		(width 0.1016)
		(layer "In2.Cu")
		(net "SAS3008_RAID_TX_P3")
	)
	(arc
		(start 98.620834 -61.649356)
		(mid 98.609917 -61.519834)
		(end 98.541078 -61.40958)
		(width 0.1016)
		(layer "In2.Cu")
		(net "SAS3008_RAID_TX_P3")
	)
	(arc
		(start 85.692996 -44.579794)
		(mid 85.776833 -44.480418)
		(end 85.806026 -44.353734)
		(width 0.1016)
		(layer "In2.Cu")
		(net "SAS3008_RAID_TX_P3")
	)
	(arc
		(start 86.298278 -49.486312)
		(mid 85.766656 -48.690589)
		(end 85.579966 -47.752)
		(width 0.1016)
		(layer "In2.Cu")
		(net "SAS3008_RAID_TX_P3")
	)
	(arc
		(start 100.784914 -63.627)
		(mid 100.465024 -63.56337)
		(end 100.193856 -63.382144)
		(width 0.1016)
		(layer "In2.Cu")
		(net "SAS3008_RAID_TX_P3")
	)
	(arc
		(start 95.944944 -58.972958)
		(mid 95.815422 -58.962041)
		(end 95.705168 -58.893202)
		(width 0.1016)
		(layer "In2.Cu")
		(net "SAS3008_RAID_TX_P3")
	)
	(arc
		(start 97.630488 -60.818522)
		(mid 97.561491 -60.708303)
		(end 97.550478 -60.578746)
		(width 0.1016)
		(layer "In2.Cu")
		(net "SAS3008_RAID_TX_P3")
	)
	(arc
		(start 103.875586 -64.110362)
		(mid 103.339723 -63.752496)
		(end 102.707694 -63.627)
		(width 0.1016)
		(layer "In2.Cu")
		(net "SAS3008_RAID_TX_P3")
	)
	(arc
		(start 91.650566 -54.67858)
		(mid 91.639523 -54.549023)
		(end 91.570556 -54.438804)
		(width 0.1016)
		(layer "In2.Cu")
		(net "SAS3008_RAID_TX_P3")
	)
	(arc
		(start 118.509796 -69.10832)
		(mid 118.205606 -68.905253)
		(end 117.846856 -68.834)
		(width 0.1016)
		(layer "In2.Cu")
		(net "SAS3008_RAID_TX_P3")
	)
	(arc
		(start 82.580988 -38.48227)
		(mid 82.658737 -38.5039)
		(end 82.724752 -38.550342)
		(width 0.1016)
		(layer "In2.Cu")
		(net "SAS3008_RAID_TX_P3")
	)
	(arc
		(start 96.18472 -59.052968)
		(mid 96.07449 -58.984034)
		(end 95.944944 -58.972958)
		(width 0.1016)
		(layer "In2.Cu")
		(net "SAS3008_RAID_TX_P3")
	)
	(arc
		(start 85.579966 -44.805854)
		(mid 85.609205 -44.679193)
		(end 85.692996 -44.579794)
		(width 0.1016)
		(layer "In2.Cu")
		(net "SAS3008_RAID_TX_P3")
	)
	(arc
		(start 107.274614 -67.509644)
		(mid 107.205617 -67.399425)
		(end 107.194604 -67.269868)
		(width 0.1016)
		(layer "In2.Cu")
		(net "SAS3008_RAID_TX_P3")
	)
	(arc
		(start 129.95402 -81.186274)
		(mid 129.827102 -80.996188)
		(end 129.78257 -80.772)
		(width 0.1016)
		(layer "In2.Cu")
		(net "SAS3008_RAID_TX_P3")
	)
	(arc
		(start 92.800932 -55.988966)
		(mid 92.731935 -55.878747)
		(end 92.720922 -55.74919)
		(width 0.1016)
		(layer "In2.Cu")
		(net "SAS3008_RAID_TX_P3")
	)
	(arc
		(start 93.2561 -56.284368)
		(mid 93.126555 -56.273318)
		(end 93.016324 -56.204358)
		(width 0.1016)
		(layer "In2.Cu")
		(net "SAS3008_RAID_TX_P3")
	)
	(segment
		(start 68.69049 -127.6604)
		(end 68.88607 -127.6604)
		(width 0.1143)
		(layer "F.Cu")
		(net "EXP_XM_ADDR_2")
	)
	(segment
		(start 66.74739 -128.59766)
		(end 66.74739 -127.7747)
		(width 0.1143)
		(layer "F.Cu")
		(net "EXP_XM_ADDR_2")
	)
	(segment
		(start 66.40449 -128.71196)
		(end 66.63309 -128.71196)
		(width 0.1143)
		(layer "F.Cu")
		(net "EXP_XM_ADDR_2")
	)
	(segment
		(start 68.48983 -129.42824)
		(end 68.57619 -129.34188)
		(width 0.1143)
		(layer "F.Cu")
		(net "EXP_XM_ADDR_2")
	)
	(segment
		(start 66.29019 -127.7747)
		(end 66.29019 -128.59766)
		(width 0.1143)
		(layer "F.Cu")
		(net "EXP_XM_ADDR_2")
	)
	(segment
		(start 68.88607 -127.6604)
		(end 69.03593 -127.51054)
		(width 0.1143)
		(layer "F.Cu")
		(net "EXP_XM_ADDR_2")
	)
	(segment
		(start 69.03593 -127.51054)
		(end 69.03593 -127.200914)
		(width 0.1143)
		(layer "F.Cu")
		(net "EXP_XM_ADDR_2")
	)
	(segment
		(start 68.57619 -129.34188)
		(end 68.57619 -127.7747)
		(width 0.1143)
		(layer "F.Cu")
		(net "EXP_XM_ADDR_2")
	)
	(segment
		(start 65.79997 -127.10668)
		(end 65.79997 -127.127)
		(width 0.1143)
		(layer "F.Cu")
		(net "EXP_XM_ADDR_2")
	)
	(segment
		(start 58.370978 -126.91745)
		(end 58.434478 -126.98095)
		(width 0.1143)
		(layer "F.Cu")
		(net "EXP_XM_ADDR_2")
	)
	(segment
		(start 66.63309 -128.71196)
		(end 66.74739 -128.59766)
		(width 0.1143)
		(layer "F.Cu")
		(net "EXP_XM_ADDR_2")
	)
	(segment
		(start 107.349798 -94.349824)
		(end 106.849672 -93.849698)
		(width 0.1143)
		(layer "F.Cu")
		(net "EXP_XM_ADDR_2")
	)
	(segment
		(start 58.434478 -126.98095)
		(end 58.839862 -126.98095)
		(width 0.1143)
		(layer "F.Cu")
		(net "EXP_XM_ADDR_2")
	)
	(segment
		(start 62.37732 -126.91745)
		(end 62.43701 -126.85776)
		(width 0.1143)
		(layer "F.Cu")
		(net "EXP_XM_ADDR_2")
	)
	(segment
		(start 68.11899 -129.33934)
		(end 68.20789 -129.42824)
		(width 0.1143)
		(layer "F.Cu")
		(net "EXP_XM_ADDR_2")
	)
	(segment
		(start 68.20789 -129.42824)
		(end 68.48983 -129.42824)
		(width 0.1143)
		(layer "F.Cu")
		(net "EXP_XM_ADDR_2")
	)
	(segment
		(start 67.279266 -129.328926)
		(end 67.593464 -129.328926)
		(width 0.1143)
		(layer "F.Cu")
		(net "EXP_XM_ADDR_2")
	)
	(segment
		(start 67.09029 -127.6604)
		(end 67.20459 -127.7747)
		(width 0.1143)
		(layer "F.Cu")
		(net "EXP_XM_ADDR_2")
	)
	(segment
		(start 58.903362 -126.91745)
		(end 62.37732 -126.91745)
		(width 0.1143)
		(layer "F.Cu")
		(net "EXP_XM_ADDR_2")
	)
	(segment
		(start 66.04889 -126.85776)
		(end 65.79997 -127.10668)
		(width 0.1143)
		(layer "F.Cu")
		(net "EXP_XM_ADDR_2")
	)
	(segment
		(start 66.74739 -127.7747)
		(end 66.86169 -127.6604)
		(width 0.1143)
		(layer "F.Cu")
		(net "EXP_XM_ADDR_2")
	)
	(segment
		(start 67.66179 -127.7747)
		(end 67.77609 -127.6604)
		(width 0.1143)
		(layer "F.Cu")
		(net "EXP_XM_ADDR_2")
	)
	(segment
		(start 67.20459 -129.25425)
		(end 67.279266 -129.328926)
		(width 0.1143)
		(layer "F.Cu")
		(net "EXP_XM_ADDR_2")
	)
	(segment
		(start 68.57619 -127.7747)
		(end 68.69049 -127.6604)
		(width 0.1143)
		(layer "F.Cu")
		(net "EXP_XM_ADDR_2")
	)
	(segment
		(start 68.00469 -127.6604)
		(end 68.11899 -127.7747)
		(width 0.1143)
		(layer "F.Cu")
		(net "EXP_XM_ADDR_2")
	)
	(segment
		(start 69.03593 -127.200914)
		(end 68.692776 -126.85776)
		(width 0.1143)
		(layer "F.Cu")
		(net "EXP_XM_ADDR_2")
	)
	(segment
		(start 58.039 -126.91745)
		(end 58.370978 -126.91745)
		(width 0.1143)
		(layer "F.Cu")
		(net "EXP_XM_ADDR_2")
	)
	(segment
		(start 68.11899 -127.7747)
		(end 68.11899 -129.33934)
		(width 0.1143)
		(layer "F.Cu")
		(net "EXP_XM_ADDR_2")
	)
	(segment
		(start 65.60947 -127.6604)
		(end 66.17589 -127.6604)
		(width 0.1143)
		(layer "F.Cu")
		(net "EXP_XM_ADDR_2")
	)
	(segment
		(start 56.558942 -127.391922)
		(end 57.564528 -127.391922)
		(width 0.1143)
		(layer "F.Cu")
		(net "EXP_XM_ADDR_2")
	)
	(segment
		(start 66.86169 -127.6604)
		(end 67.09029 -127.6604)
		(width 0.1143)
		(layer "F.Cu")
		(net "EXP_XM_ADDR_2")
	)
	(segment
		(start 67.77609 -127.6604)
		(end 68.00469 -127.6604)
		(width 0.1143)
		(layer "F.Cu")
		(net "EXP_XM_ADDR_2")
	)
	(segment
		(start 57.564528 -127.391922)
		(end 58.039 -126.91745)
		(width 0.1143)
		(layer "F.Cu")
		(net "EXP_XM_ADDR_2")
	)
	(segment
		(start 67.66179 -129.2606)
		(end 67.66179 -127.7747)
		(width 0.1143)
		(layer "F.Cu")
		(net "EXP_XM_ADDR_2")
	)
	(segment
		(start 66.29019 -128.59766)
		(end 66.40449 -128.71196)
		(width 0.1143)
		(layer "F.Cu")
		(net "EXP_XM_ADDR_2")
	)
	(segment
		(start 64.80683 -126.85776)
		(end 65.60947 -127.6604)
		(width 0.1143)
		(layer "F.Cu")
		(net "EXP_XM_ADDR_2")
	)
	(segment
		(start 68.692776 -126.85776)
		(end 66.04889 -126.85776)
		(width 0.1143)
		(layer "F.Cu")
		(net "EXP_XM_ADDR_2")
	)
	(segment
		(start 62.43701 -126.85776)
		(end 64.80683 -126.85776)
		(width 0.1143)
		(layer "F.Cu")
		(net "EXP_XM_ADDR_2")
	)
	(segment
		(start 67.593464 -129.328926)
		(end 67.66179 -129.2606)
		(width 0.1143)
		(layer "F.Cu")
		(net "EXP_XM_ADDR_2")
	)
	(segment
		(start 66.17589 -127.6604)
		(end 66.29019 -127.7747)
		(width 0.1143)
		(layer "F.Cu")
		(net "EXP_XM_ADDR_2")
	)
	(segment
		(start 67.20459 -127.7747)
		(end 67.20459 -129.25425)
		(width 0.1143)
		(layer "F.Cu")
		(net "EXP_XM_ADDR_2")
	)
	(segment
		(start 58.839862 -126.98095)
		(end 58.903362 -126.91745)
		(width 0.1143)
		(layer "F.Cu")
		(net "EXP_XM_ADDR_2")
	)
	(via
		(at 65.79997 -126.2888)
		(size 0.7112)
		(drill 0.3556)
		(layers "F.Cu" "B.Cu")
		(net "EXP_XM_ADDR_2")
	)
	(via
		(at 65.79997 -127.127)
		(size 0.5588)
		(drill 0.3048)
		(layers "F.Cu" "B.Cu")
		(net "EXP_XM_ADDR_2")
	)
	(via
		(at 106.849672 -93.849698)
		(size 0.508)
		(drill 0.254)
		(layers "F.Cu" "B.Cu")
		(net "EXP_XM_ADDR_2")
	)
	(segment
		(start 65.79997 -127.127)
		(end 65.79997 -126.2888)
		(width 0.1143)
		(layer "B.Cu")
		(net "EXP_XM_ADDR_2")
	)
	(segment
		(start 93.576902 -94.76232)
		(end 93.576902 -94.43974)
		(width 0.127)
		(layer "In2.Cu")
		(net "EXP_XM_ADDR_2")
	)
	(segment
		(start 103.665528 -93.2942)
		(end 103.547926 -93.176598)
		(width 0.127)
		(layer "In2.Cu")
		(net "EXP_XM_ADDR_2")
	)
	(segment
		(start 93.957902 -94.88932)
		(end 93.703902 -94.88932)
		(width 0.127)
		(layer "In2.Cu")
		(net "EXP_XM_ADDR_2")
	)
	(segment
		(start 93.703902 -94.88932)
		(end 93.576902 -94.76232)
		(width 0.127)
		(layer "In2.Cu")
		(net "EXP_XM_ADDR_2")
	)
	(segment
		(start 94.211902 -94.31274)
		(end 94.084902 -94.43974)
		(width 0.127)
		(layer "In2.Cu")
		(net "EXP_XM_ADDR_2")
	)
	(segment
		(start 81.06537 -102.395782)
		(end 81.06537 -104.485948)
		(width 0.127)
		(layer "In2.Cu")
		(net "EXP_XM_ADDR_2")
	)
	(segment
		(start 106.849672 -93.849698)
		(end 106.802428 -93.849698)
		(width 0.127)
		(layer "In2.Cu")
		(net "EXP_XM_ADDR_2")
	)
	(segment
		(start 65.83807 -126.313184)
		(end 65.79997 -126.351284)
		(width 0.127)
		(layer "In2.Cu")
		(net "EXP_XM_ADDR_2")
	)
	(segment
		(start 94.78645 -94.31274)
		(end 94.211902 -94.31274)
		(width 0.127)
		(layer "In2.Cu")
		(net "EXP_XM_ADDR_2")
	)
	(segment
		(start 94.084902 -94.76232)
		(end 93.957902 -94.88932)
		(width 0.127)
		(layer "In2.Cu")
		(net "EXP_XM_ADDR_2")
	)
	(segment
		(start 94.992444 -94.106746)
		(end 94.78645 -94.31274)
		(width 0.127)
		(layer "In2.Cu")
		(net "EXP_XM_ADDR_2")
	)
	(segment
		(start 81.06537 -104.485948)
		(end 65.83807 -119.713248)
		(width 0.127)
		(layer "In2.Cu")
		(net "EXP_XM_ADDR_2")
	)
	(segment
		(start 65.83807 -119.713248)
		(end 65.83807 -126.313184)
		(width 0.127)
		(layer "In2.Cu")
		(net "EXP_XM_ADDR_2")
	)
	(segment
		(start 103.547926 -93.176598)
		(end 101.549962 -93.176598)
		(width 0.127)
		(layer "In2.Cu")
		(net "EXP_XM_ADDR_2")
	)
	(segment
		(start 65.79997 -126.351284)
		(end 65.79997 -127.127)
		(width 0.127)
		(layer "In2.Cu")
		(net "EXP_XM_ADDR_2")
	)
	(segment
		(start 106.24693 -93.2942)
		(end 103.665528 -93.2942)
		(width 0.127)
		(layer "In2.Cu")
		(net "EXP_XM_ADDR_2")
	)
	(segment
		(start 101.549962 -93.176598)
		(end 100.619814 -94.106746)
		(width 0.127)
		(layer "In2.Cu")
		(net "EXP_XM_ADDR_2")
	)
	(segment
		(start 100.619814 -94.106746)
		(end 94.992444 -94.106746)
		(width 0.127)
		(layer "In2.Cu")
		(net "EXP_XM_ADDR_2")
	)
	(segment
		(start 93.576902 -94.43974)
		(end 93.449902 -94.31274)
		(width 0.127)
		(layer "In2.Cu")
		(net "EXP_XM_ADDR_2")
	)
	(segment
		(start 106.802428 -93.849698)
		(end 106.24693 -93.2942)
		(width 0.127)
		(layer "In2.Cu")
		(net "EXP_XM_ADDR_2")
	)
	(segment
		(start 94.084902 -94.43974)
		(end 94.084902 -94.76232)
		(width 0.127)
		(layer "In2.Cu")
		(net "EXP_XM_ADDR_2")
	)
	(segment
		(start 89.148412 -94.31274)
		(end 81.06537 -102.395782)
		(width 0.127)
		(layer "In2.Cu")
		(net "EXP_XM_ADDR_2")
	)
	(segment
		(start 93.449902 -94.31274)
		(end 89.148412 -94.31274)
		(width 0.127)
		(layer "In2.Cu")
		(net "EXP_XM_ADDR_2")
	)
	(segment
		(start 106.689652 -109.056932)
		(end 107.560364 -108.18622)
		(width 0.1016)
		(layer "F.Cu")
		(net "SAS_HDD_TX10_N")
	)
	(segment
		(start 107.73283 -107.76966)
		(end 107.73283 -106.57078)
		(width 0.1016)
		(layer "F.Cu")
		(net "SAS_HDD_TX10_N")
	)
	(segment
		(start 103.950262 -112.445292)
		(end 106.078782 -110.316518)
		(width 0.1016)
		(layer "F.Cu")
		(net "SAS_HDD_TX10_N")
	)
	(segment
		(start 103.66502 -113.522252)
		(end 103.66502 -113.133632)
		(width 0.1016)
		(layer "F.Cu")
		(net "SAS_HDD_TX10_N")
	)
	(segment
		(start 103.51897 -114.0206)
		(end 103.51897 -113.773458)
		(width 0.1016)
		(layer "F.Cu")
		(net "SAS_HDD_TX10_N")
	)
	(segment
		(start 103.556054 -113.683796)
		(end 103.627936 -113.611914)
		(width 0.1016)
		(layer "F.Cu")
		(net "SAS_HDD_TX10_N")
	)
	(segment
		(start 106.078782 -110.316518)
		(end 106.230928 -110.164372)
		(width 0.1016)
		(layer "F.Cu")
		(net "SAS_HDD_TX10_N")
	)
	(segment
		(start 108.159804 -105.540048)
		(end 108.349796 -105.350056)
		(width 0.1016)
		(layer "F.Cu")
		(net "SAS_HDD_TX10_N")
	)
	(arc
		(start 103.627936 -113.611914)
		(mid 103.655369 -113.570763)
		(end 103.66502 -113.522252)
		(width 0.1016)
		(layer "F.Cu")
		(net "SAS_HDD_TX10_N")
	)
	(arc
		(start 107.73283 -106.57078)
		(mid 107.843791 -106.01294)
		(end 108.159804 -105.540048)
		(width 0.1016)
		(layer "F.Cu")
		(net "SAS_HDD_TX10_N")
	)
	(arc
		(start 106.230928 -110.164372)
		(mid 106.317978 -110.033953)
		(end 106.34853 -109.880146)
		(width 0.1016)
		(layer "F.Cu")
		(net "SAS_HDD_TX10_N")
	)
	(arc
		(start 107.560364 -108.18622)
		(mid 107.681507 -108.010012)
		(end 107.731814 -107.802172)
		(width 0.1016)
		(layer "F.Cu")
		(net "SAS_HDD_TX10_N")
	)
	(arc
		(start 103.66502 -113.133632)
		(mid 103.739197 -112.761098)
		(end 103.950262 -112.445292)
		(width 0.1016)
		(layer "F.Cu")
		(net "SAS_HDD_TX10_N")
	)
	(arc
		(start 106.34853 -109.880146)
		(mid 106.437258 -109.434642)
		(end 106.689652 -109.056932)
		(width 0.1016)
		(layer "F.Cu")
		(net "SAS_HDD_TX10_N")
	)
	(arc
		(start 103.51897 -113.773458)
		(mid 103.528603 -113.72494)
		(end 103.556054 -113.683796)
		(width 0.1016)
		(layer "F.Cu")
		(net "SAS_HDD_TX10_N")
	)
	(arc
		(start 107.731814 -107.802172)
		(mid 107.732543 -107.785923)
		(end 107.73283 -107.76966)
		(width 0.1016)
		(layer "F.Cu")
		(net "SAS_HDD_TX10_N")
	)
	(segment
		(start 138.39952 -46.492414)
		(end 138.49985 -46.592744)
		(width 0.1143)
		(layer "F.Cu")
		(net "XM_ADDR_13")
	)
	(segment
		(start 138.107674 -47.146972)
		(end 138.107674 -47.500032)
		(width 0.1143)
		(layer "F.Cu")
		(net "XM_ADDR_13")
	)
	(segment
		(start 138.099546 -42.7101)
		(end 138.099546 -46.345094)
		(width 0.1143)
		(layer "F.Cu")
		(net "XM_ADDR_13")
	)
	(segment
		(start 138.246866 -46.492414)
		(end 138.39952 -46.492414)
		(width 0.1143)
		(layer "F.Cu")
		(net "XM_ADDR_13")
	)
	(segment
		(start 138.099546 -46.345094)
		(end 138.246866 -46.492414)
		(width 0.1143)
		(layer "F.Cu")
		(net "XM_ADDR_13")
	)
	(segment
		(start 138.49985 -46.919642)
		(end 138.39952 -47.019972)
		(width 0.1143)
		(layer "F.Cu")
		(net "XM_ADDR_13")
	)
	(segment
		(start 138.43 -47.829216)
		(end 138.43 -49.53)
		(width 0.1143)
		(layer "F.Cu")
		(net "XM_ADDR_13")
	)
	(segment
		(start 138.28395 -47.683166)
		(end 138.43 -47.829216)
		(width 0.1143)
		(layer "F.Cu")
		(net "XM_ADDR_13")
	)
	(segment
		(start 114.168174 -54.99989)
		(end 114.870484 -55.7022)
		(width 0.1143)
		(layer "F.Cu")
		(net "XM_ADDR_13")
	)
	(segment
		(start 138.39952 -47.019972)
		(end 138.234674 -47.019972)
		(width 0.1143)
		(layer "F.Cu")
		(net "XM_ADDR_13")
	)
	(segment
		(start 113.949988 -54.99989)
		(end 114.168174 -54.99989)
		(width 0.1143)
		(layer "F.Cu")
		(net "XM_ADDR_13")
	)
	(segment
		(start 138.234674 -47.019972)
		(end 138.107674 -47.146972)
		(width 0.1143)
		(layer "F.Cu")
		(net "XM_ADDR_13")
	)
	(segment
		(start 114.870484 -55.7022)
		(end 115.247166 -55.7022)
		(width 0.1143)
		(layer "F.Cu")
		(net "XM_ADDR_13")
	)
	(segment
		(start 138.0744 -42.684954)
		(end 138.099546 -42.7101)
		(width 0.1143)
		(layer "F.Cu")
		(net "XM_ADDR_13")
	)
	(segment
		(start 138.107674 -47.500032)
		(end 138.28395 -47.676308)
		(width 0.1143)
		(layer "F.Cu")
		(net "XM_ADDR_13")
	)
	(segment
		(start 138.0744 -40.89908)
		(end 138.0744 -42.684954)
		(width 0.1143)
		(layer "F.Cu")
		(net "XM_ADDR_13")
	)
	(segment
		(start 138.28395 -47.676308)
		(end 138.28395 -47.683166)
		(width 0.1143)
		(layer "F.Cu")
		(net "XM_ADDR_13")
	)
	(segment
		(start 138.49985 -46.592744)
		(end 138.49985 -46.919642)
		(width 0.1143)
		(layer "F.Cu")
		(net "XM_ADDR_13")
	)
	(via
		(at 115.247166 -55.7022)
		(size 0.508)
		(drill 0.254)
		(layers "F.Cu" "B.Cu")
		(net "XM_ADDR_13")
	)
	(via
		(at 138.43 -49.53)
		(size 0.5588)
		(drill 0.3048)
		(layers "F.Cu" "B.Cu")
		(net "XM_ADDR_13")
	)
	(via
		(at 138.0744 -40.89908)
		(size 0.7112)
		(drill 0.3556)
		(layers "F.Cu" "B.Cu")
		(net "XM_ADDR_13")
	)
	(segment
		(start 144.988788 -50.6349)
		(end 144.395698 -50.6349)
		(width 0.127)
		(layer "In5.Cu")
		(net "XM_ADDR_13")
	)
	(segment
		(start 138.521186 -50.241962)
		(end 138.394186 -50.368962)
		(width 0.127)
		(layer "In5.Cu")
		(net "XM_ADDR_13")
	)
	(segment
		(start 123.952254 -54.3306)
		(end 117.550438 -54.3306)
		(width 0.127)
		(layer "In5.Cu")
		(net "XM_ADDR_13")
	)
	(segment
		(start 138.775186 -50.241962)
		(end 138.521186 -50.241962)
		(width 0.127)
		(layer "In5.Cu")
		(net "XM_ADDR_13")
	)
	(segment
		(start 142.58417 -50.214276)
		(end 142.58417 -49.8983)
		(width 0.127)
		(layer "In5.Cu")
		(net "XM_ADDR_13")
	)
	(segment
		(start 142.45717 -50.341276)
		(end 142.58417 -50.214276)
		(width 0.127)
		(layer "In5.Cu")
		(net "XM_ADDR_13")
	)
	(segment
		(start 144.988788 -49.2125)
		(end 145.115788 -49.3395)
		(width 0.127)
		(layer "In5.Cu")
		(net "XM_ADDR_13")
	)
	(segment
		(start 143.77797 -49.3395)
		(end 143.90497 -49.2125)
		(width 0.127)
		(layer "In5.Cu")
		(net "XM_ADDR_13")
	)
	(segment
		(start 139.918186 -50.700432)
		(end 139.918186 -50.03927)
		(width 0.127)
		(layer "In5.Cu")
		(net "XM_ADDR_13")
	)
	(segment
		(start 139.791186 -49.91227)
		(end 139.537186 -49.91227)
		(width 0.127)
		(layer "In5.Cu")
		(net "XM_ADDR_13")
	)
	(segment
		(start 139.918186 -50.03927)
		(end 139.791186 -49.91227)
		(width 0.127)
		(layer "In5.Cu")
		(net "XM_ADDR_13")
	)
	(segment
		(start 140.93317 -49.7713)
		(end 141.06017 -49.8983)
		(width 0.127)
		(layer "In5.Cu")
		(net "XM_ADDR_13")
	)
	(segment
		(start 138.267186 -50.827432)
		(end 137.835386 -50.827432)
		(width 0.127)
		(layer "In5.Cu")
		(net "XM_ADDR_13")
	)
	(segment
		(start 141.06017 -49.8983)
		(end 141.06017 -50.214276)
		(width 0.127)
		(layer "In5.Cu")
		(net "XM_ADDR_13")
	)
	(segment
		(start 138.394186 -50.368962)
		(end 138.394186 -50.700432)
		(width 0.127)
		(layer "In5.Cu")
		(net "XM_ADDR_13")
	)
	(segment
		(start 139.410186 -50.700432)
		(end 139.283186 -50.827432)
		(width 0.127)
		(layer "In5.Cu")
		(net "XM_ADDR_13")
	)
	(segment
		(start 141.94917 -49.7713)
		(end 142.07617 -49.8983)
		(width 0.127)
		(layer "In5.Cu")
		(net "XM_ADDR_13")
	)
	(segment
		(start 138.902186 -50.368962)
		(end 138.775186 -50.241962)
		(width 0.127)
		(layer "In5.Cu")
		(net "XM_ADDR_13")
	)
	(segment
		(start 142.20317 -50.341276)
		(end 142.45717 -50.341276)
		(width 0.127)
		(layer "In5.Cu")
		(net "XM_ADDR_13")
	)
	(segment
		(start 141.56817 -50.214276)
		(end 141.56817 -49.8983)
		(width 0.127)
		(layer "In5.Cu")
		(net "XM_ADDR_13")
	)
	(segment
		(start 116.05514 -54.894226)
		(end 115.247166 -55.7022)
		(width 0.127)
		(layer "In5.Cu")
		(net "XM_ADDR_13")
	)
	(segment
		(start 135.30961 -49.53)
		(end 132.211318 -52.628292)
		(width 0.127)
		(layer "In5.Cu")
		(net "XM_ADDR_13")
	)
	(segment
		(start 141.56817 -49.8983)
		(end 141.69517 -49.7713)
		(width 0.127)
		(layer "In5.Cu")
		(net "XM_ADDR_13")
	)
	(segment
		(start 140.045186 -50.827432)
		(end 139.918186 -50.700432)
		(width 0.127)
		(layer "In5.Cu")
		(net "XM_ADDR_13")
	)
	(segment
		(start 131.495292 -52.628038)
		(end 125.654816 -52.628038)
		(width 0.127)
		(layer "In5.Cu")
		(net "XM_ADDR_13")
	)
	(segment
		(start 143.77797 -50.186082)
		(end 143.77797 -49.3395)
		(width 0.127)
		(layer "In5.Cu")
		(net "XM_ADDR_13")
	)
	(segment
		(start 144.203166 -50.827432)
		(end 140.045186 -50.827432)
		(width 0.127)
		(layer "In5.Cu")
		(net "XM_ADDR_13")
	)
	(segment
		(start 138.902186 -50.700432)
		(end 138.902186 -50.368962)
		(width 0.127)
		(layer "In5.Cu")
		(net "XM_ADDR_13")
	)
	(segment
		(start 116.986812 -54.894226)
		(end 116.05514 -54.894226)
		(width 0.127)
		(layer "In5.Cu")
		(net "XM_ADDR_13")
	)
	(segment
		(start 125.654816 -52.628038)
		(end 123.952254 -54.3306)
		(width 0.127)
		(layer "In5.Cu")
		(net "XM_ADDR_13")
	)
	(segment
		(start 142.58417 -49.8983)
		(end 142.71117 -49.7713)
		(width 0.127)
		(layer "In5.Cu")
		(net "XM_ADDR_13")
	)
	(segment
		(start 140.49375 -49.7713)
		(end 140.93317 -49.7713)
		(width 0.127)
		(layer "In5.Cu")
		(net "XM_ADDR_13")
	)
	(segment
		(start 139.283186 -50.827432)
		(end 139.029186 -50.827432)
		(width 0.127)
		(layer "In5.Cu")
		(net "XM_ADDR_13")
	)
	(segment
		(start 145.115788 -49.3395)
		(end 145.115788 -50.5079)
		(width 0.127)
		(layer "In5.Cu")
		(net "XM_ADDR_13")
	)
	(segment
		(start 139.410186 -50.03927)
		(end 139.410186 -50.700432)
		(width 0.127)
		(layer "In5.Cu")
		(net "XM_ADDR_13")
	)
	(segment
		(start 140.18895 -49.4665)
		(end 140.49375 -49.7713)
		(width 0.127)
		(layer "In5.Cu")
		(net "XM_ADDR_13")
	)
	(segment
		(start 141.69517 -49.7713)
		(end 141.94917 -49.7713)
		(width 0.127)
		(layer "In5.Cu")
		(net "XM_ADDR_13")
	)
	(segment
		(start 141.44117 -50.341276)
		(end 141.56817 -50.214276)
		(width 0.127)
		(layer "In5.Cu")
		(net "XM_ADDR_13")
	)
	(segment
		(start 143.14297 -49.7713)
		(end 143.26997 -49.8983)
		(width 0.127)
		(layer "In5.Cu")
		(net "XM_ADDR_13")
	)
	(segment
		(start 143.26997 -49.8983)
		(end 143.26997 -50.186082)
		(width 0.127)
		(layer "In5.Cu")
		(net "XM_ADDR_13")
	)
	(segment
		(start 142.07617 -50.214276)
		(end 142.20317 -50.341276)
		(width 0.127)
		(layer "In5.Cu")
		(net "XM_ADDR_13")
	)
	(segment
		(start 138.4935 -49.4665)
		(end 140.18895 -49.4665)
		(width 0.127)
		(layer "In5.Cu")
		(net "XM_ADDR_13")
	)
	(segment
		(start 143.90497 -49.2125)
		(end 144.988788 -49.2125)
		(width 0.127)
		(layer "In5.Cu")
		(net "XM_ADDR_13")
	)
	(segment
		(start 138.394186 -50.700432)
		(end 138.267186 -50.827432)
		(width 0.127)
		(layer "In5.Cu")
		(net "XM_ADDR_13")
	)
	(segment
		(start 143.26997 -50.186082)
		(end 143.39697 -50.313082)
		(width 0.127)
		(layer "In5.Cu")
		(net "XM_ADDR_13")
	)
	(segment
		(start 131.495546 -52.628292)
		(end 131.495292 -52.628038)
		(width 0.127)
		(layer "In5.Cu")
		(net "XM_ADDR_13")
	)
	(segment
		(start 139.029186 -50.827432)
		(end 138.902186 -50.700432)
		(width 0.127)
		(layer "In5.Cu")
		(net "XM_ADDR_13")
	)
	(segment
		(start 143.39697 -50.313082)
		(end 143.65097 -50.313082)
		(width 0.127)
		(layer "In5.Cu")
		(net "XM_ADDR_13")
	)
	(segment
		(start 136.537954 -49.53)
		(end 135.30961 -49.53)
		(width 0.127)
		(layer "In5.Cu")
		(net "XM_ADDR_13")
	)
	(segment
		(start 139.537186 -49.91227)
		(end 139.410186 -50.03927)
		(width 0.127)
		(layer "In5.Cu")
		(net "XM_ADDR_13")
	)
	(segment
		(start 138.43 -49.53)
		(end 138.4935 -49.4665)
		(width 0.127)
		(layer "In5.Cu")
		(net "XM_ADDR_13")
	)
	(segment
		(start 145.115788 -50.5079)
		(end 144.988788 -50.6349)
		(width 0.127)
		(layer "In5.Cu")
		(net "XM_ADDR_13")
	)
	(segment
		(start 144.395698 -50.6349)
		(end 144.203166 -50.827432)
		(width 0.127)
		(layer "In5.Cu")
		(net "XM_ADDR_13")
	)
	(segment
		(start 143.65097 -50.313082)
		(end 143.77797 -50.186082)
		(width 0.127)
		(layer "In5.Cu")
		(net "XM_ADDR_13")
	)
	(segment
		(start 132.211318 -52.628292)
		(end 131.495546 -52.628292)
		(width 0.127)
		(layer "In5.Cu")
		(net "XM_ADDR_13")
	)
	(segment
		(start 141.18717 -50.341276)
		(end 141.44117 -50.341276)
		(width 0.127)
		(layer "In5.Cu")
		(net "XM_ADDR_13")
	)
	(segment
		(start 117.550438 -54.3306)
		(end 116.986812 -54.894226)
		(width 0.127)
		(layer "In5.Cu")
		(net "XM_ADDR_13")
	)
	(segment
		(start 141.06017 -50.214276)
		(end 141.18717 -50.341276)
		(width 0.127)
		(layer "In5.Cu")
		(net "XM_ADDR_13")
	)
	(segment
		(start 142.07617 -49.8983)
		(end 142.07617 -50.214276)
		(width 0.127)
		(layer "In5.Cu")
		(net "XM_ADDR_13")
	)
	(segment
		(start 142.71117 -49.7713)
		(end 143.14297 -49.7713)
		(width 0.127)
		(layer "In5.Cu")
		(net "XM_ADDR_13")
	)
	(segment
		(start 137.835386 -50.827432)
		(end 136.537954 -49.53)
		(width 0.127)
		(layer "In5.Cu")
		(net "XM_ADDR_13")
	)
	(segment
		(start 201.041 -112.395)
		(end 201.422 -112.014)
		(width 0.508)
		(layer "F.Cu")
		(net "P1V5_E_VBST")
	)
	(segment
		(start 202.336908 -111.633)
		(end 201.422 -111.633)
		(width 0.508)
		(layer "F.Cu")
		(net "P1V5_E_VBST")
	)
	(segment
		(start 201.422 -112.014)
		(end 201.422 -111.633)
		(width 0.508)
		(layer "F.Cu")
		(net "P1V5_E_VBST")
	)
	(segment
		(start 200.590658 -112.845342)
		(end 201.041 -112.395)
		(width 0.3048)
		(layer "F.Cu")
		(net "P1V5_E_VBST")
	)
	(segment
		(start 200.590658 -113.022888)
		(end 200.590658 -112.845342)
		(width 0.3048)
		(layer "F.Cu")
		(net "P1V5_E_VBST")
	)
	(segment
		(start 202.888596 -111.081312)
		(end 202.336908 -111.633)
		(width 0.508)
		(layer "F.Cu")
		(net "P1V5_E_VBST")
	)
	(via
		(at 201.422 -111.633)
		(size 0.7112)
		(drill 0.3556)
		(layers "F.Cu" "B.Cu")
		(net "P1V5_E_VBST")
	)
	(segment
		(start 56.558942 -130.392932)
		(end 57.32018 -130.392932)
		(width 0.1143)
		(layer "F.Cu")
		(net "EXP_XM_ADDR_8")
	)
	(segment
		(start 106.3498 -92.349828)
		(end 105.849674 -91.849702)
		(width 0.1143)
		(layer "F.Cu")
		(net "EXP_XM_ADDR_8")
	)
	(segment
		(start 57.32018 -130.392932)
		(end 57.356248 -130.429)
		(width 0.1143)
		(layer "F.Cu")
		(net "EXP_XM_ADDR_8")
	)
	(segment
		(start 57.356248 -130.429)
		(end 60.21197 -130.429)
		(width 0.1143)
		(layer "F.Cu")
		(net "EXP_XM_ADDR_8")
	)
	(via
		(at 60.21197 -131.191)
		(size 0.7112)
		(drill 0.3556)
		(layers "F.Cu" "B.Cu")
		(net "EXP_XM_ADDR_8")
	)
	(via
		(at 105.849674 -91.849702)
		(size 0.508)
		(drill 0.254)
		(layers "F.Cu" "B.Cu")
		(net "EXP_XM_ADDR_8")
	)
	(via
		(at 60.21197 -130.429)
		(size 0.5588)
		(drill 0.3048)
		(layers "F.Cu" "B.Cu")
		(net "EXP_XM_ADDR_8")
	)
	(segment
		(start 60.21197 -130.429)
		(end 60.21197 -131.191)
		(width 0.1143)
		(layer "B.Cu")
		(net "EXP_XM_ADDR_8")
	)
	(segment
		(start 79.377032 -97.738692)
		(end 79.55661 -97.559114)
		(width 0.127)
		(layer "In2.Cu")
		(net "EXP_XM_ADDR_8")
	)
	(segment
		(start 104.268778 -89.861644)
		(end 104.837738 -90.430604)
		(width 0.127)
		(layer "In2.Cu")
		(net "EXP_XM_ADDR_8")
	)
	(segment
		(start 78.727554 -95.831406)
		(end 79.91602 -97.019872)
		(width 0.127)
		(layer "In2.Cu")
		(net "EXP_XM_ADDR_8")
	)
	(segment
		(start 79.086964 -95.471996)
		(end 79.086964 -95.292164)
		(width 0.127)
		(layer "In2.Cu")
		(net "EXP_XM_ADDR_8")
	)
	(segment
		(start 60.211208 -117.219984)
		(end 60.211208 -116.904516)
		(width 0.127)
		(layer "In2.Cu")
		(net "EXP_XM_ADDR_8")
	)
	(segment
		(start 77.649324 -96.909636)
		(end 77.649324 -96.729804)
		(width 0.127)
		(layer "In2.Cu")
		(net "EXP_XM_ADDR_8")
	)
	(segment
		(start 77.649324 -96.729804)
		(end 77.828902 -96.550226)
		(width 0.127)
		(layer "In2.Cu")
		(net "EXP_XM_ADDR_8")
	)
	(segment
		(start 79.55661 -97.559114)
		(end 79.55661 -97.379282)
		(width 0.127)
		(layer "In2.Cu")
		(net "EXP_XM_ADDR_8")
	)
	(segment
		(start 79.55661 -97.379282)
		(end 78.368144 -96.190816)
		(width 0.127)
		(layer "In2.Cu")
		(net "EXP_XM_ADDR_8")
	)
	(segment
		(start 102.154228 -89.430606)
		(end 104.023414 -89.430606)
		(width 0.127)
		(layer "In2.Cu")
		(net "EXP_XM_ADDR_8")
	)
	(segment
		(start 90.7923 -87.3887)
		(end 99.803712 -87.3887)
		(width 0.127)
		(layer "In2.Cu")
		(net "EXP_XM_ADDR_8")
	)
	(segment
		(start 80.27543 -96.840294)
		(end 80.27543 -96.660462)
		(width 0.127)
		(layer "In2.Cu")
		(net "EXP_XM_ADDR_8")
	)
	(segment
		(start 100.307394 -87.892382)
		(end 100.307394 -87.947754)
		(width 0.127)
		(layer "In2.Cu")
		(net "EXP_XM_ADDR_8")
	)
	(segment
		(start 104.023414 -89.430606)
		(end 104.268778 -89.67597)
		(width 0.127)
		(layer "In2.Cu")
		(net "EXP_XM_ADDR_8")
	)
	(segment
		(start 60.211462 -130.266948)
		(end 60.211462 -117.220238)
		(width 0.127)
		(layer "In2.Cu")
		(net "EXP_XM_ADDR_8")
	)
	(segment
		(start 78.83779 -98.098102)
		(end 77.649324 -96.909636)
		(width 0.127)
		(layer "In2.Cu")
		(net "EXP_XM_ADDR_8")
	)
	(segment
		(start 78.368144 -96.190816)
		(end 78.368144 -96.010984)
		(width 0.127)
		(layer "In2.Cu")
		(net "EXP_XM_ADDR_8")
	)
	(segment
		(start 79.446374 -95.112586)
		(end 80.63484 -96.301052)
		(width 0.127)
		(layer "In2.Cu")
		(net "EXP_XM_ADDR_8")
	)
	(segment
		(start 60.211462 -117.220238)
		(end 60.211208 -117.219984)
		(width 0.127)
		(layer "In2.Cu")
		(net "EXP_XM_ADDR_8")
	)
	(segment
		(start 78.008734 -96.550226)
		(end 79.1972 -97.738692)
		(width 0.127)
		(layer "In2.Cu")
		(net "EXP_XM_ADDR_8")
	)
	(segment
		(start 80.814672 -96.301052)
		(end 85.316568 -91.799156)
		(width 0.127)
		(layer "In2.Cu")
		(net "EXP_XM_ADDR_8")
	)
	(segment
		(start 85.733128 -91.799156)
		(end 88.377776 -89.154508)
		(width 0.127)
		(layer "In2.Cu")
		(net "EXP_XM_ADDR_8")
	)
	(segment
		(start 89.026492 -89.154508)
		(end 90.7923 -87.3887)
		(width 0.127)
		(layer "In2.Cu")
		(net "EXP_XM_ADDR_8")
	)
	(segment
		(start 100.915724 -88.556084)
		(end 101.279706 -88.556084)
		(width 0.127)
		(layer "In2.Cu")
		(net "EXP_XM_ADDR_8")
	)
	(segment
		(start 60.21197 -130.429)
		(end 60.21197 -130.267456)
		(width 0.127)
		(layer "In2.Cu")
		(net "EXP_XM_ADDR_8")
	)
	(segment
		(start 104.837738 -90.430604)
		(end 105.023412 -90.430604)
		(width 0.127)
		(layer "In2.Cu")
		(net "EXP_XM_ADDR_8")
	)
	(segment
		(start 105.023412 -90.430604)
		(end 105.268776 -90.675968)
		(width 0.127)
		(layer "In2.Cu")
		(net "EXP_XM_ADDR_8")
	)
	(segment
		(start 101.279706 -88.556084)
		(end 102.154228 -89.430606)
		(width 0.127)
		(layer "In2.Cu")
		(net "EXP_XM_ADDR_8")
	)
	(segment
		(start 79.1972 -97.738692)
		(end 79.377032 -97.738692)
		(width 0.127)
		(layer "In2.Cu")
		(net "EXP_XM_ADDR_8")
	)
	(segment
		(start 80.095852 -97.019872)
		(end 80.27543 -96.840294)
		(width 0.127)
		(layer "In2.Cu")
		(net "EXP_XM_ADDR_8")
	)
	(segment
		(start 80.27543 -96.660462)
		(end 79.086964 -95.471996)
		(width 0.127)
		(layer "In2.Cu")
		(net "EXP_XM_ADDR_8")
	)
	(segment
		(start 105.268776 -91.268804)
		(end 105.849674 -91.849702)
		(width 0.127)
		(layer "In2.Cu")
		(net "EXP_XM_ADDR_8")
	)
	(segment
		(start 78.547722 -95.831406)
		(end 78.727554 -95.831406)
		(width 0.127)
		(layer "In2.Cu")
		(net "EXP_XM_ADDR_8")
	)
	(segment
		(start 78.83779 -98.277934)
		(end 78.83779 -98.098102)
		(width 0.127)
		(layer "In2.Cu")
		(net "EXP_XM_ADDR_8")
	)
	(segment
		(start 80.63484 -96.301052)
		(end 80.814672 -96.301052)
		(width 0.127)
		(layer "In2.Cu")
		(net "EXP_XM_ADDR_8")
	)
	(segment
		(start 79.91602 -97.019872)
		(end 80.095852 -97.019872)
		(width 0.127)
		(layer "In2.Cu")
		(net "EXP_XM_ADDR_8")
	)
	(segment
		(start 99.803712 -87.3887)
		(end 100.307394 -87.892382)
		(width 0.127)
		(layer "In2.Cu")
		(net "EXP_XM_ADDR_8")
	)
	(segment
		(start 60.211208 -116.904516)
		(end 78.83779 -98.277934)
		(width 0.127)
		(layer "In2.Cu")
		(net "EXP_XM_ADDR_8")
	)
	(segment
		(start 105.268776 -90.675968)
		(end 105.268776 -91.268804)
		(width 0.127)
		(layer "In2.Cu")
		(net "EXP_XM_ADDR_8")
	)
	(segment
		(start 79.086964 -95.292164)
		(end 79.266542 -95.112586)
		(width 0.127)
		(layer "In2.Cu")
		(net "EXP_XM_ADDR_8")
	)
	(segment
		(start 104.268778 -89.67597)
		(end 104.268778 -89.861644)
		(width 0.127)
		(layer "In2.Cu")
		(net "EXP_XM_ADDR_8")
	)
	(segment
		(start 85.316568 -91.799156)
		(end 85.733128 -91.799156)
		(width 0.127)
		(layer "In2.Cu")
		(net "EXP_XM_ADDR_8")
	)
	(segment
		(start 88.377776 -89.154508)
		(end 89.026492 -89.154508)
		(width 0.127)
		(layer "In2.Cu")
		(net "EXP_XM_ADDR_8")
	)
	(segment
		(start 60.21197 -130.267456)
		(end 60.211462 -130.266948)
		(width 0.127)
		(layer "In2.Cu")
		(net "EXP_XM_ADDR_8")
	)
	(segment
		(start 79.266542 -95.112586)
		(end 79.446374 -95.112586)
		(width 0.127)
		(layer "In2.Cu")
		(net "EXP_XM_ADDR_8")
	)
	(segment
		(start 77.828902 -96.550226)
		(end 78.008734 -96.550226)
		(width 0.127)
		(layer "In2.Cu")
		(net "EXP_XM_ADDR_8")
	)
	(segment
		(start 78.368144 -96.010984)
		(end 78.547722 -95.831406)
		(width 0.127)
		(layer "In2.Cu")
		(net "EXP_XM_ADDR_8")
	)
	(segment
		(start 100.307394 -87.947754)
		(end 100.915724 -88.556084)
		(width 0.127)
		(layer "In2.Cu")
		(net "EXP_XM_ADDR_8")
	)
	(segment
		(start 144.526 -45.339)
		(end 144.526 -45.900848)
		(width 0.1143)
		(layer "F.Cu")
		(net "XM_ADDR_18")
	)
	(segment
		(start 145.135092 -46.50994)
		(end 145.135092 -46.634908)
		(width 0.1143)
		(layer "F.Cu")
		(net "XM_ADDR_18")
	)
	(segment
		(start 144.526 -45.900848)
		(end 145.135092 -46.50994)
		(width 0.1143)
		(layer "F.Cu")
		(net "XM_ADDR_18")
	)
	(segment
		(start 144.599406 -45.265594)
		(end 144.526 -45.339)
		(width 0.1143)
		(layer "F.Cu")
		(net "XM_ADDR_18")
	)
	(segment
		(start 144.599406 -42.7101)
		(end 144.599406 -45.265594)
		(width 0.1143)
		(layer "F.Cu")
		(net "XM_ADDR_18")
	)
	(segment
		(start 115.148868 -50.999898)
		(end 115.399566 -50.7492)
		(width 0.1143)
		(layer "F.Cu")
		(net "XM_ADDR_18")
	)
	(segment
		(start 113.949988 -50.999898)
		(end 115.148868 -50.999898)
		(width 0.1143)
		(layer "F.Cu")
		(net "XM_ADDR_18")
	)
	(via
		(at 115.399566 -50.7492)
		(size 0.508)
		(drill 0.254)
		(layers "F.Cu" "B.Cu")
		(net "XM_ADDR_18")
	)
	(via
		(at 145.135092 -46.634908)
		(size 0.5588)
		(drill 0.3048)
		(layers "F.Cu" "B.Cu")
		(net "XM_ADDR_18")
	)
	(segment
		(start 144.399 -45.847)
		(end 145.135092 -46.583092)
		(width 0.1143)
		(layer "B.Cu")
		(net "XM_ADDR_18")
	)
	(segment
		(start 145.135092 -46.583092)
		(end 145.135092 -46.634908)
		(width 0.1143)
		(layer "B.Cu")
		(net "XM_ADDR_18")
	)
	(segment
		(start 142.968218 -44.709588)
		(end 143.222218 -44.709588)
		(width 0.127)
		(layer "In5.Cu")
		(net "XM_ADDR_18")
	)
	(segment
		(start 141.774418 -45.0088)
		(end 142.206218 -45.0088)
		(width 0.127)
		(layer "In5.Cu")
		(net "XM_ADDR_18")
	)
	(segment
		(start 137.147554 -43.60799)
		(end 137.274554 -43.73499)
		(width 0.127)
		(layer "In5.Cu")
		(net "XM_ADDR_18")
	)
	(segment
		(start 141.012418 -45.0088)
		(end 141.139418 -44.8818)
		(width 0.127)
		(layer "In5.Cu")
		(net "XM_ADDR_18")
	)
	(segment
		(start 128.12776 -45.5676)
		(end 132.480304 -45.5676)
		(width 0.127)
		(layer "In5.Cu")
		(net "XM_ADDR_18")
	)
	(segment
		(start 141.139418 -44.8818)
		(end 141.139418 -43.130216)
		(width 0.127)
		(layer "In5.Cu")
		(net "XM_ADDR_18")
	)
	(segment
		(start 143.984218 -44.717462)
		(end 145.008092 -44.717462)
		(width 0.127)
		(layer "In5.Cu")
		(net "XM_ADDR_18")
	)
	(segment
		(start 140.504418 -43.003216)
		(end 140.631418 -43.130216)
		(width 0.127)
		(layer "In5.Cu")
		(net "XM_ADDR_18")
	)
	(segment
		(start 137.274554 -44.8818)
		(end 137.401554 -45.0088)
		(width 0.127)
		(layer "In5.Cu")
		(net "XM_ADDR_18")
	)
	(segment
		(start 143.349218 -44.836588)
		(end 143.349218 -45.380402)
		(width 0.127)
		(layer "In5.Cu")
		(net "XM_ADDR_18")
	)
	(segment
		(start 142.206218 -45.0088)
		(end 142.333218 -45.1358)
		(width 0.127)
		(layer "In5.Cu")
		(net "XM_ADDR_18")
	)
	(segment
		(start 139.996418 -45.0088)
		(end 140.123418 -44.8818)
		(width 0.127)
		(layer "In5.Cu")
		(net "XM_ADDR_18")
	)
	(segment
		(start 138.290554 -43.73499)
		(end 138.290554 -44.8818)
		(width 0.127)
		(layer "In5.Cu")
		(net "XM_ADDR_18")
	)
	(segment
		(start 140.758418 -45.0088)
		(end 141.012418 -45.0088)
		(width 0.127)
		(layer "In5.Cu")
		(net "XM_ADDR_18")
	)
	(segment
		(start 141.139418 -43.130216)
		(end 141.266418 -43.003216)
		(width 0.127)
		(layer "In5.Cu")
		(net "XM_ADDR_18")
	)
	(segment
		(start 140.123418 -44.8818)
		(end 140.123418 -43.130216)
		(width 0.127)
		(layer "In5.Cu")
		(net "XM_ADDR_18")
	)
	(segment
		(start 115.6208 -50.7492)
		(end 115.697 -50.673)
		(width 0.127)
		(layer "In5.Cu")
		(net "XM_ADDR_18")
	)
	(segment
		(start 141.647418 -43.130216)
		(end 141.647418 -44.8818)
		(width 0.127)
		(layer "In5.Cu")
		(net "XM_ADDR_18")
	)
	(segment
		(start 142.460218 -45.507402)
		(end 142.714218 -45.507402)
		(width 0.127)
		(layer "In5.Cu")
		(net "XM_ADDR_18")
	)
	(segment
		(start 143.222218 -44.709588)
		(end 143.349218 -44.836588)
		(width 0.127)
		(layer "In5.Cu")
		(net "XM_ADDR_18")
	)
	(segment
		(start 142.714218 -45.507402)
		(end 142.841218 -45.380402)
		(width 0.127)
		(layer "In5.Cu")
		(net "XM_ADDR_18")
	)
	(segment
		(start 135.541766 -44.62907)
		(end 135.541766 -43.754548)
		(width 0.127)
		(layer "In5.Cu")
		(net "XM_ADDR_18")
	)
	(segment
		(start 140.250418 -43.003216)
		(end 140.504418 -43.003216)
		(width 0.127)
		(layer "In5.Cu")
		(net "XM_ADDR_18")
	)
	(segment
		(start 137.401554 -45.0088)
		(end 137.655554 -45.0088)
		(width 0.127)
		(layer "In5.Cu")
		(net "XM_ADDR_18")
	)
	(segment
		(start 135.688324 -43.60799)
		(end 137.147554 -43.60799)
		(width 0.127)
		(layer "In5.Cu")
		(net "XM_ADDR_18")
	)
	(segment
		(start 138.163554 -43.60799)
		(end 138.290554 -43.73499)
		(width 0.127)
		(layer "In5.Cu")
		(net "XM_ADDR_18")
	)
	(segment
		(start 141.520418 -43.003216)
		(end 141.647418 -43.130216)
		(width 0.127)
		(layer "In5.Cu")
		(net "XM_ADDR_18")
	)
	(segment
		(start 138.798554 -44.8818)
		(end 138.798554 -43.73499)
		(width 0.127)
		(layer "In5.Cu")
		(net "XM_ADDR_18")
	)
	(segment
		(start 145.008092 -44.717462)
		(end 145.135092 -44.844462)
		(width 0.127)
		(layer "In5.Cu")
		(net "XM_ADDR_18")
	)
	(segment
		(start 143.730218 -45.507402)
		(end 143.857218 -45.380402)
		(width 0.127)
		(layer "In5.Cu")
		(net "XM_ADDR_18")
	)
	(segment
		(start 140.123418 -43.130216)
		(end 140.250418 -43.003216)
		(width 0.127)
		(layer "In5.Cu")
		(net "XM_ADDR_18")
	)
	(segment
		(start 137.655554 -45.0088)
		(end 137.782554 -44.8818)
		(width 0.127)
		(layer "In5.Cu")
		(net "XM_ADDR_18")
	)
	(segment
		(start 139.306554 -44.8818)
		(end 139.433554 -45.0088)
		(width 0.127)
		(layer "In5.Cu")
		(net "XM_ADDR_18")
	)
	(segment
		(start 138.417554 -45.0088)
		(end 138.671554 -45.0088)
		(width 0.127)
		(layer "In5.Cu")
		(net "XM_ADDR_18")
	)
	(segment
		(start 143.349218 -45.380402)
		(end 143.476218 -45.507402)
		(width 0.127)
		(layer "In5.Cu")
		(net "XM_ADDR_18")
	)
	(segment
		(start 135.541766 -43.754548)
		(end 135.688324 -43.60799)
		(width 0.127)
		(layer "In5.Cu")
		(net "XM_ADDR_18")
	)
	(segment
		(start 142.333218 -45.1358)
		(end 142.333218 -45.380402)
		(width 0.127)
		(layer "In5.Cu")
		(net "XM_ADDR_18")
	)
	(segment
		(start 132.480304 -45.5676)
		(end 133.039104 -45.0088)
		(width 0.127)
		(layer "In5.Cu")
		(net "XM_ADDR_18")
	)
	(segment
		(start 123.295918 -46.2407)
		(end 127.45466 -46.2407)
		(width 0.127)
		(layer "In5.Cu")
		(net "XM_ADDR_18")
	)
	(segment
		(start 115.399566 -50.7492)
		(end 115.6208 -50.7492)
		(width 0.127)
		(layer "In5.Cu")
		(net "XM_ADDR_18")
	)
	(segment
		(start 141.647418 -44.8818)
		(end 141.774418 -45.0088)
		(width 0.127)
		(layer "In5.Cu")
		(net "XM_ADDR_18")
	)
	(segment
		(start 142.841218 -44.836588)
		(end 142.968218 -44.709588)
		(width 0.127)
		(layer "In5.Cu")
		(net "XM_ADDR_18")
	)
	(segment
		(start 143.857218 -44.844462)
		(end 143.984218 -44.717462)
		(width 0.127)
		(layer "In5.Cu")
		(net "XM_ADDR_18")
	)
	(segment
		(start 127.45466 -46.2407)
		(end 128.12776 -45.5676)
		(width 0.127)
		(layer "In5.Cu")
		(net "XM_ADDR_18")
	)
	(segment
		(start 135.162036 -45.0088)
		(end 135.541766 -44.62907)
		(width 0.127)
		(layer "In5.Cu")
		(net "XM_ADDR_18")
	)
	(segment
		(start 116.205 -50.673)
		(end 117.0432 -49.8348)
		(width 0.127)
		(layer "In5.Cu")
		(net "XM_ADDR_18")
	)
	(segment
		(start 138.798554 -43.73499)
		(end 138.925554 -43.60799)
		(width 0.127)
		(layer "In5.Cu")
		(net "XM_ADDR_18")
	)
	(segment
		(start 143.476218 -45.507402)
		(end 143.730218 -45.507402)
		(width 0.127)
		(layer "In5.Cu")
		(net "XM_ADDR_18")
	)
	(segment
		(start 139.179554 -43.60799)
		(end 139.306554 -43.73499)
		(width 0.127)
		(layer "In5.Cu")
		(net "XM_ADDR_18")
	)
	(segment
		(start 139.306554 -43.73499)
		(end 139.306554 -44.8818)
		(width 0.127)
		(layer "In5.Cu")
		(net "XM_ADDR_18")
	)
	(segment
		(start 142.841218 -45.380402)
		(end 142.841218 -44.836588)
		(width 0.127)
		(layer "In5.Cu")
		(net "XM_ADDR_18")
	)
	(segment
		(start 115.697 -50.673)
		(end 116.205 -50.673)
		(width 0.127)
		(layer "In5.Cu")
		(net "XM_ADDR_18")
	)
	(segment
		(start 145.135092 -44.844462)
		(end 145.135092 -46.634908)
		(width 0.127)
		(layer "In5.Cu")
		(net "XM_ADDR_18")
	)
	(segment
		(start 137.782554 -43.73499)
		(end 137.909554 -43.60799)
		(width 0.127)
		(layer "In5.Cu")
		(net "XM_ADDR_18")
	)
	(segment
		(start 137.909554 -43.60799)
		(end 138.163554 -43.60799)
		(width 0.127)
		(layer "In5.Cu")
		(net "XM_ADDR_18")
	)
	(segment
		(start 119.701818 -49.8348)
		(end 123.295918 -46.2407)
		(width 0.127)
		(layer "In5.Cu")
		(net "XM_ADDR_18")
	)
	(segment
		(start 140.631418 -43.130216)
		(end 140.631418 -44.8818)
		(width 0.127)
		(layer "In5.Cu")
		(net "XM_ADDR_18")
	)
	(segment
		(start 117.0432 -49.8348)
		(end 119.701818 -49.8348)
		(width 0.127)
		(layer "In5.Cu")
		(net "XM_ADDR_18")
	)
	(segment
		(start 137.274554 -43.73499)
		(end 137.274554 -44.8818)
		(width 0.127)
		(layer "In5.Cu")
		(net "XM_ADDR_18")
	)
	(segment
		(start 138.290554 -44.8818)
		(end 138.417554 -45.0088)
		(width 0.127)
		(layer "In5.Cu")
		(net "XM_ADDR_18")
	)
	(segment
		(start 143.857218 -45.380402)
		(end 143.857218 -44.844462)
		(width 0.127)
		(layer "In5.Cu")
		(net "XM_ADDR_18")
	)
	(segment
		(start 140.631418 -44.8818)
		(end 140.758418 -45.0088)
		(width 0.127)
		(layer "In5.Cu")
		(net "XM_ADDR_18")
	)
	(segment
		(start 138.671554 -45.0088)
		(end 138.798554 -44.8818)
		(width 0.127)
		(layer "In5.Cu")
		(net "XM_ADDR_18")
	)
	(segment
		(start 142.333218 -45.380402)
		(end 142.460218 -45.507402)
		(width 0.127)
		(layer "In5.Cu")
		(net "XM_ADDR_18")
	)
	(segment
		(start 133.039104 -45.0088)
		(end 135.162036 -45.0088)
		(width 0.127)
		(layer "In5.Cu")
		(net "XM_ADDR_18")
	)
	(segment
		(start 138.925554 -43.60799)
		(end 139.179554 -43.60799)
		(width 0.127)
		(layer "In5.Cu")
		(net "XM_ADDR_18")
	)
	(segment
		(start 139.433554 -45.0088)
		(end 139.996418 -45.0088)
		(width 0.127)
		(layer "In5.Cu")
		(net "XM_ADDR_18")
	)
	(segment
		(start 137.782554 -44.8818)
		(end 137.782554 -43.73499)
		(width 0.127)
		(layer "In5.Cu")
		(net "XM_ADDR_18")
	)
	(segment
		(start 141.266418 -43.003216)
		(end 141.520418 -43.003216)
		(width 0.127)
		(layer "In5.Cu")
		(net "XM_ADDR_18")
	)
	(segment
		(start 60.62218 -127.28575)
		(end 60.73648 -127.40005)
		(width 0.1143)
		(layer "F.Cu")
		(net "EXP_XM_ADDR_3")
	)
	(segment
		(start 58.804048 -127.46355)
		(end 58.804048 -127.74295)
		(width 0.1143)
		(layer "F.Cu")
		(net "EXP_XM_ADDR_3")
	)
	(segment
		(start 58.461148 -127.34925)
		(end 58.689748 -127.34925)
		(width 0.1143)
		(layer "F.Cu")
		(net "EXP_XM_ADDR_3")
	)
	(segment
		(start 59.718448 -127.46355)
		(end 59.718448 -127.632968)
		(width 0.1143)
		(layer "F.Cu")
		(net "EXP_XM_ADDR_3")
	)
	(segment
		(start 59.604148 -127.34925)
		(end 59.718448 -127.46355)
		(width 0.1143)
		(layer "F.Cu")
		(net "EXP_XM_ADDR_3")
	)
	(segment
		(start 60.85078 -127.74295)
		(end 61.21908 -127.74295)
		(width 0.1143)
		(layer "F.Cu")
		(net "EXP_XM_ADDR_3")
	)
	(segment
		(start 58.804048 -127.74295)
		(end 58.918348 -127.85725)
		(width 0.1143)
		(layer "F.Cu")
		(net "EXP_XM_ADDR_3")
	)
	(segment
		(start 60.16498 -127.74295)
		(end 60.27928 -127.62865)
		(width 0.1143)
		(layer "F.Cu")
		(net "EXP_XM_ADDR_3")
	)
	(segment
		(start 58.346848 -127.46355)
		(end 58.461148 -127.34925)
		(width 0.1143)
		(layer "F.Cu")
		(net "EXP_XM_ADDR_3")
	)
	(segment
		(start 59.146948 -127.85725)
		(end 59.261248 -127.74295)
		(width 0.1143)
		(layer "F.Cu")
		(net "EXP_XM_ADDR_3")
	)
	(segment
		(start 58.346848 -127.74295)
		(end 58.346848 -127.46355)
		(width 0.1143)
		(layer "F.Cu")
		(net "EXP_XM_ADDR_3")
	)
	(segment
		(start 102.349808 -92.349828)
		(end 102.06228 -92.0623)
		(width 0.1143)
		(layer "F.Cu")
		(net "EXP_XM_ADDR_3")
	)
	(segment
		(start 58.689748 -127.34925)
		(end 58.804048 -127.46355)
		(width 0.1143)
		(layer "F.Cu")
		(net "EXP_XM_ADDR_3")
	)
	(segment
		(start 61.21908 -127.74295)
		(end 61.58103 -127.381)
		(width 0.1143)
		(layer "F.Cu")
		(net "EXP_XM_ADDR_3")
	)
	(segment
		(start 102.06228 -92.0623)
		(end 101.70033 -92.0623)
		(width 0.1143)
		(layer "F.Cu")
		(net "EXP_XM_ADDR_3")
	)
	(segment
		(start 60.27928 -127.62865)
		(end 60.27928 -127.40005)
		(width 0.1143)
		(layer "F.Cu")
		(net "EXP_XM_ADDR_3")
	)
	(segment
		(start 60.73648 -127.62865)
		(end 60.85078 -127.74295)
		(width 0.1143)
		(layer "F.Cu")
		(net "EXP_XM_ADDR_3")
	)
	(segment
		(start 59.261248 -127.46355)
		(end 59.375548 -127.34925)
		(width 0.1143)
		(layer "F.Cu")
		(net "EXP_XM_ADDR_3")
	)
	(segment
		(start 58.918348 -127.85725)
		(end 59.146948 -127.85725)
		(width 0.1143)
		(layer "F.Cu")
		(net "EXP_XM_ADDR_3")
	)
	(segment
		(start 57.809384 -127.85725)
		(end 58.232548 -127.85725)
		(width 0.1143)
		(layer "F.Cu")
		(net "EXP_XM_ADDR_3")
	)
	(segment
		(start 56.558942 -127.892302)
		(end 57.774332 -127.892302)
		(width 0.1143)
		(layer "F.Cu")
		(net "EXP_XM_ADDR_3")
	)
	(segment
		(start 62.605412 -127.381)
		(end 62.639702 -127.34671)
		(width 0.1143)
		(layer "F.Cu")
		(net "EXP_XM_ADDR_3")
	)
	(segment
		(start 60.39358 -127.28575)
		(end 60.62218 -127.28575)
		(width 0.1143)
		(layer "F.Cu")
		(net "EXP_XM_ADDR_3")
	)
	(segment
		(start 60.27928 -127.40005)
		(end 60.39358 -127.28575)
		(width 0.1143)
		(layer "F.Cu")
		(net "EXP_XM_ADDR_3")
	)
	(segment
		(start 59.82843 -127.74295)
		(end 60.16498 -127.74295)
		(width 0.1143)
		(layer "F.Cu")
		(net "EXP_XM_ADDR_3")
	)
	(segment
		(start 57.774332 -127.892302)
		(end 57.809384 -127.85725)
		(width 0.1143)
		(layer "F.Cu")
		(net "EXP_XM_ADDR_3")
	)
	(segment
		(start 61.58103 -127.381)
		(end 62.605412 -127.381)
		(width 0.1143)
		(layer "F.Cu")
		(net "EXP_XM_ADDR_3")
	)
	(segment
		(start 59.375548 -127.34925)
		(end 59.604148 -127.34925)
		(width 0.1143)
		(layer "F.Cu")
		(net "EXP_XM_ADDR_3")
	)
	(segment
		(start 59.261248 -127.74295)
		(end 59.261248 -127.46355)
		(width 0.1143)
		(layer "F.Cu")
		(net "EXP_XM_ADDR_3")
	)
	(segment
		(start 58.232548 -127.85725)
		(end 58.346848 -127.74295)
		(width 0.1143)
		(layer "F.Cu")
		(net "EXP_XM_ADDR_3")
	)
	(segment
		(start 59.718448 -127.632968)
		(end 59.82843 -127.74295)
		(width 0.1143)
		(layer "F.Cu")
		(net "EXP_XM_ADDR_3")
	)
	(segment
		(start 60.73648 -127.40005)
		(end 60.73648 -127.62865)
		(width 0.1143)
		(layer "F.Cu")
		(net "EXP_XM_ADDR_3")
	)
	(via
		(at 62.639702 -127.34671)
		(size 0.5588)
		(drill 0.3048)
		(layers "F.Cu" "B.Cu")
		(net "EXP_XM_ADDR_3")
	)
	(via
		(at 101.70033 -92.0623)
		(size 0.508)
		(drill 0.254)
		(layers "F.Cu" "B.Cu")
		(net "EXP_XM_ADDR_3")
	)
	(via
		(at 63.5508 -127.3556)
		(size 0.7112)
		(drill 0.3556)
		(layers "F.Cu" "B.Cu")
		(net "EXP_XM_ADDR_3")
	)
	(segment
		(start 63.54191 -127.34671)
		(end 63.5508 -127.3556)
		(width 0.1143)
		(layer "B.Cu")
		(net "EXP_XM_ADDR_3")
	)
	(segment
		(start 62.639702 -127.34671)
		(end 63.54191 -127.34671)
		(width 0.1143)
		(layer "B.Cu")
		(net "EXP_XM_ADDR_3")
	)
	(segment
		(start 69.991478 -109.99978)
		(end 69.811646 -109.99978)
		(width 0.127)
		(layer "In2.Cu")
		(net "EXP_XM_ADDR_3")
	)
	(segment
		(start 76.098908 -105.504742)
		(end 75.91933 -105.68432)
		(width 0.127)
		(layer "In2.Cu")
		(net "EXP_XM_ADDR_3")
	)
	(segment
		(start 73.583038 -107.84078)
		(end 72.866758 -107.1245)
		(width 0.127)
		(layer "In2.Cu")
		(net "EXP_XM_ADDR_3")
	)
	(segment
		(start 63.17107 -125.207268)
		(end 62.639702 -125.738636)
		(width 0.127)
		(layer "In2.Cu")
		(net "EXP_XM_ADDR_3")
	)
	(segment
		(start 74.304398 -105.68686)
		(end 74.124566 -105.68686)
		(width 0.127)
		(layer "In2.Cu")
		(net "EXP_XM_ADDR_3")
	)
	(segment
		(start 75.380088 -106.04373)
		(end 75.380088 -106.223562)
		(width 0.127)
		(layer "In2.Cu")
		(net "EXP_XM_ADDR_3")
	)
	(segment
		(start 72.507348 -107.304078)
		(end 72.507348 -107.48391)
		(width 0.127)
		(layer "In2.Cu")
		(net "EXP_XM_ADDR_3")
	)
	(segment
		(start 73.223628 -108.380022)
		(end 73.04405 -108.5596)
		(width 0.127)
		(layer "In2.Cu")
		(net "EXP_XM_ADDR_3")
	)
	(segment
		(start 71.249286 -108.56214)
		(end 71.069708 -108.741718)
		(width 0.127)
		(layer "In2.Cu")
		(net "EXP_XM_ADDR_3")
	)
	(segment
		(start 74.663808 -105.32745)
		(end 75.380088 -106.04373)
		(width 0.127)
		(layer "In2.Cu")
		(net "EXP_XM_ADDR_3")
	)
	(segment
		(start 72.147938 -107.84332)
		(end 71.968106 -107.84332)
		(width 0.127)
		(layer "In2.Cu")
		(net "EXP_XM_ADDR_3")
	)
	(segment
		(start 72.686926 -107.1245)
		(end 72.507348 -107.304078)
		(width 0.127)
		(layer "In2.Cu")
		(net "EXP_XM_ADDR_3")
	)
	(segment
		(start 75.023218 -104.96804)
		(end 74.843386 -104.96804)
		(width 0.127)
		(layer "In2.Cu")
		(net "EXP_XM_ADDR_3")
	)
	(segment
		(start 75.020678 -106.40314)
		(end 74.304398 -105.68686)
		(width 0.127)
		(layer "In2.Cu")
		(net "EXP_XM_ADDR_3")
	)
	(segment
		(start 74.661268 -106.76255)
		(end 74.661268 -106.942382)
		(width 0.127)
		(layer "In2.Cu")
		(net "EXP_XM_ADDR_3")
	)
	(segment
		(start 72.145398 -109.27842)
		(end 71.429118 -108.56214)
		(width 0.127)
		(layer "In2.Cu")
		(net "EXP_XM_ADDR_3")
	)
	(segment
		(start 89.009728 -90.678508)
		(end 75.382628 -104.305608)
		(width 0.127)
		(layer "In2.Cu")
		(net "EXP_XM_ADDR_3")
	)
	(segment
		(start 73.942448 -107.48137)
		(end 73.942448 -107.661202)
		(width 0.127)
		(layer "In2.Cu")
		(net "EXP_XM_ADDR_3")
	)
	(segment
		(start 71.069708 -108.92155)
		(end 71.785988 -109.63783)
		(width 0.127)
		(layer "In2.Cu")
		(net "EXP_XM_ADDR_3")
	)
	(segment
		(start 72.866758 -107.1245)
		(end 72.686926 -107.1245)
		(width 0.127)
		(layer "In2.Cu")
		(net "EXP_XM_ADDR_3")
	)
	(segment
		(start 73.942448 -107.661202)
		(end 73.76287 -107.84078)
		(width 0.127)
		(layer "In2.Cu")
		(net "EXP_XM_ADDR_3")
	)
	(segment
		(start 71.968106 -107.84332)
		(end 71.788528 -108.022898)
		(width 0.127)
		(layer "In2.Cu")
		(net "EXP_XM_ADDR_3")
	)
	(segment
		(start 74.663808 -105.147618)
		(end 74.663808 -105.32745)
		(width 0.127)
		(layer "In2.Cu")
		(net "EXP_XM_ADDR_3")
	)
	(segment
		(start 73.226168 -106.585258)
		(end 73.226168 -106.76509)
		(width 0.127)
		(layer "In2.Cu")
		(net "EXP_XM_ADDR_3")
	)
	(segment
		(start 71.067168 -110.35665)
		(end 71.067168 -110.536482)
		(width 0.127)
		(layer "In2.Cu")
		(net "EXP_XM_ADDR_3")
	)
	(segment
		(start 70.350888 -109.64037)
		(end 71.067168 -110.35665)
		(width 0.127)
		(layer "In2.Cu")
		(net "EXP_XM_ADDR_3")
	)
	(segment
		(start 70.348348 -111.255302)
		(end 63.17107 -118.43258)
		(width 0.127)
		(layer "In2.Cu")
		(net "EXP_XM_ADDR_3")
	)
	(segment
		(start 73.944988 -105.866438)
		(end 73.944988 -106.04627)
		(width 0.127)
		(layer "In2.Cu")
		(net "EXP_XM_ADDR_3")
	)
	(segment
		(start 62.639702 -125.738636)
		(end 62.639702 -127.34671)
		(width 0.127)
		(layer "In2.Cu")
		(net "EXP_XM_ADDR_3")
	)
	(segment
		(start 74.843386 -104.96804)
		(end 74.663808 -105.147618)
		(width 0.127)
		(layer "In2.Cu")
		(net "EXP_XM_ADDR_3")
	)
	(segment
		(start 75.382628 -104.305608)
		(end 75.382628 -104.60863)
		(width 0.127)
		(layer "In2.Cu")
		(net "EXP_XM_ADDR_3")
	)
	(segment
		(start 72.864218 -108.5596)
		(end 72.147938 -107.84332)
		(width 0.127)
		(layer "In2.Cu")
		(net "EXP_XM_ADDR_3")
	)
	(segment
		(start 71.429118 -108.56214)
		(end 71.249286 -108.56214)
		(width 0.127)
		(layer "In2.Cu")
		(net "EXP_XM_ADDR_3")
	)
	(segment
		(start 63.17107 -118.43258)
		(end 63.17107 -125.207268)
		(width 0.127)
		(layer "In2.Cu")
		(net "EXP_XM_ADDR_3")
	)
	(segment
		(start 72.504808 -108.91901)
		(end 72.504808 -109.098842)
		(width 0.127)
		(layer "In2.Cu")
		(net "EXP_XM_ADDR_3")
	)
	(segment
		(start 73.405746 -106.40568)
		(end 73.226168 -106.585258)
		(width 0.127)
		(layer "In2.Cu")
		(net "EXP_XM_ADDR_3")
	)
	(segment
		(start 74.48169 -107.12196)
		(end 74.301858 -107.12196)
		(width 0.127)
		(layer "In2.Cu")
		(net "EXP_XM_ADDR_3")
	)
	(segment
		(start 71.067168 -110.536482)
		(end 70.88759 -110.71606)
		(width 0.127)
		(layer "In2.Cu")
		(net "EXP_XM_ADDR_3")
	)
	(segment
		(start 70.530466 -109.28096)
		(end 70.350888 -109.460538)
		(width 0.127)
		(layer "In2.Cu")
		(net "EXP_XM_ADDR_3")
	)
	(segment
		(start 74.301858 -107.12196)
		(end 73.585578 -106.40568)
		(width 0.127)
		(layer "In2.Cu")
		(net "EXP_XM_ADDR_3")
	)
	(segment
		(start 76.098908 -105.32491)
		(end 76.098908 -105.504742)
		(width 0.127)
		(layer "In2.Cu")
		(net "EXP_XM_ADDR_3")
	)
	(segment
		(start 73.76287 -107.84078)
		(end 73.583038 -107.84078)
		(width 0.127)
		(layer "In2.Cu")
		(net "EXP_XM_ADDR_3")
	)
	(segment
		(start 71.785988 -109.63783)
		(end 71.785988 -109.817662)
		(width 0.127)
		(layer "In2.Cu")
		(net "EXP_XM_ADDR_3")
	)
	(segment
		(start 75.380088 -106.223562)
		(end 75.20051 -106.40314)
		(width 0.127)
		(layer "In2.Cu")
		(net "EXP_XM_ADDR_3")
	)
	(segment
		(start 71.069708 -108.741718)
		(end 71.069708 -108.92155)
		(width 0.127)
		(layer "In2.Cu")
		(net "EXP_XM_ADDR_3")
	)
	(segment
		(start 71.60641 -109.99724)
		(end 71.426578 -109.99724)
		(width 0.127)
		(layer "In2.Cu")
		(net "EXP_XM_ADDR_3")
	)
	(segment
		(start 75.91933 -105.68432)
		(end 75.739498 -105.68432)
		(width 0.127)
		(layer "In2.Cu")
		(net "EXP_XM_ADDR_3")
	)
	(segment
		(start 69.811646 -109.99978)
		(end 69.632068 -110.179358)
		(width 0.127)
		(layer "In2.Cu")
		(net "EXP_XM_ADDR_3")
	)
	(segment
		(start 70.348348 -111.07547)
		(end 70.348348 -111.255302)
		(width 0.127)
		(layer "In2.Cu")
		(net "EXP_XM_ADDR_3")
	)
	(segment
		(start 73.226168 -106.76509)
		(end 73.942448 -107.48137)
		(width 0.127)
		(layer "In2.Cu")
		(net "EXP_XM_ADDR_3")
	)
	(segment
		(start 71.785988 -109.817662)
		(end 71.60641 -109.99724)
		(width 0.127)
		(layer "In2.Cu")
		(net "EXP_XM_ADDR_3")
	)
	(segment
		(start 69.632068 -110.179358)
		(end 69.632068 -110.35919)
		(width 0.127)
		(layer "In2.Cu")
		(net "EXP_XM_ADDR_3")
	)
	(segment
		(start 74.661268 -106.942382)
		(end 74.48169 -107.12196)
		(width 0.127)
		(layer "In2.Cu")
		(net "EXP_XM_ADDR_3")
	)
	(segment
		(start 99.850448 -90.860626)
		(end 99.66833 -90.678508)
		(width 0.127)
		(layer "In2.Cu")
		(net "EXP_XM_ADDR_3")
	)
	(segment
		(start 71.426578 -109.99724)
		(end 70.710298 -109.28096)
		(width 0.127)
		(layer "In2.Cu")
		(net "EXP_XM_ADDR_3")
	)
	(segment
		(start 100.498656 -90.860626)
		(end 99.850448 -90.860626)
		(width 0.127)
		(layer "In2.Cu")
		(net "EXP_XM_ADDR_3")
	)
	(segment
		(start 101.70033 -92.0623)
		(end 100.498656 -90.860626)
		(width 0.127)
		(layer "In2.Cu")
		(net "EXP_XM_ADDR_3")
	)
	(segment
		(start 72.504808 -109.098842)
		(end 72.32523 -109.27842)
		(width 0.127)
		(layer "In2.Cu")
		(net "EXP_XM_ADDR_3")
	)
	(segment
		(start 69.632068 -110.35919)
		(end 70.348348 -111.07547)
		(width 0.127)
		(layer "In2.Cu")
		(net "EXP_XM_ADDR_3")
	)
	(segment
		(start 73.223628 -108.20019)
		(end 73.223628 -108.380022)
		(width 0.127)
		(layer "In2.Cu")
		(net "EXP_XM_ADDR_3")
	)
	(segment
		(start 71.788528 -108.022898)
		(end 71.788528 -108.20273)
		(width 0.127)
		(layer "In2.Cu")
		(net "EXP_XM_ADDR_3")
	)
	(segment
		(start 71.788528 -108.20273)
		(end 72.504808 -108.91901)
		(width 0.127)
		(layer "In2.Cu")
		(net "EXP_XM_ADDR_3")
	)
	(segment
		(start 70.350888 -109.460538)
		(end 70.350888 -109.64037)
		(width 0.127)
		(layer "In2.Cu")
		(net "EXP_XM_ADDR_3")
	)
	(segment
		(start 73.585578 -106.40568)
		(end 73.405746 -106.40568)
		(width 0.127)
		(layer "In2.Cu")
		(net "EXP_XM_ADDR_3")
	)
	(segment
		(start 75.739498 -105.68432)
		(end 75.023218 -104.96804)
		(width 0.127)
		(layer "In2.Cu")
		(net "EXP_XM_ADDR_3")
	)
	(segment
		(start 70.707758 -110.71606)
		(end 69.991478 -109.99978)
		(width 0.127)
		(layer "In2.Cu")
		(net "EXP_XM_ADDR_3")
	)
	(segment
		(start 73.944988 -106.04627)
		(end 74.661268 -106.76255)
		(width 0.127)
		(layer "In2.Cu")
		(net "EXP_XM_ADDR_3")
	)
	(segment
		(start 70.88759 -110.71606)
		(end 70.707758 -110.71606)
		(width 0.127)
		(layer "In2.Cu")
		(net "EXP_XM_ADDR_3")
	)
	(segment
		(start 99.66833 -90.678508)
		(end 89.009728 -90.678508)
		(width 0.127)
		(layer "In2.Cu")
		(net "EXP_XM_ADDR_3")
	)
	(segment
		(start 73.04405 -108.5596)
		(end 72.864218 -108.5596)
		(width 0.127)
		(layer "In2.Cu")
		(net "EXP_XM_ADDR_3")
	)
	(segment
		(start 75.382628 -104.60863)
		(end 76.098908 -105.32491)
		(width 0.127)
		(layer "In2.Cu")
		(net "EXP_XM_ADDR_3")
	)
	(segment
		(start 70.710298 -109.28096)
		(end 70.530466 -109.28096)
		(width 0.127)
		(layer "In2.Cu")
		(net "EXP_XM_ADDR_3")
	)
	(segment
		(start 74.124566 -105.68686)
		(end 73.944988 -105.866438)
		(width 0.127)
		(layer "In2.Cu")
		(net "EXP_XM_ADDR_3")
	)
	(segment
		(start 72.32523 -109.27842)
		(end 72.145398 -109.27842)
		(width 0.127)
		(layer "In2.Cu")
		(net "EXP_XM_ADDR_3")
	)
	(segment
		(start 75.20051 -106.40314)
		(end 75.020678 -106.40314)
		(width 0.127)
		(layer "In2.Cu")
		(net "EXP_XM_ADDR_3")
	)
	(segment
		(start 72.507348 -107.48391)
		(end 73.223628 -108.20019)
		(width 0.127)
		(layer "In2.Cu")
		(net "EXP_XM_ADDR_3")
	)
	(segment
		(start 107.96651 -107.81538)
		(end 107.96651 -106.721402)
		(width 0.1016)
		(layer "F.Cu")
		(net "SAS_HDD_TX10_P")
	)
	(segment
		(start 108.06049 -106.49458)
		(end 108.102654 -106.452416)
		(width 0.1016)
		(layer "F.Cu")
		(net "SAS_HDD_TX10_P")
	)
	(segment
		(start 104.192832 -112.687862)
		(end 106.321352 -110.559088)
		(width 0.1016)
		(layer "F.Cu")
		(net "SAS_HDD_TX10_P")
	)
	(segment
		(start 106.321352 -110.559088)
		(end 106.473498 -110.406942)
		(width 0.1016)
		(layer "F.Cu")
		(net "SAS_HDD_TX10_P")
	)
	(segment
		(start 104.00792 -113.522252)
		(end 104.00792 -113.133886)
		(width 0.1016)
		(layer "F.Cu")
		(net "SAS_HDD_TX10_P")
	)
	(segment
		(start 104.15397 -114.0206)
		(end 104.15397 -113.773458)
		(width 0.1016)
		(layer "F.Cu")
		(net "SAS_HDD_TX10_P")
	)
	(segment
		(start 104.116886 -113.683796)
		(end 104.045004 -113.611914)
		(width 0.1016)
		(layer "F.Cu")
		(net "SAS_HDD_TX10_P")
	)
	(segment
		(start 106.932222 -109.299502)
		(end 107.60329 -108.628434)
		(width 0.1016)
		(layer "F.Cu")
		(net "SAS_HDD_TX10_P")
	)
	(arc
		(start 104.15397 -113.773458)
		(mid 104.144337 -113.72494)
		(end 104.116886 -113.683796)
		(width 0.1016)
		(layer "F.Cu")
		(net "SAS_HDD_TX10_P")
	)
	(arc
		(start 104.00792 -113.133886)
		(mid 104.05603 -112.892491)
		(end 104.192832 -112.687862)
		(width 0.1016)
		(layer "F.Cu")
		(net "SAS_HDD_TX10_P")
	)
	(arc
		(start 107.977686 -106.637074)
		(mid 107.989236 -106.602531)
		(end 108.00461 -106.56951)
		(width 0.1016)
		(layer "F.Cu")
		(net "SAS_HDD_TX10_P")
	)
	(arc
		(start 108.00461 -106.56951)
		(mid 108.029813 -106.530005)
		(end 108.06049 -106.49458)
		(width 0.1016)
		(layer "F.Cu")
		(net "SAS_HDD_TX10_P")
	)
	(arc
		(start 104.045004 -113.611914)
		(mid 104.017571 -113.570763)
		(end 104.00792 -113.522252)
		(width 0.1016)
		(layer "F.Cu")
		(net "SAS_HDD_TX10_P")
	)
	(arc
		(start 106.473498 -110.406942)
		(mid 106.634994 -110.165246)
		(end 106.691684 -109.880146)
		(width 0.1016)
		(layer "F.Cu")
		(net "SAS_HDD_TX10_P")
	)
	(arc
		(start 107.96651 -106.721402)
		(mid 107.969275 -106.678863)
		(end 107.977686 -106.637074)
		(width 0.1016)
		(layer "F.Cu")
		(net "SAS_HDD_TX10_P")
	)
	(arc
		(start 108.102654 -106.452416)
		(mid 108.216044 -106.376651)
		(end 108.349796 -106.350054)
		(width 0.1016)
		(layer "F.Cu")
		(net "SAS_HDD_TX10_P")
	)
	(arc
		(start 107.60329 -108.628434)
		(mid 107.871556 -108.260623)
		(end 107.96651 -107.81538)
		(width 0.1016)
		(layer "F.Cu")
		(net "SAS_HDD_TX10_P")
	)
	(arc
		(start 106.691684 -109.880146)
		(mid 106.754193 -109.565893)
		(end 106.932222 -109.299502)
		(width 0.1016)
		(layer "F.Cu")
		(net "SAS_HDD_TX10_P")
	)
	(segment
		(start 146.099276 -61.9379)
		(end 146.099276 -59.231276)
		(width 0.1143)
		(layer "F.Cu")
		(net "XM_DATA_0")
	)
	(segment
		(start 146.076416 -59.208416)
		(end 146.076416 -59.115198)
		(width 0.1143)
		(layer "F.Cu")
		(net "XM_DATA_0")
	)
	(segment
		(start 145.44294 -58.82894)
		(end 144.45615 -57.84215)
		(width 0.1143)
		(layer "F.Cu")
		(net "XM_DATA_0")
	)
	(segment
		(start 146.076416 -59.115198)
		(end 145.790158 -58.82894)
		(width 0.1143)
		(layer "F.Cu")
		(net "XM_DATA_0")
	)
	(segment
		(start 146.099276 -59.231276)
		(end 146.076416 -59.208416)
		(width 0.1143)
		(layer "F.Cu")
		(net "XM_DATA_0")
	)
	(segment
		(start 144.45615 -55.18785)
		(end 144.526 -55.118)
		(width 0.1143)
		(layer "F.Cu")
		(net "XM_DATA_0")
	)
	(segment
		(start 112.350042 -50.999898)
		(end 112.750092 -50.599848)
		(width 0.1143)
		(layer "F.Cu")
		(net "XM_DATA_0")
	)
	(segment
		(start 144.45615 -57.84215)
		(end 144.45615 -55.18785)
		(width 0.1143)
		(layer "F.Cu")
		(net "XM_DATA_0")
	)
	(segment
		(start 145.790158 -58.82894)
		(end 145.44294 -58.82894)
		(width 0.1143)
		(layer "F.Cu")
		(net "XM_DATA_0")
	)
	(via
		(at 112.750092 -50.599848)
		(size 0.508)
		(drill 0.254)
		(layers "F.Cu" "B.Cu")
		(net "XM_DATA_0")
	)
	(via
		(at 143.383 -55.118)
		(size 0.7112)
		(drill 0.3556)
		(layers "F.Cu" "B.Cu")
		(net "XM_DATA_0")
	)
	(via
		(at 144.526 -55.118)
		(size 0.5588)
		(drill 0.3048)
		(layers "F.Cu" "B.Cu")
		(net "XM_DATA_0")
	)
	(segment
		(start 142.87119 -55.118)
		(end 141.256766 -53.503576)
		(width 0.1143)
		(layer "B.Cu")
		(net "XM_DATA_0")
	)
	(segment
		(start 140.309346 -53.822346)
		(end 140.309346 -53.643022)
		(width 0.1143)
		(layer "B.Cu")
		(net "XM_DATA_0")
	)
	(segment
		(start 140.453364 -53.966364)
		(end 140.309346 -53.822346)
		(width 0.1143)
		(layer "B.Cu")
		(net "XM_DATA_0")
	)
	(segment
		(start 140.447522 -52.483512)
		(end 136.8171 -52.483512)
		(width 0.1143)
		(layer "B.Cu")
		(net "XM_DATA_0")
	)
	(segment
		(start 116.847874 -51.82235)
		(end 115.77447 -51.82235)
		(width 0.1143)
		(layer "B.Cu")
		(net "XM_DATA_0")
	)
	(segment
		(start 115.77447 -51.82235)
		(end 115.32997 -51.37785)
		(width 0.1143)
		(layer "B.Cu")
		(net "XM_DATA_0")
	)
	(segment
		(start 119.082312 -52.068476)
		(end 117.094 -52.068476)
		(width 0.1143)
		(layer "B.Cu")
		(net "XM_DATA_0")
	)
	(segment
		(start 140.77188 -52.80787)
		(end 140.447522 -52.483512)
		(width 0.1143)
		(layer "B.Cu")
		(net "XM_DATA_0")
	)
	(segment
		(start 113.585244 -51.435)
		(end 112.750092 -50.599848)
		(width 0.1143)
		(layer "B.Cu")
		(net "XM_DATA_0")
	)
	(segment
		(start 115.32997 -51.37785)
		(end 114.87277 -51.37785)
		(width 0.1143)
		(layer "B.Cu")
		(net "XM_DATA_0")
	)
	(segment
		(start 143.383 -55.118)
		(end 142.87119 -55.118)
		(width 0.1143)
		(layer "B.Cu")
		(net "XM_DATA_0")
	)
	(segment
		(start 117.094 -52.068476)
		(end 116.847874 -51.82235)
		(width 0.1143)
		(layer "B.Cu")
		(net "XM_DATA_0")
	)
	(segment
		(start 140.309346 -53.643022)
		(end 140.77188 -53.180234)
		(width 0.1143)
		(layer "B.Cu")
		(net "XM_DATA_0")
	)
	(segment
		(start 136.8171 -52.483512)
		(end 136.633712 -52.6669)
		(width 0.1143)
		(layer "B.Cu")
		(net "XM_DATA_0")
	)
	(segment
		(start 136.633712 -52.6669)
		(end 119.680736 -52.6669)
		(width 0.1143)
		(layer "B.Cu")
		(net "XM_DATA_0")
	)
	(segment
		(start 114.81562 -51.435)
		(end 113.585244 -51.435)
		(width 0.1143)
		(layer "B.Cu")
		(net "XM_DATA_0")
	)
	(segment
		(start 144.526 -55.118)
		(end 143.383 -55.118)
		(width 0.1143)
		(layer "B.Cu")
		(net "XM_DATA_0")
	)
	(segment
		(start 114.87277 -51.37785)
		(end 114.81562 -51.435)
		(width 0.1143)
		(layer "B.Cu")
		(net "XM_DATA_0")
	)
	(segment
		(start 141.256766 -53.503576)
		(end 141.095222 -53.503576)
		(width 0.1143)
		(layer "B.Cu")
		(net "XM_DATA_0")
	)
	(segment
		(start 141.095222 -53.503576)
		(end 140.632688 -53.966364)
		(width 0.1143)
		(layer "B.Cu")
		(net "XM_DATA_0")
	)
	(segment
		(start 140.632688 -53.966364)
		(end 140.453364 -53.966364)
		(width 0.1143)
		(layer "B.Cu")
		(net "XM_DATA_0")
	)
	(segment
		(start 119.680736 -52.6669)
		(end 119.082312 -52.068476)
		(width 0.1143)
		(layer "B.Cu")
		(net "XM_DATA_0")
	)
	(segment
		(start 140.77188 -53.180234)
		(end 140.77188 -52.80787)
		(width 0.1143)
		(layer "B.Cu")
		(net "XM_DATA_0")
	)
	(segment
		(start 201.39152 -115.323874)
		(end 201.39152 -116.04752)
		(width 0.254)
		(layer "F.Cu")
		(net "P1V5_E_VO")
	)
	(segment
		(start 204.857096 -119.272812)
		(end 204.616812 -119.272812)
		(width 0.254)
		(layer "F.Cu")
		(net "P1V5_E_VO")
	)
	(segment
		(start 201.39152 -116.04752)
		(end 203.708 -118.364)
		(width 0.254)
		(layer "F.Cu")
		(net "P1V5_E_VO")
	)
	(segment
		(start 204.616812 -119.272812)
		(end 203.708 -118.364)
		(width 0.254)
		(layer "F.Cu")
		(net "P1V5_E_VO")
	)
	(via
		(at 203.708 -118.364)
		(size 0.7112)
		(drill 0.3556)
		(layers "F.Cu" "B.Cu")
		(net "P1V5_E_VO")
	)
	(segment
		(start 57.794906 -128.392682)
		(end 57.962038 -128.22555)
		(width 0.1143)
		(layer "F.Cu")
		(net "EXP_XM_ADDR_4")
	)
	(segment
		(start 60.468002 -128.11125)
		(end 62.204854 -128.11125)
		(width 0.1143)
		(layer "F.Cu")
		(net "EXP_XM_ADDR_4")
	)
	(segment
		(start 103.89489 -91.894914)
		(end 103.89489 -91.89466)
		(width 0.1143)
		(layer "F.Cu")
		(net "EXP_XM_ADDR_4")
	)
	(segment
		(start 104.349804 -92.349828)
		(end 103.89489 -91.894914)
		(width 0.1143)
		(layer "F.Cu")
		(net "EXP_XM_ADDR_4")
	)
	(segment
		(start 60.353702 -128.22555)
		(end 60.468002 -128.11125)
		(width 0.1143)
		(layer "F.Cu")
		(net "EXP_XM_ADDR_4")
	)
	(segment
		(start 103.89489 -91.89466)
		(end 103.86695 -91.86672)
		(width 0.1143)
		(layer "F.Cu")
		(net "EXP_XM_ADDR_4")
	)
	(segment
		(start 62.204854 -128.11125)
		(end 62.28207 -128.188466)
		(width 0.1143)
		(layer "F.Cu")
		(net "EXP_XM_ADDR_4")
	)
	(segment
		(start 56.558942 -128.392682)
		(end 57.794906 -128.392682)
		(width 0.1143)
		(layer "F.Cu")
		(net "EXP_XM_ADDR_4")
	)
	(segment
		(start 57.962038 -128.22555)
		(end 60.353702 -128.22555)
		(width 0.1143)
		(layer "F.Cu")
		(net "EXP_XM_ADDR_4")
	)
	(via
		(at 103.86695 -91.86672)
		(size 0.508)
		(drill 0.254)
		(layers "F.Cu" "B.Cu")
		(net "EXP_XM_ADDR_4")
	)
	(via
		(at 61.2648 -127.4572)
		(size 0.7112)
		(drill 0.3556)
		(layers "F.Cu" "B.Cu")
		(net "EXP_XM_ADDR_4")
	)
	(via
		(at 62.28207 -128.188466)
		(size 0.5588)
		(drill 0.3048)
		(layers "F.Cu" "B.Cu")
		(net "EXP_XM_ADDR_4")
	)
	(segment
		(start 61.996066 -128.188466)
		(end 62.28207 -128.188466)
		(width 0.1143)
		(layer "B.Cu")
		(net "EXP_XM_ADDR_4")
	)
	(segment
		(start 61.2648 -127.4572)
		(end 61.996066 -128.188466)
		(width 0.1143)
		(layer "B.Cu")
		(net "EXP_XM_ADDR_4")
	)
	(segment
		(start 67.639438 -113.245392)
		(end 67.81927 -113.245392)
		(width 0.127)
		(layer "In2.Cu")
		(net "EXP_XM_ADDR_4")
	)
	(segment
		(start 65.842388 -115.222274)
		(end 65.842388 -115.042442)
		(width 0.127)
		(layer "In2.Cu")
		(net "EXP_XM_ADDR_4")
	)
	(segment
		(start 64.586612 -114.685318)
		(end 64.766444 -114.685318)
		(width 0.127)
		(layer "In2.Cu")
		(net "EXP_XM_ADDR_4")
	)
	(segment
		(start 64.766444 -114.685318)
		(end 65.482978 -115.401852)
		(width 0.127)
		(layer "In2.Cu")
		(net "EXP_XM_ADDR_4")
	)
	(segment
		(start 68.717668 -112.167162)
		(end 68.001134 -111.450628)
		(width 0.127)
		(layer "In2.Cu")
		(net "EXP_XM_ADDR_4")
	)
	(segment
		(start 65.844674 -113.607088)
		(end 65.844674 -113.427256)
		(width 0.127)
		(layer "In2.Cu")
		(net "EXP_XM_ADDR_4")
	)
	(segment
		(start 69.00799 -110.26394)
		(end 69.00799 -110.141258)
		(width 0.127)
		(layer "In2.Cu")
		(net "EXP_XM_ADDR_4")
	)
	(segment
		(start 101.59619 -90.87358)
		(end 102.58933 -91.86672)
		(width 0.127)
		(layer "In2.Cu")
		(net "EXP_XM_ADDR_4")
	)
	(segment
		(start 69.077078 -111.807752)
		(end 69.25691 -111.807752)
		(width 0.127)
		(layer "In2.Cu")
		(net "EXP_XM_ADDR_4")
	)
	(segment
		(start 66.204084 -113.247678)
		(end 66.920618 -113.964212)
		(width 0.127)
		(layer "In2.Cu")
		(net "EXP_XM_ADDR_4")
	)
	(segment
		(start 68.001134 -111.270796)
		(end 68.180712 -111.091218)
		(width 0.127)
		(layer "In2.Cu")
		(net "EXP_XM_ADDR_4")
	)
	(segment
		(start 65.482978 -115.401852)
		(end 65.66281 -115.401852)
		(width 0.127)
		(layer "In2.Cu")
		(net "EXP_XM_ADDR_4")
	)
	(segment
		(start 66.561208 -114.503454)
		(end 66.561208 -114.323622)
		(width 0.127)
		(layer "In2.Cu")
		(net "EXP_XM_ADDR_4")
	)
	(segment
		(start 64.407034 -114.864896)
		(end 64.586612 -114.685318)
		(width 0.127)
		(layer "In2.Cu")
		(net "EXP_XM_ADDR_4")
	)
	(segment
		(start 67.81927 -113.245392)
		(end 67.998848 -113.065814)
		(width 0.127)
		(layer "In2.Cu")
		(net "EXP_XM_ADDR_4")
	)
	(segment
		(start 65.842388 -115.042442)
		(end 65.125854 -114.325908)
		(width 0.127)
		(layer "In2.Cu")
		(net "EXP_XM_ADDR_4")
	)
	(segment
		(start 64.047624 -115.404138)
		(end 64.764158 -116.120672)
		(width 0.127)
		(layer "In2.Cu")
		(net "EXP_XM_ADDR_4")
	)
	(segment
		(start 62.144402 -128.050798)
		(end 62.144402 -125.694948)
		(width 0.127)
		(layer "In2.Cu")
		(net "EXP_XM_ADDR_4")
	)
	(segment
		(start 64.764158 -116.120672)
		(end 64.94399 -116.120672)
		(width 0.127)
		(layer "In2.Cu")
		(net "EXP_XM_ADDR_4")
	)
	(segment
		(start 66.38163 -114.683032)
		(end 66.561208 -114.503454)
		(width 0.127)
		(layer "In2.Cu")
		(net "EXP_XM_ADDR_4")
	)
	(segment
		(start 65.125854 -114.146076)
		(end 65.305432 -113.966498)
		(width 0.127)
		(layer "In2.Cu")
		(net "EXP_XM_ADDR_4")
	)
	(segment
		(start 69.518276 -111.546386)
		(end 69.518276 -111.343186)
		(width 0.127)
		(layer "In2.Cu")
		(net "EXP_XM_ADDR_4")
	)
	(segment
		(start 67.280028 -113.784634)
		(end 67.280028 -113.604802)
		(width 0.127)
		(layer "In2.Cu")
		(net "EXP_XM_ADDR_4")
	)
	(segment
		(start 67.282314 -111.989616)
		(end 67.461892 -111.810038)
		(width 0.127)
		(layer "In2.Cu")
		(net "EXP_XM_ADDR_4")
	)
	(segment
		(start 66.920618 -113.964212)
		(end 67.10045 -113.964212)
		(width 0.127)
		(layer "In2.Cu")
		(net "EXP_XM_ADDR_4")
	)
	(segment
		(start 67.461892 -111.810038)
		(end 67.641724 -111.810038)
		(width 0.127)
		(layer "In2.Cu")
		(net "EXP_XM_ADDR_4")
	)
	(segment
		(start 62.79007 -125.04928)
		(end 62.79007 -118.274592)
		(width 0.127)
		(layer "In2.Cu")
		(net "EXP_XM_ADDR_4")
	)
	(segment
		(start 65.485264 -113.966498)
		(end 66.201798 -114.683032)
		(width 0.127)
		(layer "In2.Cu")
		(net "EXP_XM_ADDR_4")
	)
	(segment
		(start 66.563494 -112.888268)
		(end 66.563494 -112.708436)
		(width 0.127)
		(layer "In2.Cu")
		(net "EXP_XM_ADDR_4")
	)
	(segment
		(start 68.360544 -111.091218)
		(end 69.077078 -111.807752)
		(width 0.127)
		(layer "In2.Cu")
		(net "EXP_XM_ADDR_4")
	)
	(segment
		(start 100.54463 -90.479626)
		(end 100.938584 -90.87358)
		(width 0.127)
		(layer "In2.Cu")
		(net "EXP_XM_ADDR_4")
	)
	(segment
		(start 66.922904 -112.528858)
		(end 67.639438 -113.245392)
		(width 0.127)
		(layer "In2.Cu")
		(net "EXP_XM_ADDR_4")
	)
	(segment
		(start 68.53809 -112.526572)
		(end 68.717668 -112.346994)
		(width 0.127)
		(layer "In2.Cu")
		(net "EXP_XM_ADDR_4")
	)
	(segment
		(start 63.688214 -115.583716)
		(end 63.867792 -115.404138)
		(width 0.127)
		(layer "In2.Cu")
		(net "EXP_XM_ADDR_4")
	)
	(segment
		(start 62.144402 -125.694948)
		(end 62.79007 -125.04928)
		(width 0.127)
		(layer "In2.Cu")
		(net "EXP_XM_ADDR_4")
	)
	(segment
		(start 68.717668 -112.346994)
		(end 68.717668 -112.167162)
		(width 0.127)
		(layer "In2.Cu")
		(net "EXP_XM_ADDR_4")
	)
	(segment
		(start 67.282314 -112.169448)
		(end 67.282314 -111.989616)
		(width 0.127)
		(layer "In2.Cu")
		(net "EXP_XM_ADDR_4")
	)
	(segment
		(start 65.125854 -114.325908)
		(end 65.125854 -114.146076)
		(width 0.127)
		(layer "In2.Cu")
		(net "EXP_XM_ADDR_4")
	)
	(segment
		(start 62.79007 -118.274592)
		(end 64.404748 -116.659914)
		(width 0.127)
		(layer "In2.Cu")
		(net "EXP_XM_ADDR_4")
	)
	(segment
		(start 63.688214 -115.763548)
		(end 63.688214 -115.583716)
		(width 0.127)
		(layer "In2.Cu")
		(net "EXP_XM_ADDR_4")
	)
	(segment
		(start 65.123568 -115.941094)
		(end 65.123568 -115.761262)
		(width 0.127)
		(layer "In2.Cu")
		(net "EXP_XM_ADDR_4")
	)
	(segment
		(start 69.00799 -110.141258)
		(end 88.85174 -90.297508)
		(width 0.127)
		(layer "In2.Cu")
		(net "EXP_XM_ADDR_4")
	)
	(segment
		(start 65.844674 -113.427256)
		(end 66.024252 -113.247678)
		(width 0.127)
		(layer "In2.Cu")
		(net "EXP_XM_ADDR_4")
	)
	(segment
		(start 68.001134 -111.450628)
		(end 68.001134 -111.270796)
		(width 0.127)
		(layer "In2.Cu")
		(net "EXP_XM_ADDR_4")
	)
	(segment
		(start 100.938584 -90.87358)
		(end 101.59619 -90.87358)
		(width 0.127)
		(layer "In2.Cu")
		(net "EXP_XM_ADDR_4")
	)
	(segment
		(start 66.563494 -112.708436)
		(end 66.743072 -112.528858)
		(width 0.127)
		(layer "In2.Cu")
		(net "EXP_XM_ADDR_4")
	)
	(segment
		(start 64.94399 -116.120672)
		(end 65.123568 -115.941094)
		(width 0.127)
		(layer "In2.Cu")
		(net "EXP_XM_ADDR_4")
	)
	(segment
		(start 68.358258 -112.526572)
		(end 68.53809 -112.526572)
		(width 0.127)
		(layer "In2.Cu")
		(net "EXP_XM_ADDR_4")
	)
	(segment
		(start 64.404748 -116.480082)
		(end 63.688214 -115.763548)
		(width 0.127)
		(layer "In2.Cu")
		(net "EXP_XM_ADDR_4")
	)
	(segment
		(start 68.88861 -110.383066)
		(end 69.00799 -110.26394)
		(width 0.127)
		(layer "In2.Cu")
		(net "EXP_XM_ADDR_4")
	)
	(segment
		(start 67.280028 -113.604802)
		(end 66.563494 -112.888268)
		(width 0.127)
		(layer "In2.Cu")
		(net "EXP_XM_ADDR_4")
	)
	(segment
		(start 68.180712 -111.091218)
		(end 68.360544 -111.091218)
		(width 0.127)
		(layer "In2.Cu")
		(net "EXP_XM_ADDR_4")
	)
	(segment
		(start 66.743072 -112.528858)
		(end 66.922904 -112.528858)
		(width 0.127)
		(layer "In2.Cu")
		(net "EXP_XM_ADDR_4")
	)
	(segment
		(start 67.998848 -113.065814)
		(end 67.998848 -112.885982)
		(width 0.127)
		(layer "In2.Cu")
		(net "EXP_XM_ADDR_4")
	)
	(segment
		(start 102.58933 -91.86672)
		(end 103.86695 -91.86672)
		(width 0.127)
		(layer "In2.Cu")
		(net "EXP_XM_ADDR_4")
	)
	(segment
		(start 99.888802 -90.297508)
		(end 100.07092 -90.479626)
		(width 0.127)
		(layer "In2.Cu")
		(net "EXP_XM_ADDR_4")
	)
	(segment
		(start 100.07092 -90.479626)
		(end 100.54463 -90.479626)
		(width 0.127)
		(layer "In2.Cu")
		(net "EXP_XM_ADDR_4")
	)
	(segment
		(start 66.201798 -114.683032)
		(end 66.38163 -114.683032)
		(width 0.127)
		(layer "In2.Cu")
		(net "EXP_XM_ADDR_4")
	)
	(segment
		(start 67.641724 -111.810038)
		(end 68.358258 -112.526572)
		(width 0.127)
		(layer "In2.Cu")
		(net "EXP_XM_ADDR_4")
	)
	(segment
		(start 64.404748 -116.659914)
		(end 64.404748 -116.480082)
		(width 0.127)
		(layer "In2.Cu")
		(net "EXP_XM_ADDR_4")
	)
	(segment
		(start 65.66281 -115.401852)
		(end 65.842388 -115.222274)
		(width 0.127)
		(layer "In2.Cu")
		(net "EXP_XM_ADDR_4")
	)
	(segment
		(start 63.867792 -115.404138)
		(end 64.047624 -115.404138)
		(width 0.127)
		(layer "In2.Cu")
		(net "EXP_XM_ADDR_4")
	)
	(segment
		(start 88.85174 -90.297508)
		(end 99.888802 -90.297508)
		(width 0.127)
		(layer "In2.Cu")
		(net "EXP_XM_ADDR_4")
	)
	(segment
		(start 67.998848 -112.885982)
		(end 67.282314 -112.169448)
		(width 0.127)
		(layer "In2.Cu")
		(net "EXP_XM_ADDR_4")
	)
	(segment
		(start 69.518276 -111.343186)
		(end 68.88861 -110.71352)
		(width 0.127)
		(layer "In2.Cu")
		(net "EXP_XM_ADDR_4")
	)
	(segment
		(start 68.88861 -110.71352)
		(end 68.88861 -110.383066)
		(width 0.127)
		(layer "In2.Cu")
		(net "EXP_XM_ADDR_4")
	)
	(segment
		(start 62.28207 -128.188466)
		(end 62.144402 -128.050798)
		(width 0.127)
		(layer "In2.Cu")
		(net "EXP_XM_ADDR_4")
	)
	(segment
		(start 66.561208 -114.323622)
		(end 65.844674 -113.607088)
		(width 0.127)
		(layer "In2.Cu")
		(net "EXP_XM_ADDR_4")
	)
	(segment
		(start 64.407034 -115.044728)
		(end 64.407034 -114.864896)
		(width 0.127)
		(layer "In2.Cu")
		(net "EXP_XM_ADDR_4")
	)
	(segment
		(start 67.10045 -113.964212)
		(end 67.280028 -113.784634)
		(width 0.127)
		(layer "In2.Cu")
		(net "EXP_XM_ADDR_4")
	)
	(segment
		(start 69.25691 -111.807752)
		(end 69.518276 -111.546386)
		(width 0.127)
		(layer "In2.Cu")
		(net "EXP_XM_ADDR_4")
	)
	(segment
		(start 66.024252 -113.247678)
		(end 66.204084 -113.247678)
		(width 0.127)
		(layer "In2.Cu")
		(net "EXP_XM_ADDR_4")
	)
	(segment
		(start 65.305432 -113.966498)
		(end 65.485264 -113.966498)
		(width 0.127)
		(layer "In2.Cu")
		(net "EXP_XM_ADDR_4")
	)
	(segment
		(start 65.123568 -115.761262)
		(end 64.407034 -115.044728)
		(width 0.127)
		(layer "In2.Cu")
		(net "EXP_XM_ADDR_4")
	)
	(segment
		(start 108.882942 -108.6104)
		(end 108.882942 -106.928666)
		(width 0.1016)
		(layer "F.Cu")
		(net "SAS_HDD_TX9_N")
	)
	(segment
		(start 108.920026 -106.839004)
		(end 109.328966 -106.430064)
		(width 0.1016)
		(layer "F.Cu")
		(net "SAS_HDD_TX9_N")
	)
	(segment
		(start 109.349794 -106.379518)
		(end 109.349794 -106.350054)
		(width 0.1016)
		(layer "F.Cu")
		(net "SAS_HDD_TX9_N")
	)
	(segment
		(start 105.44302 -113.560352)
		(end 105.44302 -113.309146)
		(width 0.1016)
		(layer "F.Cu")
		(net "SAS_HDD_TX9_N")
	)
	(segment
		(start 105.29697 -114.0206)
		(end 105.29697 -113.811558)
		(width 0.1016)
		(layer "F.Cu")
		(net "SAS_HDD_TX9_N")
	)
	(segment
		(start 105.808018 -112.427766)
		(end 108.357924 -109.87786)
		(width 0.1016)
		(layer "F.Cu")
		(net "SAS_HDD_TX9_N")
	)
	(segment
		(start 105.334054 -113.721896)
		(end 105.405936 -113.650014)
		(width 0.1016)
		(layer "F.Cu")
		(net "SAS_HDD_TX9_N")
	)
	(arc
		(start 108.882942 -106.928666)
		(mid 108.892575 -106.880148)
		(end 108.920026 -106.839004)
		(width 0.1016)
		(layer "F.Cu")
		(net "SAS_HDD_TX9_N")
	)
	(arc
		(start 109.328966 -106.430064)
		(mid 109.344378 -106.406858)
		(end 109.349794 -106.379518)
		(width 0.1016)
		(layer "F.Cu")
		(net "SAS_HDD_TX9_N")
	)
	(arc
		(start 105.44302 -113.309146)
		(mid 105.537865 -112.832149)
		(end 105.808018 -112.427766)
		(width 0.1016)
		(layer "F.Cu")
		(net "SAS_HDD_TX9_N")
	)
	(arc
		(start 108.357924 -109.87786)
		(mid 108.74648 -109.296344)
		(end 108.882942 -108.6104)
		(width 0.1016)
		(layer "F.Cu")
		(net "SAS_HDD_TX9_N")
	)
	(arc
		(start 105.29697 -113.811558)
		(mid 105.306603 -113.76304)
		(end 105.334054 -113.721896)
		(width 0.1016)
		(layer "F.Cu")
		(net "SAS_HDD_TX9_N")
	)
	(arc
		(start 105.405936 -113.650014)
		(mid 105.433369 -113.608863)
		(end 105.44302 -113.560352)
		(width 0.1016)
		(layer "F.Cu")
		(net "SAS_HDD_TX9_N")
	)
	(segment
		(start 107.926886 -55.367174)
		(end 107.926886 -55.386478)
		(width 0.1143)
		(layer "F.Cu")
		(net "XM_DATA_5")
	)
	(segment
		(start 107.559602 -54.99989)
		(end 107.926886 -55.367174)
		(width 0.1143)
		(layer "F.Cu")
		(net "XM_DATA_5")
	)
	(segment
		(start 140.63345 -60.073794)
		(end 140.63345 -54.841902)
		(width 0.1143)
		(layer "F.Cu")
		(net "XM_DATA_5")
	)
	(segment
		(start 140.598906 -61.9379)
		(end 140.598906 -60.108338)
		(width 0.1143)
		(layer "F.Cu")
		(net "XM_DATA_5")
	)
	(segment
		(start 140.598906 -60.108338)
		(end 140.63345 -60.073794)
		(width 0.1143)
		(layer "F.Cu")
		(net "XM_DATA_5")
	)
	(segment
		(start 107.54995 -54.99989)
		(end 107.559602 -54.99989)
		(width 0.1143)
		(layer "F.Cu")
		(net "XM_DATA_5")
	)
	(segment
		(start 107.926886 -55.386478)
		(end 107.944666 -55.404258)
		(width 0.1143)
		(layer "F.Cu")
		(net "XM_DATA_5")
	)
	(via
		(at 107.944666 -55.404258)
		(size 0.508)
		(drill 0.254)
		(layers "F.Cu" "B.Cu")
		(net "XM_DATA_5")
	)
	(via
		(at 137.795 -54.737)
		(size 0.7112)
		(drill 0.3556)
		(layers "F.Cu" "B.Cu")
		(net "XM_DATA_5")
	)
	(via
		(at 140.63345 -54.841902)
		(size 0.5588)
		(drill 0.3048)
		(layers "F.Cu" "B.Cu")
		(net "XM_DATA_5")
	)
	(segment
		(start 118.224554 -53.327554)
		(end 118.222776 -53.325776)
		(width 0.1143)
		(layer "B.Cu")
		(net "XM_DATA_5")
	)
	(segment
		(start 137.4521 -55.0799)
		(end 137.033 -55.0799)
		(width 0.1143)
		(layer "B.Cu")
		(net "XM_DATA_5")
	)
	(segment
		(start 114.736626 -52.987194)
		(end 113.264696 -54.459124)
		(width 0.1143)
		(layer "B.Cu")
		(net "XM_DATA_5")
	)
	(segment
		(start 137.795 -54.737)
		(end 137.4521 -55.0799)
		(width 0.1143)
		(layer "B.Cu")
		(net "XM_DATA_5")
	)
	(segment
		(start 136.9187 -54.3433)
		(end 136.8044 -54.229)
		(width 0.1143)
		(layer "B.Cu")
		(net "XM_DATA_5")
	)
	(segment
		(start 109.497876 -54.459124)
		(end 109.079538 -54.877462)
		(width 0.1143)
		(layer "B.Cu")
		(net "XM_DATA_5")
	)
	(segment
		(start 136.9187 -54.9656)
		(end 136.9187 -54.3433)
		(width 0.1143)
		(layer "B.Cu")
		(net "XM_DATA_5")
	)
	(segment
		(start 139.705588 -55.769764)
		(end 140.63345 -54.841902)
		(width 0.1143)
		(layer "B.Cu")
		(net "XM_DATA_5")
	)
	(segment
		(start 130.255518 -54.063646)
		(end 130.255264 -54.0639)
		(width 0.1143)
		(layer "B.Cu")
		(net "XM_DATA_5")
	)
	(segment
		(start 118.43639 -53.327554)
		(end 118.224554 -53.327554)
		(width 0.1143)
		(layer "B.Cu")
		(net "XM_DATA_5")
	)
	(segment
		(start 138.427714 -55.483506)
		(end 138.713972 -55.769764)
		(width 0.1143)
		(layer "B.Cu")
		(net "XM_DATA_5")
	)
	(segment
		(start 130.255264 -54.0639)
		(end 119.17299 -54.0639)
		(width 0.1143)
		(layer "B.Cu")
		(net "XM_DATA_5")
	)
	(segment
		(start 136.5758 -54.229)
		(end 136.4615 -54.3433)
		(width 0.1143)
		(layer "B.Cu")
		(net "XM_DATA_5")
	)
	(segment
		(start 137.033 -55.0799)
		(end 136.9187 -54.9656)
		(width 0.1143)
		(layer "B.Cu")
		(net "XM_DATA_5")
	)
	(segment
		(start 138.713972 -55.769764)
		(end 139.705588 -55.769764)
		(width 0.1143)
		(layer "B.Cu")
		(net "XM_DATA_5")
	)
	(segment
		(start 136.3472 -55.0799)
		(end 131.618736 -55.0799)
		(width 0.1143)
		(layer "B.Cu")
		(net "XM_DATA_5")
	)
	(segment
		(start 130.602482 -54.063646)
		(end 130.255518 -54.063646)
		(width 0.1143)
		(layer "B.Cu")
		(net "XM_DATA_5")
	)
	(segment
		(start 118.222776 -53.325776)
		(end 116.13642 -53.325776)
		(width 0.1143)
		(layer "B.Cu")
		(net "XM_DATA_5")
	)
	(segment
		(start 113.264696 -54.459124)
		(end 109.497876 -54.459124)
		(width 0.1143)
		(layer "B.Cu")
		(net "XM_DATA_5")
	)
	(segment
		(start 108.471462 -54.877462)
		(end 107.944666 -55.404258)
		(width 0.1143)
		(layer "B.Cu")
		(net "XM_DATA_5")
	)
	(segment
		(start 131.618736 -55.0799)
		(end 130.602482 -54.063646)
		(width 0.1143)
		(layer "B.Cu")
		(net "XM_DATA_5")
	)
	(segment
		(start 137.795 -54.737)
		(end 138.427714 -55.369714)
		(width 0.1143)
		(layer "B.Cu")
		(net "XM_DATA_5")
	)
	(segment
		(start 118.457472 -53.348382)
		(end 118.457218 -53.348382)
		(width 0.1143)
		(layer "B.Cu")
		(net "XM_DATA_5")
	)
	(segment
		(start 136.4615 -54.9656)
		(end 136.3472 -55.0799)
		(width 0.1143)
		(layer "B.Cu")
		(net "XM_DATA_5")
	)
	(segment
		(start 118.457218 -53.348382)
		(end 118.43639 -53.327554)
		(width 0.1143)
		(layer "B.Cu")
		(net "XM_DATA_5")
	)
	(segment
		(start 109.079538 -54.877462)
		(end 108.471462 -54.877462)
		(width 0.1143)
		(layer "B.Cu")
		(net "XM_DATA_5")
	)
	(segment
		(start 116.13642 -53.325776)
		(end 115.797838 -52.987194)
		(width 0.1143)
		(layer "B.Cu")
		(net "XM_DATA_5")
	)
	(segment
		(start 119.17299 -54.0639)
		(end 118.457472 -53.348382)
		(width 0.1143)
		(layer "B.Cu")
		(net "XM_DATA_5")
	)
	(segment
		(start 136.4615 -54.3433)
		(end 136.4615 -54.9656)
		(width 0.1143)
		(layer "B.Cu")
		(net "XM_DATA_5")
	)
	(segment
		(start 136.8044 -54.229)
		(end 136.5758 -54.229)
		(width 0.1143)
		(layer "B.Cu")
		(net "XM_DATA_5")
	)
	(segment
		(start 115.797838 -52.987194)
		(end 114.736626 -52.987194)
		(width 0.1143)
		(layer "B.Cu")
		(net "XM_DATA_5")
	)
	(segment
		(start 138.427714 -55.369714)
		(end 138.427714 -55.483506)
		(width 0.1143)
		(layer "B.Cu")
		(net "XM_DATA_5")
	)
	(segment
		(start 194.049396 -113.811812)
		(end 194.049396 -112.084612)
		(width 0.508)
		(layer "F.Cu")
		(net "P1V5_E_SNB")
	)
	(segment
		(start 192.639188 -113.811812)
		(end 194.049396 -113.811812)
		(width 0.508)
		(layer "F.Cu")
		(net "P1V5_E_SNB")
	)
	(segment
		(start 194.049396 -112.084612)
		(end 193.998596 -112.033812)
		(width 0.508)
		(layer "F.Cu")
		(net "P1V5_E_SNB")
	)
	(segment
		(start 192.532 -113.919)
		(end 192.639188 -113.811812)
		(width 0.508)
		(layer "F.Cu")
		(net "P1V5_E_SNB")
	)
	(via
		(at 192.532 -113.919)
		(size 0.7112)
		(drill 0.3556)
		(layers "F.Cu" "B.Cu")
		(net "P1V5_E_SNB")
	)
	(segment
		(start 74.718164 -129.413)
		(end 74.491342 -129.413)
		(width 0.1143)
		(layer "F.Cu")
		(net "XM_DATA0")
	)
	(segment
		(start 74.738992 -129.392172)
		(end 74.718164 -129.413)
		(width 0.1143)
		(layer "F.Cu")
		(net "XM_DATA0")
	)
	(segment
		(start 75.786742 -129.392172)
		(end 74.738992 -129.392172)
		(width 0.1143)
		(layer "F.Cu")
		(net "XM_DATA0")
	)
	(segment
		(start 107.349798 -93.349826)
		(end 106.849672 -92.8497)
		(width 0.1143)
		(layer "F.Cu")
		(net "XM_DATA0")
	)
	(via
		(at 74.491342 -129.413)
		(size 0.5588)
		(drill 0.3048)
		(layers "F.Cu" "B.Cu")
		(net "XM_DATA0")
	)
	(via
		(at 92.370148 -94.954852)
		(size 0.7112)
		(drill 0.3556)
		(layers "F.Cu" "B.Cu")
		(net "XM_DATA0")
	)
	(via
		(at 106.849672 -92.8497)
		(size 0.508)
		(drill 0.254)
		(layers "F.Cu" "B.Cu")
		(net "XM_DATA0")
	)
	(segment
		(start 81.8134 -95.922338)
		(end 81.8134 -95.760794)
		(width 0.1143)
		(layer "B.Cu")
		(net "XM_DATA0")
	)
	(segment
		(start 79.226664 -98.34753)
		(end 79.388462 -98.185732)
		(width 0.1143)
		(layer "B.Cu")
		(net "XM_DATA0")
	)
	(segment
		(start 77.710792 -102.166674)
		(end 76.639928 -101.09581)
		(width 0.1143)
		(layer "B.Cu")
		(net "XM_DATA0")
	)
	(segment
		(start 78.195678 -101.843332)
		(end 78.357476 -101.681534)
		(width 0.1143)
		(layer "B.Cu")
		(net "XM_DATA0")
	)
	(segment
		(start 85.084158 -94.954852)
		(end 92.370148 -94.954852)
		(width 0.1143)
		(layer "B.Cu")
		(net "XM_DATA0")
	)
	(segment
		(start 76.639928 -101.09581)
		(end 76.639928 -100.934266)
		(width 0.1143)
		(layer "B.Cu")
		(net "XM_DATA0")
	)
	(segment
		(start 78.842362 -101.196648)
		(end 80.297528 -99.741482)
		(width 0.1143)
		(layer "B.Cu")
		(net "XM_DATA0")
	)
	(segment
		(start 79.388462 -98.185732)
		(end 79.550006 -98.185732)
		(width 0.1143)
		(layer "B.Cu")
		(net "XM_DATA0")
	)
	(segment
		(start 80.782414 -99.256596)
		(end 80.944212 -99.094798)
		(width 0.1143)
		(layer "B.Cu")
		(net "XM_DATA0")
	)
	(segment
		(start 77.710792 -102.328218)
		(end 77.710792 -102.166674)
		(width 0.1143)
		(layer "B.Cu")
		(net "XM_DATA0")
	)
	(segment
		(start 75.993244 -101.58095)
		(end 76.155042 -101.419152)
		(width 0.1143)
		(layer "B.Cu")
		(net "XM_DATA0")
	)
	(segment
		(start 79.550006 -98.185732)
		(end 80.62087 -99.256596)
		(width 0.1143)
		(layer "B.Cu")
		(net "XM_DATA0")
	)
	(segment
		(start 78.680818 -101.196648)
		(end 78.842362 -101.196648)
		(width 0.1143)
		(layer "B.Cu")
		(net "XM_DATA0")
	)
	(segment
		(start 76.316586 -101.419152)
		(end 77.38745 -102.490016)
		(width 0.1143)
		(layer "B.Cu")
		(net "XM_DATA0")
	)
	(segment
		(start 82.884264 -97.154746)
		(end 82.884264 -96.993202)
		(width 0.1143)
		(layer "B.Cu")
		(net "XM_DATA0")
	)
	(segment
		(start 82.621882 -94.952312)
		(end 82.783426 -94.952312)
		(width 0.1143)
		(layer "B.Cu")
		(net "XM_DATA0")
	)
	(segment
		(start 77.064108 -102.974902)
		(end 77.064108 -102.813358)
		(width 0.1143)
		(layer "B.Cu")
		(net "XM_DATA0")
	)
	(segment
		(start 82.460084 -95.11411)
		(end 82.621882 -94.952312)
		(width 0.1143)
		(layer "B.Cu")
		(net "XM_DATA0")
	)
	(segment
		(start 78.357476 -101.681534)
		(end 78.357476 -101.51999)
		(width 0.1143)
		(layer "B.Cu")
		(net "XM_DATA0")
	)
	(segment
		(start 72.95642 -107.08259)
		(end 77.064108 -102.974902)
		(width 0.1143)
		(layer "B.Cu")
		(net "XM_DATA0")
	)
	(segment
		(start 80.297528 -99.741482)
		(end 80.297528 -99.579938)
		(width 0.1143)
		(layer "B.Cu")
		(net "XM_DATA0")
	)
	(segment
		(start 82.460084 -95.275654)
		(end 82.460084 -95.11411)
		(width 0.1143)
		(layer "B.Cu")
		(net "XM_DATA0")
	)
	(segment
		(start 106.31297 -93.386402)
		(end 106.849672 -92.8497)
		(width 0.1143)
		(layer "B.Cu")
		(net "XM_DATA0")
	)
	(segment
		(start 76.639928 -100.934266)
		(end 76.801726 -100.772468)
		(width 0.1143)
		(layer "B.Cu")
		(net "XM_DATA0")
	)
	(segment
		(start 79.873348 -97.86239)
		(end 79.873348 -97.700846)
		(width 0.1143)
		(layer "B.Cu")
		(net "XM_DATA0")
	)
	(segment
		(start 78.357476 -101.51999)
		(end 77.286612 -100.449126)
		(width 0.1143)
		(layer "B.Cu")
		(net "XM_DATA0")
	)
	(segment
		(start 81.267554 -98.609912)
		(end 81.429098 -98.609912)
		(width 0.1143)
		(layer "B.Cu")
		(net "XM_DATA0")
	)
	(segment
		(start 76.96327 -100.772468)
		(end 78.034134 -101.843332)
		(width 0.1143)
		(layer "B.Cu")
		(net "XM_DATA0")
	)
	(segment
		(start 78.034134 -101.843332)
		(end 78.195678 -101.843332)
		(width 0.1143)
		(layer "B.Cu")
		(net "XM_DATA0")
	)
	(segment
		(start 79.226664 -98.509074)
		(end 79.226664 -98.34753)
		(width 0.1143)
		(layer "B.Cu")
		(net "XM_DATA0")
	)
	(segment
		(start 80.944212 -98.933254)
		(end 79.873348 -97.86239)
		(width 0.1143)
		(layer "B.Cu")
		(net "XM_DATA0")
	)
	(segment
		(start 74.491342 -129.413)
		(end 72.95642 -127.878078)
		(width 0.1143)
		(layer "B.Cu")
		(net "XM_DATA0")
	)
	(segment
		(start 83.530948 -96.508062)
		(end 83.530948 -96.346518)
		(width 0.1143)
		(layer "B.Cu")
		(net "XM_DATA0")
	)
	(segment
		(start 75.993244 -101.742494)
		(end 75.993244 -101.58095)
		(width 0.1143)
		(layer "B.Cu")
		(net "XM_DATA0")
	)
	(segment
		(start 82.136742 -95.598996)
		(end 83.207606 -96.66986)
		(width 0.1143)
		(layer "B.Cu")
		(net "XM_DATA0")
	)
	(segment
		(start 80.19669 -97.539048)
		(end 81.267554 -98.609912)
		(width 0.1143)
		(layer "B.Cu")
		(net "XM_DATA0")
	)
	(segment
		(start 79.873348 -97.700846)
		(end 80.035146 -97.539048)
		(width 0.1143)
		(layer "B.Cu")
		(net "XM_DATA0")
	)
	(segment
		(start 82.783426 -94.952312)
		(end 83.85429 -96.023176)
		(width 0.1143)
		(layer "B.Cu")
		(net "XM_DATA0")
	)
	(segment
		(start 80.035146 -97.539048)
		(end 80.19669 -97.539048)
		(width 0.1143)
		(layer "B.Cu")
		(net "XM_DATA0")
	)
	(segment
		(start 81.975198 -95.598996)
		(end 82.136742 -95.598996)
		(width 0.1143)
		(layer "B.Cu")
		(net "XM_DATA0")
	)
	(segment
		(start 72.95642 -127.878078)
		(end 72.95642 -107.08259)
		(width 0.1143)
		(layer "B.Cu")
		(net "XM_DATA0")
	)
	(segment
		(start 83.530948 -96.346518)
		(end 82.460084 -95.275654)
		(width 0.1143)
		(layer "B.Cu")
		(net "XM_DATA0")
	)
	(segment
		(start 83.36915 -96.66986)
		(end 83.530948 -96.508062)
		(width 0.1143)
		(layer "B.Cu")
		(net "XM_DATA0")
	)
	(segment
		(start 76.155042 -101.419152)
		(end 76.316586 -101.419152)
		(width 0.1143)
		(layer "B.Cu")
		(net "XM_DATA0")
	)
	(segment
		(start 80.62087 -99.256596)
		(end 80.782414 -99.256596)
		(width 0.1143)
		(layer "B.Cu")
		(net "XM_DATA0")
	)
	(segment
		(start 105.328466 -94.954852)
		(end 106.31297 -93.970348)
		(width 0.1143)
		(layer "B.Cu")
		(net "XM_DATA0")
	)
	(segment
		(start 77.44841 -100.125784)
		(end 77.609954 -100.125784)
		(width 0.1143)
		(layer "B.Cu")
		(net "XM_DATA0")
	)
	(segment
		(start 83.85429 -96.023176)
		(end 84.015834 -96.023176)
		(width 0.1143)
		(layer "B.Cu")
		(net "XM_DATA0")
	)
	(segment
		(start 80.297528 -99.579938)
		(end 79.226664 -98.509074)
		(width 0.1143)
		(layer "B.Cu")
		(net "XM_DATA0")
	)
	(segment
		(start 82.884264 -96.993202)
		(end 81.8134 -95.922338)
		(width 0.1143)
		(layer "B.Cu")
		(net "XM_DATA0")
	)
	(segment
		(start 83.207606 -96.66986)
		(end 83.36915 -96.66986)
		(width 0.1143)
		(layer "B.Cu")
		(net "XM_DATA0")
	)
	(segment
		(start 92.370148 -94.954852)
		(end 105.328466 -94.954852)
		(width 0.1143)
		(layer "B.Cu")
		(net "XM_DATA0")
	)
	(segment
		(start 106.31297 -93.970348)
		(end 106.31297 -93.386402)
		(width 0.1143)
		(layer "B.Cu")
		(net "XM_DATA0")
	)
	(segment
		(start 77.609954 -100.125784)
		(end 78.680818 -101.196648)
		(width 0.1143)
		(layer "B.Cu")
		(net "XM_DATA0")
	)
	(segment
		(start 84.015834 -96.023176)
		(end 85.084158 -94.954852)
		(width 0.1143)
		(layer "B.Cu")
		(net "XM_DATA0")
	)
	(segment
		(start 76.801726 -100.772468)
		(end 76.96327 -100.772468)
		(width 0.1143)
		(layer "B.Cu")
		(net "XM_DATA0")
	)
	(segment
		(start 77.38745 -102.490016)
		(end 77.548994 -102.490016)
		(width 0.1143)
		(layer "B.Cu")
		(net "XM_DATA0")
	)
	(segment
		(start 80.944212 -99.094798)
		(end 80.944212 -98.933254)
		(width 0.1143)
		(layer "B.Cu")
		(net "XM_DATA0")
	)
	(segment
		(start 77.064108 -102.813358)
		(end 75.993244 -101.742494)
		(width 0.1143)
		(layer "B.Cu")
		(net "XM_DATA0")
	)
	(segment
		(start 81.8134 -95.760794)
		(end 81.975198 -95.598996)
		(width 0.1143)
		(layer "B.Cu")
		(net "XM_DATA0")
	)
	(segment
		(start 77.286612 -100.287582)
		(end 77.44841 -100.125784)
		(width 0.1143)
		(layer "B.Cu")
		(net "XM_DATA0")
	)
	(segment
		(start 77.286612 -100.449126)
		(end 77.286612 -100.287582)
		(width 0.1143)
		(layer "B.Cu")
		(net "XM_DATA0")
	)
	(segment
		(start 81.429098 -98.609912)
		(end 82.884264 -97.154746)
		(width 0.1143)
		(layer "B.Cu")
		(net "XM_DATA0")
	)
	(segment
		(start 77.548994 -102.490016)
		(end 77.710792 -102.328218)
		(width 0.1143)
		(layer "B.Cu")
		(net "XM_DATA0")
	)
	(segment
		(start 109.225842 -108.6104)
		(end 109.225842 -107.487466)
		(width 0.1016)
		(layer "F.Cu")
		(net "SAS_HDD_TX9_P")
	)
	(segment
		(start 106.050588 -112.670336)
		(end 108.600494 -110.12043)
		(width 0.1016)
		(layer "F.Cu")
		(net "SAS_HDD_TX9_P")
	)
	(segment
		(start 105.78592 -113.565432)
		(end 105.78592 -113.3094)
		(width 0.1016)
		(layer "F.Cu")
		(net "SAS_HDD_TX9_P")
	)
	(segment
		(start 109.262926 -107.397804)
		(end 109.310678 -107.350052)
		(width 0.1016)
		(layer "F.Cu")
		(net "SAS_HDD_TX9_P")
	)
	(segment
		(start 105.894886 -113.726976)
		(end 105.823004 -113.655094)
		(width 0.1016)
		(layer "F.Cu")
		(net "SAS_HDD_TX9_P")
	)
	(segment
		(start 105.93197 -114.0206)
		(end 105.93197 -113.816638)
		(width 0.1016)
		(layer "F.Cu")
		(net "SAS_HDD_TX9_P")
	)
	(segment
		(start 109.310678 -107.350052)
		(end 109.349794 -107.350052)
		(width 0.1016)
		(layer "F.Cu")
		(net "SAS_HDD_TX9_P")
	)
	(arc
		(start 105.93197 -113.816638)
		(mid 105.922337 -113.76812)
		(end 105.894886 -113.726976)
		(width 0.1016)
		(layer "F.Cu")
		(net "SAS_HDD_TX9_P")
	)
	(arc
		(start 105.78592 -113.3094)
		(mid 105.854697 -112.963543)
		(end 106.050588 -112.670336)
		(width 0.1016)
		(layer "F.Cu")
		(net "SAS_HDD_TX9_P")
	)
	(arc
		(start 108.600494 -110.12043)
		(mid 109.06333 -109.427607)
		(end 109.225842 -108.6104)
		(width 0.1016)
		(layer "F.Cu")
		(net "SAS_HDD_TX9_P")
	)
	(arc
		(start 109.225842 -107.487466)
		(mid 109.235475 -107.438948)
		(end 109.262926 -107.397804)
		(width 0.1016)
		(layer "F.Cu")
		(net "SAS_HDD_TX9_P")
	)
	(arc
		(start 105.823004 -113.655094)
		(mid 105.795571 -113.613943)
		(end 105.78592 -113.565432)
		(width 0.1016)
		(layer "F.Cu")
		(net "SAS_HDD_TX9_P")
	)
	(segment
		(start 110.750096 -56.599836)
		(end 110.750096 -58.16473)
		(width 0.1143)
		(layer "F.Cu")
		(net "XM_ADDR_3")
	)
	(segment
		(start 147.599146 -42.7101)
		(end 147.599146 -43.713146)
		(width 0.1143)
		(layer "F.Cu")
		(net "XM_ADDR_3")
	)
	(segment
		(start 147.599146 -43.713146)
		(end 149.1615 -45.2755)
		(width 0.1143)
		(layer "F.Cu")
		(net "XM_ADDR_3")
	)
	(segment
		(start 110.289086 -59.048396)
		(end 110.289086 -58.88228)
		(width 0.1143)
		(layer "F.Cu")
		(net "XM_ADDR_3")
	)
	(segment
		(start 110.289086 -58.88228)
		(end 110.878366 -58.293)
		(width 0.1143)
		(layer "F.Cu")
		(net "XM_ADDR_3")
	)
	(segment
		(start 149.1615 -45.2755)
		(end 149.1615 -51.4223)
		(width 0.1143)
		(layer "F.Cu")
		(net "XM_ADDR_3")
	)
	(segment
		(start 149.1615 -51.4223)
		(end 149.14245 -51.44135)
		(width 0.1143)
		(layer "F.Cu")
		(net "XM_ADDR_3")
	)
	(segment
		(start 110.750096 -58.16473)
		(end 110.878366 -58.293)
		(width 0.1143)
		(layer "F.Cu")
		(net "XM_ADDR_3")
	)
	(via
		(at 110.878366 -58.293)
		(size 0.508)
		(drill 0.254)
		(layers "F.Cu" "B.Cu")
		(net "XM_ADDR_3")
	)
	(via
		(at 149.14245 -51.44135)
		(size 0.5588)
		(drill 0.3048)
		(layers "F.Cu" "B.Cu")
		(net "XM_ADDR_3")
	)
	(via
		(at 110.289086 -59.048396)
		(size 0.7112)
		(drill 0.3556)
		(layers "F.Cu" "B.Cu")
		(net "XM_ADDR_3")
	)
	(segment
		(start 147.001992 -54.56682)
		(end 146.82216 -54.56682)
		(width 0.127)
		(layer "In5.Cu")
		(net "XM_ADDR_3")
	)
	(segment
		(start 148.8821 -53.204872)
		(end 148.069808 -54.017164)
		(width 0.127)
		(layer "In5.Cu")
		(net "XM_ADDR_3")
	)
	(segment
		(start 148.8821 -51.7017)
		(end 148.8821 -53.204872)
		(width 0.127)
		(layer "In5.Cu")
		(net "XM_ADDR_3")
	)
	(segment
		(start 147.530566 -54.556406)
		(end 147.350988 -54.735984)
		(width 0.127)
		(layer "In5.Cu")
		(net "XM_ADDR_3")
	)
	(segment
		(start 146.811746 -55.095394)
		(end 146.811746 -55.275226)
		(width 0.127)
		(layer "In5.Cu")
		(net "XM_ADDR_3")
	)
	(segment
		(start 149.14245 -51.44135)
		(end 148.8821 -51.7017)
		(width 0.127)
		(layer "In5.Cu")
		(net "XM_ADDR_3")
	)
	(segment
		(start 116.74729 -59.0423)
		(end 114.040666 -59.0423)
		(width 0.127)
		(layer "In5.Cu")
		(net "XM_ADDR_3")
	)
	(segment
		(start 147.720812 -53.848)
		(end 147.54098 -53.848)
		(width 0.127)
		(layer "In5.Cu")
		(net "XM_ADDR_3")
	)
	(segment
		(start 138.526774 -56.299862)
		(end 137.99693 -56.829706)
		(width 0.127)
		(layer "In5.Cu")
		(net "XM_ADDR_3")
	)
	(segment
		(start 147.54098 -53.848)
		(end 147.361402 -54.027578)
		(width 0.127)
		(layer "In5.Cu")
		(net "XM_ADDR_3")
	)
	(segment
		(start 112.540288 -57.9247)
		(end 111.246666 -57.9247)
		(width 0.127)
		(layer "In5.Cu")
		(net "XM_ADDR_3")
	)
	(segment
		(start 146.10334 -55.28564)
		(end 145.923762 -55.465218)
		(width 0.127)
		(layer "In5.Cu")
		(net "XM_ADDR_3")
	)
	(segment
		(start 146.632168 -55.454804)
		(end 146.452336 -55.454804)
		(width 0.127)
		(layer "In5.Cu")
		(net "XM_ADDR_3")
	)
	(segment
		(start 147.350988 -54.735984)
		(end 147.171156 -54.735984)
		(width 0.127)
		(layer "In5.Cu")
		(net "XM_ADDR_3")
	)
	(segment
		(start 148.069808 -54.017164)
		(end 147.889976 -54.017164)
		(width 0.127)
		(layer "In5.Cu")
		(net "XM_ADDR_3")
	)
	(segment
		(start 137.99693 -56.829706)
		(end 126.340108 -56.829706)
		(width 0.127)
		(layer "In5.Cu")
		(net "XM_ADDR_3")
	)
	(segment
		(start 146.811746 -55.275226)
		(end 146.632168 -55.454804)
		(width 0.127)
		(layer "In5.Cu")
		(net "XM_ADDR_3")
	)
	(segment
		(start 146.642582 -54.92623)
		(end 146.811746 -55.095394)
		(width 0.127)
		(layer "In5.Cu")
		(net "XM_ADDR_3")
	)
	(segment
		(start 146.092926 -55.814214)
		(end 146.092926 -55.994046)
		(width 0.127)
		(layer "In5.Cu")
		(net "XM_ADDR_3")
	)
	(segment
		(start 146.092926 -55.994046)
		(end 145.78711 -56.299862)
		(width 0.127)
		(layer "In5.Cu")
		(net "XM_ADDR_3")
	)
	(segment
		(start 147.361402 -54.20741)
		(end 147.530566 -54.376574)
		(width 0.127)
		(layer "In5.Cu")
		(net "XM_ADDR_3")
	)
	(segment
		(start 146.642582 -54.746398)
		(end 146.642582 -54.92623)
		(width 0.127)
		(layer "In5.Cu")
		(net "XM_ADDR_3")
	)
	(segment
		(start 114.040666 -59.0423)
		(end 113.088166 -58.0898)
		(width 0.127)
		(layer "In5.Cu")
		(net "XM_ADDR_3")
	)
	(segment
		(start 147.530566 -54.376574)
		(end 147.530566 -54.556406)
		(width 0.127)
		(layer "In5.Cu")
		(net "XM_ADDR_3")
	)
	(segment
		(start 145.923762 -55.465218)
		(end 145.923762 -55.64505)
		(width 0.127)
		(layer "In5.Cu")
		(net "XM_ADDR_3")
	)
	(segment
		(start 146.82216 -54.56682)
		(end 146.642582 -54.746398)
		(width 0.127)
		(layer "In5.Cu")
		(net "XM_ADDR_3")
	)
	(segment
		(start 147.361402 -54.027578)
		(end 147.361402 -54.20741)
		(width 0.127)
		(layer "In5.Cu")
		(net "XM_ADDR_3")
	)
	(segment
		(start 117.859302 -57.930288)
		(end 116.74729 -59.0423)
		(width 0.127)
		(layer "In5.Cu")
		(net "XM_ADDR_3")
	)
	(segment
		(start 145.78711 -56.299862)
		(end 138.526774 -56.299862)
		(width 0.127)
		(layer "In5.Cu")
		(net "XM_ADDR_3")
	)
	(segment
		(start 147.171156 -54.735984)
		(end 147.001992 -54.56682)
		(width 0.127)
		(layer "In5.Cu")
		(net "XM_ADDR_3")
	)
	(segment
		(start 147.889976 -54.017164)
		(end 147.720812 -53.848)
		(width 0.127)
		(layer "In5.Cu")
		(net "XM_ADDR_3")
	)
	(segment
		(start 113.088166 -58.0898)
		(end 112.705388 -58.0898)
		(width 0.127)
		(layer "In5.Cu")
		(net "XM_ADDR_3")
	)
	(segment
		(start 145.923762 -55.64505)
		(end 146.092926 -55.814214)
		(width 0.127)
		(layer "In5.Cu")
		(net "XM_ADDR_3")
	)
	(segment
		(start 111.246666 -57.9247)
		(end 110.878366 -58.293)
		(width 0.127)
		(layer "In5.Cu")
		(net "XM_ADDR_3")
	)
	(segment
		(start 112.705388 -58.0898)
		(end 112.540288 -57.9247)
		(width 0.127)
		(layer "In5.Cu")
		(net "XM_ADDR_3")
	)
	(segment
		(start 146.283172 -55.28564)
		(end 146.10334 -55.28564)
		(width 0.127)
		(layer "In5.Cu")
		(net "XM_ADDR_3")
	)
	(segment
		(start 126.340108 -56.829706)
		(end 125.239526 -57.930288)
		(width 0.127)
		(layer "In5.Cu")
		(net "XM_ADDR_3")
	)
	(segment
		(start 146.452336 -55.454804)
		(end 146.283172 -55.28564)
		(width 0.127)
		(layer "In5.Cu")
		(net "XM_ADDR_3")
	)
	(segment
		(start 125.239526 -57.930288)
		(end 117.859302 -57.930288)
		(width 0.127)
		(layer "In5.Cu")
		(net "XM_ADDR_3")
	)
	(segment
		(start 201.896218 -114.823748)
		(end 202.6285 -115.55603)
		(width 0.3048)
		(layer "F.Cu")
		(net "P1V5_E_VCC")
	)
	(segment
		(start 203.2 -116.332)
		(end 203.727812 -116.859812)
		(width 0.508)
		(layer "F.Cu")
		(net "P1V5_E_VCC")
	)
	(segment
		(start 201.37882 -114.823748)
		(end 201.896218 -114.823748)
		(width 0.3048)
		(layer "F.Cu")
		(net "P1V5_E_VCC")
	)
	(segment
		(start 203.727812 -116.859812)
		(end 204.793596 -116.859812)
		(width 0.508)
		(layer "F.Cu")
		(net "P1V5_E_VCC")
	)
	(segment
		(start 204.793596 -116.859812)
		(end 204.793596 -118.129812)
		(width 0.508)
		(layer "F.Cu")
		(net "P1V5_E_VCC")
	)
	(segment
		(start 202.6285 -115.7605)
		(end 203.2 -116.332)
		(width 0.508)
		(layer "F.Cu")
		(net "P1V5_E_VCC")
	)
	(segment
		(start 202.6285 -115.55603)
		(end 202.6285 -115.7605)
		(width 0.3048)
		(layer "F.Cu")
		(net "P1V5_E_VCC")
	)
	(via
		(at 203.2 -116.332)
		(size 0.7112)
		(drill 0.3556)
		(layers "F.Cu" "B.Cu")
		(net "P1V5_E_VCC")
	)
	(segment
		(start 57.397142 -129.392172)
		(end 57.46877 -129.4638)
		(width 0.1143)
		(layer "F.Cu")
		(net "EXP_XM_ADDR_6")
	)
	(segment
		(start 57.46877 -129.4638)
		(end 59.62777 -129.4638)
		(width 0.1143)
		(layer "F.Cu")
		(net "EXP_XM_ADDR_6")
	)
	(segment
		(start 56.558942 -129.392172)
		(end 57.397142 -129.392172)
		(width 0.1143)
		(layer "F.Cu")
		(net "EXP_XM_ADDR_6")
	)
	(segment
		(start 108.349796 -93.349826)
		(end 107.84967 -92.8497)
		(width 0.1143)
		(layer "F.Cu")
		(net "EXP_XM_ADDR_6")
	)
	(via
		(at 107.84967 -92.8497)
		(size 0.508)
		(drill 0.254)
		(layers "F.Cu" "B.Cu")
		(net "EXP_XM_ADDR_6")
	)
	(via
		(at 59.62777 -129.4638)
		(size 0.5588)
		(drill 0.3048)
		(layers "F.Cu" "B.Cu")
		(net "EXP_XM_ADDR_6")
	)
	(via
		(at 58.7248 -129.4892)
		(size 0.7112)
		(drill 0.3556)
		(layers "F.Cu" "B.Cu")
		(net "EXP_XM_ADDR_6")
	)
	(segment
		(start 58.7248 -129.4892)
		(end 59.3344 -129.4892)
		(width 0.1143)
		(layer "B.Cu")
		(net "EXP_XM_ADDR_6")
	)
	(segment
		(start 59.3344 -129.4892)
		(end 59.3598 -129.4638)
		(width 0.1143)
		(layer "B.Cu")
		(net "EXP_XM_ADDR_6")
	)
	(segment
		(start 59.3598 -129.4638)
		(end 59.62777 -129.4638)
		(width 0.1143)
		(layer "B.Cu")
		(net "EXP_XM_ADDR_6")
	)
	(segment
		(start 59.82081 -116.755672)
		(end 59.82081 -129.27076)
		(width 0.127)
		(layer "In2.Cu")
		(net "EXP_XM_ADDR_6")
	)
	(segment
		(start 75.6285 -98.265742)
		(end 76.880212 -99.5172)
		(width 0.127)
		(layer "In2.Cu")
		(net "EXP_XM_ADDR_6")
	)
	(segment
		(start 77.83195 -98.564446)
		(end 77.83195 -98.744786)
		(width 0.127)
		(layer "In2.Cu")
		(net "EXP_XM_ADDR_6")
	)
	(segment
		(start 106.837734 -91.430602)
		(end 106.22407 -90.816938)
		(width 0.127)
		(layer "In2.Cu")
		(net "EXP_XM_ADDR_6")
	)
	(segment
		(start 107.84967 -92.8497)
		(end 107.268772 -92.268802)
		(width 0.127)
		(layer "In2.Cu")
		(net "EXP_XM_ADDR_6")
	)
	(segment
		(start 80.6704 -95.289624)
		(end 80.4164 -95.289624)
		(width 0.127)
		(layer "In2.Cu")
		(net "EXP_XM_ADDR_6")
	)
	(segment
		(start 104.998012 -89.405206)
		(end 104.357424 -89.405206)
		(width 0.127)
		(layer "In2.Cu")
		(net "EXP_XM_ADDR_6")
	)
	(segment
		(start 80.4164 -95.289624)
		(end 80.2894 -95.162624)
		(width 0.127)
		(layer "In2.Cu")
		(net "EXP_XM_ADDR_6")
	)
	(segment
		(start 75.808586 -97.906332)
		(end 75.6285 -98.086418)
		(width 0.127)
		(layer "In2.Cu")
		(net "EXP_XM_ADDR_6")
	)
	(segment
		(start 104.128824 -89.176606)
		(end 102.433628 -89.176606)
		(width 0.127)
		(layer "In2.Cu")
		(net "EXP_XM_ADDR_6")
	)
	(segment
		(start 101.559106 -88.302084)
		(end 101.021134 -88.302084)
		(width 0.127)
		(layer "In2.Cu")
		(net "EXP_XM_ADDR_6")
	)
	(segment
		(start 85.15858 -91.418156)
		(end 82.025236 -94.5515)
		(width 0.127)
		(layer "In2.Cu")
		(net "EXP_XM_ADDR_6")
	)
	(segment
		(start 106.22407 -90.631264)
		(end 105.978706 -90.3859)
		(width 0.127)
		(layer "In2.Cu")
		(net "EXP_XM_ADDR_6")
	)
	(segment
		(start 79.28864 -94.5515)
		(end 76.643738 -97.196402)
		(width 0.127)
		(layer "In2.Cu")
		(net "EXP_XM_ADDR_6")
	)
	(segment
		(start 107.268772 -91.675966)
		(end 107.023408 -91.430602)
		(width 0.127)
		(layer "In2.Cu")
		(net "EXP_XM_ADDR_6")
	)
	(segment
		(start 105.793032 -90.3859)
		(end 105.268776 -89.861644)
		(width 0.127)
		(layer "In2.Cu")
		(net "EXP_XM_ADDR_6")
	)
	(segment
		(start 80.9244 -94.5515)
		(end 80.7974 -94.6785)
		(width 0.127)
		(layer "In2.Cu")
		(net "EXP_XM_ADDR_6")
	)
	(segment
		(start 80.2894 -94.6785)
		(end 80.1624 -94.5515)
		(width 0.127)
		(layer "In2.Cu")
		(net "EXP_XM_ADDR_6")
	)
	(segment
		(start 85.57514 -91.418156)
		(end 85.15858 -91.418156)
		(width 0.127)
		(layer "In2.Cu")
		(net "EXP_XM_ADDR_6")
	)
	(segment
		(start 107.268772 -92.268802)
		(end 107.268772 -91.675966)
		(width 0.127)
		(layer "In2.Cu")
		(net "EXP_XM_ADDR_6")
	)
	(segment
		(start 104.357424 -89.405206)
		(end 104.128824 -89.176606)
		(width 0.127)
		(layer "In2.Cu")
		(net "EXP_XM_ADDR_6")
	)
	(segment
		(start 59.82081 -129.27076)
		(end 59.62777 -129.4638)
		(width 0.127)
		(layer "In2.Cu")
		(net "EXP_XM_ADDR_6")
	)
	(segment
		(start 88.219788 -88.773508)
		(end 85.57514 -91.418156)
		(width 0.127)
		(layer "In2.Cu")
		(net "EXP_XM_ADDR_6")
	)
	(segment
		(start 101.021134 -88.302084)
		(end 100.55987 -87.84082)
		(width 0.127)
		(layer "In2.Cu")
		(net "EXP_XM_ADDR_6")
	)
	(segment
		(start 80.7974 -95.162624)
		(end 80.6704 -95.289624)
		(width 0.127)
		(layer "In2.Cu")
		(net "EXP_XM_ADDR_6")
	)
	(segment
		(start 105.268776 -89.861644)
		(end 105.268776 -89.67597)
		(width 0.127)
		(layer "In2.Cu")
		(net "EXP_XM_ADDR_6")
	)
	(segment
		(start 107.023408 -91.430602)
		(end 106.837734 -91.430602)
		(width 0.127)
		(layer "In2.Cu")
		(net "EXP_XM_ADDR_6")
	)
	(segment
		(start 82.025236 -94.5515)
		(end 80.9244 -94.5515)
		(width 0.127)
		(layer "In2.Cu")
		(net "EXP_XM_ADDR_6")
	)
	(segment
		(start 90.634312 -87.0077)
		(end 88.868504 -88.773508)
		(width 0.127)
		(layer "In2.Cu")
		(net "EXP_XM_ADDR_6")
	)
	(segment
		(start 105.978706 -90.3859)
		(end 105.793032 -90.3859)
		(width 0.127)
		(layer "In2.Cu")
		(net "EXP_XM_ADDR_6")
	)
	(segment
		(start 76.880212 -99.5172)
		(end 76.880212 -99.696524)
		(width 0.127)
		(layer "In2.Cu")
		(net "EXP_XM_ADDR_6")
	)
	(segment
		(start 88.868504 -88.773508)
		(end 88.219788 -88.773508)
		(width 0.127)
		(layer "In2.Cu")
		(net "EXP_XM_ADDR_6")
	)
	(segment
		(start 80.1624 -94.5515)
		(end 79.28864 -94.5515)
		(width 0.127)
		(layer "In2.Cu")
		(net "EXP_XM_ADDR_6")
	)
	(segment
		(start 74.723752 -101.852984)
		(end 59.82081 -116.755672)
		(width 0.127)
		(layer "In2.Cu")
		(net "EXP_XM_ADDR_6")
	)
	(segment
		(start 80.7974 -94.6785)
		(end 80.7974 -95.162624)
		(width 0.127)
		(layer "In2.Cu")
		(net "EXP_XM_ADDR_6")
	)
	(segment
		(start 102.433628 -89.176606)
		(end 101.559106 -88.302084)
		(width 0.127)
		(layer "In2.Cu")
		(net "EXP_XM_ADDR_6")
	)
	(segment
		(start 77.239622 -99.15779)
		(end 75.98791 -97.906332)
		(width 0.127)
		(layer "In2.Cu")
		(net "EXP_XM_ADDR_6")
	)
	(segment
		(start 99.9617 -87.0077)
		(end 90.634312 -87.0077)
		(width 0.127)
		(layer "In2.Cu")
		(net "EXP_XM_ADDR_6")
	)
	(segment
		(start 105.268776 -89.67597)
		(end 104.998012 -89.405206)
		(width 0.127)
		(layer "In2.Cu")
		(net "EXP_XM_ADDR_6")
	)
	(segment
		(start 75.98791 -97.906332)
		(end 75.808586 -97.906332)
		(width 0.127)
		(layer "In2.Cu")
		(net "EXP_XM_ADDR_6")
	)
	(segment
		(start 76.643738 -97.196402)
		(end 76.643738 -97.376234)
		(width 0.127)
		(layer "In2.Cu")
		(net "EXP_XM_ADDR_6")
	)
	(segment
		(start 80.2894 -95.162624)
		(end 80.2894 -94.6785)
		(width 0.127)
		(layer "In2.Cu")
		(net "EXP_XM_ADDR_6")
	)
	(segment
		(start 77.418946 -99.15779)
		(end 77.239622 -99.15779)
		(width 0.127)
		(layer "In2.Cu")
		(net "EXP_XM_ADDR_6")
	)
	(segment
		(start 75.6285 -98.086418)
		(end 75.6285 -98.265742)
		(width 0.127)
		(layer "In2.Cu")
		(net "EXP_XM_ADDR_6")
	)
	(segment
		(start 106.22407 -90.816938)
		(end 106.22407 -90.631264)
		(width 0.127)
		(layer "In2.Cu")
		(net "EXP_XM_ADDR_6")
	)
	(segment
		(start 76.880212 -99.696524)
		(end 74.723752 -101.852984)
		(width 0.127)
		(layer "In2.Cu")
		(net "EXP_XM_ADDR_6")
	)
	(segment
		(start 100.55987 -87.60587)
		(end 99.9617 -87.0077)
		(width 0.127)
		(layer "In2.Cu")
		(net "EXP_XM_ADDR_6")
	)
	(segment
		(start 76.643738 -97.376234)
		(end 77.83195 -98.564446)
		(width 0.127)
		(layer "In2.Cu")
		(net "EXP_XM_ADDR_6")
	)
	(segment
		(start 77.83195 -98.744786)
		(end 77.418946 -99.15779)
		(width 0.127)
		(layer "In2.Cu")
		(net "EXP_XM_ADDR_6")
	)
	(segment
		(start 100.55987 -87.84082)
		(end 100.55987 -87.60587)
		(width 0.127)
		(layer "In2.Cu")
		(net "EXP_XM_ADDR_6")
	)
	(segment
		(start 108.617004 -111.26724)
		(end 109.313726 -110.570518)
		(width 0.1016)
		(layer "F.Cu")
		(net "SAS_HDD_TX8_N")
	)
	(segment
		(start 109.62513 -109.819186)
		(end 109.62513 -108.71454)
		(width 0.1016)
		(layer "F.Cu")
		(net "SAS_HDD_TX8_N")
	)
	(segment
		(start 109.730794 -106.909108)
		(end 109.733842 -106.90606)
		(width 0.1016)
		(layer "F.Cu")
		(net "SAS_HDD_TX8_N")
	)
	(segment
		(start 109.733842 -106.90606)
		(end 109.733842 -106.3117)
		(width 0.1016)
		(layer "F.Cu")
		(net "SAS_HDD_TX8_N")
	)
	(segment
		(start 107.07497 -114.0206)
		(end 107.07497 -113.98758)
		(width 0.1016)
		(layer "F.Cu")
		(net "SAS_HDD_TX8_N")
	)
	(segment
		(start 107.66425 -112.222534)
		(end 108.544106 -111.342678)
		(width 0.1016)
		(layer "F.Cu")
		(net "SAS_HDD_TX8_N")
	)
	(segment
		(start 108.612178 -111.27232)
		(end 108.614464 -111.26978)
		(width 0.1016)
		(layer "F.Cu")
		(net "SAS_HDD_TX8_N")
	)
	(segment
		(start 107.098338 -113.931192)
		(end 107.202986 -113.826544)
		(width 0.1016)
		(layer "F.Cu")
		(net "SAS_HDD_TX8_N")
	)
	(segment
		(start 109.730794 -107.872784)
		(end 109.730794 -106.909108)
		(width 0.1016)
		(layer "F.Cu")
		(net "SAS_HDD_TX8_N")
	)
	(segment
		(start 109.97819 -105.721404)
		(end 110.349792 -105.350056)
		(width 0.1016)
		(layer "F.Cu")
		(net "SAS_HDD_TX8_N")
	)
	(segment
		(start 107.24007 -113.736882)
		(end 107.24007 -113.246662)
		(width 0.1016)
		(layer "F.Cu")
		(net "SAS_HDD_TX8_N")
	)
	(arc
		(start 107.07497 -113.98758)
		(mid 107.081041 -113.957059)
		(end 107.098338 -113.931192)
		(width 0.1016)
		(layer "F.Cu")
		(net "SAS_HDD_TX8_N")
	)
	(arc
		(start 108.614464 -111.26978)
		(mid 108.615723 -111.268499)
		(end 108.617004 -111.26724)
		(width 0.1016)
		(layer "F.Cu")
		(net "SAS_HDD_TX8_N")
	)
	(arc
		(start 109.62513 -108.71454)
		(mid 109.636534 -108.513101)
		(end 109.670596 -108.314236)
		(width 0.1016)
		(layer "F.Cu")
		(net "SAS_HDD_TX8_N")
	)
	(arc
		(start 109.670596 -108.314236)
		(mid 109.715656 -108.095551)
		(end 109.730794 -107.872784)
		(width 0.1016)
		(layer "F.Cu")
		(net "SAS_HDD_TX8_N")
	)
	(arc
		(start 109.313726 -110.570518)
		(mid 109.54411 -110.225818)
		(end 109.62513 -109.819186)
		(width 0.1016)
		(layer "F.Cu")
		(net "SAS_HDD_TX8_N")
	)
	(arc
		(start 107.202986 -113.826544)
		(mid 107.230419 -113.785393)
		(end 107.24007 -113.736882)
		(width 0.1016)
		(layer "F.Cu")
		(net "SAS_HDD_TX8_N")
	)
	(arc
		(start 107.24007 -113.246662)
		(mid 107.350301 -112.692404)
		(end 107.66425 -112.222534)
		(width 0.1016)
		(layer "F.Cu")
		(net "SAS_HDD_TX8_N")
	)
	(arc
		(start 109.733842 -106.3117)
		(mid 109.797293 -105.992242)
		(end 109.97819 -105.721404)
		(width 0.1016)
		(layer "F.Cu")
		(net "SAS_HDD_TX8_N")
	)
	(arc
		(start 108.544106 -111.342678)
		(mid 108.560032 -111.326599)
		(end 108.575856 -111.31042)
		(width 0.1016)
		(layer "F.Cu")
		(net "SAS_HDD_TX8_N")
	)
	(arc
		(start 108.575856 -111.31042)
		(mid 108.594086 -111.291436)
		(end 108.612178 -111.27232)
		(width 0.1016)
		(layer "F.Cu")
		(net "SAS_HDD_TX8_N")
	)
	(segment
		(start 112.350042 -54.19979)
		(end 112.749838 -53.799994)
		(width 0.1143)
		(layer "F.Cu")
		(net "XM_ADDR_9")
	)
	(segment
		(start 142.596362 -48.75784)
		(end 142.596362 -49.015396)
		(width 0.1143)
		(layer "F.Cu")
		(net "XM_ADDR_9")
	)
	(segment
		(start 140.098526 -41.003474)
		(end 140.098526 -42.7101)
		(width 0.1143)
		(layer "F.Cu")
		(net "XM_ADDR_9")
	)
	(segment
		(start 142.335758 -49.276)
		(end 142.113 -49.276)
		(width 0.1143)
		(layer "F.Cu")
		(net "XM_ADDR_9")
	)
	(segment
		(start 142.09903 -48.422052)
		(end 142.260574 -48.422052)
		(width 0.1143)
		(layer "F.Cu")
		(net "XM_ADDR_9")
	)
	(segment
		(start 140.208 -40.894)
		(end 140.098526 -41.003474)
		(width 0.1143)
		(layer "F.Cu")
		(net "XM_ADDR_9")
	)
	(segment
		(start 141.49705 -48.862488)
		(end 141.658594 -48.862488)
		(width 0.1143)
		(layer "F.Cu")
		(net "XM_ADDR_9")
	)
	(segment
		(start 141.1732 -47.334678)
		(end 141.775688 -47.937166)
		(width 0.1143)
		(layer "F.Cu")
		(net "XM_ADDR_9")
	)
	(segment
		(start 142.260574 -48.422052)
		(end 142.596362 -48.75784)
		(width 0.1143)
		(layer "F.Cu")
		(net "XM_ADDR_9")
	)
	(segment
		(start 141.775688 -48.09871)
		(end 141.335252 -48.539146)
		(width 0.1143)
		(layer "F.Cu")
		(net "XM_ADDR_9")
	)
	(segment
		(start 141.1732 -46.769528)
		(end 141.1732 -47.334678)
		(width 0.1143)
		(layer "F.Cu")
		(net "XM_ADDR_9")
	)
	(segment
		(start 142.596362 -49.015396)
		(end 142.335758 -49.276)
		(width 0.1143)
		(layer "F.Cu")
		(net "XM_ADDR_9")
	)
	(segment
		(start 141.775688 -47.937166)
		(end 141.775688 -48.09871)
		(width 0.1143)
		(layer "F.Cu")
		(net "XM_ADDR_9")
	)
	(segment
		(start 141.335252 -48.70069)
		(end 141.49705 -48.862488)
		(width 0.1143)
		(layer "F.Cu")
		(net "XM_ADDR_9")
	)
	(segment
		(start 141.658594 -48.862488)
		(end 142.09903 -48.422052)
		(width 0.1143)
		(layer "F.Cu")
		(net "XM_ADDR_9")
	)
	(segment
		(start 140.098526 -42.7101)
		(end 140.098526 -45.694854)
		(width 0.1143)
		(layer "F.Cu")
		(net "XM_ADDR_9")
	)
	(segment
		(start 140.098526 -45.694854)
		(end 141.1732 -46.769528)
		(width 0.1143)
		(layer "F.Cu")
		(net "XM_ADDR_9")
	)
	(segment
		(start 141.335252 -48.539146)
		(end 141.335252 -48.70069)
		(width 0.1143)
		(layer "F.Cu")
		(net "XM_ADDR_9")
	)
	(via
		(at 140.208 -40.894)
		(size 0.7112)
		(drill 0.3556)
		(layers "F.Cu" "B.Cu")
		(net "XM_ADDR_9")
	)
	(via
		(at 112.749838 -53.799994)
		(size 0.508)
		(drill 0.254)
		(layers "F.Cu" "B.Cu")
		(net "XM_ADDR_9")
	)
	(via
		(at 142.113 -49.276)
		(size 0.5588)
		(drill 0.3048)
		(layers "F.Cu" "B.Cu")
		(net "XM_ADDR_9")
	)
	(segment
		(start 116.148612 -53.819044)
		(end 114.201956 -53.819044)
		(width 0.127)
		(layer "In5.Cu")
		(net "XM_ADDR_9")
	)
	(segment
		(start 113.424462 -53.802026)
		(end 112.75187 -53.802026)
		(width 0.127)
		(layer "In5.Cu")
		(net "XM_ADDR_9")
	)
	(segment
		(start 116.967 -53.467)
		(end 116.631974 -53.802026)
		(width 0.127)
		(layer "In5.Cu")
		(net "XM_ADDR_9")
	)
	(segment
		(start 109.504988 -54.97322)
		(end 109.377988 -54.84622)
		(width 0.127)
		(layer "In5.Cu")
		(net "XM_ADDR_9")
	)
	(segment
		(start 131.853432 -51.764438)
		(end 125.296676 -51.764438)
		(width 0.127)
		(layer "In5.Cu")
		(net "XM_ADDR_9")
	)
	(segment
		(start 114.201956 -53.819044)
		(end 114.074956 -53.946044)
		(width 0.127)
		(layer "In5.Cu")
		(net "XM_ADDR_9")
	)
	(segment
		(start 109.377988 -54.84622)
		(end 109.377988 -54.59222)
		(width 0.127)
		(layer "In5.Cu")
		(net "XM_ADDR_9")
	)
	(segment
		(start 111.754158 -55.98922)
		(end 111.627158 -55.86222)
		(width 0.127)
		(layer "In5.Cu")
		(net "XM_ADDR_9")
	)
	(segment
		(start 113.551462 -54.227476)
		(end 113.551462 -53.929026)
		(width 0.127)
		(layer "In5.Cu")
		(net "XM_ADDR_9")
	)
	(segment
		(start 113.313718 -54.46522)
		(end 113.551462 -54.227476)
		(width 0.127)
		(layer "In5.Cu")
		(net "XM_ADDR_9")
	)
	(segment
		(start 112.266222 -54.97322)
		(end 112.139222 -55.10022)
		(width 0.127)
		(layer "In5.Cu")
		(net "XM_ADDR_9")
	)
	(segment
		(start 114.074956 -53.946044)
		(end 114.074956 -54.464204)
		(width 0.127)
		(layer "In5.Cu")
		(net "XM_ADDR_9")
	)
	(segment
		(start 112.139222 -55.35422)
		(end 112.266222 -55.48122)
		(width 0.127)
		(layer "In5.Cu")
		(net "XM_ADDR_9")
	)
	(segment
		(start 111.627158 -55.86222)
		(end 111.627158 -55.10022)
		(width 0.127)
		(layer "In5.Cu")
		(net "XM_ADDR_9")
	)
	(segment
		(start 109.377988 -54.59222)
		(end 109.504988 -54.46522)
		(width 0.127)
		(layer "In5.Cu")
		(net "XM_ADDR_9")
	)
	(segment
		(start 113.43894 -55.98922)
		(end 111.754158 -55.98922)
		(width 0.127)
		(layer "In5.Cu")
		(net "XM_ADDR_9")
	)
	(segment
		(start 114.074956 -54.464204)
		(end 113.56594 -54.97322)
		(width 0.127)
		(layer "In5.Cu")
		(net "XM_ADDR_9")
	)
	(segment
		(start 141.74343 -48.6029)
		(end 135.01497 -48.6029)
		(width 0.127)
		(layer "In5.Cu")
		(net "XM_ADDR_9")
	)
	(segment
		(start 111.627158 -55.10022)
		(end 111.500158 -54.97322)
		(width 0.127)
		(layer "In5.Cu")
		(net "XM_ADDR_9")
	)
	(segment
		(start 113.43894 -55.48122)
		(end 113.56594 -55.60822)
		(width 0.127)
		(layer "In5.Cu")
		(net "XM_ADDR_9")
	)
	(segment
		(start 113.551462 -53.929026)
		(end 113.424462 -53.802026)
		(width 0.127)
		(layer "In5.Cu")
		(net "XM_ADDR_9")
	)
	(segment
		(start 142.113 -48.97247)
		(end 141.74343 -48.6029)
		(width 0.127)
		(layer "In5.Cu")
		(net "XM_ADDR_9")
	)
	(segment
		(start 112.75187 -53.802026)
		(end 112.749838 -53.799994)
		(width 0.127)
		(layer "In5.Cu")
		(net "XM_ADDR_9")
	)
	(segment
		(start 111.500158 -54.97322)
		(end 109.504988 -54.97322)
		(width 0.127)
		(layer "In5.Cu")
		(net "XM_ADDR_9")
	)
	(segment
		(start 112.139222 -55.10022)
		(end 112.139222 -55.35422)
		(width 0.127)
		(layer "In5.Cu")
		(net "XM_ADDR_9")
	)
	(segment
		(start 113.56594 -55.86222)
		(end 113.43894 -55.98922)
		(width 0.127)
		(layer "In5.Cu")
		(net "XM_ADDR_9")
	)
	(segment
		(start 109.504988 -54.46522)
		(end 113.313718 -54.46522)
		(width 0.127)
		(layer "In5.Cu")
		(net "XM_ADDR_9")
	)
	(segment
		(start 116.16563 -53.802026)
		(end 116.148612 -53.819044)
		(width 0.127)
		(layer "In5.Cu")
		(net "XM_ADDR_9")
	)
	(segment
		(start 142.113 -49.276)
		(end 142.113 -48.97247)
		(width 0.127)
		(layer "In5.Cu")
		(net "XM_ADDR_9")
	)
	(segment
		(start 113.56594 -54.97322)
		(end 112.266222 -54.97322)
		(width 0.127)
		(layer "In5.Cu")
		(net "XM_ADDR_9")
	)
	(segment
		(start 112.266222 -55.48122)
		(end 113.43894 -55.48122)
		(width 0.127)
		(layer "In5.Cu")
		(net "XM_ADDR_9")
	)
	(segment
		(start 125.296676 -51.764438)
		(end 123.594114 -53.467)
		(width 0.127)
		(layer "In5.Cu")
		(net "XM_ADDR_9")
	)
	(segment
		(start 113.56594 -55.60822)
		(end 113.56594 -55.86222)
		(width 0.127)
		(layer "In5.Cu")
		(net "XM_ADDR_9")
	)
	(segment
		(start 135.01497 -48.6029)
		(end 131.853432 -51.764438)
		(width 0.127)
		(layer "In5.Cu")
		(net "XM_ADDR_9")
	)
	(segment
		(start 123.594114 -53.467)
		(end 116.967 -53.467)
		(width 0.127)
		(layer "In5.Cu")
		(net "XM_ADDR_9")
	)
	(segment
		(start 116.631974 -53.802026)
		(end 116.16563 -53.802026)
		(width 0.127)
		(layer "In5.Cu")
		(net "XM_ADDR_9")
	)
	(segment
		(start 197.596252 -114.823748)
		(end 196.85 -115.57)
		(width 0.254)
		(layer "F.Cu")
		(net "P1V5_E_EN_R")
	)
	(segment
		(start 196.6595 -115.7605)
		(end 196.85 -115.57)
		(width 0.254)
		(layer "F.Cu")
		(net "P1V5_E_EN_R")
	)
	(segment
		(start 193.802 -115.7605)
		(end 194.818 -115.7605)
		(width 0.254)
		(layer "F.Cu")
		(net "P1V5_E_EN_R")
	)
	(segment
		(start 198.302372 -114.823748)
		(end 197.596252 -114.823748)
		(width 0.254)
		(layer "F.Cu")
		(net "P1V5_E_EN_R")
	)
	(segment
		(start 194.818 -115.7605)
		(end 195.834 -115.7605)
		(width 0.254)
		(layer "F.Cu")
		(net "P1V5_E_EN_R")
	)
	(segment
		(start 195.834 -115.7605)
		(end 196.6595 -115.7605)
		(width 0.254)
		(layer "F.Cu")
		(net "P1V5_E_EN_R")
	)
	(via
		(at 196.85 -115.57)
		(size 0.7112)
		(drill 0.3556)
		(layers "F.Cu" "B.Cu")
		(net "P1V5_E_EN_R")
	)
	(segment
		(start 61.21908 -142.33017)
		(end 61.59119 -142.70228)
		(width 0.1143)
		(layer "F.Cu")
		(net "EXP_XM_ADDR_23")
	)
	(segment
		(start 56.558942 -139.392152)
		(end 60.882022 -139.392152)
		(width 0.1143)
		(layer "F.Cu")
		(net "EXP_XM_ADDR_23")
	)
	(segment
		(start 63.829946 -142.2654)
		(end 63.829946 -139.577064)
		(width 0.1143)
		(layer "F.Cu")
		(net "EXP_XM_ADDR_23")
	)
	(segment
		(start 60.882022 -139.392152)
		(end 61.21908 -139.72921)
		(width 0.1143)
		(layer "F.Cu")
		(net "EXP_XM_ADDR_23")
	)
	(segment
		(start 61.59119 -142.70228)
		(end 63.39459 -142.70228)
		(width 0.1143)
		(layer "F.Cu")
		(net "EXP_XM_ADDR_23")
	)
	(segment
		(start 93.38183 -92.709492)
		(end 93.38183 -92.3163)
		(width 0.1143)
		(layer "F.Cu")
		(net "EXP_XM_ADDR_23")
	)
	(segment
		(start 63.46317 -142.6337)
		(end 63.46317 -142.632176)
		(width 0.1143)
		(layer "F.Cu")
		(net "EXP_XM_ADDR_23")
	)
	(segment
		(start 92.66047 -94.234)
		(end 92.66047 -93.430852)
		(width 0.1143)
		(layer "F.Cu")
		(net "EXP_XM_ADDR_23")
	)
	(segment
		(start 61.21908 -139.72921)
		(end 61.21908 -142.33017)
		(width 0.1143)
		(layer "F.Cu")
		(net "EXP_XM_ADDR_23")
	)
	(segment
		(start 93.38183 -92.3163)
		(end 93.38691 -92.31122)
		(width 0.1143)
		(layer "F.Cu")
		(net "EXP_XM_ADDR_23")
	)
	(segment
		(start 92.66047 -93.430852)
		(end 93.38183 -92.709492)
		(width 0.1143)
		(layer "F.Cu")
		(net "EXP_XM_ADDR_23")
	)
	(segment
		(start 63.46317 -142.632176)
		(end 63.829946 -142.2654)
		(width 0.1143)
		(layer "F.Cu")
		(net "EXP_XM_ADDR_23")
	)
	(segment
		(start 63.39459 -142.70228)
		(end 63.46317 -142.6337)
		(width 0.1143)
		(layer "F.Cu")
		(net "EXP_XM_ADDR_23")
	)
	(segment
		(start 63.829946 -139.577064)
		(end 64.02197 -139.38504)
		(width 0.1143)
		(layer "F.Cu")
		(net "EXP_XM_ADDR_23")
	)
	(segment
		(start 106.3498 -93.349826)
		(end 105.849674 -92.8497)
		(width 0.1143)
		(layer "F.Cu")
		(net "EXP_XM_ADDR_23")
	)
	(via
		(at 93.38691 -92.31122)
		(size 0.508)
		(drill 0.254)
		(layers "F.Cu" "B.Cu")
		(net "EXP_XM_ADDR_23")
	)
	(via
		(at 64.02197 -139.38504)
		(size 0.5588)
		(drill 0.3048)
		(layers "F.Cu" "B.Cu")
		(net "EXP_XM_ADDR_23")
	)
	(via
		(at 105.849674 -92.8497)
		(size 0.508)
		(drill 0.254)
		(layers "F.Cu" "B.Cu")
		(net "EXP_XM_ADDR_23")
	)
	(via
		(at 63.1698 -139.3952)
		(size 0.7112)
		(drill 0.3556)
		(layers "F.Cu" "B.Cu")
		(net "EXP_XM_ADDR_23")
	)
	(segment
		(start 64.02197 -139.38504)
		(end 63.17996 -139.38504)
		(width 0.1143)
		(layer "B.Cu")
		(net "EXP_XM_ADDR_23")
	)
	(segment
		(start 63.17996 -139.38504)
		(end 63.1698 -139.3952)
		(width 0.1143)
		(layer "B.Cu")
		(net "EXP_XM_ADDR_23")
	)
	(segment
		(start 63.939166 -134.694676)
		(end 64.08547 -134.84098)
		(width 0.127)
		(layer "In2.Cu")
		(net "EXP_XM_ADDR_23")
	)
	(segment
		(start 101.004878 -91.999308)
		(end 101.48697 -92.4814)
		(width 0.127)
		(layer "In2.Cu")
		(net "EXP_XM_ADDR_23")
	)
	(segment
		(start 98.96983 -91.9607)
		(end 99.008438 -91.999308)
		(width 0.127)
		(layer "In2.Cu")
		(net "EXP_XM_ADDR_23")
	)
	(segment
		(start 88.520524 -92.784676)
		(end 79.54137 -101.76383)
		(width 0.127)
		(layer "In2.Cu")
		(net "EXP_XM_ADDR_23")
	)
	(segment
		(start 63.939166 -130.018536)
		(end 63.939166 -134.694676)
		(width 0.127)
		(layer "In2.Cu")
		(net "EXP_XM_ADDR_23")
	)
	(segment
		(start 64.08547 -135.633206)
		(end 64.02197 -135.696706)
		(width 0.127)
		(layer "In2.Cu")
		(net "EXP_XM_ADDR_23")
	)
	(segment
		(start 99.008438 -91.999308)
		(end 101.004878 -91.999308)
		(width 0.127)
		(layer "In2.Cu")
		(net "EXP_XM_ADDR_23")
	)
	(segment
		(start 64.31407 -125.681232)
		(end 64.00927 -125.986032)
		(width 0.127)
		(layer "In2.Cu")
		(net "EXP_XM_ADDR_23")
	)
	(segment
		(start 64.31407 -119.081296)
		(end 64.31407 -125.681232)
		(width 0.127)
		(layer "In2.Cu")
		(net "EXP_XM_ADDR_23")
	)
	(segment
		(start 64.00927 -125.986032)
		(end 64.00927 -129.948432)
		(width 0.127)
		(layer "In2.Cu")
		(net "EXP_XM_ADDR_23")
	)
	(segment
		(start 79.54137 -101.76383)
		(end 79.54137 -103.853996)
		(width 0.127)
		(layer "In2.Cu")
		(net "EXP_XM_ADDR_23")
	)
	(segment
		(start 79.54137 -103.853996)
		(end 64.31407 -119.081296)
		(width 0.127)
		(layer "In2.Cu")
		(net "EXP_XM_ADDR_23")
	)
	(segment
		(start 64.02197 -135.696706)
		(end 64.02197 -139.38504)
		(width 0.127)
		(layer "In2.Cu")
		(net "EXP_XM_ADDR_23")
	)
	(segment
		(start 64.08547 -134.84098)
		(end 64.08547 -135.633206)
		(width 0.127)
		(layer "In2.Cu")
		(net "EXP_XM_ADDR_23")
	)
	(segment
		(start 92.913454 -92.784676)
		(end 88.520524 -92.784676)
		(width 0.127)
		(layer "In2.Cu")
		(net "EXP_XM_ADDR_23")
	)
	(segment
		(start 105.29951 -92.4306)
		(end 105.71861 -92.8497)
		(width 0.127)
		(layer "In2.Cu")
		(net "EXP_XM_ADDR_23")
	)
	(segment
		(start 103.640128 -92.4306)
		(end 105.29951 -92.4306)
		(width 0.127)
		(layer "In2.Cu")
		(net "EXP_XM_ADDR_23")
	)
	(segment
		(start 93.73743 -91.9607)
		(end 98.96983 -91.9607)
		(width 0.127)
		(layer "In2.Cu")
		(net "EXP_XM_ADDR_23")
	)
	(segment
		(start 105.71861 -92.8497)
		(end 105.849674 -92.8497)
		(width 0.127)
		(layer "In2.Cu")
		(net "EXP_XM_ADDR_23")
	)
	(segment
		(start 64.00927 -129.948432)
		(end 63.939166 -130.018536)
		(width 0.127)
		(layer "In2.Cu")
		(net "EXP_XM_ADDR_23")
	)
	(segment
		(start 101.48697 -92.4814)
		(end 103.589328 -92.4814)
		(width 0.127)
		(layer "In2.Cu")
		(net "EXP_XM_ADDR_23")
	)
	(segment
		(start 93.38691 -92.31122)
		(end 93.73743 -91.9607)
		(width 0.127)
		(layer "In2.Cu")
		(net "EXP_XM_ADDR_23")
	)
	(segment
		(start 103.589328 -92.4814)
		(end 103.640128 -92.4306)
		(width 0.127)
		(layer "In2.Cu")
		(net "EXP_XM_ADDR_23")
	)
	(segment
		(start 93.38691 -92.31122)
		(end 92.913454 -92.784676)
		(width 0.127)
		(layer "In2.Cu")
		(net "EXP_XM_ADDR_23")
	)
	(segment
		(start 107.672886 -113.856516)
		(end 107.620054 -113.803684)
		(width 0.1016)
		(layer "F.Cu")
		(net "SAS_HDD_TX8_P")
	)
	(segment
		(start 110.039404 -106.660442)
		(end 110.349792 -106.350054)
		(width 0.1016)
		(layer "F.Cu")
		(net "SAS_HDD_TX8_P")
	)
	(segment
		(start 108.78693 -111.584994)
		(end 108.787184 -111.584994)
		(width 0.1016)
		(layer "F.Cu")
		(net "SAS_HDD_TX8_P")
	)
	(segment
		(start 109.96803 -109.81944)
		(end 109.96803 -106.922316)
		(width 0.1016)
		(layer "F.Cu")
		(net "SAS_HDD_TX8_P")
	)
	(segment
		(start 107.70997 -114.0206)
		(end 107.70997 -113.946178)
		(width 0.1016)
		(layer "F.Cu")
		(net "SAS_HDD_TX8_P")
	)
	(segment
		(start 108.862114 -111.507524)
		(end 109.556296 -110.813088)
		(width 0.1016)
		(layer "F.Cu")
		(net "SAS_HDD_TX8_P")
	)
	(segment
		(start 107.90682 -112.465104)
		(end 108.78693 -111.584994)
		(width 0.1016)
		(layer "F.Cu")
		(net "SAS_HDD_TX8_P")
	)
	(segment
		(start 107.58297 -113.714022)
		(end 107.58297 -113.246916)
		(width 0.1016)
		(layer "F.Cu")
		(net "SAS_HDD_TX8_P")
	)
	(arc
		(start 108.787184 -111.584994)
		(mid 108.824913 -111.546514)
		(end 108.862114 -111.507524)
		(width 0.1016)
		(layer "F.Cu")
		(net "SAS_HDD_TX8_P")
	)
	(arc
		(start 109.96803 -106.922316)
		(mid 109.986192 -106.786602)
		(end 110.039404 -106.660442)
		(width 0.1016)
		(layer "F.Cu")
		(net "SAS_HDD_TX8_P")
	)
	(arc
		(start 107.58297 -113.246916)
		(mid 107.667134 -112.823797)
		(end 107.90682 -112.465104)
		(width 0.1016)
		(layer "F.Cu")
		(net "SAS_HDD_TX8_P")
	)
	(arc
		(start 107.70997 -113.946178)
		(mid 107.700337 -113.89766)
		(end 107.672886 -113.856516)
		(width 0.1016)
		(layer "F.Cu")
		(net "SAS_HDD_TX8_P")
	)
	(arc
		(start 109.556296 -110.813088)
		(mid 109.860995 -110.357213)
		(end 109.96803 -109.81944)
		(width 0.1016)
		(layer "F.Cu")
		(net "SAS_HDD_TX8_P")
	)
	(arc
		(start 107.620054 -113.803684)
		(mid 107.592621 -113.762533)
		(end 107.58297 -113.714022)
		(width 0.1016)
		(layer "F.Cu")
		(net "SAS_HDD_TX8_P")
	)
	(segment
		(start 143.61795 -59.03595)
		(end 143.61795 -54.376066)
		(width 0.1143)
		(layer "F.Cu")
		(net "XM_DATA_2")
	)
	(segment
		(start 144.099026 -61.9379)
		(end 144.099026 -59.517026)
		(width 0.1143)
		(layer "F.Cu")
		(net "XM_DATA_2")
	)
	(segment
		(start 145.151094 -52.842922)
		(end 145.151094 -52.803298)
		(width 0.1143)
		(layer "F.Cu")
		(net "XM_DATA_2")
	)
	(segment
		(start 144.099026 -59.517026)
		(end 143.61795 -59.03595)
		(width 0.1143)
		(layer "F.Cu")
		(net "XM_DATA_2")
	)
	(segment
		(start 112.350042 -49.399952)
		(end 112.749838 -49.000156)
		(width 0.1143)
		(layer "F.Cu")
		(net "XM_DATA_2")
	)
	(segment
		(start 143.61795 -54.376066)
		(end 145.151094 -52.842922)
		(width 0.1143)
		(layer "F.Cu")
		(net "XM_DATA_2")
	)
	(via
		(at 118.314978 -50.27676)
		(size 0.7112)
		(drill 0.3556)
		(layers "F.Cu" "B.Cu")
		(net "XM_DATA_2")
	)
	(via
		(at 145.151094 -52.803298)
		(size 0.5588)
		(drill 0.3048)
		(layers "F.Cu" "B.Cu")
		(net "XM_DATA_2")
	)
	(via
		(at 112.749838 -49.000156)
		(size 0.508)
		(drill 0.254)
		(layers "F.Cu" "B.Cu")
		(net "XM_DATA_2")
	)
	(segment
		(start 116.56314 -48.524922)
		(end 118.314978 -50.27676)
		(width 0.1143)
		(layer "B.Cu")
		(net "XM_DATA_2")
	)
	(segment
		(start 118.314978 -50.27676)
		(end 118.762018 -50.7238)
		(width 0.1143)
		(layer "B.Cu")
		(net "XM_DATA_2")
	)
	(segment
		(start 118.762018 -50.7238)
		(end 120.1928 -50.7238)
		(width 0.1143)
		(layer "B.Cu")
		(net "XM_DATA_2")
	)
	(segment
		(start 140.231368 -50.48885)
		(end 141.266418 -51.5239)
		(width 0.1143)
		(layer "B.Cu")
		(net "XM_DATA_2")
	)
	(segment
		(start 138.819128 -50.61585)
		(end 138.946128 -50.48885)
		(width 0.1143)
		(layer "B.Cu")
		(net "XM_DATA_2")
	)
	(segment
		(start 120.269 -50.8)
		(end 138.692128 -50.8)
		(width 0.1143)
		(layer "B.Cu")
		(net "XM_DATA_2")
	)
	(segment
		(start 141.31163 -51.5239)
		(end 143.026892 -53.239162)
		(width 0.1143)
		(layer "B.Cu")
		(net "XM_DATA_2")
	)
	(segment
		(start 141.266418 -51.5239)
		(end 141.31163 -51.5239)
		(width 0.1143)
		(layer "B.Cu")
		(net "XM_DATA_2")
	)
	(segment
		(start 113.11255 -48.637444)
		(end 115.2144 -48.637444)
		(width 0.1143)
		(layer "B.Cu")
		(net "XM_DATA_2")
	)
	(segment
		(start 138.819128 -50.673)
		(end 138.819128 -50.61585)
		(width 0.1143)
		(layer "B.Cu")
		(net "XM_DATA_2")
	)
	(segment
		(start 138.692128 -50.8)
		(end 138.819128 -50.673)
		(width 0.1143)
		(layer "B.Cu")
		(net "XM_DATA_2")
	)
	(segment
		(start 120.1928 -50.7238)
		(end 120.269 -50.8)
		(width 0.1143)
		(layer "B.Cu")
		(net "XM_DATA_2")
	)
	(segment
		(start 115.2144 -48.637444)
		(end 115.326922 -48.524922)
		(width 0.1143)
		(layer "B.Cu")
		(net "XM_DATA_2")
	)
	(segment
		(start 144.71523 -53.239162)
		(end 145.151094 -52.803298)
		(width 0.1143)
		(layer "B.Cu")
		(net "XM_DATA_2")
	)
	(segment
		(start 112.749838 -49.000156)
		(end 113.11255 -48.637444)
		(width 0.1143)
		(layer "B.Cu")
		(net "XM_DATA_2")
	)
	(segment
		(start 138.946128 -50.48885)
		(end 140.231368 -50.48885)
		(width 0.1143)
		(layer "B.Cu")
		(net "XM_DATA_2")
	)
	(segment
		(start 115.326922 -48.524922)
		(end 116.56314 -48.524922)
		(width 0.1143)
		(layer "B.Cu")
		(net "XM_DATA_2")
	)
	(segment
		(start 143.026892 -53.239162)
		(end 144.71523 -53.239162)
		(width 0.1143)
		(layer "B.Cu")
		(net "XM_DATA_2")
	)
	(segment
		(start 103.549958 -56.599836)
		(end 103.549958 -59.266582)
		(width 0.1143)
		(layer "F.Cu")
		(net "JTAG_IOC_TDI")
	)
	(segment
		(start 106.082846 -61.39815)
		(end 106.091228 -61.39815)
		(width 0.1143)
		(layer "F.Cu")
		(net "JTAG_IOC_TDI")
	)
	(segment
		(start 107.917488 -61.52515)
		(end 109.074966 -62.682628)
		(width 0.1143)
		(layer "F.Cu")
		(net "JTAG_IOC_TDI")
	)
	(segment
		(start 105.436162 -61.152786)
		(end 105.837482 -61.152786)
		(width 0.1143)
		(layer "F.Cu")
		(net "JTAG_IOC_TDI")
	)
	(segment
		(start 109.074966 -65.4431)
		(end 109.074966 -64.2366)
		(width 0.1143)
		(layer "F.Cu")
		(net "JTAG_IOC_TDI")
	)
	(segment
		(start 106.091228 -61.39815)
		(end 106.218228 -61.52515)
		(width 0.1143)
		(layer "F.Cu")
		(net "JTAG_IOC_TDI")
	)
	(segment
		(start 109.074966 -62.682628)
		(end 109.074966 -64.2366)
		(width 0.1143)
		(layer "F.Cu")
		(net "JTAG_IOC_TDI")
	)
	(segment
		(start 103.549958 -59.266582)
		(end 105.436162 -61.152786)
		(width 0.1143)
		(layer "F.Cu")
		(net "JTAG_IOC_TDI")
	)
	(segment
		(start 106.218228 -61.52515)
		(end 107.917488 -61.52515)
		(width 0.1143)
		(layer "F.Cu")
		(net "JTAG_IOC_TDI")
	)
	(segment
		(start 105.837482 -61.152786)
		(end 106.082846 -61.39815)
		(width 0.1143)
		(layer "F.Cu")
		(net "JTAG_IOC_TDI")
	)
	(segment
		(start 205.466188 -120.669812)
		(end 205.74 -120.396)
		(width 0.254)
		(layer "F.Cu")
		(net "P1V5_E_CC_R")
	)
	(segment
		(start 205.746096 -119.717312)
		(end 205.74 -120.396)
		(width 0.254)
		(layer "F.Cu")
		(net "P1V5_E_CC_R")
	)
	(segment
		(start 204.597 -120.669812)
		(end 203.333096 -120.669812)
		(width 0.254)
		(layer "F.Cu")
		(net "P1V5_E_CC_R")
	)
	(segment
		(start 204.597 -120.669812)
		(end 205.466188 -120.669812)
		(width 0.254)
		(layer "F.Cu")
		(net "P1V5_E_CC_R")
	)
	(segment
		(start 203.333096 -120.669812)
		(end 203.2635 -120.600216)
		(width 0.254)
		(layer "F.Cu")
		(net "P1V5_E_CC_R")
	)
	(segment
		(start 205.746096 -119.272812)
		(end 205.746096 -119.717312)
		(width 0.254)
		(layer "F.Cu")
		(net "P1V5_E_CC_R")
	)
	(segment
		(start 203.2635 -120.600216)
		(end 203.2635 -119.634)
		(width 0.254)
		(layer "F.Cu")
		(net "P1V5_E_CC_R")
	)
	(via
		(at 204.597 -120.669812)
		(size 0.7112)
		(drill 0.3556)
		(layers "F.Cu" "B.Cu")
		(net "P1V5_E_CC_R")
	)
	(segment
		(start 98.82886 -97.15119)
		(end 98.82886 -97.822258)
		(width 0.1143)
		(layer "F.Cu")
		(net "EXP_XM_ADDR_14")
	)
	(segment
		(start 74.19467 -138.57224)
		(end 74.19467 -138.19886)
		(width 0.1143)
		(layer "F.Cu")
		(net "EXP_XM_ADDR_14")
	)
	(segment
		(start 68.35267 -138.97356)
		(end 73.79335 -138.97356)
		(width 0.1143)
		(layer "F.Cu")
		(net "EXP_XM_ADDR_14")
	)
	(segment
		(start 56.558942 -137.892282)
		(end 67.880992 -137.892282)
		(width 0.1143)
		(layer "F.Cu")
		(net "EXP_XM_ADDR_14")
	)
	(segment
		(start 98.019616 -97.957132)
		(end 97.346516 -97.957132)
		(width 0.1143)
		(layer "F.Cu")
		(net "EXP_XM_ADDR_14")
	)
	(segment
		(start 73.79335 -138.97356)
		(end 74.19467 -138.57224)
		(width 0.1143)
		(layer "F.Cu")
		(net "EXP_XM_ADDR_14")
	)
	(segment
		(start 68.23075 -138.85164)
		(end 68.35267 -138.97356)
		(width 0.1143)
		(layer "F.Cu")
		(net "EXP_XM_ADDR_14")
	)
	(segment
		(start 68.22821 -138.85164)
		(end 68.23075 -138.85164)
		(width 0.1143)
		(layer "F.Cu")
		(net "EXP_XM_ADDR_14")
	)
	(segment
		(start 67.880992 -137.892282)
		(end 68.20281 -138.2141)
		(width 0.1143)
		(layer "F.Cu")
		(net "EXP_XM_ADDR_14")
	)
	(segment
		(start 69.277738 -138.00328)
		(end 68.948554 -138.332464)
		(width 0.1143)
		(layer "F.Cu")
		(net "EXP_XM_ADDR_14")
	)
	(segment
		(start 98.82886 -97.822258)
		(end 98.557588 -98.09353)
		(width 0.1143)
		(layer "F.Cu")
		(net "EXP_XM_ADDR_14")
	)
	(segment
		(start 73.99909 -138.00328)
		(end 69.277738 -138.00328)
		(width 0.1143)
		(layer "F.Cu")
		(net "EXP_XM_ADDR_14")
	)
	(segment
		(start 100.112576 -95.867474)
		(end 98.82886 -97.15119)
		(width 0.1143)
		(layer "F.Cu")
		(net "EXP_XM_ADDR_14")
	)
	(segment
		(start 68.20281 -138.82624)
		(end 68.22821 -138.85164)
		(width 0.1143)
		(layer "F.Cu")
		(net "EXP_XM_ADDR_14")
	)
	(segment
		(start 68.20281 -138.2141)
		(end 68.20281 -138.82624)
		(width 0.1143)
		(layer "F.Cu")
		(net "EXP_XM_ADDR_14")
	)
	(segment
		(start 101.83241 -95.867474)
		(end 100.112576 -95.867474)
		(width 0.1143)
		(layer "F.Cu")
		(net "EXP_XM_ADDR_14")
	)
	(segment
		(start 98.557588 -98.09353)
		(end 98.156014 -98.09353)
		(width 0.1143)
		(layer "F.Cu")
		(net "EXP_XM_ADDR_14")
	)
	(segment
		(start 97.346516 -97.957132)
		(end 97.231962 -97.842578)
		(width 0.1143)
		(layer "F.Cu")
		(net "EXP_XM_ADDR_14")
	)
	(segment
		(start 102.349808 -95.350076)
		(end 101.83241 -95.867474)
		(width 0.1143)
		(layer "F.Cu")
		(net "EXP_XM_ADDR_14")
	)
	(segment
		(start 98.156014 -98.09353)
		(end 98.019616 -97.957132)
		(width 0.1143)
		(layer "F.Cu")
		(net "EXP_XM_ADDR_14")
	)
	(segment
		(start 74.19467 -138.19886)
		(end 73.99909 -138.00328)
		(width 0.1143)
		(layer "F.Cu")
		(net "EXP_XM_ADDR_14")
	)
	(via
		(at 68.948554 -138.332464)
		(size 0.5588)
		(drill 0.3048)
		(layers "F.Cu" "B.Cu")
		(net "EXP_XM_ADDR_14")
	)
	(via
		(at 68.9356 -139.1412)
		(size 0.7112)
		(drill 0.3556)
		(layers "F.Cu" "B.Cu")
		(net "EXP_XM_ADDR_14")
	)
	(via
		(at 97.231962 -97.842578)
		(size 0.508)
		(drill 0.254)
		(layers "F.Cu" "B.Cu")
		(net "EXP_XM_ADDR_14")
	)
	(segment
		(start 68.9356 -138.338814)
		(end 68.94195 -138.332464)
		(width 0.1143)
		(layer "B.Cu")
		(net "EXP_XM_ADDR_14")
	)
	(segment
		(start 68.94195 -138.332464)
		(end 68.948554 -138.332464)
		(width 0.1143)
		(layer "B.Cu")
		(net "EXP_XM_ADDR_14")
	)
	(segment
		(start 68.9356 -139.1412)
		(end 68.9356 -138.338814)
		(width 0.1143)
		(layer "B.Cu")
		(net "EXP_XM_ADDR_14")
	)
	(segment
		(start 88.46693 -103.571548)
		(end 91.26347 -100.775008)
		(width 0.127)
		(layer "In2.Cu")
		(net "EXP_XM_ADDR_14")
	)
	(segment
		(start 68.948554 -138.332464)
		(end 68.948554 -138.022584)
		(width 0.127)
		(layer "In2.Cu")
		(net "EXP_XM_ADDR_14")
	)
	(segment
		(start 96.045528 -99.029012)
		(end 97.231962 -97.842578)
		(width 0.127)
		(layer "In2.Cu")
		(net "EXP_XM_ADDR_14")
	)
	(segment
		(start 69.31787 -131.120134)
		(end 69.396356 -131.041648)
		(width 0.127)
		(layer "In2.Cu")
		(net "EXP_XM_ADDR_14")
	)
	(segment
		(start 71.57339 -128.547876)
		(end 71.57339 -120.13438)
		(width 0.127)
		(layer "In2.Cu")
		(net "EXP_XM_ADDR_14")
	)
	(segment
		(start 71.57339 -120.13438)
		(end 79.01178 -112.69599)
		(width 0.127)
		(layer "In2.Cu")
		(net "EXP_XM_ADDR_14")
	)
	(segment
		(start 79.225648 -111.19739)
		(end 82.401918 -108.02112)
		(width 0.127)
		(layer "In2.Cu")
		(net "EXP_XM_ADDR_14")
	)
	(segment
		(start 68.948554 -138.022584)
		(end 68.737734 -137.811764)
		(width 0.127)
		(layer "In2.Cu")
		(net "EXP_XM_ADDR_14")
	)
	(segment
		(start 94.471744 -100.775008)
		(end 96.045528 -99.201224)
		(width 0.127)
		(layer "In2.Cu")
		(net "EXP_XM_ADDR_14")
	)
	(segment
		(start 79.01178 -111.41075)
		(end 79.22514 -111.19739)
		(width 0.127)
		(layer "In2.Cu")
		(net "EXP_XM_ADDR_14")
	)
	(segment
		(start 69.11467 -136.66343)
		(end 69.11467 -134.63778)
		(width 0.127)
		(layer "In2.Cu")
		(net "EXP_XM_ADDR_14")
	)
	(segment
		(start 71.573644 -128.54813)
		(end 71.57339 -128.547876)
		(width 0.127)
		(layer "In2.Cu")
		(net "EXP_XM_ADDR_14")
	)
	(segment
		(start 88.46693 -105.636568)
		(end 88.46693 -103.571548)
		(width 0.127)
		(layer "In2.Cu")
		(net "EXP_XM_ADDR_14")
	)
	(segment
		(start 79.01178 -112.655858)
		(end 79.01686 -112.650778)
		(width 0.127)
		(layer "In2.Cu")
		(net "EXP_XM_ADDR_14")
	)
	(segment
		(start 79.01178 -112.136682)
		(end 79.01178 -111.41075)
		(width 0.127)
		(layer "In2.Cu")
		(net "EXP_XM_ADDR_14")
	)
	(segment
		(start 79.01178 -112.69599)
		(end 79.01178 -112.655858)
		(width 0.127)
		(layer "In2.Cu")
		(net "EXP_XM_ADDR_14")
	)
	(segment
		(start 68.737734 -137.811764)
		(end 68.737734 -137.040366)
		(width 0.127)
		(layer "In2.Cu")
		(net "EXP_XM_ADDR_14")
	)
	(segment
		(start 71.573644 -128.863598)
		(end 71.573644 -128.54813)
		(width 0.127)
		(layer "In2.Cu")
		(net "EXP_XM_ADDR_14")
	)
	(segment
		(start 86.082378 -108.02112)
		(end 88.46693 -105.636568)
		(width 0.127)
		(layer "In2.Cu")
		(net "EXP_XM_ADDR_14")
	)
	(segment
		(start 69.11467 -134.63778)
		(end 69.31787 -134.43458)
		(width 0.127)
		(layer "In2.Cu")
		(net "EXP_XM_ADDR_14")
	)
	(segment
		(start 96.045528 -99.201224)
		(end 96.045528 -99.029012)
		(width 0.127)
		(layer "In2.Cu")
		(net "EXP_XM_ADDR_14")
	)
	(segment
		(start 79.22514 -111.19739)
		(end 79.225648 -111.19739)
		(width 0.127)
		(layer "In2.Cu")
		(net "EXP_XM_ADDR_14")
	)
	(segment
		(start 69.31787 -134.43458)
		(end 69.31787 -131.120134)
		(width 0.127)
		(layer "In2.Cu")
		(net "EXP_XM_ADDR_14")
	)
	(segment
		(start 91.26347 -100.775008)
		(end 94.471744 -100.775008)
		(width 0.127)
		(layer "In2.Cu")
		(net "EXP_XM_ADDR_14")
	)
	(segment
		(start 69.396356 -131.041648)
		(end 69.511164 -130.926586)
		(width 0.127)
		(layer "In2.Cu")
		(net "EXP_XM_ADDR_14")
	)
	(segment
		(start 68.737734 -137.040366)
		(end 69.11467 -136.66343)
		(width 0.127)
		(layer "In2.Cu")
		(net "EXP_XM_ADDR_14")
	)
	(segment
		(start 69.511164 -130.926586)
		(end 71.573644 -128.863598)
		(width 0.127)
		(layer "In2.Cu")
		(net "EXP_XM_ADDR_14")
	)
	(segment
		(start 79.01686 -112.650778)
		(end 79.01686 -112.141762)
		(width 0.127)
		(layer "In2.Cu")
		(net "EXP_XM_ADDR_14")
	)
	(segment
		(start 79.01686 -112.141762)
		(end 79.01178 -112.136682)
		(width 0.127)
		(layer "In2.Cu")
		(net "EXP_XM_ADDR_14")
	)
	(segment
		(start 82.401918 -108.02112)
		(end 86.082378 -108.02112)
		(width 0.127)
		(layer "In2.Cu")
		(net "EXP_XM_ADDR_14")
	)
	(segment
		(start 111.00689 -109.879384)
		(end 111.00689 -107.787948)
		(width 0.1016)
		(layer "F.Cu")
		(net "SAS_HDD_TX7_N")
	)
	(segment
		(start 111.27867 -106.350054)
		(end 111.34979 -106.350054)
		(width 0.1016)
		(layer "F.Cu")
		(net "SAS_HDD_TX7_N")
	)
	(segment
		(start 109.475778 -111.935006)
		(end 110.63605 -110.774734)
		(width 0.1016)
		(layer "F.Cu")
		(net "SAS_HDD_TX7_N")
	)
	(segment
		(start 111.055658 -106.573066)
		(end 111.27867 -106.350054)
		(width 0.1016)
		(layer "F.Cu")
		(net "SAS_HDD_TX7_N")
	)
	(segment
		(start 108.990892 -113.57864)
		(end 108.990892 -113.106454)
		(width 0.1016)
		(layer "F.Cu")
		(net "SAS_HDD_TX7_N")
	)
	(segment
		(start 108.85297 -114.0206)
		(end 108.85297 -113.821718)
		(width 0.1016)
		(layer "F.Cu")
		(net "SAS_HDD_TX7_N")
	)
	(segment
		(start 110.86973 -107.456732)
		(end 110.86973 -107.022138)
		(width 0.1016)
		(layer "F.Cu")
		(net "SAS_HDD_TX7_N")
	)
	(segment
		(start 108.890054 -113.732056)
		(end 108.953808 -113.668302)
		(width 0.1016)
		(layer "F.Cu")
		(net "SAS_HDD_TX7_N")
	)
	(arc
		(start 108.990892 -113.106454)
		(mid 109.116807 -112.472495)
		(end 109.475778 -111.935006)
		(width 0.1016)
		(layer "F.Cu")
		(net "SAS_HDD_TX7_N")
	)
	(arc
		(start 108.953808 -113.668302)
		(mid 108.981241 -113.627151)
		(end 108.990892 -113.57864)
		(width 0.1016)
		(layer "F.Cu")
		(net "SAS_HDD_TX7_N")
	)
	(arc
		(start 111.00689 -107.787948)
		(mid 110.989063 -107.698328)
		(end 110.93831 -107.62234)
		(width 0.1016)
		(layer "F.Cu")
		(net "SAS_HDD_TX7_N")
	)
	(arc
		(start 110.86973 -107.022138)
		(mid 110.918051 -106.77912)
		(end 111.055658 -106.573066)
		(width 0.1016)
		(layer "F.Cu")
		(net "SAS_HDD_TX7_N")
	)
	(arc
		(start 110.63605 -110.774734)
		(mid 110.910531 -110.363944)
		(end 111.00689 -109.879384)
		(width 0.1016)
		(layer "F.Cu")
		(net "SAS_HDD_TX7_N")
	)
	(arc
		(start 110.93831 -107.62234)
		(mid 110.887541 -107.546358)
		(end 110.86973 -107.456732)
		(width 0.1016)
		(layer "F.Cu")
		(net "SAS_HDD_TX7_N")
	)
	(arc
		(start 108.85297 -113.821718)
		(mid 108.862603 -113.7732)
		(end 108.890054 -113.732056)
		(width 0.1016)
		(layer "F.Cu")
		(net "SAS_HDD_TX7_N")
	)
	(segment
		(start 144.099026 -45.966126)
		(end 144.099026 -42.7101)
		(width 0.1143)
		(layer "F.Cu")
		(net "XM_ADDR_19")
	)
	(segment
		(start 144.099026 -40.54094)
		(end 144.099026 -42.7101)
		(width 0.1143)
		(layer "F.Cu")
		(net "XM_ADDR_19")
	)
	(segment
		(start 145.288 -48.006)
		(end 145.288 -47.479458)
		(width 0.1143)
		(layer "F.Cu")
		(net "XM_ADDR_19")
	)
	(segment
		(start 144.126966 -40.513)
		(end 144.099026 -40.54094)
		(width 0.1143)
		(layer "F.Cu")
		(net "XM_ADDR_19")
	)
	(segment
		(start 145.288 -47.479458)
		(end 144.646142 -46.8376)
		(width 0.1143)
		(layer "F.Cu")
		(net "XM_ADDR_19")
	)
	(segment
		(start 112.350042 -52.599844)
		(end 112.749838 -52.200048)
		(width 0.1143)
		(layer "F.Cu")
		(net "XM_ADDR_19")
	)
	(segment
		(start 144.646142 -46.613826)
		(end 144.1069 -46.074584)
		(width 0.1143)
		(layer "F.Cu")
		(net "XM_ADDR_19")
	)
	(segment
		(start 144.1069 -46.074584)
		(end 144.1069 -45.974)
		(width 0.1143)
		(layer "F.Cu")
		(net "XM_ADDR_19")
	)
	(segment
		(start 144.1069 -45.974)
		(end 144.099026 -45.966126)
		(width 0.1143)
		(layer "F.Cu")
		(net "XM_ADDR_19")
	)
	(segment
		(start 144.646142 -46.8376)
		(end 144.646142 -46.613826)
		(width 0.1143)
		(layer "F.Cu")
		(net "XM_ADDR_19")
	)
	(via
		(at 112.749838 -52.200048)
		(size 0.508)
		(drill 0.254)
		(layers "F.Cu" "B.Cu")
		(net "XM_ADDR_19")
	)
	(via
		(at 145.288 -48.006)
		(size 0.5588)
		(drill 0.3048)
		(layers "F.Cu" "B.Cu")
		(net "XM_ADDR_19")
	)
	(segment
		(start 114.860578 -52.200048)
		(end 112.749838 -52.200048)
		(width 0.127)
		(layer "In5.Cu")
		(net "XM_ADDR_19")
	)
	(segment
		(start 145.925794 -45.856906)
		(end 146.052794 -45.729906)
		(width 0.127)
		(layer "In5.Cu")
		(net "XM_ADDR_19")
	)
	(segment
		(start 147.322794 -48.7807)
		(end 143.14297 -48.7807)
		(width 0.127)
		(layer "In5.Cu")
		(net "XM_ADDR_19")
	)
	(segment
		(start 125.415294 -47.536354)
		(end 121.696734 -51.254914)
		(width 0.127)
		(layer "In5.Cu")
		(net "XM_ADDR_19")
	)
	(segment
		(start 145.925794 -47.879)
		(end 145.925794 -45.856906)
		(width 0.127)
		(layer "In5.Cu")
		(net "XM_ADDR_19")
	)
	(segment
		(start 117.020086 -51.254914)
		(end 116.459 -51.816)
		(width 0.127)
		(layer "In5.Cu")
		(net "XM_ADDR_19")
	)
	(segment
		(start 116.459 -51.816)
		(end 116.2812 -51.816)
		(width 0.127)
		(layer "In5.Cu")
		(net "XM_ADDR_19")
	)
	(segment
		(start 133.613906 -47.536354)
		(end 125.415294 -47.536354)
		(width 0.127)
		(layer "In5.Cu")
		(net "XM_ADDR_19")
	)
	(segment
		(start 146.941794 -45.856906)
		(end 147.068794 -45.729906)
		(width 0.127)
		(layer "In5.Cu")
		(net "XM_ADDR_19")
	)
	(segment
		(start 116.2812 -51.816)
		(end 115.8875 -52.2097)
		(width 0.127)
		(layer "In5.Cu")
		(net "XM_ADDR_19")
	)
	(segment
		(start 146.052794 -45.729906)
		(end 146.306794 -45.729906)
		(width 0.127)
		(layer "In5.Cu")
		(net "XM_ADDR_19")
	)
	(segment
		(start 145.798794 -48.006)
		(end 145.925794 -47.879)
		(width 0.127)
		(layer "In5.Cu")
		(net "XM_ADDR_19")
	)
	(segment
		(start 146.560794 -48.006)
		(end 146.814794 -48.006)
		(width 0.127)
		(layer "In5.Cu")
		(net "XM_ADDR_19")
	)
	(segment
		(start 146.814794 -48.006)
		(end 146.941794 -47.879)
		(width 0.127)
		(layer "In5.Cu")
		(net "XM_ADDR_19")
	)
	(segment
		(start 147.322794 -45.729906)
		(end 147.449794 -45.856906)
		(width 0.127)
		(layer "In5.Cu")
		(net "XM_ADDR_19")
	)
	(segment
		(start 140.88237 -46.5201)
		(end 134.63016 -46.5201)
		(width 0.127)
		(layer "In5.Cu")
		(net "XM_ADDR_19")
	)
	(segment
		(start 143.14297 -48.7807)
		(end 140.88237 -46.5201)
		(width 0.127)
		(layer "In5.Cu")
		(net "XM_ADDR_19")
	)
	(segment
		(start 115.8875 -52.2097)
		(end 114.87023 -52.2097)
		(width 0.127)
		(layer "In5.Cu")
		(net "XM_ADDR_19")
	)
	(segment
		(start 146.941794 -47.879)
		(end 146.941794 -45.856906)
		(width 0.127)
		(layer "In5.Cu")
		(net "XM_ADDR_19")
	)
	(segment
		(start 121.696734 -51.254914)
		(end 117.020086 -51.254914)
		(width 0.127)
		(layer "In5.Cu")
		(net "XM_ADDR_19")
	)
	(segment
		(start 146.433794 -47.879)
		(end 146.560794 -48.006)
		(width 0.127)
		(layer "In5.Cu")
		(net "XM_ADDR_19")
	)
	(segment
		(start 147.068794 -45.729906)
		(end 147.322794 -45.729906)
		(width 0.127)
		(layer "In5.Cu")
		(net "XM_ADDR_19")
	)
	(segment
		(start 146.433794 -45.856906)
		(end 146.433794 -47.879)
		(width 0.127)
		(layer "In5.Cu")
		(net "XM_ADDR_19")
	)
	(segment
		(start 147.449794 -48.6537)
		(end 147.322794 -48.7807)
		(width 0.127)
		(layer "In5.Cu")
		(net "XM_ADDR_19")
	)
	(segment
		(start 147.449794 -45.856906)
		(end 147.449794 -48.6537)
		(width 0.127)
		(layer "In5.Cu")
		(net "XM_ADDR_19")
	)
	(segment
		(start 145.288 -48.006)
		(end 145.798794 -48.006)
		(width 0.127)
		(layer "In5.Cu")
		(net "XM_ADDR_19")
	)
	(segment
		(start 134.63016 -46.5201)
		(end 133.613906 -47.536354)
		(width 0.127)
		(layer "In5.Cu")
		(net "XM_ADDR_19")
	)
	(segment
		(start 114.87023 -52.2097)
		(end 114.860578 -52.200048)
		(width 0.127)
		(layer "In5.Cu")
		(net "XM_ADDR_19")
	)
	(segment
		(start 146.306794 -45.729906)
		(end 146.433794 -45.856906)
		(width 0.127)
		(layer "In5.Cu")
		(net "XM_ADDR_19")
	)
	(segment
		(start 110.236 -63.5)
		(end 110.236 -62.103)
		(width 0.1143)
		(layer "F.Cu")
		(net "JTAG_IOC_TMS")
	)
	(segment
		(start 108.562394 -60.911486)
		(end 109.753908 -62.103)
		(width 0.1143)
		(layer "F.Cu")
		(net "JTAG_IOC_TMS")
	)
	(segment
		(start 104.756966 -58.300366)
		(end 106.15295 -59.69635)
		(width 0.1143)
		(layer "F.Cu")
		(net "JTAG_IOC_TMS")
	)
	(segment
		(start 107.239562 -60.911486)
		(end 108.562394 -60.911486)
		(width 0.1143)
		(layer "F.Cu")
		(net "JTAG_IOC_TMS")
	)
	(segment
		(start 108.331 -68.072)
		(end 108.43895 -68.17995)
		(width 0.1143)
		(layer "F.Cu")
		(net "JTAG_IOC_TMS")
	)
	(segment
		(start 110.910116 -64.174116)
		(end 110.236 -63.5)
		(width 0.1143)
		(layer "F.Cu")
		(net "JTAG_IOC_TMS")
	)
	(segment
		(start 106.783378 -60.4647)
		(end 106.792776 -60.4647)
		(width 0.1143)
		(layer "F.Cu")
		(net "JTAG_IOC_TMS")
	)
	(segment
		(start 106.15295 -59.69635)
		(end 106.15295 -59.834272)
		(width 0.1143)
		(layer "F.Cu")
		(net "JTAG_IOC_TMS")
	)
	(segment
		(start 104.350058 -55.79999)
		(end 104.350058 -55.854092)
		(width 0.1143)
		(layer "F.Cu")
		(net "JTAG_IOC_TMS")
	)
	(segment
		(start 104.350058 -55.854092)
		(end 104.756966 -56.261)
		(width 0.1143)
		(layer "F.Cu")
		(net "JTAG_IOC_TMS")
	)
	(segment
		(start 109.753908 -62.103)
		(end 110.236 -62.103)
		(width 0.1143)
		(layer "F.Cu")
		(net "JTAG_IOC_TMS")
	)
	(segment
		(start 104.756966 -56.261)
		(end 104.756966 -58.300366)
		(width 0.1143)
		(layer "F.Cu")
		(net "JTAG_IOC_TMS")
	)
	(segment
		(start 109.1692 -68.17995)
		(end 109.65815 -67.691)
		(width 0.1143)
		(layer "F.Cu")
		(net "JTAG_IOC_TMS")
	)
	(segment
		(start 110.910116 -67.131692)
		(end 110.910116 -64.174116)
		(width 0.1143)
		(layer "F.Cu")
		(net "JTAG_IOC_TMS")
	)
	(segment
		(start 107.8865 -68.072)
		(end 108.331 -68.072)
		(width 0.1143)
		(layer "F.Cu")
		(net "JTAG_IOC_TMS")
	)
	(segment
		(start 108.43895 -68.17995)
		(end 109.1692 -68.17995)
		(width 0.1143)
		(layer "F.Cu")
		(net "JTAG_IOC_TMS")
	)
	(segment
		(start 109.65815 -67.691)
		(end 110.350808 -67.691)
		(width 0.1143)
		(layer "F.Cu")
		(net "JTAG_IOC_TMS")
	)
	(segment
		(start 110.350808 -67.691)
		(end 110.910116 -67.131692)
		(width 0.1143)
		(layer "F.Cu")
		(net "JTAG_IOC_TMS")
	)
	(segment
		(start 106.792776 -60.4647)
		(end 107.239562 -60.911486)
		(width 0.1143)
		(layer "F.Cu")
		(net "JTAG_IOC_TMS")
	)
	(segment
		(start 106.15295 -59.834272)
		(end 106.783378 -60.4647)
		(width 0.1143)
		(layer "F.Cu")
		(net "JTAG_IOC_TMS")
	)
	(segment
		(start 57.81548 -128.893062)
		(end 58.108342 -128.6002)
		(width 0.1143)
		(layer "F.Cu")
		(net "EXP_XM_ADDR_5")
	)
	(segment
		(start 61.461904 -128.6002)
		(end 61.468762 -128.607058)
		(width 0.1143)
		(layer "F.Cu")
		(net "EXP_XM_ADDR_5")
	)
	(segment
		(start 56.558942 -128.893062)
		(end 57.81548 -128.893062)
		(width 0.1143)
		(layer "F.Cu")
		(net "EXP_XM_ADDR_5")
	)
	(segment
		(start 58.108342 -128.6002)
		(end 61.461904 -128.6002)
		(width 0.1143)
		(layer "F.Cu")
		(net "EXP_XM_ADDR_5")
	)
	(segment
		(start 105.349802 -92.349828)
		(end 104.849676 -91.849702)
		(width 0.1143)
		(layer "F.Cu")
		(net "EXP_XM_ADDR_5")
	)
	(via
		(at 61.468 -129.4384)
		(size 0.7112)
		(drill 0.3556)
		(layers "F.Cu" "B.Cu")
		(net "EXP_XM_ADDR_5")
	)
	(via
		(at 104.849676 -91.849702)
		(size 0.508)
		(drill 0.254)
		(layers "F.Cu" "B.Cu")
		(net "EXP_XM_ADDR_5")
	)
	(via
		(at 61.468762 -128.607058)
		(size 0.5588)
		(drill 0.3048)
		(layers "F.Cu" "B.Cu")
		(net "EXP_XM_ADDR_5")
	)
	(segment
		(start 61.468762 -128.607058)
		(end 61.468 -128.60782)
		(width 0.1143)
		(layer "B.Cu")
		(net "EXP_XM_ADDR_5")
	)
	(segment
		(start 61.468 -128.60782)
		(end 61.468 -129.4384)
		(width 0.1143)
		(layer "B.Cu")
		(net "EXP_XM_ADDR_5")
	)
	(segment
		(start 61.54547 -122.26036)
		(end 61.41847 -122.13336)
		(width 0.127)
		(layer "In2.Cu")
		(net "EXP_XM_ADDR_5")
	)
	(segment
		(start 61.41847 -118.83136)
		(end 61.54547 -118.70436)
		(width 0.127)
		(layer "In2.Cu")
		(net "EXP_XM_ADDR_5")
	)
	(segment
		(start 62.28207 -121.24436)
		(end 61.54547 -121.24436)
		(width 0.127)
		(layer "In2.Cu")
		(net "EXP_XM_ADDR_5")
	)
	(segment
		(start 62.584838 -117.761512)
		(end 62.764162 -117.761512)
		(width 0.127)
		(layer "In2.Cu")
		(net "EXP_XM_ADDR_5")
	)
	(segment
		(start 62.28207 -123.78436)
		(end 62.40907 -123.65736)
		(width 0.127)
		(layer "In2.Cu")
		(net "EXP_XM_ADDR_5")
	)
	(segment
		(start 62.28207 -119.21236)
		(end 61.54547 -119.21236)
		(width 0.127)
		(layer "In2.Cu")
		(net "EXP_XM_ADDR_5")
	)
	(segment
		(start 62.40907 -121.37136)
		(end 62.28207 -121.24436)
		(width 0.127)
		(layer "In2.Cu")
		(net "EXP_XM_ADDR_5")
	)
	(segment
		(start 101.043994 -90.61958)
		(end 101.79431 -90.61958)
		(width 0.127)
		(layer "In2.Cu")
		(net "EXP_XM_ADDR_5")
	)
	(segment
		(start 61.688472 -117.044216)
		(end 61.867796 -117.044216)
		(width 0.127)
		(layer "In2.Cu")
		(net "EXP_XM_ADDR_5")
	)
	(segment
		(start 62.28207 -118.70436)
		(end 62.408816 -118.577614)
		(width 0.127)
		(layer "In2.Cu")
		(net "EXP_XM_ADDR_5")
	)
	(segment
		(start 61.41847 -120.10136)
		(end 61.41847 -119.84736)
		(width 0.127)
		(layer "In2.Cu")
		(net "EXP_XM_ADDR_5")
	)
	(segment
		(start 62.28207 -121.75236)
		(end 62.40907 -121.62536)
		(width 0.127)
		(layer "In2.Cu")
		(net "EXP_XM_ADDR_5")
	)
	(segment
		(start 100.230686 -89.920826)
		(end 100.408486 -90.098626)
		(width 0.127)
		(layer "In2.Cu")
		(net "EXP_XM_ADDR_5")
	)
	(segment
		(start 61.54547 -118.70436)
		(end 62.28207 -118.70436)
		(width 0.127)
		(layer "In2.Cu")
		(net "EXP_XM_ADDR_5")
	)
	(segment
		(start 62.40907 -119.59336)
		(end 62.40907 -119.33936)
		(width 0.127)
		(layer "In2.Cu")
		(net "EXP_XM_ADDR_5")
	)
	(segment
		(start 101.79431 -90.61958)
		(end 102.56647 -91.39174)
		(width 0.127)
		(layer "In2.Cu")
		(net "EXP_XM_ADDR_5")
	)
	(segment
		(start 63.663068 -116.683282)
		(end 62.946026 -115.965986)
		(width 0.127)
		(layer "In2.Cu")
		(net "EXP_XM_ADDR_5")
	)
	(segment
		(start 61.54547 -119.21236)
		(end 61.41847 -119.08536)
		(width 0.127)
		(layer "In2.Cu")
		(net "EXP_XM_ADDR_5")
	)
	(segment
		(start 100.767642 -90.343228)
		(end 101.043994 -90.61958)
		(width 0.127)
		(layer "In2.Cu")
		(net "EXP_XM_ADDR_5")
	)
	(segment
		(start 62.28207 -119.72036)
		(end 62.40907 -119.59336)
		(width 0.127)
		(layer "In2.Cu")
		(net "EXP_XM_ADDR_5")
	)
	(segment
		(start 61.41847 -119.84736)
		(end 61.54547 -119.72036)
		(width 0.127)
		(layer "In2.Cu")
		(net "EXP_XM_ADDR_5")
	)
	(segment
		(start 61.41847 -117.314218)
		(end 61.688472 -117.044216)
		(width 0.127)
		(layer "In2.Cu")
		(net "EXP_XM_ADDR_5")
	)
	(segment
		(start 62.408816 -118.577614)
		(end 62.408816 -118.323106)
		(width 0.127)
		(layer "In2.Cu")
		(net "EXP_XM_ADDR_5")
	)
	(segment
		(start 63.482982 -117.042692)
		(end 63.663068 -116.862606)
		(width 0.127)
		(layer "In2.Cu")
		(net "EXP_XM_ADDR_5")
	)
	(segment
		(start 62.40907 -120.60936)
		(end 62.40907 -120.35536)
		(width 0.127)
		(layer "In2.Cu")
		(net "EXP_XM_ADDR_5")
	)
	(segment
		(start 62.28207 -120.22836)
		(end 61.54547 -120.22836)
		(width 0.127)
		(layer "In2.Cu")
		(net "EXP_XM_ADDR_5")
	)
	(segment
		(start 62.28207 -122.26036)
		(end 61.54547 -122.26036)
		(width 0.127)
		(layer "In2.Cu")
		(net "EXP_XM_ADDR_5")
	)
	(segment
		(start 104.573832 -91.849702)
		(end 104.849676 -91.849702)
		(width 0.127)
		(layer "In2.Cu")
		(net "EXP_XM_ADDR_5")
	)
	(segment
		(start 62.40907 -123.40336)
		(end 62.28207 -123.27636)
		(width 0.127)
		(layer "In2.Cu")
		(net "EXP_XM_ADDR_5")
	)
	(segment
		(start 62.227206 -116.684806)
		(end 62.227206 -116.505482)
		(width 0.127)
		(layer "In2.Cu")
		(net "EXP_XM_ADDR_5")
	)
	(segment
		(start 61.54547 -120.22836)
		(end 61.41847 -120.10136)
		(width 0.127)
		(layer "In2.Cu")
		(net "EXP_XM_ADDR_5")
	)
	(segment
		(start 61.41847 -120.86336)
		(end 61.54547 -120.73636)
		(width 0.127)
		(layer "In2.Cu")
		(net "EXP_XM_ADDR_5")
	)
	(segment
		(start 61.41847 -124.891292)
		(end 61.41847 -123.91136)
		(width 0.127)
		(layer "In2.Cu")
		(net "EXP_XM_ADDR_5")
	)
	(segment
		(start 62.227206 -116.505482)
		(end 62.407292 -116.325396)
		(width 0.127)
		(layer "In2.Cu")
		(net "EXP_XM_ADDR_5")
	)
	(segment
		(start 62.944248 -117.581426)
		(end 62.944248 -117.402102)
		(width 0.127)
		(layer "In2.Cu")
		(net "EXP_XM_ADDR_5")
	)
	(segment
		(start 102.56647 -91.39174)
		(end 104.11587 -91.39174)
		(width 0.127)
		(layer "In2.Cu")
		(net "EXP_XM_ADDR_5")
	)
	(segment
		(start 61.54547 -121.75236)
		(end 62.28207 -121.75236)
		(width 0.127)
		(layer "In2.Cu")
		(net "EXP_XM_ADDR_5")
	)
	(segment
		(start 62.407292 -116.325396)
		(end 62.586616 -116.325396)
		(width 0.127)
		(layer "In2.Cu")
		(net "EXP_XM_ADDR_5")
	)
	(segment
		(start 61.41847 -119.08536)
		(end 61.41847 -118.83136)
		(width 0.127)
		(layer "In2.Cu")
		(net "EXP_XM_ADDR_5")
	)
	(segment
		(start 62.28207 -122.76836)
		(end 62.40907 -122.64136)
		(width 0.127)
		(layer "In2.Cu")
		(net "EXP_XM_ADDR_5")
	)
	(segment
		(start 62.408816 -118.323106)
		(end 62.28207 -118.19636)
		(width 0.127)
		(layer "In2.Cu")
		(net "EXP_XM_ADDR_5")
	)
	(segment
		(start 62.40907 -123.65736)
		(end 62.40907 -123.40336)
		(width 0.127)
		(layer "In2.Cu")
		(net "EXP_XM_ADDR_5")
	)
	(segment
		(start 62.40907 -120.35536)
		(end 62.28207 -120.22836)
		(width 0.127)
		(layer "In2.Cu")
		(net "EXP_XM_ADDR_5")
	)
	(segment
		(start 62.946026 -115.965986)
		(end 62.946026 -115.664234)
		(width 0.127)
		(layer "In2.Cu")
		(net "EXP_XM_ADDR_5")
	)
	(segment
		(start 61.468762 -124.941584)
		(end 61.41847 -124.891292)
		(width 0.127)
		(layer "In2.Cu")
		(net "EXP_XM_ADDR_5")
	)
	(segment
		(start 61.54547 -121.24436)
		(end 61.41847 -121.11736)
		(width 0.127)
		(layer "In2.Cu")
		(net "EXP_XM_ADDR_5")
	)
	(segment
		(start 61.54547 -122.76836)
		(end 62.28207 -122.76836)
		(width 0.127)
		(layer "In2.Cu")
		(net "EXP_XM_ADDR_5")
	)
	(segment
		(start 104.11587 -91.39174)
		(end 104.573832 -91.849702)
		(width 0.127)
		(layer "In2.Cu")
		(net "EXP_XM_ADDR_5")
	)
	(segment
		(start 61.468762 -128.607058)
		(end 61.468762 -124.941584)
		(width 0.127)
		(layer "In2.Cu")
		(net "EXP_XM_ADDR_5")
	)
	(segment
		(start 62.28207 -120.73636)
		(end 62.40907 -120.60936)
		(width 0.127)
		(layer "In2.Cu")
		(net "EXP_XM_ADDR_5")
	)
	(segment
		(start 61.54547 -119.72036)
		(end 62.28207 -119.72036)
		(width 0.127)
		(layer "In2.Cu")
		(net "EXP_XM_ADDR_5")
	)
	(segment
		(start 61.54547 -120.73636)
		(end 62.28207 -120.73636)
		(width 0.127)
		(layer "In2.Cu")
		(net "EXP_XM_ADDR_5")
	)
	(segment
		(start 100.54463 -90.098626)
		(end 100.767642 -90.321638)
		(width 0.127)
		(layer "In2.Cu")
		(net "EXP_XM_ADDR_5")
	)
	(segment
		(start 62.944248 -117.402102)
		(end 62.227206 -116.684806)
		(width 0.127)
		(layer "In2.Cu")
		(net "EXP_XM_ADDR_5")
	)
	(segment
		(start 62.40907 -121.62536)
		(end 62.40907 -121.37136)
		(width 0.127)
		(layer "In2.Cu")
		(net "EXP_XM_ADDR_5")
	)
	(segment
		(start 62.28207 -123.27636)
		(end 61.54547 -123.27636)
		(width 0.127)
		(layer "In2.Cu")
		(net "EXP_XM_ADDR_5")
	)
	(segment
		(start 62.28207 -118.19636)
		(end 61.54547 -118.19636)
		(width 0.127)
		(layer "In2.Cu")
		(net "EXP_XM_ADDR_5")
	)
	(segment
		(start 100.228908 -89.920826)
		(end 100.230686 -89.920826)
		(width 0.127)
		(layer "In2.Cu")
		(net "EXP_XM_ADDR_5")
	)
	(segment
		(start 61.41847 -122.89536)
		(end 61.54547 -122.76836)
		(width 0.127)
		(layer "In2.Cu")
		(net "EXP_XM_ADDR_5")
	)
	(segment
		(start 61.54547 -123.78436)
		(end 62.28207 -123.78436)
		(width 0.127)
		(layer "In2.Cu")
		(net "EXP_XM_ADDR_5")
	)
	(segment
		(start 62.586616 -116.325396)
		(end 63.303658 -117.042692)
		(width 0.127)
		(layer "In2.Cu")
		(net "EXP_XM_ADDR_5")
	)
	(segment
		(start 62.40907 -122.64136)
		(end 62.40907 -122.38736)
		(width 0.127)
		(layer "In2.Cu")
		(net "EXP_XM_ADDR_5")
	)
	(segment
		(start 61.41847 -121.87936)
		(end 61.54547 -121.75236)
		(width 0.127)
		(layer "In2.Cu")
		(net "EXP_XM_ADDR_5")
	)
	(segment
		(start 62.764162 -117.761512)
		(end 62.944248 -117.581426)
		(width 0.127)
		(layer "In2.Cu")
		(net "EXP_XM_ADDR_5")
	)
	(segment
		(start 63.303658 -117.042692)
		(end 63.482982 -117.042692)
		(width 0.127)
		(layer "In2.Cu")
		(net "EXP_XM_ADDR_5")
	)
	(segment
		(start 61.41847 -123.14936)
		(end 61.41847 -122.89536)
		(width 0.127)
		(layer "In2.Cu")
		(net "EXP_XM_ADDR_5")
	)
	(segment
		(start 61.41847 -121.11736)
		(end 61.41847 -120.86336)
		(width 0.127)
		(layer "In2.Cu")
		(net "EXP_XM_ADDR_5")
	)
	(segment
		(start 61.41847 -123.91136)
		(end 61.54547 -123.78436)
		(width 0.127)
		(layer "In2.Cu")
		(net "EXP_XM_ADDR_5")
	)
	(segment
		(start 63.663068 -116.862606)
		(end 63.663068 -116.683282)
		(width 0.127)
		(layer "In2.Cu")
		(net "EXP_XM_ADDR_5")
	)
	(segment
		(start 88.693752 -89.916508)
		(end 100.22459 -89.916508)
		(width 0.127)
		(layer "In2.Cu")
		(net "EXP_XM_ADDR_5")
	)
	(segment
		(start 62.40907 -122.38736)
		(end 62.28207 -122.26036)
		(width 0.127)
		(layer "In2.Cu")
		(net "EXP_XM_ADDR_5")
	)
	(segment
		(start 62.40907 -119.33936)
		(end 62.28207 -119.21236)
		(width 0.127)
		(layer "In2.Cu")
		(net "EXP_XM_ADDR_5")
	)
	(segment
		(start 100.767642 -90.321638)
		(end 100.767642 -90.343228)
		(width 0.127)
		(layer "In2.Cu")
		(net "EXP_XM_ADDR_5")
	)
	(segment
		(start 61.867796 -117.044216)
		(end 62.584838 -117.761512)
		(width 0.127)
		(layer "In2.Cu")
		(net "EXP_XM_ADDR_5")
	)
	(segment
		(start 61.54547 -118.19636)
		(end 61.41847 -118.06936)
		(width 0.127)
		(layer "In2.Cu")
		(net "EXP_XM_ADDR_5")
	)
	(segment
		(start 61.54547 -123.27636)
		(end 61.41847 -123.14936)
		(width 0.127)
		(layer "In2.Cu")
		(net "EXP_XM_ADDR_5")
	)
	(segment
		(start 61.41847 -118.06936)
		(end 61.41847 -117.314218)
		(width 0.127)
		(layer "In2.Cu")
		(net "EXP_XM_ADDR_5")
	)
	(segment
		(start 61.41847 -122.13336)
		(end 61.41847 -121.87936)
		(width 0.127)
		(layer "In2.Cu")
		(net "EXP_XM_ADDR_5")
	)
	(segment
		(start 100.408486 -90.098626)
		(end 100.54463 -90.098626)
		(width 0.127)
		(layer "In2.Cu")
		(net "EXP_XM_ADDR_5")
	)
	(segment
		(start 62.946026 -115.664234)
		(end 88.693752 -89.916508)
		(width 0.127)
		(layer "In2.Cu")
		(net "EXP_XM_ADDR_5")
	)
	(segment
		(start 100.22459 -89.916508)
		(end 100.228908 -89.920826)
		(width 0.127)
		(layer "In2.Cu")
		(net "EXP_XM_ADDR_5")
	)
	(segment
		(start 109.333792 -113.529364)
		(end 109.333792 -113.1062)
		(width 0.1016)
		(layer "F.Cu")
		(net "SAS_HDD_TX7_P")
	)
	(segment
		(start 109.48797 -114.0206)
		(end 109.48797 -113.788698)
		(width 0.1016)
		(layer "F.Cu")
		(net "SAS_HDD_TX7_P")
	)
	(segment
		(start 109.718348 -112.177576)
		(end 110.87862 -111.017304)
		(width 0.1016)
		(layer "F.Cu")
		(net "SAS_HDD_TX7_P")
	)
	(segment
		(start 111.34979 -109.879384)
		(end 111.34979 -107.769152)
		(width 0.1016)
		(layer "F.Cu")
		(net "SAS_HDD_TX7_P")
	)
	(segment
		(start 111.349536 -107.769152)
		(end 111.34979 -107.350052)
		(width 0.1016)
		(layer "F.Cu")
		(net "SAS_HDD_TX7_P")
	)
	(segment
		(start 109.450886 -113.699036)
		(end 109.370876 -113.619026)
		(width 0.1016)
		(layer "F.Cu")
		(net "SAS_HDD_TX7_P")
	)
	(segment
		(start 111.34979 -107.769152)
		(end 111.349536 -107.769152)
		(width 0.1016)
		(layer "F.Cu")
		(net "SAS_HDD_TX7_P")
	)
	(arc
		(start 109.333792 -113.1062)
		(mid 109.433737 -112.603654)
		(end 109.718348 -112.177576)
		(width 0.1016)
		(layer "F.Cu")
		(net "SAS_HDD_TX7_P")
	)
	(arc
		(start 109.48797 -113.788698)
		(mid 109.478337 -113.74018)
		(end 109.450886 -113.699036)
		(width 0.1016)
		(layer "F.Cu")
		(net "SAS_HDD_TX7_P")
	)
	(arc
		(start 110.87862 -111.017304)
		(mid 111.227381 -110.495207)
		(end 111.34979 -109.879384)
		(width 0.1016)
		(layer "F.Cu")
		(net "SAS_HDD_TX7_P")
	)
	(arc
		(start 109.370876 -113.619026)
		(mid 109.343443 -113.577875)
		(end 109.333792 -113.529364)
		(width 0.1016)
		(layer "F.Cu")
		(net "SAS_HDD_TX7_P")
	)
	(segment
		(start 140.7541 -47.541942)
		(end 140.753846 -47.542196)
		(width 0.1143)
		(layer "F.Cu")
		(net "XM_ADDR_10")
	)
	(segment
		(start 113.150142 -54.19979)
		(end 113.464848 -54.19979)
		(width 0.1143)
		(layer "F.Cu")
		(net "XM_ADDR_10")
	)
	(segment
		(start 115.007898 -54.003702)
		(end 115.763802 -54.003702)
		(width 0.1143)
		(layer "F.Cu")
		(net "XM_ADDR_10")
	)
	(segment
		(start 140.753846 -47.542196)
		(end 140.753846 -48.932846)
		(width 0.1143)
		(layer "F.Cu")
		(net "XM_ADDR_10")
	)
	(segment
		(start 113.807748 -53.85689)
		(end 114.083084 -53.85689)
		(width 0.1143)
		(layer "F.Cu")
		(net "XM_ADDR_10")
	)
	(segment
		(start 115.890802 -54.130702)
		(end 115.890802 -54.6354)
		(width 0.1143)
		(layer "F.Cu")
		(net "XM_ADDR_10")
	)
	(segment
		(start 139.599416 -45.78858)
		(end 140.7541 -46.943264)
		(width 0.1143)
		(layer "F.Cu")
		(net "XM_ADDR_10")
	)
	(segment
		(start 140.753846 -48.932846)
		(end 141.097 -49.276)
		(width 0.1143)
		(layer "F.Cu")
		(net "XM_ADDR_10")
	)
	(segment
		(start 114.880898 -54.130702)
		(end 115.007898 -54.003702)
		(width 0.1143)
		(layer "F.Cu")
		(net "XM_ADDR_10")
	)
	(segment
		(start 115.890802 -54.6354)
		(end 115.763802 -54.7624)
		(width 0.1143)
		(layer "F.Cu")
		(net "XM_ADDR_10")
	)
	(segment
		(start 113.464848 -54.19979)
		(end 113.807748 -53.85689)
		(width 0.1143)
		(layer "F.Cu")
		(net "XM_ADDR_10")
	)
	(segment
		(start 139.599416 -42.7101)
		(end 139.599416 -45.78858)
		(width 0.1143)
		(layer "F.Cu")
		(net "XM_ADDR_10")
	)
	(segment
		(start 114.880898 -54.335934)
		(end 114.880898 -54.130702)
		(width 0.1143)
		(layer "F.Cu")
		(net "XM_ADDR_10")
	)
	(segment
		(start 114.286538 -54.060344)
		(end 114.286538 -54.335934)
		(width 0.1143)
		(layer "F.Cu")
		(net "XM_ADDR_10")
	)
	(segment
		(start 115.763802 -54.7624)
		(end 115.272566 -54.7624)
		(width 0.1143)
		(layer "F.Cu")
		(net "XM_ADDR_10")
	)
	(segment
		(start 114.083084 -53.85689)
		(end 114.286538 -54.060344)
		(width 0.1143)
		(layer "F.Cu")
		(net "XM_ADDR_10")
	)
	(segment
		(start 114.286538 -54.335934)
		(end 114.413538 -54.462934)
		(width 0.1143)
		(layer "F.Cu")
		(net "XM_ADDR_10")
	)
	(segment
		(start 114.753898 -54.462934)
		(end 114.880898 -54.335934)
		(width 0.1143)
		(layer "F.Cu")
		(net "XM_ADDR_10")
	)
	(segment
		(start 114.413538 -54.462934)
		(end 114.753898 -54.462934)
		(width 0.1143)
		(layer "F.Cu")
		(net "XM_ADDR_10")
	)
	(segment
		(start 115.763802 -54.003702)
		(end 115.890802 -54.130702)
		(width 0.1143)
		(layer "F.Cu")
		(net "XM_ADDR_10")
	)
	(segment
		(start 140.7541 -46.943264)
		(end 140.7541 -47.541942)
		(width 0.1143)
		(layer "F.Cu")
		(net "XM_ADDR_10")
	)
	(via
		(at 141.097 -48.387)
		(size 0.7112)
		(drill 0.3556)
		(layers "F.Cu" "B.Cu")
		(net "XM_ADDR_10")
	)
	(via
		(at 115.272566 -54.7624)
		(size 0.508)
		(drill 0.254)
		(layers "F.Cu" "B.Cu")
		(net "XM_ADDR_10")
	)
	(via
		(at 141.097 -49.276)
		(size 0.5588)
		(drill 0.3048)
		(layers "F.Cu" "B.Cu")
		(net "XM_ADDR_10")
	)
	(segment
		(start 141.097 -48.387)
		(end 141.097 -49.276)
		(width 0.1143)
		(layer "B.Cu")
		(net "XM_ADDR_10")
	)
	(segment
		(start 141.097 -49.276)
		(end 140.8557 -49.0347)
		(width 0.127)
		(layer "In5.Cu")
		(net "XM_ADDR_10")
	)
	(segment
		(start 115.146582 -56.186832)
		(end 114.63274 -56.186832)
		(width 0.127)
		(layer "In5.Cu")
		(net "XM_ADDR_10")
	)
	(segment
		(start 115.586764 -54.073044)
		(end 114.825526 -54.073044)
		(width 0.127)
		(layer "In5.Cu")
		(net "XM_ADDR_10")
	)
	(segment
		(start 110.469426 -56.80075)
		(end 110.596426 -56.92775)
		(width 0.127)
		(layer "In5.Cu")
		(net "XM_ADDR_10")
	)
	(segment
		(start 125.475746 -52.196238)
		(end 123.773184 -53.8988)
		(width 0.127)
		(layer "In5.Cu")
		(net "XM_ADDR_10")
	)
	(segment
		(start 140.8557 -49.0347)
		(end 135.19404 -49.0347)
		(width 0.127)
		(layer "In5.Cu")
		(net "XM_ADDR_10")
	)
	(segment
		(start 115.048284 -56.931306)
		(end 115.273582 -56.706008)
		(width 0.127)
		(layer "In5.Cu")
		(net "XM_ADDR_10")
	)
	(segment
		(start 114.50574 -56.059832)
		(end 114.50574 -55.294784)
		(width 0.127)
		(layer "In5.Cu")
		(net "XM_ADDR_10")
	)
	(segment
		(start 116.629942 -54.640226)
		(end 116.153946 -54.640226)
		(width 0.127)
		(layer "In5.Cu")
		(net "XM_ADDR_10")
	)
	(segment
		(start 114.182652 -56.931306)
		(end 115.048284 -56.931306)
		(width 0.127)
		(layer "In5.Cu")
		(net "XM_ADDR_10")
	)
	(segment
		(start 123.773184 -53.8988)
		(end 117.371368 -53.8988)
		(width 0.127)
		(layer "In5.Cu")
		(net "XM_ADDR_10")
	)
	(segment
		(start 131.674616 -52.196492)
		(end 131.674362 -52.196238)
		(width 0.127)
		(layer "In5.Cu")
		(net "XM_ADDR_10")
	)
	(segment
		(start 113.765076 -56.268112)
		(end 110.596426 -56.268112)
		(width 0.127)
		(layer "In5.Cu")
		(net "XM_ADDR_10")
	)
	(segment
		(start 117.371368 -53.8988)
		(end 116.629942 -54.640226)
		(width 0.127)
		(layer "In5.Cu")
		(net "XM_ADDR_10")
	)
	(segment
		(start 115.273582 -56.313832)
		(end 115.146582 -56.186832)
		(width 0.127)
		(layer "In5.Cu")
		(net "XM_ADDR_10")
	)
	(segment
		(start 131.674362 -52.196238)
		(end 125.475746 -52.196238)
		(width 0.127)
		(layer "In5.Cu")
		(net "XM_ADDR_10")
	)
	(segment
		(start 135.19404 -49.0347)
		(end 132.032248 -52.196492)
		(width 0.127)
		(layer "In5.Cu")
		(net "XM_ADDR_10")
	)
	(segment
		(start 115.273582 -56.706008)
		(end 115.273582 -56.313832)
		(width 0.127)
		(layer "In5.Cu")
		(net "XM_ADDR_10")
	)
	(segment
		(start 114.825526 -54.073044)
		(end 113.900712 -54.997858)
		(width 0.127)
		(layer "In5.Cu")
		(net "XM_ADDR_10")
	)
	(segment
		(start 132.032248 -52.196492)
		(end 131.674616 -52.196492)
		(width 0.127)
		(layer "In5.Cu")
		(net "XM_ADDR_10")
	)
	(segment
		(start 113.900712 -56.132476)
		(end 113.765076 -56.268112)
		(width 0.127)
		(layer "In5.Cu")
		(net "XM_ADDR_10")
	)
	(segment
		(start 110.596426 -56.268112)
		(end 110.469426 -56.395112)
		(width 0.127)
		(layer "In5.Cu")
		(net "XM_ADDR_10")
	)
	(segment
		(start 113.900712 -54.997858)
		(end 113.900712 -56.132476)
		(width 0.127)
		(layer "In5.Cu")
		(net "XM_ADDR_10")
	)
	(segment
		(start 116.153946 -54.640226)
		(end 115.586764 -54.073044)
		(width 0.127)
		(layer "In5.Cu")
		(net "XM_ADDR_10")
	)
	(segment
		(start 110.596426 -56.92775)
		(end 114.179096 -56.92775)
		(width 0.127)
		(layer "In5.Cu")
		(net "XM_ADDR_10")
	)
	(segment
		(start 114.50574 -55.294784)
		(end 115.038124 -54.7624)
		(width 0.127)
		(layer "In5.Cu")
		(net "XM_ADDR_10")
	)
	(segment
		(start 115.038124 -54.7624)
		(end 115.272566 -54.7624)
		(width 0.127)
		(layer "In5.Cu")
		(net "XM_ADDR_10")
	)
	(segment
		(start 114.63274 -56.186832)
		(end 114.50574 -56.059832)
		(width 0.127)
		(layer "In5.Cu")
		(net "XM_ADDR_10")
	)
	(segment
		(start 110.469426 -56.395112)
		(end 110.469426 -56.80075)
		(width 0.127)
		(layer "In5.Cu")
		(net "XM_ADDR_10")
	)
	(segment
		(start 114.179096 -56.92775)
		(end 114.182652 -56.931306)
		(width 0.127)
		(layer "In5.Cu")
		(net "XM_ADDR_10")
	)
	(segment
		(start 103.549958 -54.99989)
		(end 103.549958 -54.998112)
		(width 0.1143)
		(layer "F.Cu")
		(net "JTAG_IOC_TCK")
	)
	(segment
		(start 103.549958 -54.998112)
		(end 103.149146 -54.5973)
		(width 0.1143)
		(layer "F.Cu")
		(net "JTAG_IOC_TCK")
	)
	(via
		(at 103.149146 -54.5973)
		(size 0.508)
		(drill 0.254)
		(layers "F.Cu" "B.Cu")
		(net "JTAG_IOC_TCK")
	)
	(segment
		(start 102.343966 -58.4835)
		(end 102.089966 -58.2295)
		(width 0.1143)
		(layer "B.Cu")
		(net "JTAG_IOC_TCK")
	)
	(segment
		(start 102.089966 -56.896)
		(end 102.089966 -57.2262)
		(width 0.1143)
		(layer "B.Cu")
		(net "JTAG_IOC_TCK")
	)
	(segment
		(start 103.149146 -54.5973)
		(end 103.149146 -55.83682)
		(width 0.1143)
		(layer "B.Cu")
		(net "JTAG_IOC_TCK")
	)
	(segment
		(start 102.089966 -58.2295)
		(end 102.089966 -57.2262)
		(width 0.1143)
		(layer "B.Cu")
		(net "JTAG_IOC_TCK")
	)
	(segment
		(start 103.149146 -55.83682)
		(end 102.089966 -56.896)
		(width 0.1143)
		(layer "B.Cu")
		(net "JTAG_IOC_TCK")
	)
	(segment
		(start 204.5335 -92.329)
		(end 204.089 -92.329)
		(width 0.127)
		(layer "F.Cu")
		(net "P1V5_E")
	)
	(via
		(at 208.026 -120.142)
		(size 0.7112)
		(drill 0.4064)
		(layers "F.Cu" "B.Cu")
		(net "P1V5_E")
	)
	(via
		(at 239.649 -123.952)
		(size 0.7112)
		(drill 0.4064)
		(layers "F.Cu" "B.Cu")
		(net "P1V5_E")
	)
	(via
		(at 244.094 -125.73)
		(size 0.7112)
		(drill 0.3556)
		(layers "F.Cu" "B.Cu")
		(net "P1V5_E")
	)
	(via
		(at 202.692 -101.727)
		(size 0.5588)
		(drill 0.3048)
		(layers "F.Cu" "B.Cu")
		(net "P1V5_E")
	)
	(via
		(at 320.802 -182.118)
		(size 0.7112)
		(drill 0.4064)
		(layers "F.Cu" "B.Cu")
		(net "P1V5_E")
	)
	(via
		(at 309.118 -136.398)
		(size 0.7112)
		(drill 0.4064)
		(layers "F.Cu" "B.Cu")
		(net "P1V5_E")
	)
	(via
		(at 201.168 -90.551)
		(size 0.7112)
		(drill 0.4064)
		(layers "F.Cu" "B.Cu")
		(net "P1V5_E")
	)
	(segment
		(start 204.216 -103.632)
		(end 204.216 -100.203)
		(width 1.016)
		(layer "B.Cu")
		(net "P1V5_E")
	)
	(segment
		(start 244.094 -125.73)
		(end 257.302 -125.73)
		(width 1.016)
		(layer "B.Cu")
		(net "P1V5_E")
	)
	(segment
		(start 202.692 -92.075)
		(end 201.168 -90.551)
		(width 1.016)
		(layer "B.Cu")
		(net "P1V5_E")
	)
	(segment
		(start 204.216 -100.203)
		(end 202.692 -98.679)
		(width 1.016)
		(layer "B.Cu")
		(net "P1V5_E")
	)
	(segment
		(start 272.796 -130.429)
		(end 303.149 -130.429)
		(width 1.016)
		(layer "B.Cu")
		(net "P1V5_E")
	)
	(segment
		(start 319.8495 -181.737)
		(end 320.421 -181.737)
		(width 0.508)
		(layer "B.Cu")
		(net "P1V5_E")
	)
	(segment
		(start 320.421 -181.737)
		(end 320.802 -182.118)
		(width 0.508)
		(layer "B.Cu")
		(net "P1V5_E")
	)
	(segment
		(start 207.899 -120.015)
		(end 207.899 -119.126)
		(width 1.016)
		(layer "B.Cu")
		(net "P1V5_E")
	)
	(segment
		(start 257.302 -125.73)
		(end 258.94665 -124.08535)
		(width 1.016)
		(layer "B.Cu")
		(net "P1V5_E")
	)
	(segment
		(start 266.45235 -124.08535)
		(end 272.796 -130.429)
		(width 1.016)
		(layer "B.Cu")
		(net "P1V5_E")
	)
	(segment
		(start 241.427 -125.73)
		(end 239.649 -123.952)
		(width 1.016)
		(layer "B.Cu")
		(net "P1V5_E")
	)
	(segment
		(start 244.094 -125.73)
		(end 241.427 -125.73)
		(width 1.016)
		(layer "B.Cu")
		(net "P1V5_E")
	)
	(segment
		(start 303.149 -130.429)
		(end 309.118 -136.398)
		(width 1.016)
		(layer "B.Cu")
		(net "P1V5_E")
	)
	(segment
		(start 199.898 -101.727)
		(end 202.692 -101.727)
		(width 0.508)
		(layer "B.Cu")
		(net "P1V5_E")
	)
	(segment
		(start 208.026 -120.142)
		(end 207.899 -120.015)
		(width 1.016)
		(layer "B.Cu")
		(net "P1V5_E")
	)
	(segment
		(start 202.692 -113.919)
		(end 202.692 -105.156)
		(width 1.016)
		(layer "B.Cu")
		(net "P1V5_E")
	)
	(segment
		(start 207.899 -119.126)
		(end 202.692 -113.919)
		(width 1.016)
		(layer "B.Cu")
		(net "P1V5_E")
	)
	(segment
		(start 258.94665 -124.08535)
		(end 266.45235 -124.08535)
		(width 1.016)
		(layer "B.Cu")
		(net "P1V5_E")
	)
	(segment
		(start 202.692 -105.156)
		(end 204.216 -103.632)
		(width 1.016)
		(layer "B.Cu")
		(net "P1V5_E")
	)
	(segment
		(start 202.692 -98.679)
		(end 202.692 -92.075)
		(width 1.016)
		(layer "B.Cu")
		(net "P1V5_E")
	)
	(segment
		(start 320.802 -180.086)
		(end 320.802 -182.118)
		(width 1.016)
		(layer "In2.Cu")
		(net "P1V5_E")
	)
	(segment
		(start 314.546742 -150.793958)
		(end 314.579 -150.826216)
		(width 1.016)
		(layer "In2.Cu")
		(net "P1V5_E")
	)
	(segment
		(start 310.668416 -136.0932)
		(end 311.3405 -136.765284)
		(width 1.016)
		(layer "In2.Cu")
		(net "P1V5_E")
	)
	(segment
		(start 311.3405 -136.765284)
		(end 311.3405 -140.33119)
		(width 1.016)
		(layer "In2.Cu")
		(net "P1V5_E")
	)
	(segment
		(start 208.026 -120.142)
		(end 208.153 -120.269)
		(width 1.016)
		(layer "In2.Cu")
		(net "P1V5_E")
	)
	(segment
		(start 309.4228 -136.0932)
		(end 310.668416 -136.0932)
		(width 1.016)
		(layer "In2.Cu")
		(net "P1V5_E")
	)
	(segment
		(start 225.044 -120.269)
		(end 225.679 -120.904)
		(width 1.016)
		(layer "In2.Cu")
		(net "P1V5_E")
	)
	(segment
		(start 309.118 -136.398)
		(end 309.4228 -136.0932)
		(width 1.016)
		(layer "In2.Cu")
		(net "P1V5_E")
	)
	(segment
		(start 318.135 -161.671)
		(end 318.135 -177.419)
		(width 1.016)
		(layer "In2.Cu")
		(net "P1V5_E")
	)
	(segment
		(start 314.579 -150.826216)
		(end 314.579 -158.115)
		(width 1.016)
		(layer "In2.Cu")
		(net "P1V5_E")
	)
	(segment
		(start 236.601 -120.904)
		(end 239.649 -123.952)
		(width 1.016)
		(layer "In2.Cu")
		(net "P1V5_E")
	)
	(segment
		(start 208.153 -120.269)
		(end 225.044 -120.269)
		(width 1.016)
		(layer "In2.Cu")
		(net "P1V5_E")
	)
	(segment
		(start 311.3405 -140.33119)
		(end 314.546742 -143.537432)
		(width 1.016)
		(layer "In2.Cu")
		(net "P1V5_E")
	)
	(segment
		(start 314.579 -158.115)
		(end 318.135 -161.671)
		(width 1.016)
		(layer "In2.Cu")
		(net "P1V5_E")
	)
	(segment
		(start 225.679 -120.904)
		(end 236.601 -120.904)
		(width 1.016)
		(layer "In2.Cu")
		(net "P1V5_E")
	)
	(segment
		(start 314.546742 -143.537432)
		(end 314.546742 -150.793958)
		(width 1.016)
		(layer "In2.Cu")
		(net "P1V5_E")
	)
	(segment
		(start 318.135 -177.419)
		(end 320.802 -180.086)
		(width 1.016)
		(layer "In2.Cu")
		(net "P1V5_E")
	)
	(segment
		(start 93.373702 -99.924108)
		(end 93.51391 -99.924108)
		(width 0.1143)
		(layer "F.Cu")
		(net "EXP_XM_ADDR_15")
	)
	(segment
		(start 62.429644 -141.96314)
		(end 62.543944 -141.84884)
		(width 0.1143)
		(layer "F.Cu")
		(net "EXP_XM_ADDR_15")
	)
	(segment
		(start 62.658244 -138.392662)
		(end 67.42557 -138.392662)
		(width 0.1143)
		(layer "F.Cu")
		(net "EXP_XM_ADDR_15")
	)
	(segment
		(start 62.543944 -141.84884)
		(end 62.543944 -141.48054)
		(width 0.1143)
		(layer "F.Cu")
		(net "EXP_XM_ADDR_15")
	)
	(segment
		(start 62.086744 -141.84884)
		(end 62.201044 -141.96314)
		(width 0.1143)
		(layer "F.Cu")
		(net "EXP_XM_ADDR_15")
	)
	(segment
		(start 62.201044 -141.96314)
		(end 62.429644 -141.96314)
		(width 0.1143)
		(layer "F.Cu")
		(net "EXP_XM_ADDR_15")
	)
	(segment
		(start 62.95009 -139.99464)
		(end 62.658244 -139.99464)
		(width 0.1143)
		(layer "F.Cu")
		(net "EXP_XM_ADDR_15")
	)
	(segment
		(start 62.658244 -139.99464)
		(end 62.543944 -139.88034)
		(width 0.1143)
		(layer "F.Cu")
		(net "EXP_XM_ADDR_15")
	)
	(segment
		(start 62.658244 -140.90904)
		(end 62.543944 -140.79474)
		(width 0.1143)
		(layer "F.Cu")
		(net "EXP_XM_ADDR_15")
	)
	(segment
		(start 62.543944 -140.79474)
		(end 62.543944 -140.56614)
		(width 0.1143)
		(layer "F.Cu")
		(net "EXP_XM_ADDR_15")
	)
	(segment
		(start 62.086744 -138.506962)
		(end 62.086744 -141.84884)
		(width 0.1143)
		(layer "F.Cu")
		(net "EXP_XM_ADDR_15")
	)
	(segment
		(start 92.66047 -100.076)
		(end 93.22181 -100.076)
		(width 0.1143)
		(layer "F.Cu")
		(net "EXP_XM_ADDR_15")
	)
	(segment
		(start 62.658244 -140.45184)
		(end 62.95009 -140.45184)
		(width 0.1143)
		(layer "F.Cu")
		(net "EXP_XM_ADDR_15")
	)
	(segment
		(start 62.543944 -138.506962)
		(end 62.658244 -138.392662)
		(width 0.1143)
		(layer "F.Cu")
		(net "EXP_XM_ADDR_15")
	)
	(segment
		(start 63.06439 -141.25194)
		(end 63.06439 -141.02334)
		(width 0.1143)
		(layer "F.Cu")
		(net "EXP_XM_ADDR_15")
	)
	(segment
		(start 61.972444 -138.392662)
		(end 62.086744 -138.506962)
		(width 0.1143)
		(layer "F.Cu")
		(net "EXP_XM_ADDR_15")
	)
	(segment
		(start 63.06439 -141.02334)
		(end 62.95009 -140.90904)
		(width 0.1143)
		(layer "F.Cu")
		(net "EXP_XM_ADDR_15")
	)
	(segment
		(start 63.06439 -140.33754)
		(end 63.06439 -140.10894)
		(width 0.1143)
		(layer "F.Cu")
		(net "EXP_XM_ADDR_15")
	)
	(segment
		(start 62.543944 -139.88034)
		(end 62.543944 -138.506962)
		(width 0.1143)
		(layer "F.Cu")
		(net "EXP_XM_ADDR_15")
	)
	(segment
		(start 63.06439 -140.10894)
		(end 62.95009 -139.99464)
		(width 0.1143)
		(layer "F.Cu")
		(net "EXP_XM_ADDR_15")
	)
	(segment
		(start 62.658244 -141.36624)
		(end 62.95009 -141.36624)
		(width 0.1143)
		(layer "F.Cu")
		(net "EXP_XM_ADDR_15")
	)
	(segment
		(start 62.95009 -140.90904)
		(end 62.658244 -140.90904)
		(width 0.1143)
		(layer "F.Cu")
		(net "EXP_XM_ADDR_15")
	)
	(segment
		(start 62.543944 -140.56614)
		(end 62.658244 -140.45184)
		(width 0.1143)
		(layer "F.Cu")
		(net "EXP_XM_ADDR_15")
	)
	(segment
		(start 56.558942 -138.392662)
		(end 61.972444 -138.392662)
		(width 0.1143)
		(layer "F.Cu")
		(net "EXP_XM_ADDR_15")
	)
	(segment
		(start 62.95009 -141.36624)
		(end 63.06439 -141.25194)
		(width 0.1143)
		(layer "F.Cu")
		(net "EXP_XM_ADDR_15")
	)
	(segment
		(start 107.349798 -95.350076)
		(end 106.849672 -95.850202)
		(width 0.1143)
		(layer "F.Cu")
		(net "EXP_XM_ADDR_15")
	)
	(segment
		(start 62.95009 -140.45184)
		(end 63.06439 -140.33754)
		(width 0.1143)
		(layer "F.Cu")
		(net "EXP_XM_ADDR_15")
	)
	(segment
		(start 62.543944 -141.48054)
		(end 62.658244 -141.36624)
		(width 0.1143)
		(layer "F.Cu")
		(net "EXP_XM_ADDR_15")
	)
	(segment
		(start 93.22181 -100.076)
		(end 93.373702 -99.924108)
		(width 0.1143)
		(layer "F.Cu")
		(net "EXP_XM_ADDR_15")
	)
	(via
		(at 67.42557 -138.392662)
		(size 0.5588)
		(drill 0.3048)
		(layers "F.Cu" "B.Cu")
		(net "EXP_XM_ADDR_15")
	)
	(via
		(at 106.849672 -95.850202)
		(size 0.508)
		(drill 0.254)
		(layers "F.Cu" "B.Cu")
		(net "EXP_XM_ADDR_15")
	)
	(via
		(at 93.51391 -99.924108)
		(size 0.508)
		(drill 0.254)
		(layers "F.Cu" "B.Cu")
		(net "EXP_XM_ADDR_15")
	)
	(via
		(at 66.5988 -138.43)
		(size 0.7112)
		(drill 0.3556)
		(layers "F.Cu" "B.Cu")
		(net "EXP_XM_ADDR_15")
	)
	(segment
		(start 67.42557 -138.392662)
		(end 66.636138 -138.392662)
		(width 0.1143)
		(layer "B.Cu")
		(net "EXP_XM_ADDR_15")
	)
	(segment
		(start 66.636138 -138.392662)
		(end 66.5988 -138.43)
		(width 0.1143)
		(layer "B.Cu")
		(net "EXP_XM_ADDR_15")
	)
	(segment
		(start 93.32087 -100.013008)
		(end 90.947494 -100.013008)
		(width 0.127)
		(layer "In2.Cu")
		(net "EXP_XM_ADDR_15")
	)
	(segment
		(start 103.09733 -95.07474)
		(end 101.395276 -96.776794)
		(width 0.127)
		(layer "In2.Cu")
		(net "EXP_XM_ADDR_15")
	)
	(segment
		(start 90.389202 -100.5713)
		(end 89.760298 -100.5713)
		(width 0.127)
		(layer "In2.Cu")
		(net "EXP_XM_ADDR_15")
	)
	(segment
		(start 87.70493 -105.320592)
		(end 85.766402 -107.25912)
		(width 0.127)
		(layer "In2.Cu")
		(net "EXP_XM_ADDR_15")
	)
	(segment
		(start 70.81139 -118.533164)
		(end 70.81139 -128.547876)
		(width 0.127)
		(layer "In2.Cu")
		(net "EXP_XM_ADDR_15")
	)
	(segment
		(start 82.08518 -107.25912)
		(end 71.127366 -118.217188)
		(width 0.127)
		(layer "In2.Cu")
		(net "EXP_XM_ADDR_15")
	)
	(segment
		(start 106.539792 -95.850202)
		(end 105.76433 -95.07474)
		(width 0.127)
		(layer "In2.Cu")
		(net "EXP_XM_ADDR_15")
	)
	(segment
		(start 93.51391 -99.924108)
		(end 93.40977 -99.924108)
		(width 0.127)
		(layer "In2.Cu")
		(net "EXP_XM_ADDR_15")
	)
	(segment
		(start 70.81139 -128.547876)
		(end 68.86067 -130.498596)
		(width 0.127)
		(layer "In2.Cu")
		(net "EXP_XM_ADDR_15")
	)
	(segment
		(start 89.760298 -100.5713)
		(end 87.70493 -102.626668)
		(width 0.127)
		(layer "In2.Cu")
		(net "EXP_XM_ADDR_15")
	)
	(segment
		(start 90.947494 -100.013008)
		(end 90.389202 -100.5713)
		(width 0.127)
		(layer "In2.Cu")
		(net "EXP_XM_ADDR_15")
	)
	(segment
		(start 85.766402 -107.25912)
		(end 82.08518 -107.25912)
		(width 0.127)
		(layer "In2.Cu")
		(net "EXP_XM_ADDR_15")
	)
	(segment
		(start 68.55587 -130.803904)
		(end 68.55587 -132.846064)
		(width 0.127)
		(layer "In2.Cu")
		(net "EXP_XM_ADDR_15")
	)
	(segment
		(start 68.55587 -132.846064)
		(end 68.07327 -133.328664)
		(width 0.127)
		(layer "In2.Cu")
		(net "EXP_XM_ADDR_15")
	)
	(segment
		(start 68.86067 -130.49885)
		(end 68.749672 -130.610102)
		(width 0.127)
		(layer "In2.Cu")
		(net "EXP_XM_ADDR_15")
	)
	(segment
		(start 93.40977 -99.924108)
		(end 93.32087 -100.013008)
		(width 0.127)
		(layer "In2.Cu")
		(net "EXP_XM_ADDR_15")
	)
	(segment
		(start 93.724984 -99.994974)
		(end 93.654118 -99.924108)
		(width 0.127)
		(layer "In2.Cu")
		(net "EXP_XM_ADDR_15")
	)
	(segment
		(start 68.86067 -130.498596)
		(end 68.86067 -130.49885)
		(width 0.127)
		(layer "In2.Cu")
		(net "EXP_XM_ADDR_15")
	)
	(segment
		(start 68.07327 -135.263382)
		(end 67.42557 -135.911082)
		(width 0.127)
		(layer "In2.Cu")
		(net "EXP_XM_ADDR_15")
	)
	(segment
		(start 67.42557 -135.911082)
		(end 67.42557 -138.392662)
		(width 0.127)
		(layer "In2.Cu")
		(net "EXP_XM_ADDR_15")
	)
	(segment
		(start 97.09404 -96.776794)
		(end 95.283274 -98.58756)
		(width 0.127)
		(layer "In2.Cu")
		(net "EXP_XM_ADDR_15")
	)
	(segment
		(start 95.283274 -98.58756)
		(end 95.283274 -98.885502)
		(width 0.127)
		(layer "In2.Cu")
		(net "EXP_XM_ADDR_15")
	)
	(segment
		(start 101.395276 -96.776794)
		(end 97.09404 -96.776794)
		(width 0.127)
		(layer "In2.Cu")
		(net "EXP_XM_ADDR_15")
	)
	(segment
		(start 95.283274 -98.885502)
		(end 94.173802 -99.994974)
		(width 0.127)
		(layer "In2.Cu")
		(net "EXP_XM_ADDR_15")
	)
	(segment
		(start 106.849672 -95.850202)
		(end 106.539792 -95.850202)
		(width 0.127)
		(layer "In2.Cu")
		(net "EXP_XM_ADDR_15")
	)
	(segment
		(start 93.654118 -99.924108)
		(end 93.51391 -99.924108)
		(width 0.127)
		(layer "In2.Cu")
		(net "EXP_XM_ADDR_15")
	)
	(segment
		(start 94.173802 -99.994974)
		(end 93.724984 -99.994974)
		(width 0.127)
		(layer "In2.Cu")
		(net "EXP_XM_ADDR_15")
	)
	(segment
		(start 105.76433 -95.07474)
		(end 103.09733 -95.07474)
		(width 0.127)
		(layer "In2.Cu")
		(net "EXP_XM_ADDR_15")
	)
	(segment
		(start 87.70493 -102.626668)
		(end 87.70493 -105.320592)
		(width 0.127)
		(layer "In2.Cu")
		(net "EXP_XM_ADDR_15")
	)
	(segment
		(start 68.749672 -130.610102)
		(end 68.55587 -130.803904)
		(width 0.127)
		(layer "In2.Cu")
		(net "EXP_XM_ADDR_15")
	)
	(segment
		(start 71.127366 -118.217188)
		(end 70.81139 -118.533164)
		(width 0.127)
		(layer "In2.Cu")
		(net "EXP_XM_ADDR_15")
	)
	(segment
		(start 68.07327 -133.328664)
		(end 68.07327 -135.263382)
		(width 0.127)
		(layer "In2.Cu")
		(net "EXP_XM_ADDR_15")
	)
	(segment
		(start 110.63097 -114.0206)
		(end 110.63097 -113.748058)
		(width 0.1016)
		(layer "F.Cu")
		(net "SAS_HDD_TX6_N")
	)
	(segment
		(start 110.668054 -113.658396)
		(end 110.746286 -113.580164)
		(width 0.1016)
		(layer "F.Cu")
		(net "SAS_HDD_TX6_N")
	)
	(segment
		(start 112.183164 -105.51668)
		(end 112.349788 -105.350056)
		(width 0.1016)
		(layer "F.Cu")
		(net "SAS_HDD_TX6_N")
	)
	(segment
		(start 111.73079 -111.034322)
		(end 111.73079 -106.60888)
		(width 0.1016)
		(layer "F.Cu")
		(net "SAS_HDD_TX6_N")
	)
	(segment
		(start 111.204248 -112.054132)
		(end 111.382048 -111.876332)
		(width 0.1016)
		(layer "F.Cu")
		(net "SAS_HDD_TX6_N")
	)
	(segment
		(start 110.78337 -113.490502)
		(end 110.78337 -113.070894)
		(width 0.1016)
		(layer "F.Cu")
		(net "SAS_HDD_TX6_N")
	)
	(arc
		(start 110.63097 -113.748058)
		(mid 110.640603 -113.69954)
		(end 110.668054 -113.658396)
		(width 0.1016)
		(layer "F.Cu")
		(net "SAS_HDD_TX6_N")
	)
	(arc
		(start 111.382048 -111.876332)
		(mid 111.640177 -111.490015)
		(end 111.73079 -111.034322)
		(width 0.1016)
		(layer "F.Cu")
		(net "SAS_HDD_TX6_N")
	)
	(arc
		(start 111.73079 -106.60888)
		(mid 111.848364 -106.017797)
		(end 112.183164 -105.51668)
		(width 0.1016)
		(layer "F.Cu")
		(net "SAS_HDD_TX6_N")
	)
	(arc
		(start 110.746286 -113.580164)
		(mid 110.773719 -113.539013)
		(end 110.78337 -113.490502)
		(width 0.1016)
		(layer "F.Cu")
		(net "SAS_HDD_TX6_N")
	)
	(arc
		(start 110.78337 -113.070894)
		(mid 110.892653 -112.52064)
		(end 111.204248 -112.054132)
		(width 0.1016)
		(layer "F.Cu")
		(net "SAS_HDD_TX6_N")
	)
	(segment
		(start 107.34802 -57.47258)
		(end 107.34802 -57.716928)
		(width 0.1143)
		(layer "F.Cu")
		(net "XM_RB")
	)
	(segment
		(start 109.0295 -59.8805)
		(end 108.331 -59.182)
		(width 0.1143)
		(layer "F.Cu")
		(net "XM_RB")
	)
	(segment
		(start 109.0295 -60.071)
		(end 109.0295 -59.8805)
		(width 0.1143)
		(layer "F.Cu")
		(net "XM_RB")
	)
	(segment
		(start 107.34802 -57.74182)
		(end 107.34802 -57.716928)
		(width 0.1143)
		(layer "F.Cu")
		(net "XM_RB")
	)
	(segment
		(start 107.823 -58.2168)
		(end 107.34802 -57.74182)
		(width 0.1143)
		(layer "F.Cu")
		(net "XM_RB")
	)
	(segment
		(start 107.54995 -56.599836)
		(end 107.54995 -57.27065)
		(width 0.1143)
		(layer "F.Cu")
		(net "XM_RB")
	)
	(segment
		(start 107.823 -58.928)
		(end 107.823 -58.2168)
		(width 0.1143)
		(layer "F.Cu")
		(net "XM_RB")
	)
	(segment
		(start 108.077 -59.182)
		(end 107.823 -58.928)
		(width 0.1143)
		(layer "F.Cu")
		(net "XM_RB")
	)
	(segment
		(start 108.331 -59.182)
		(end 108.077 -59.182)
		(width 0.1143)
		(layer "F.Cu")
		(net "XM_RB")
	)
	(segment
		(start 107.54995 -57.27065)
		(end 107.34802 -57.47258)
		(width 0.1143)
		(layer "F.Cu")
		(net "XM_RB")
	)
	(via
		(at 107.34802 -57.716928)
		(size 0.508)
		(drill 0.254)
		(layers "F.Cu" "B.Cu")
		(net "XM_RB")
	)
	(segment
		(start 108.085128 -57.946798)
		(end 107.552998 -57.946798)
		(width 0.1143)
		(layer "B.Cu")
		(net "XM_RB")
	)
	(segment
		(start 107.552998 -57.946798)
		(end 107.34802 -57.74182)
		(width 0.1143)
		(layer "B.Cu")
		(net "XM_RB")
	)
	(segment
		(start 107.34802 -57.74182)
		(end 107.34802 -57.716928)
		(width 0.1143)
		(layer "B.Cu")
		(net "XM_RB")
	)
	(segment
		(start 199.59066 -116.112036)
		(end 199.59066 -117.27434)
		(width 0.254)
		(layer "F.Cu")
		(net "P1V5_E_SS")
	)
	(segment
		(start 196.983096 -120.669812)
		(end 196.983096 -119.881904)
		(width 0.254)
		(layer "F.Cu")
		(net "P1V5_E_SS")
	)
	(segment
		(start 196.983096 -119.881904)
		(end 197.612 -119.253)
		(width 0.254)
		(layer "F.Cu")
		(net "P1V5_E_SS")
	)
	(segment
		(start 199.59066 -117.27434)
		(end 197.612 -119.253)
		(width 0.254)
		(layer "F.Cu")
		(net "P1V5_E_SS")
	)
	(via
		(at 197.612 -119.253)
		(size 0.7112)
		(drill 0.3556)
		(layers "F.Cu" "B.Cu")
		(net "P1V5_E_SS")
	)
	(segment
		(start 56.558942 -135.392922)
		(end 63.062612 -135.392922)
		(width 0.1143)
		(layer "F.Cu")
		(net "EXP_XM_ADDR_9")
	)
	(segment
		(start 63.20917 -135.246364)
		(end 63.20917 -135.2042)
		(width 0.1143)
		(layer "F.Cu")
		(net "EXP_XM_ADDR_9")
	)
	(segment
		(start 101.11232 -90.7923)
		(end 100.99802 -90.9066)
		(width 0.1143)
		(layer "F.Cu")
		(net "EXP_XM_ADDR_9")
	)
	(segment
		(start 101.22662 -90.409776)
		(end 101.11232 -90.524076)
		(width 0.1143)
		(layer "F.Cu")
		(net "EXP_XM_ADDR_9")
	)
	(segment
		(start 101.11232 -90.524076)
		(end 101.11232 -90.7923)
		(width 0.1143)
		(layer "F.Cu")
		(net "EXP_XM_ADDR_9")
	)
	(segment
		(start 103.349806 -91.34983)
		(end 102.906576 -90.9066)
		(width 0.1143)
		(layer "F.Cu")
		(net "EXP_XM_ADDR_9")
	)
	(segment
		(start 100.99802 -90.9066)
		(end 100.76942 -90.9066)
		(width 0.1143)
		(layer "F.Cu")
		(net "EXP_XM_ADDR_9")
	)
	(segment
		(start 100.65512 -90.524076)
		(end 100.54082 -90.409776)
		(width 0.1143)
		(layer "F.Cu")
		(net "EXP_XM_ADDR_9")
	)
	(segment
		(start 63.062612 -135.392922)
		(end 63.20917 -135.246364)
		(width 0.1143)
		(layer "F.Cu")
		(net "EXP_XM_ADDR_9")
	)
	(segment
		(start 99.71532 -90.9066)
		(end 99.473512 -91.148408)
		(width 0.1143)
		(layer "F.Cu")
		(net "EXP_XM_ADDR_9")
	)
	(segment
		(start 101.56952 -90.524076)
		(end 101.45522 -90.409776)
		(width 0.1143)
		(layer "F.Cu")
		(net "EXP_XM_ADDR_9")
	)
	(segment
		(start 100.08362 -90.9066)
		(end 99.71532 -90.9066)
		(width 0.1143)
		(layer "F.Cu")
		(net "EXP_XM_ADDR_9")
	)
	(segment
		(start 101.56952 -90.7923)
		(end 101.56952 -90.524076)
		(width 0.1143)
		(layer "F.Cu")
		(net "EXP_XM_ADDR_9")
	)
	(segment
		(start 100.19792 -90.7923)
		(end 100.08362 -90.9066)
		(width 0.1143)
		(layer "F.Cu")
		(net "EXP_XM_ADDR_9")
	)
	(segment
		(start 100.54082 -90.409776)
		(end 100.31222 -90.409776)
		(width 0.1143)
		(layer "F.Cu")
		(net "EXP_XM_ADDR_9")
	)
	(segment
		(start 100.19792 -90.524076)
		(end 100.19792 -90.7923)
		(width 0.1143)
		(layer "F.Cu")
		(net "EXP_XM_ADDR_9")
	)
	(segment
		(start 101.45522 -90.409776)
		(end 101.22662 -90.409776)
		(width 0.1143)
		(layer "F.Cu")
		(net "EXP_XM_ADDR_9")
	)
	(segment
		(start 100.65512 -90.7923)
		(end 100.65512 -90.524076)
		(width 0.1143)
		(layer "F.Cu")
		(net "EXP_XM_ADDR_9")
	)
	(segment
		(start 100.76942 -90.9066)
		(end 100.65512 -90.7923)
		(width 0.1143)
		(layer "F.Cu")
		(net "EXP_XM_ADDR_9")
	)
	(segment
		(start 100.31222 -90.409776)
		(end 100.19792 -90.524076)
		(width 0.1143)
		(layer "F.Cu")
		(net "EXP_XM_ADDR_9")
	)
	(segment
		(start 101.68382 -90.9066)
		(end 101.56952 -90.7923)
		(width 0.1143)
		(layer "F.Cu")
		(net "EXP_XM_ADDR_9")
	)
	(segment
		(start 102.906576 -90.9066)
		(end 101.68382 -90.9066)
		(width 0.1143)
		(layer "F.Cu")
		(net "EXP_XM_ADDR_9")
	)
	(via
		(at 63.20917 -135.2042)
		(size 0.5588)
		(drill 0.3048)
		(layers "F.Cu" "B.Cu")
		(net "EXP_XM_ADDR_9")
	)
	(via
		(at 63.00343 -134.35838)
		(size 0.7112)
		(drill 0.3556)
		(layers "F.Cu" "B.Cu")
		(net "EXP_XM_ADDR_9")
	)
	(via
		(at 99.473512 -91.148408)
		(size 0.508)
		(drill 0.254)
		(layers "F.Cu" "B.Cu")
		(net "EXP_XM_ADDR_9")
	)
	(segment
		(start 63.20917 -134.56412)
		(end 63.00343 -134.35838)
		(width 0.1143)
		(layer "B.Cu")
		(net "EXP_XM_ADDR_9")
	)
	(segment
		(start 63.20917 -135.2042)
		(end 63.20917 -134.56412)
		(width 0.1143)
		(layer "B.Cu")
		(net "EXP_XM_ADDR_9")
	)
	(segment
		(start 63.15837 -125.758956)
		(end 63.55207 -125.365256)
		(width 0.127)
		(layer "In2.Cu")
		(net "EXP_XM_ADDR_9")
	)
	(segment
		(start 90.217244 -91.895676)
		(end 90.217244 -91.275408)
		(width 0.127)
		(layer "In2.Cu")
		(net "EXP_XM_ADDR_9")
	)
	(segment
		(start 91.233244 -91.275408)
		(end 91.360244 -91.148408)
		(width 0.127)
		(layer "In2.Cu")
		(net "EXP_XM_ADDR_9")
	)
	(segment
		(start 78.779116 -101.448108)
		(end 89.078816 -91.148408)
		(width 0.127)
		(layer "In2.Cu")
		(net "EXP_XM_ADDR_9")
	)
	(segment
		(start 90.725244 -91.895676)
		(end 90.852244 -92.022676)
		(width 0.127)
		(layer "In2.Cu")
		(net "EXP_XM_ADDR_9")
	)
	(segment
		(start 90.852244 -92.022676)
		(end 91.106244 -92.022676)
		(width 0.127)
		(layer "In2.Cu")
		(net "EXP_XM_ADDR_9")
	)
	(segment
		(start 78.779116 -102.20198)
		(end 78.779116 -101.448108)
		(width 0.127)
		(layer "In2.Cu")
		(net "EXP_XM_ADDR_9")
	)
	(segment
		(start 77.081634 -103.26878)
		(end 77.261466 -103.26878)
		(width 0.127)
		(layer "In2.Cu")
		(net "EXP_XM_ADDR_9")
	)
	(segment
		(start 91.741244 -91.895676)
		(end 91.868244 -92.022676)
		(width 0.127)
		(layer "In2.Cu")
		(net "EXP_XM_ADDR_9")
	)
	(segment
		(start 63.55207 -118.76532)
		(end 76.986892 -105.330498)
		(width 0.127)
		(layer "In2.Cu")
		(net "EXP_XM_ADDR_9")
	)
	(segment
		(start 78.065122 -104.072436)
		(end 78.244954 -104.072436)
		(width 0.127)
		(layer "In2.Cu")
		(net "EXP_XM_ADDR_9")
	)
	(segment
		(start 63.55207 -125.365256)
		(end 63.55207 -118.76532)
		(width 0.127)
		(layer "In2.Cu")
		(net "EXP_XM_ADDR_9")
	)
	(segment
		(start 63.01867 -129.537968)
		(end 63.04407 -129.512568)
		(width 0.127)
		(layer "In2.Cu")
		(net "EXP_XM_ADDR_9")
	)
	(segment
		(start 78.77937 -103.15702)
		(end 78.65237 -103.03002)
		(width 0.127)
		(layer "In2.Cu")
		(net "EXP_XM_ADDR_9")
	)
	(segment
		(start 78.65237 -103.03002)
		(end 78.10373 -103.03002)
		(width 0.127)
		(layer "In2.Cu")
		(net "EXP_XM_ADDR_9")
	)
	(segment
		(start 78.77937 -102.202234)
		(end 78.779116 -102.20198)
		(width 0.127)
		(layer "In2.Cu")
		(net "EXP_XM_ADDR_9")
	)
	(segment
		(start 89.582244 -91.148408)
		(end 89.709244 -91.275408)
		(width 0.127)
		(layer "In2.Cu")
		(net "EXP_XM_ADDR_9")
	)
	(segment
		(start 92.249244 -91.895676)
		(end 92.249244 -91.275408)
		(width 0.127)
		(layer "In2.Cu")
		(net "EXP_XM_ADDR_9")
	)
	(segment
		(start 77.705712 -104.611678)
		(end 77.705712 -104.431846)
		(width 0.127)
		(layer "In2.Cu")
		(net "EXP_XM_ADDR_9")
	)
	(segment
		(start 90.725244 -91.275408)
		(end 90.725244 -91.895676)
		(width 0.127)
		(layer "In2.Cu")
		(net "EXP_XM_ADDR_9")
	)
	(segment
		(start 76.542646 -103.9876)
		(end 77.346302 -104.791256)
		(width 0.127)
		(layer "In2.Cu")
		(net "EXP_XM_ADDR_9")
	)
	(segment
		(start 78.10373 -103.03002)
		(end 77.97673 -102.90302)
		(width 0.127)
		(layer "In2.Cu")
		(net "EXP_XM_ADDR_9")
	)
	(segment
		(start 77.97673 -102.64902)
		(end 78.10373 -102.52202)
		(width 0.127)
		(layer "In2.Cu")
		(net "EXP_XM_ADDR_9")
	)
	(segment
		(start 76.902056 -103.62819)
		(end 76.902056 -103.448358)
		(width 0.127)
		(layer "In2.Cu")
		(net "EXP_XM_ADDR_9")
	)
	(segment
		(start 91.106244 -92.022676)
		(end 91.233244 -91.895676)
		(width 0.127)
		(layer "In2.Cu")
		(net "EXP_XM_ADDR_9")
	)
	(segment
		(start 63.04407 -129.973832)
		(end 63.01867 -129.948432)
		(width 0.127)
		(layer "In2.Cu")
		(net "EXP_XM_ADDR_9")
	)
	(segment
		(start 77.346302 -104.791256)
		(end 77.526134 -104.791256)
		(width 0.127)
		(layer "In2.Cu")
		(net "EXP_XM_ADDR_9")
	)
	(segment
		(start 90.344244 -91.148408)
		(end 90.598244 -91.148408)
		(width 0.127)
		(layer "In2.Cu")
		(net "EXP_XM_ADDR_9")
	)
	(segment
		(start 91.868244 -92.022676)
		(end 92.122244 -92.022676)
		(width 0.127)
		(layer "In2.Cu")
		(net "EXP_XM_ADDR_9")
	)
	(segment
		(start 89.078816 -91.148408)
		(end 89.582244 -91.148408)
		(width 0.127)
		(layer "In2.Cu")
		(net "EXP_XM_ADDR_9")
	)
	(segment
		(start 63.04407 -135.0391)
		(end 63.04407 -129.973832)
		(width 0.127)
		(layer "In2.Cu")
		(net "EXP_XM_ADDR_9")
	)
	(segment
		(start 78.10373 -102.52202)
		(end 78.65237 -102.52202)
		(width 0.127)
		(layer "In2.Cu")
		(net "EXP_XM_ADDR_9")
	)
	(segment
		(start 91.741244 -91.275408)
		(end 91.741244 -91.895676)
		(width 0.127)
		(layer "In2.Cu")
		(net "EXP_XM_ADDR_9")
	)
	(segment
		(start 63.04407 -129.512568)
		(end 63.04407 -128.698752)
		(width 0.127)
		(layer "In2.Cu")
		(net "EXP_XM_ADDR_9")
	)
	(segment
		(start 78.65237 -102.52202)
		(end 78.77937 -102.39502)
		(width 0.127)
		(layer "In2.Cu")
		(net "EXP_XM_ADDR_9")
	)
	(segment
		(start 77.97673 -102.90302)
		(end 77.97673 -102.64902)
		(width 0.127)
		(layer "In2.Cu")
		(net "EXP_XM_ADDR_9")
	)
	(segment
		(start 78.77937 -103.53802)
		(end 78.77937 -103.15702)
		(width 0.127)
		(layer "In2.Cu")
		(net "EXP_XM_ADDR_9")
	)
	(segment
		(start 92.249244 -91.275408)
		(end 92.376244 -91.148408)
		(width 0.127)
		(layer "In2.Cu")
		(net "EXP_XM_ADDR_9")
	)
	(segment
		(start 76.183236 -104.34701)
		(end 76.183236 -104.167178)
		(width 0.127)
		(layer "In2.Cu")
		(net "EXP_XM_ADDR_9")
	)
	(segment
		(start 77.526134 -104.791256)
		(end 77.705712 -104.611678)
		(width 0.127)
		(layer "In2.Cu")
		(net "EXP_XM_ADDR_9")
	)
	(segment
		(start 89.709244 -91.275408)
		(end 89.709244 -91.895676)
		(width 0.127)
		(layer "In2.Cu")
		(net "EXP_XM_ADDR_9")
	)
	(segment
		(start 92.122244 -92.022676)
		(end 92.249244 -91.895676)
		(width 0.127)
		(layer "In2.Cu")
		(net "EXP_XM_ADDR_9")
	)
	(segment
		(start 90.090244 -92.022676)
		(end 90.217244 -91.895676)
		(width 0.127)
		(layer "In2.Cu")
		(net "EXP_XM_ADDR_9")
	)
	(segment
		(start 76.986892 -105.150666)
		(end 76.183236 -104.34701)
		(width 0.127)
		(layer "In2.Cu")
		(net "EXP_XM_ADDR_9")
	)
	(segment
		(start 63.15837 -128.584452)
		(end 63.15837 -125.758956)
		(width 0.127)
		(layer "In2.Cu")
		(net "EXP_XM_ADDR_9")
	)
	(segment
		(start 89.709244 -91.895676)
		(end 89.836244 -92.022676)
		(width 0.127)
		(layer "In2.Cu")
		(net "EXP_XM_ADDR_9")
	)
	(segment
		(start 90.598244 -91.148408)
		(end 90.725244 -91.275408)
		(width 0.127)
		(layer "In2.Cu")
		(net "EXP_XM_ADDR_9")
	)
	(segment
		(start 89.836244 -92.022676)
		(end 90.090244 -92.022676)
		(width 0.127)
		(layer "In2.Cu")
		(net "EXP_XM_ADDR_9")
	)
	(segment
		(start 92.376244 -91.148408)
		(end 99.473512 -91.148408)
		(width 0.127)
		(layer "In2.Cu")
		(net "EXP_XM_ADDR_9")
	)
	(segment
		(start 76.986892 -105.330498)
		(end 76.986892 -105.150666)
		(width 0.127)
		(layer "In2.Cu")
		(net "EXP_XM_ADDR_9")
	)
	(segment
		(start 76.902056 -103.448358)
		(end 77.081634 -103.26878)
		(width 0.127)
		(layer "In2.Cu")
		(net "EXP_XM_ADDR_9")
	)
	(segment
		(start 77.705712 -104.431846)
		(end 76.902056 -103.62819)
		(width 0.127)
		(layer "In2.Cu")
		(net "EXP_XM_ADDR_9")
	)
	(segment
		(start 63.20917 -135.2042)
		(end 63.04407 -135.0391)
		(width 0.127)
		(layer "In2.Cu")
		(net "EXP_XM_ADDR_9")
	)
	(segment
		(start 76.362814 -103.9876)
		(end 76.542646 -103.9876)
		(width 0.127)
		(layer "In2.Cu")
		(net "EXP_XM_ADDR_9")
	)
	(segment
		(start 91.360244 -91.148408)
		(end 91.614244 -91.148408)
		(width 0.127)
		(layer "In2.Cu")
		(net "EXP_XM_ADDR_9")
	)
	(segment
		(start 90.217244 -91.275408)
		(end 90.344244 -91.148408)
		(width 0.127)
		(layer "In2.Cu")
		(net "EXP_XM_ADDR_9")
	)
	(segment
		(start 78.244954 -104.072436)
		(end 78.77937 -103.53802)
		(width 0.127)
		(layer "In2.Cu")
		(net "EXP_XM_ADDR_9")
	)
	(segment
		(start 63.01867 -129.948432)
		(end 63.01867 -129.537968)
		(width 0.127)
		(layer "In2.Cu")
		(net "EXP_XM_ADDR_9")
	)
	(segment
		(start 76.183236 -104.167178)
		(end 76.362814 -103.9876)
		(width 0.127)
		(layer "In2.Cu")
		(net "EXP_XM_ADDR_9")
	)
	(segment
		(start 63.04407 -128.698752)
		(end 63.15837 -128.584452)
		(width 0.127)
		(layer "In2.Cu")
		(net "EXP_XM_ADDR_9")
	)
	(segment
		(start 78.77937 -102.39502)
		(end 78.77937 -102.202234)
		(width 0.127)
		(layer "In2.Cu")
		(net "EXP_XM_ADDR_9")
	)
	(segment
		(start 91.614244 -91.148408)
		(end 91.741244 -91.275408)
		(width 0.127)
		(layer "In2.Cu")
		(net "EXP_XM_ADDR_9")
	)
	(segment
		(start 77.261466 -103.26878)
		(end 78.065122 -104.072436)
		(width 0.127)
		(layer "In2.Cu")
		(net "EXP_XM_ADDR_9")
	)
	(segment
		(start 91.233244 -91.895676)
		(end 91.233244 -91.275408)
		(width 0.127)
		(layer "In2.Cu")
		(net "EXP_XM_ADDR_9")
	)
	(segment
		(start 143.19885 -54.162706)
		(end 144.312132 -53.049424)
		(width 0.1143)
		(layer "F.Cu")
		(net "XM_DATA_3")
	)
	(segment
		(start 113.949988 -48.599852)
		(end 114.349784 -48.200056)
		(width 0.1143)
		(layer "F.Cu")
		(net "XM_DATA_3")
	)
	(segment
		(start 144.312132 -53.049424)
		(end 144.312132 -52.43957)
		(width 0.1143)
		(layer "F.Cu")
		(net "XM_DATA_3")
	)
	(segment
		(start 143.19885 -59.052206)
		(end 143.19885 -54.162706)
		(width 0.1143)
		(layer "F.Cu")
		(net "XM_DATA_3")
	)
	(segment
		(start 143.099536 -60.803536)
		(end 142.927324 -60.631324)
		(width 0.1143)
		(layer "F.Cu")
		(net "XM_DATA_3")
	)
	(segment
		(start 142.927324 -60.631324)
		(end 142.927324 -59.323732)
		(width 0.1143)
		(layer "F.Cu")
		(net "XM_DATA_3")
	)
	(segment
		(start 143.099536 -61.9379)
		(end 143.099536 -60.803536)
		(width 0.1143)
		(layer "F.Cu")
		(net "XM_DATA_3")
	)
	(segment
		(start 142.927324 -59.323732)
		(end 143.19885 -59.052206)
		(width 0.1143)
		(layer "F.Cu")
		(net "XM_DATA_3")
	)
	(via
		(at 114.349784 -48.200056)
		(size 0.508)
		(drill 0.254)
		(layers "F.Cu" "B.Cu")
		(net "XM_DATA_3")
	)
	(via
		(at 144.312132 -52.43957)
		(size 0.5588)
		(drill 0.3048)
		(layers "F.Cu" "B.Cu")
		(net "XM_DATA_3")
	)
	(via
		(at 142.358872 -51.762152)
		(size 0.7112)
		(drill 0.3556)
		(layers "F.Cu" "B.Cu")
		(net "XM_DATA_3")
	)
	(segment
		(start 137.5664 -50.2666)
		(end 137.5664 -50.1523)
		(width 0.1143)
		(layer "B.Cu")
		(net "XM_DATA_3")
	)
	(segment
		(start 143.20139 -52.820062)
		(end 143.069056 -52.687728)
		(width 0.1143)
		(layer "B.Cu")
		(net "XM_DATA_3")
	)
	(segment
		(start 143.069056 -52.687728)
		(end 143.068294 -52.687728)
		(width 0.1143)
		(layer "B.Cu")
		(net "XM_DATA_3")
	)
	(segment
		(start 143.068294 -52.687728)
		(end 142.82674 -52.446174)
		(width 0.1143)
		(layer "B.Cu")
		(net "XM_DATA_3")
	)
	(segment
		(start 142.298674 -51.762152)
		(end 140.574522 -50.038)
		(width 0.1143)
		(layer "B.Cu")
		(net "XM_DATA_3")
	)
	(segment
		(start 136.652 -49.657)
		(end 136.271 -49.657)
		(width 0.1143)
		(layer "B.Cu")
		(net "XM_DATA_3")
	)
	(segment
		(start 119.236998 -50.292)
		(end 118.390162 -49.445164)
		(width 0.1143)
		(layer "B.Cu")
		(net "XM_DATA_3")
	)
	(segment
		(start 137.5664 -50.1523)
		(end 137.4521 -50.038)
		(width 0.1143)
		(layer "B.Cu")
		(net "XM_DATA_3")
	)
	(segment
		(start 138.1379 -50.038)
		(end 138.0236 -50.1523)
		(width 0.1143)
		(layer "B.Cu")
		(net "XM_DATA_3")
	)
	(segment
		(start 142.82674 -52.446174)
		(end 142.82674 -52.23002)
		(width 0.1143)
		(layer "B.Cu")
		(net "XM_DATA_3")
	)
	(segment
		(start 142.358872 -51.762152)
		(end 142.298674 -51.762152)
		(width 0.1143)
		(layer "B.Cu")
		(net "XM_DATA_3")
	)
	(segment
		(start 137.6807 -50.3809)
		(end 137.5664 -50.2666)
		(width 0.1143)
		(layer "B.Cu")
		(net "XM_DATA_3")
	)
	(segment
		(start 144.312132 -52.43957)
		(end 144.300956 -52.450746)
		(width 0.1143)
		(layer "B.Cu")
		(net "XM_DATA_3")
	)
	(segment
		(start 135.636 -50.292)
		(end 119.236998 -50.292)
		(width 0.1143)
		(layer "B.Cu")
		(net "XM_DATA_3")
	)
	(segment
		(start 137.9093 -50.3809)
		(end 137.6807 -50.3809)
		(width 0.1143)
		(layer "B.Cu")
		(net "XM_DATA_3")
	)
	(segment
		(start 138.0236 -50.1523)
		(end 138.0236 -50.2666)
		(width 0.1143)
		(layer "B.Cu")
		(net "XM_DATA_3")
	)
	(segment
		(start 144.300956 -52.450746)
		(end 144.300956 -52.693062)
		(width 0.1143)
		(layer "B.Cu")
		(net "XM_DATA_3")
	)
	(segment
		(start 138.0236 -50.2666)
		(end 137.9093 -50.3809)
		(width 0.1143)
		(layer "B.Cu")
		(net "XM_DATA_3")
	)
	(segment
		(start 116.740686 -48.07585)
		(end 114.47399 -48.07585)
		(width 0.1143)
		(layer "B.Cu")
		(net "XM_DATA_3")
	)
	(segment
		(start 118.11 -49.445164)
		(end 116.740686 -48.07585)
		(width 0.1143)
		(layer "B.Cu")
		(net "XM_DATA_3")
	)
	(segment
		(start 114.47399 -48.07585)
		(end 114.349784 -48.200056)
		(width 0.1143)
		(layer "B.Cu")
		(net "XM_DATA_3")
	)
	(segment
		(start 140.574522 -50.038)
		(end 138.1379 -50.038)
		(width 0.1143)
		(layer "B.Cu")
		(net "XM_DATA_3")
	)
	(segment
		(start 137.4521 -50.038)
		(end 137.033 -50.038)
		(width 0.1143)
		(layer "B.Cu")
		(net "XM_DATA_3")
	)
	(segment
		(start 137.033 -50.038)
		(end 136.652 -49.657)
		(width 0.1143)
		(layer "B.Cu")
		(net "XM_DATA_3")
	)
	(segment
		(start 144.173956 -52.820062)
		(end 143.20139 -52.820062)
		(width 0.1143)
		(layer "B.Cu")
		(net "XM_DATA_3")
	)
	(segment
		(start 136.271 -49.657)
		(end 135.636 -50.292)
		(width 0.1143)
		(layer "B.Cu")
		(net "XM_DATA_3")
	)
	(segment
		(start 144.300956 -52.693062)
		(end 144.173956 -52.820062)
		(width 0.1143)
		(layer "B.Cu")
		(net "XM_DATA_3")
	)
	(segment
		(start 142.82674 -52.23002)
		(end 142.358872 -51.762152)
		(width 0.1143)
		(layer "B.Cu")
		(net "XM_DATA_3")
	)
	(segment
		(start 118.390162 -49.445164)
		(end 118.11 -49.445164)
		(width 0.1143)
		(layer "B.Cu")
		(net "XM_DATA_3")
	)
	(segment
		(start 201.39152 -113.82375)
		(end 202.91425 -113.82375)
		(width 0.3048)
		(layer "F.Cu")
		(net "P1V5_E_VIN")
	)
	(segment
		(start 201.37882 -114.323876)
		(end 203.049124 -114.323876)
		(width 0.3048)
		(layer "F.Cu")
		(net "P1V5_E_VIN")
	)
	(via
		(at 208.026 -114.554)
		(size 0.7112)
		(drill 0.3556)
		(layers "F.Cu" "B.Cu")
		(net "P1V5_E_VIN")
	)
	(segment
		(start 77.106272 -127.762)
		(end 76.97597 -127.892302)
		(width 0.1143)
		(layer "F.Cu")
		(net "EXP_XM_NOR_CS_N")
	)
	(segment
		(start 106.849672 -89.849706)
		(end 107.349798 -90.349832)
		(width 0.1143)
		(layer "F.Cu")
		(net "EXP_XM_NOR_CS_N")
	)
	(segment
		(start 76.97597 -127.892302)
		(end 75.786742 -127.892302)
		(width 0.1143)
		(layer "F.Cu")
		(net "EXP_XM_NOR_CS_N")
	)
	(segment
		(start 74.17943 -128.243838)
		(end 74.530966 -127.892302)
		(width 0.1143)
		(layer "F.Cu")
		(net "EXP_XM_NOR_CS_N")
	)
	(segment
		(start 74.530966 -127.892302)
		(end 75.786742 -127.892302)
		(width 0.1143)
		(layer "F.Cu")
		(net "EXP_XM_NOR_CS_N")
	)
	(segment
		(start 79.444342 -128.951482)
		(end 78.25486 -127.762)
		(width 0.1143)
		(layer "F.Cu")
		(net "EXP_XM_NOR_CS_N")
	)
	(segment
		(start 78.25486 -127.762)
		(end 77.106272 -127.762)
		(width 0.1143)
		(layer "F.Cu")
		(net "EXP_XM_NOR_CS_N")
	)
	(via
		(at 74.851768 -127.884936)
		(size 0.7112)
		(drill 0.3556)
		(layers "F.Cu" "B.Cu")
		(net "EXP_XM_NOR_CS_N")
	)
	(via
		(at 106.849672 -89.849706)
		(size 0.508)
		(drill 0.254)
		(layers "F.Cu" "B.Cu")
		(net "EXP_XM_NOR_CS_N")
	)
	(via
		(at 74.17943 -128.243838)
		(size 0.5588)
		(drill 0.3048)
		(layers "F.Cu" "B.Cu")
		(net "EXP_XM_NOR_CS_N")
	)
	(segment
		(start 74.492866 -128.243838)
		(end 74.851768 -127.884936)
		(width 0.1143)
		(layer "B.Cu")
		(net "EXP_XM_NOR_CS_N")
	)
	(segment
		(start 74.17943 -128.243838)
		(end 74.492866 -128.243838)
		(width 0.1143)
		(layer "B.Cu")
		(net "EXP_XM_NOR_CS_N")
	)
	(segment
		(start 83.89874 -110.322106)
		(end 84.828126 -111.251492)
		(width 0.127)
		(layer "In2.Cu")
		(net "EXP_XM_NOR_CS_N")
	)
	(segment
		(start 83.929728 -112.329722)
		(end 83.749896 -112.329722)
		(width 0.127)
		(layer "In2.Cu")
		(net "EXP_XM_NOR_CS_N")
	)
	(segment
		(start 80.30464 -113.916206)
		(end 81.234026 -114.845592)
		(width 0.127)
		(layer "In2.Cu")
		(net "EXP_XM_NOR_CS_N")
	)
	(segment
		(start 108.486194 -95.1357)
		(end 108.0643 -95.1357)
		(width 0.127)
		(layer "In2.Cu")
		(net "EXP_XM_NOR_CS_N")
	)
	(segment
		(start 84.828126 -111.431324)
		(end 84.648548 -111.610902)
		(width 0.127)
		(layer "In2.Cu")
		(net "EXP_XM_NOR_CS_N")
	)
	(segment
		(start 83.390486 -112.868964)
		(end 83.210908 -113.048542)
		(width 0.127)
		(layer "In2.Cu")
		(net "EXP_XM_NOR_CS_N")
	)
	(segment
		(start 109.268768 -90.675968)
		(end 109.268768 -94.023434)
		(width 0.127)
		(layer "In2.Cu")
		(net "EXP_XM_NOR_CS_N")
	)
	(segment
		(start 107.023408 -96.269302)
		(end 102.718108 -96.269302)
		(width 0.127)
		(layer "In2.Cu")
		(net "EXP_XM_NOR_CS_N")
	)
	(segment
		(start 81.952846 -114.126772)
		(end 81.952846 -114.306604)
		(width 0.127)
		(layer "In2.Cu")
		(net "EXP_XM_NOR_CS_N")
	)
	(segment
		(start 100.203762 -98.6155)
		(end 99.36861 -98.6155)
		(width 0.127)
		(layer "In2.Cu")
		(net "EXP_XM_NOR_CS_N")
	)
	(segment
		(start 83.17992 -111.040926)
		(end 84.109306 -111.970312)
		(width 0.127)
		(layer "In2.Cu")
		(net "EXP_XM_NOR_CS_N")
	)
	(segment
		(start 79.22641 -114.994436)
		(end 79.046578 -114.994436)
		(width 0.127)
		(layer "In2.Cu")
		(net "EXP_XM_NOR_CS_N")
	)
	(segment
		(start 83.53933 -110.681516)
		(end 83.359498 -110.681516)
		(width 0.127)
		(layer "In2.Cu")
		(net "EXP_XM_NOR_CS_N")
	)
	(segment
		(start 82.4611 -111.759746)
		(end 83.390486 -112.689132)
		(width 0.127)
		(layer "In2.Cu")
		(net "EXP_XM_NOR_CS_N")
	)
	(segment
		(start 100.959412 -97.85985)
		(end 100.203762 -98.6155)
		(width 0.127)
		(layer "In2.Cu")
		(net "EXP_XM_NOR_CS_N")
	)
	(segment
		(start 82.4611 -111.579914)
		(end 82.4611 -111.759746)
		(width 0.127)
		(layer "In2.Cu")
		(net "EXP_XM_NOR_CS_N")
	)
	(segment
		(start 80.874616 -115.205002)
		(end 79.94523 -114.275616)
		(width 0.127)
		(layer "In2.Cu")
		(net "EXP_XM_NOR_CS_N")
	)
	(segment
		(start 81.921858 -112.119156)
		(end 81.74228 -112.298734)
		(width 0.127)
		(layer "In2.Cu")
		(net "EXP_XM_NOR_CS_N")
	)
	(segment
		(start 102.718108 -96.269302)
		(end 101.12756 -97.85985)
		(width 0.127)
		(layer "In2.Cu")
		(net "EXP_XM_NOR_CS_N")
	)
	(segment
		(start 108.998766 -95.3008)
		(end 108.651294 -95.3008)
		(width 0.127)
		(layer "In2.Cu")
		(net "EXP_XM_NOR_CS_N")
	)
	(segment
		(start 81.952846 -114.306604)
		(end 81.773268 -114.486182)
		(width 0.127)
		(layer "In2.Cu")
		(net "EXP_XM_NOR_CS_N")
	)
	(segment
		(start 75.364848 -127.510032)
		(end 74.631042 -128.243838)
		(width 0.127)
		(layer "In2.Cu")
		(net "EXP_XM_NOR_CS_N")
	)
	(segment
		(start 109.24413 -95.055436)
		(end 108.998766 -95.3008)
		(width 0.127)
		(layer "In2.Cu")
		(net "EXP_XM_NOR_CS_N")
	)
	(segment
		(start 99.25812 -98.726498)
		(end 95.68561 -102.299008)
		(width 0.127)
		(layer "In2.Cu")
		(net "EXP_XM_NOR_CS_N")
	)
	(segment
		(start 84.468716 -111.610902)
		(end 83.53933 -110.681516)
		(width 0.127)
		(layer "In2.Cu")
		(net "EXP_XM_NOR_CS_N")
	)
	(segment
		(start 108.651294 -95.3008)
		(end 108.486194 -95.1357)
		(width 0.127)
		(layer "In2.Cu")
		(net "EXP_XM_NOR_CS_N")
	)
	(segment
		(start 101.12756 -97.85985)
		(end 100.959412 -97.85985)
		(width 0.127)
		(layer "In2.Cu")
		(net "EXP_XM_NOR_CS_N")
	)
	(segment
		(start 80.155796 -115.923822)
		(end 79.22641 -114.994436)
		(width 0.127)
		(layer "In2.Cu")
		(net "EXP_XM_NOR_CS_N")
	)
	(segment
		(start 107.373166 -90.3732)
		(end 108.966 -90.3732)
		(width 0.127)
		(layer "In2.Cu")
		(net "EXP_XM_NOR_CS_N")
	)
	(segment
		(start 84.648548 -111.610902)
		(end 84.468716 -111.610902)
		(width 0.127)
		(layer "In2.Cu")
		(net "EXP_XM_NOR_CS_N")
	)
	(segment
		(start 84.109306 -111.970312)
		(end 84.109306 -112.150144)
		(width 0.127)
		(layer "In2.Cu")
		(net "EXP_XM_NOR_CS_N")
	)
	(segment
		(start 107.268772 -95.931228)
		(end 107.268772 -96.023938)
		(width 0.127)
		(layer "In2.Cu")
		(net "EXP_XM_NOR_CS_N")
	)
	(segment
		(start 80.66405 -113.556796)
		(end 80.484218 -113.556796)
		(width 0.127)
		(layer "In2.Cu")
		(net "EXP_XM_NOR_CS_N")
	)
	(segment
		(start 83.89874 -110.142274)
		(end 83.89874 -110.322106)
		(width 0.127)
		(layer "In2.Cu")
		(net "EXP_XM_NOR_CS_N")
	)
	(segment
		(start 109.24413 -94.048072)
		(end 109.24413 -95.055436)
		(width 0.127)
		(layer "In2.Cu")
		(net "EXP_XM_NOR_CS_N")
	)
	(segment
		(start 82.640678 -111.400336)
		(end 82.4611 -111.579914)
		(width 0.127)
		(layer "In2.Cu")
		(net "EXP_XM_NOR_CS_N")
	)
	(segment
		(start 99.36861 -98.6155)
		(end 99.25812 -98.726498)
		(width 0.127)
		(layer "In2.Cu")
		(net "EXP_XM_NOR_CS_N")
	)
	(segment
		(start 78.327758 -115.713256)
		(end 78.14818 -115.892834)
		(width 0.127)
		(layer "In2.Cu")
		(net "EXP_XM_NOR_CS_N")
	)
	(segment
		(start 79.796386 -116.283232)
		(end 79.796386 -116.463064)
		(width 0.127)
		(layer "In2.Cu")
		(net "EXP_XM_NOR_CS_N")
	)
	(segment
		(start 78.50759 -115.713256)
		(end 78.327758 -115.713256)
		(width 0.127)
		(layer "In2.Cu")
		(net "EXP_XM_NOR_CS_N")
	)
	(segment
		(start 84.078318 -109.962696)
		(end 83.89874 -110.142274)
		(width 0.127)
		(layer "In2.Cu")
		(net "EXP_XM_NOR_CS_N")
	)
	(segment
		(start 81.593436 -114.486182)
		(end 80.66405 -113.556796)
		(width 0.127)
		(layer "In2.Cu")
		(net "EXP_XM_NOR_CS_N")
	)
	(segment
		(start 81.203038 -112.837976)
		(end 81.02346 -113.017554)
		(width 0.127)
		(layer "In2.Cu")
		(net "EXP_XM_NOR_CS_N")
	)
	(segment
		(start 80.484218 -113.556796)
		(end 80.30464 -113.736374)
		(width 0.127)
		(layer "In2.Cu")
		(net "EXP_XM_NOR_CS_N")
	)
	(segment
		(start 79.616808 -116.642642)
		(end 79.436976 -116.642642)
		(width 0.127)
		(layer "In2.Cu")
		(net "EXP_XM_NOR_CS_N")
	)
	(segment
		(start 81.234026 -114.845592)
		(end 81.234026 -115.025424)
		(width 0.127)
		(layer "In2.Cu")
		(net "EXP_XM_NOR_CS_N")
	)
	(segment
		(start 79.077566 -117.181884)
		(end 75.364848 -120.894602)
		(width 0.127)
		(layer "In2.Cu")
		(net "EXP_XM_NOR_CS_N")
	)
	(segment
		(start 79.765398 -114.275616)
		(end 79.58582 -114.455194)
		(width 0.127)
		(layer "In2.Cu")
		(net "EXP_XM_NOR_CS_N")
	)
	(segment
		(start 79.58582 -114.455194)
		(end 79.58582 -114.635026)
		(width 0.127)
		(layer "In2.Cu")
		(net "EXP_XM_NOR_CS_N")
	)
	(segment
		(start 82.312256 -113.767362)
		(end 81.38287 -112.837976)
		(width 0.127)
		(layer "In2.Cu")
		(net "EXP_XM_NOR_CS_N")
	)
	(segment
		(start 83.390486 -112.689132)
		(end 83.390486 -112.868964)
		(width 0.127)
		(layer "In2.Cu")
		(net "EXP_XM_NOR_CS_N")
	)
	(segment
		(start 80.515206 -115.744244)
		(end 80.335628 -115.923822)
		(width 0.127)
		(layer "In2.Cu")
		(net "EXP_XM_NOR_CS_N")
	)
	(segment
		(start 79.94523 -114.275616)
		(end 79.765398 -114.275616)
		(width 0.127)
		(layer "In2.Cu")
		(net "EXP_XM_NOR_CS_N")
	)
	(segment
		(start 74.631042 -128.243838)
		(end 74.17943 -128.243838)
		(width 0.127)
		(layer "In2.Cu")
		(net "EXP_XM_NOR_CS_N")
	)
	(segment
		(start 107.268772 -96.023938)
		(end 107.023408 -96.269302)
		(width 0.127)
		(layer "In2.Cu")
		(net "EXP_XM_NOR_CS_N")
	)
	(segment
		(start 82.492088 -113.767362)
		(end 82.312256 -113.767362)
		(width 0.127)
		(layer "In2.Cu")
		(net "EXP_XM_NOR_CS_N")
	)
	(segment
		(start 78.867 -115.174014)
		(end 78.867 -115.353846)
		(width 0.127)
		(layer "In2.Cu")
		(net "EXP_XM_NOR_CS_N")
	)
	(segment
		(start 108.0643 -95.1357)
		(end 107.268772 -95.931228)
		(width 0.127)
		(layer "In2.Cu")
		(net "EXP_XM_NOR_CS_N")
	)
	(segment
		(start 106.849672 -89.849706)
		(end 107.373166 -90.3732)
		(width 0.127)
		(layer "In2.Cu")
		(net "EXP_XM_NOR_CS_N")
	)
	(segment
		(start 83.359498 -110.681516)
		(end 83.17992 -110.861094)
		(width 0.127)
		(layer "In2.Cu")
		(net "EXP_XM_NOR_CS_N")
	)
	(segment
		(start 80.515206 -115.564412)
		(end 80.515206 -115.744244)
		(width 0.127)
		(layer "In2.Cu")
		(net "EXP_XM_NOR_CS_N")
	)
	(segment
		(start 78.14818 -115.892834)
		(end 78.14818 -116.072666)
		(width 0.127)
		(layer "In2.Cu")
		(net "EXP_XM_NOR_CS_N")
	)
	(segment
		(start 81.234026 -115.025424)
		(end 81.054448 -115.205002)
		(width 0.127)
		(layer "In2.Cu")
		(net "EXP_XM_NOR_CS_N")
	)
	(segment
		(start 82.671666 -113.587784)
		(end 82.492088 -113.767362)
		(width 0.127)
		(layer "In2.Cu")
		(net "EXP_XM_NOR_CS_N")
	)
	(segment
		(start 78.867 -115.353846)
		(end 79.796386 -116.283232)
		(width 0.127)
		(layer "In2.Cu")
		(net "EXP_XM_NOR_CS_N")
	)
	(segment
		(start 78.14818 -116.072666)
		(end 79.077566 -117.002052)
		(width 0.127)
		(layer "In2.Cu")
		(net "EXP_XM_NOR_CS_N")
	)
	(segment
		(start 83.17992 -110.861094)
		(end 83.17992 -111.040926)
		(width 0.127)
		(layer "In2.Cu")
		(net "EXP_XM_NOR_CS_N")
	)
	(segment
		(start 93.960442 -102.299008)
		(end 85.367368 -110.892082)
		(width 0.127)
		(layer "In2.Cu")
		(net "EXP_XM_NOR_CS_N")
	)
	(segment
		(start 109.268768 -94.023434)
		(end 109.24413 -94.048072)
		(width 0.127)
		(layer "In2.Cu")
		(net "EXP_XM_NOR_CS_N")
	)
	(segment
		(start 75.364848 -120.894602)
		(end 75.364848 -127.510032)
		(width 0.127)
		(layer "In2.Cu")
		(net "EXP_XM_NOR_CS_N")
	)
	(segment
		(start 79.046578 -114.994436)
		(end 78.867 -115.174014)
		(width 0.127)
		(layer "In2.Cu")
		(net "EXP_XM_NOR_CS_N")
	)
	(segment
		(start 81.38287 -112.837976)
		(end 81.203038 -112.837976)
		(width 0.127)
		(layer "In2.Cu")
		(net "EXP_XM_NOR_CS_N")
	)
	(segment
		(start 79.436976 -116.642642)
		(end 78.50759 -115.713256)
		(width 0.127)
		(layer "In2.Cu")
		(net "EXP_XM_NOR_CS_N")
	)
	(segment
		(start 84.109306 -112.150144)
		(end 83.929728 -112.329722)
		(width 0.127)
		(layer "In2.Cu")
		(net "EXP_XM_NOR_CS_N")
	)
	(segment
		(start 80.335628 -115.923822)
		(end 80.155796 -115.923822)
		(width 0.127)
		(layer "In2.Cu")
		(net "EXP_XM_NOR_CS_N")
	)
	(segment
		(start 79.58582 -114.635026)
		(end 80.515206 -115.564412)
		(width 0.127)
		(layer "In2.Cu")
		(net "EXP_XM_NOR_CS_N")
	)
	(segment
		(start 81.74228 -112.478566)
		(end 82.671666 -113.407952)
		(width 0.127)
		(layer "In2.Cu")
		(net "EXP_XM_NOR_CS_N")
	)
	(segment
		(start 82.82051 -111.400336)
		(end 82.640678 -111.400336)
		(width 0.127)
		(layer "In2.Cu")
		(net "EXP_XM_NOR_CS_N")
	)
	(segment
		(start 83.031076 -113.048542)
		(end 82.10169 -112.119156)
		(width 0.127)
		(layer "In2.Cu")
		(net "EXP_XM_NOR_CS_N")
	)
	(segment
		(start 84.25815 -109.962696)
		(end 84.078318 -109.962696)
		(width 0.127)
		(layer "In2.Cu")
		(net "EXP_XM_NOR_CS_N")
	)
	(segment
		(start 85.367368 -110.892082)
		(end 85.187536 -110.892082)
		(width 0.127)
		(layer "In2.Cu")
		(net "EXP_XM_NOR_CS_N")
	)
	(segment
		(start 82.10169 -112.119156)
		(end 81.921858 -112.119156)
		(width 0.127)
		(layer "In2.Cu")
		(net "EXP_XM_NOR_CS_N")
	)
	(segment
		(start 81.054448 -115.205002)
		(end 80.874616 -115.205002)
		(width 0.127)
		(layer "In2.Cu")
		(net "EXP_XM_NOR_CS_N")
	)
	(segment
		(start 81.74228 -112.298734)
		(end 81.74228 -112.478566)
		(width 0.127)
		(layer "In2.Cu")
		(net "EXP_XM_NOR_CS_N")
	)
	(segment
		(start 79.077566 -117.002052)
		(end 79.077566 -117.181884)
		(width 0.127)
		(layer "In2.Cu")
		(net "EXP_XM_NOR_CS_N")
	)
	(segment
		(start 79.796386 -116.463064)
		(end 79.616808 -116.642642)
		(width 0.127)
		(layer "In2.Cu")
		(net "EXP_XM_NOR_CS_N")
	)
	(segment
		(start 80.30464 -113.736374)
		(end 80.30464 -113.916206)
		(width 0.127)
		(layer "In2.Cu")
		(net "EXP_XM_NOR_CS_N")
	)
	(segment
		(start 83.210908 -113.048542)
		(end 83.031076 -113.048542)
		(width 0.127)
		(layer "In2.Cu")
		(net "EXP_XM_NOR_CS_N")
	)
	(segment
		(start 81.773268 -114.486182)
		(end 81.593436 -114.486182)
		(width 0.127)
		(layer "In2.Cu")
		(net "EXP_XM_NOR_CS_N")
	)
	(segment
		(start 82.671666 -113.407952)
		(end 82.671666 -113.587784)
		(width 0.127)
		(layer "In2.Cu")
		(net "EXP_XM_NOR_CS_N")
	)
	(segment
		(start 108.966 -90.3732)
		(end 109.268768 -90.675968)
		(width 0.127)
		(layer "In2.Cu")
		(net "EXP_XM_NOR_CS_N")
	)
	(segment
		(start 95.68561 -102.299008)
		(end 93.960442 -102.299008)
		(width 0.127)
		(layer "In2.Cu")
		(net "EXP_XM_NOR_CS_N")
	)
	(segment
		(start 81.02346 -113.017554)
		(end 81.02346 -113.197386)
		(width 0.127)
		(layer "In2.Cu")
		(net "EXP_XM_NOR_CS_N")
	)
	(segment
		(start 84.828126 -111.251492)
		(end 84.828126 -111.431324)
		(width 0.127)
		(layer "In2.Cu")
		(net "EXP_XM_NOR_CS_N")
	)
	(segment
		(start 85.187536 -110.892082)
		(end 84.25815 -109.962696)
		(width 0.127)
		(layer "In2.Cu")
		(net "EXP_XM_NOR_CS_N")
	)
	(segment
		(start 81.02346 -113.197386)
		(end 81.952846 -114.126772)
		(width 0.127)
		(layer "In2.Cu")
		(net "EXP_XM_NOR_CS_N")
	)
	(segment
		(start 83.749896 -112.329722)
		(end 82.82051 -111.400336)
		(width 0.127)
		(layer "In2.Cu")
		(net "EXP_XM_NOR_CS_N")
	)
	(segment
		(start 111.446818 -112.296702)
		(end 111.624618 -112.118902)
		(width 0.1016)
		(layer "F.Cu")
		(net "SAS_HDD_TX6_P")
	)
	(segment
		(start 111.228886 -113.668556)
		(end 111.163354 -113.603024)
		(width 0.1016)
		(layer "F.Cu")
		(net "SAS_HDD_TX6_P")
	)
	(segment
		(start 111.96447 -108.666534)
		(end 111.96447 -106.622596)
		(width 0.1016)
		(layer "F.Cu")
		(net "SAS_HDD_TX6_P")
	)
	(segment
		(start 111.12627 -113.513362)
		(end 111.12627 -113.07064)
		(width 0.1016)
		(layer "F.Cu")
		(net "SAS_HDD_TX6_P")
	)
	(segment
		(start 112.242092 -106.350054)
		(end 112.349788 -106.350054)
		(width 0.1016)
		(layer "F.Cu")
		(net "SAS_HDD_TX6_P")
	)
	(segment
		(start 111.26597 -114.0206)
		(end 111.26597 -113.758218)
		(width 0.1016)
		(layer "F.Cu")
		(net "SAS_HDD_TX6_P")
	)
	(segment
		(start 112.07369 -111.034322)
		(end 112.07369 -109.001052)
		(width 0.1016)
		(layer "F.Cu")
		(net "SAS_HDD_TX6_P")
	)
	(arc
		(start 111.12627 -113.07064)
		(mid 111.209583 -112.651798)
		(end 111.446818 -112.296702)
		(width 0.1016)
		(layer "F.Cu")
		(net "SAS_HDD_TX6_P")
	)
	(arc
		(start 112.051592 -106.412284)
		(mid 112.141885 -106.365989)
		(end 112.242092 -106.350054)
		(width 0.1016)
		(layer "F.Cu")
		(net "SAS_HDD_TX6_P")
	)
	(arc
		(start 111.163354 -113.603024)
		(mid 111.135921 -113.561873)
		(end 111.12627 -113.513362)
		(width 0.1016)
		(layer "F.Cu")
		(net "SAS_HDD_TX6_P")
	)
	(arc
		(start 111.624618 -112.118902)
		(mid 111.957027 -111.621277)
		(end 112.07369 -111.034322)
		(width 0.1016)
		(layer "F.Cu")
		(net "SAS_HDD_TX6_P")
	)
	(arc
		(start 112.07369 -109.001052)
		(mid 112.063267 -108.913505)
		(end 112.032542 -108.830872)
		(width 0.1016)
		(layer "F.Cu")
		(net "SAS_HDD_TX6_P")
	)
	(arc
		(start 111.96447 -106.622596)
		(mid 111.987111 -106.508773)
		(end 112.051592 -106.412284)
		(width 0.1016)
		(layer "F.Cu")
		(net "SAS_HDD_TX6_P")
	)
	(arc
		(start 111.26597 -113.758218)
		(mid 111.256337 -113.7097)
		(end 111.228886 -113.668556)
		(width 0.1016)
		(layer "F.Cu")
		(net "SAS_HDD_TX6_P")
	)
	(arc
		(start 112.032542 -108.830872)
		(mid 111.982162 -108.755473)
		(end 111.96447 -108.666534)
		(width 0.1016)
		(layer "F.Cu")
		(net "SAS_HDD_TX6_P")
	)
	(segment
		(start 141.598396 -44.71035)
		(end 143.51635 -46.628304)
		(width 0.1143)
		(layer "F.Cu")
		(net "XM_WE_N")
	)
	(segment
		(start 141.598396 -42.7101)
		(end 141.598396 -44.71035)
		(width 0.1143)
		(layer "F.Cu")
		(net "XM_WE_N")
	)
	(segment
		(start 141.351 -40.005)
		(end 141.351 -40.259)
		(width 0.1143)
		(layer "F.Cu")
		(net "XM_WE_N")
	)
	(segment
		(start 143.51635 -51.214528)
		(end 141.54785 -53.183028)
		(width 0.1143)
		(layer "F.Cu")
		(net "XM_WE_N")
	)
	(segment
		(start 141.54785 -53.183028)
		(end 141.54785 -54.589172)
		(width 0.1143)
		(layer "F.Cu")
		(net "XM_WE_N")
	)
	(segment
		(start 140.716 -39.37)
		(end 141.351 -40.005)
		(width 0.1143)
		(layer "F.Cu")
		(net "XM_WE_N")
	)
	(segment
		(start 143.51635 -46.628304)
		(end 143.51635 -51.214528)
		(width 0.1143)
		(layer "F.Cu")
		(net "XM_WE_N")
	)
	(segment
		(start 109.140244 -56.599836)
		(end 109.15015 -56.599836)
		(width 0.1143)
		(layer "F.Cu")
		(net "XM_WE_N")
	)
	(segment
		(start 141.351 -41.154604)
		(end 141.598396 -41.402)
		(width 0.1143)
		(layer "F.Cu")
		(net "XM_WE_N")
	)
	(segment
		(start 141.351 -40.259)
		(end 141.351 -41.154604)
		(width 0.1143)
		(layer "F.Cu")
		(net "XM_WE_N")
	)
	(segment
		(start 108.755688 -56.21528)
		(end 109.140244 -56.599836)
		(width 0.1143)
		(layer "F.Cu")
		(net "XM_WE_N")
	)
	(segment
		(start 141.598396 -41.402)
		(end 141.598396 -42.7101)
		(width 0.1143)
		(layer "F.Cu")
		(net "XM_WE_N")
	)
	(segment
		(start 140.716 -39.3065)
		(end 140.716 -39.37)
		(width 0.1143)
		(layer "F.Cu")
		(net "XM_WE_N")
	)
	(via
		(at 108.755688 -56.21528)
		(size 0.508)
		(drill 0.254)
		(layers "F.Cu" "B.Cu")
		(net "XM_WE_N")
	)
	(via
		(at 141.351 -40.259)
		(size 0.7112)
		(drill 0.3556)
		(layers "F.Cu" "B.Cu")
		(net "XM_WE_N")
	)
	(via
		(at 140.97 -55.753)
		(size 0.7112)
		(drill 0.3556)
		(layers "F.Cu" "B.Cu")
		(net "XM_WE_N")
	)
	(via
		(at 141.54785 -54.589172)
		(size 0.5588)
		(drill 0.3048)
		(layers "F.Cu" "B.Cu")
		(net "XM_WE_N")
	)
	(segment
		(start 109.146594 -55.824374)
		(end 108.755688 -56.21528)
		(width 0.1143)
		(layer "B.Cu")
		(net "XM_WE_N")
	)
	(segment
		(start 116.882926 -53.746654)
		(end 116.703348 -53.567076)
		(width 0.1143)
		(layer "B.Cu")
		(net "XM_WE_N")
	)
	(segment
		(start 115.324636 -53.567076)
		(end 114.191288 -54.700424)
		(width 0.1143)
		(layer "B.Cu")
		(net "XM_WE_N")
	)
	(segment
		(start 109.146594 -55.228998)
		(end 109.146594 -55.824374)
		(width 0.1143)
		(layer "B.Cu")
		(net "XM_WE_N")
	)
	(segment
		(start 114.191288 -54.700424)
		(end 109.675168 -54.700424)
		(width 0.1143)
		(layer "B.Cu")
		(net "XM_WE_N")
	)
	(segment
		(start 141.54785 -54.589172)
		(end 141.54785 -55.17515)
		(width 0.1143)
		(layer "B.Cu")
		(net "XM_WE_N")
	)
	(segment
		(start 130.429 -54.483)
		(end 118.999254 -54.483)
		(width 0.1143)
		(layer "B.Cu")
		(net "XM_WE_N")
	)
	(segment
		(start 141.54785 -55.17515)
		(end 140.97 -55.753)
		(width 0.1143)
		(layer "B.Cu")
		(net "XM_WE_N")
	)
	(segment
		(start 131.445 -55.499)
		(end 130.429 -54.483)
		(width 0.1143)
		(layer "B.Cu")
		(net "XM_WE_N")
	)
	(segment
		(start 140.534136 -56.188864)
		(end 138.350498 -56.188864)
		(width 0.1143)
		(layer "B.Cu")
		(net "XM_WE_N")
	)
	(segment
		(start 140.97 -55.753)
		(end 140.534136 -56.188864)
		(width 0.1143)
		(layer "B.Cu")
		(net "XM_WE_N")
	)
	(segment
		(start 118.262654 -53.746654)
		(end 116.882926 -53.746654)
		(width 0.1143)
		(layer "B.Cu")
		(net "XM_WE_N")
	)
	(segment
		(start 118.283482 -53.767482)
		(end 118.262654 -53.746654)
		(width 0.1143)
		(layer "B.Cu")
		(net "XM_WE_N")
	)
	(segment
		(start 116.703348 -53.567076)
		(end 115.324636 -53.567076)
		(width 0.1143)
		(layer "B.Cu")
		(net "XM_WE_N")
	)
	(segment
		(start 137.660634 -55.499)
		(end 131.445 -55.499)
		(width 0.1143)
		(layer "B.Cu")
		(net "XM_WE_N")
	)
	(segment
		(start 138.350498 -56.188864)
		(end 137.660634 -55.499)
		(width 0.1143)
		(layer "B.Cu")
		(net "XM_WE_N")
	)
	(segment
		(start 118.283736 -53.767482)
		(end 118.283482 -53.767482)
		(width 0.1143)
		(layer "B.Cu")
		(net "XM_WE_N")
	)
	(segment
		(start 118.999254 -54.483)
		(end 118.283736 -53.767482)
		(width 0.1143)
		(layer "B.Cu")
		(net "XM_WE_N")
	)
	(segment
		(start 109.675168 -54.700424)
		(end 109.146594 -55.228998)
		(width 0.1143)
		(layer "B.Cu")
		(net "XM_WE_N")
	)
	(via
		(at 198.7804 -105.3465)
		(size 0.7112)
		(drill 0.3556)
		(layers "F.Cu" "B.Cu")
		(net "P1V5_E_SW")
	)
	(via
		(at 198.7804 -104.394)
		(size 0.7112)
		(drill 0.4064)
		(layers "F.Cu" "B.Cu")
		(net "P1V5_E_SW")
	)
	(segment
		(start 199.898 -105.3465)
		(end 198.7804 -105.3465)
		(width 0.508)
		(layer "B.Cu")
		(net "P1V5_E_SW")
	)
	(segment
		(start 198.7804 -105.3465)
		(end 198.7804 -104.394)
		(width 0.508)
		(layer "B.Cu")
		(net "P1V5_E_SW")
	)
	(segment
		(start 71.245984 -130.601466)
		(end 71.119238 -130.601466)
		(width 0.1143)
		(layer "F.Cu")
		(net "XM_DATA1")
	)
	(segment
		(start 102.349808 -89.349834)
		(end 102.280974 -89.281)
		(width 0.1143)
		(layer "F.Cu")
		(net "XM_DATA1")
	)
	(segment
		(start 75.786742 -130.392932)
		(end 71.454518 -130.392932)
		(width 0.1143)
		(layer "F.Cu")
		(net "XM_DATA1")
	)
	(segment
		(start 102.280974 -89.281)
		(end 101.411786 -89.281)
		(width 0.1143)
		(layer "F.Cu")
		(net "XM_DATA1")
	)
	(segment
		(start 71.454518 -130.392932)
		(end 71.245984 -130.601466)
		(width 0.1143)
		(layer "F.Cu")
		(net "XM_DATA1")
	)
	(segment
		(start 101.411786 -89.281)
		(end 101.10597 -88.975184)
		(width 0.1143)
		(layer "F.Cu")
		(net "XM_DATA1")
	)
	(via
		(at 71.119238 -130.601466)
		(size 0.5588)
		(drill 0.3048)
		(layers "F.Cu" "B.Cu")
		(net "XM_DATA1")
	)
	(via
		(at 101.10597 -88.975184)
		(size 0.508)
		(drill 0.254)
		(layers "F.Cu" "B.Cu")
		(net "XM_DATA1")
	)
	(via
		(at 77.051916 -91.0971)
		(size 0.7112)
		(drill 0.3556)
		(layers "F.Cu" "B.Cu")
		(net "XM_DATA1")
	)
	(segment
		(start 70.45833 -97.852484)
		(end 70.874636 -98.26879)
		(width 0.1143)
		(layer "B.Cu")
		(net "XM_DATA1")
	)
	(segment
		(start 71.197978 -97.945448)
		(end 70.781672 -97.529142)
		(width 0.1143)
		(layer "B.Cu")
		(net "XM_DATA1")
	)
	(segment
		(start 70.94347 -97.2058)
		(end 71.105014 -97.2058)
		(width 0.1143)
		(layer "B.Cu")
		(net "XM_DATA1")
	)
	(segment
		(start 100.520246 -89.560908)
		(end 101.10597 -88.975184)
		(width 0.1143)
		(layer "B.Cu")
		(net "XM_DATA1")
	)
	(segment
		(start 72.611234 -94.318836)
		(end 73.140062 -94.847664)
		(width 0.1143)
		(layer "B.Cu")
		(net "XM_DATA1")
	)
	(segment
		(start 74.874628 -91.893898)
		(end 75.036426 -91.7321)
		(width 0.1143)
		(layer "B.Cu")
		(net "XM_DATA1")
	)
	(segment
		(start 87.461852 -89.560908)
		(end 100.520246 -89.560908)
		(width 0.1143)
		(layer "B.Cu")
		(net "XM_DATA1")
	)
	(segment
		(start 72.81672 -95.171006)
		(end 72.287892 -94.642178)
		(width 0.1143)
		(layer "B.Cu")
		(net "XM_DATA1")
	)
	(segment
		(start 76.373482 -91.614244)
		(end 76.534772 -91.614244)
		(width 0.1143)
		(layer "B.Cu")
		(net "XM_DATA1")
	)
	(segment
		(start 72.491346 -96.65208)
		(end 72.07504 -96.235774)
		(width 0.1143)
		(layer "B.Cu")
		(net "XM_DATA1")
	)
	(segment
		(start 72.934576 -93.995494)
		(end 72.934576 -93.83395)
		(width 0.1143)
		(layer "B.Cu")
		(net "XM_DATA1")
	)
	(segment
		(start 72.934576 -93.83395)
		(end 73.096374 -93.672152)
		(width 0.1143)
		(layer "B.Cu")
		(net "XM_DATA1")
	)
	(segment
		(start 73.257918 -93.672152)
		(end 73.786746 -94.20098)
		(width 0.1143)
		(layer "B.Cu")
		(net "XM_DATA1")
	)
	(segment
		(start 73.94829 -94.20098)
		(end 74.110088 -94.039182)
		(width 0.1143)
		(layer "B.Cu")
		(net "XM_DATA1")
	)
	(segment
		(start 72.491346 -96.813624)
		(end 72.491346 -96.65208)
		(width 0.1143)
		(layer "B.Cu")
		(net "XM_DATA1")
	)
	(segment
		(start 72.44969 -94.318836)
		(end 72.611234 -94.318836)
		(width 0.1143)
		(layer "B.Cu")
		(net "XM_DATA1")
	)
	(segment
		(start 70.874636 -98.26879)
		(end 71.03618 -98.26879)
		(width 0.1143)
		(layer "B.Cu")
		(net "XM_DATA1")
	)
	(segment
		(start 70.296786 -97.852484)
		(end 70.45833 -97.852484)
		(width 0.1143)
		(layer "B.Cu")
		(net "XM_DATA1")
	)
	(segment
		(start 75.403456 -92.58427)
		(end 74.874628 -92.055442)
		(width 0.1143)
		(layer "B.Cu")
		(net "XM_DATA1")
	)
	(segment
		(start 74.227944 -92.702126)
		(end 74.227944 -92.540582)
		(width 0.1143)
		(layer "B.Cu")
		(net "XM_DATA1")
	)
	(segment
		(start 74.110088 -94.039182)
		(end 74.110088 -93.877638)
		(width 0.1143)
		(layer "B.Cu")
		(net "XM_DATA1")
	)
	(segment
		(start 70.01002 -129.492248)
		(end 70.01002 -98.13925)
		(width 0.1143)
		(layer "B.Cu")
		(net "XM_DATA1")
	)
	(segment
		(start 73.58126 -93.187266)
		(end 73.743058 -93.025468)
		(width 0.1143)
		(layer "B.Cu")
		(net "XM_DATA1")
	)
	(segment
		(start 76.05014 -91.937586)
		(end 75.521312 -91.408758)
		(width 0.1143)
		(layer "B.Cu")
		(net "XM_DATA1")
	)
	(segment
		(start 71.428356 -96.882458)
		(end 71.428356 -96.720914)
		(width 0.1143)
		(layer "B.Cu")
		(net "XM_DATA1")
	)
	(segment
		(start 72.287892 -94.480634)
		(end 72.44969 -94.318836)
		(width 0.1143)
		(layer "B.Cu")
		(net "XM_DATA1")
	)
	(segment
		(start 71.03618 -98.26879)
		(end 71.197978 -98.106992)
		(width 0.1143)
		(layer "B.Cu")
		(net "XM_DATA1")
	)
	(segment
		(start 73.743058 -93.025468)
		(end 73.904602 -93.025468)
		(width 0.1143)
		(layer "B.Cu")
		(net "XM_DATA1")
	)
	(segment
		(start 75.888342 -92.260928)
		(end 76.05014 -92.09913)
		(width 0.1143)
		(layer "B.Cu")
		(net "XM_DATA1")
	)
	(segment
		(start 74.227944 -92.540582)
		(end 74.389742 -92.378784)
		(width 0.1143)
		(layer "B.Cu")
		(net "XM_DATA1")
	)
	(segment
		(start 72.287892 -94.642178)
		(end 72.287892 -94.480634)
		(width 0.1143)
		(layer "B.Cu")
		(net "XM_DATA1")
	)
	(segment
		(start 74.43343 -93.554296)
		(end 74.594974 -93.554296)
		(width 0.1143)
		(layer "B.Cu")
		(net "XM_DATA1")
	)
	(segment
		(start 74.110088 -93.877638)
		(end 73.58126 -93.34881)
		(width 0.1143)
		(layer "B.Cu")
		(net "XM_DATA1")
	)
	(segment
		(start 72.168004 -96.975422)
		(end 72.329548 -96.975422)
		(width 0.1143)
		(layer "B.Cu")
		(net "XM_DATA1")
	)
	(segment
		(start 86.247986 -90.77452)
		(end 87.055706 -89.9668)
		(width 0.1143)
		(layer "B.Cu")
		(net "XM_DATA1")
	)
	(segment
		(start 75.521312 -91.408758)
		(end 75.521312 -91.247214)
		(width 0.1143)
		(layer "B.Cu")
		(net "XM_DATA1")
	)
	(segment
		(start 74.551286 -92.378784)
		(end 75.080114 -92.907612)
		(width 0.1143)
		(layer "B.Cu")
		(net "XM_DATA1")
	)
	(segment
		(start 73.786746 -94.20098)
		(end 73.94829 -94.20098)
		(width 0.1143)
		(layer "B.Cu")
		(net "XM_DATA1")
	)
	(segment
		(start 73.140062 -94.847664)
		(end 73.301606 -94.847664)
		(width 0.1143)
		(layer "B.Cu")
		(net "XM_DATA1")
	)
	(segment
		(start 70.781672 -97.367598)
		(end 70.94347 -97.2058)
		(width 0.1143)
		(layer "B.Cu")
		(net "XM_DATA1")
	)
	(segment
		(start 71.197978 -98.106992)
		(end 71.197978 -97.945448)
		(width 0.1143)
		(layer "B.Cu")
		(net "XM_DATA1")
	)
	(segment
		(start 75.403456 -92.745814)
		(end 75.403456 -92.58427)
		(width 0.1143)
		(layer "B.Cu")
		(net "XM_DATA1")
	)
	(segment
		(start 71.119238 -130.601466)
		(end 70.01002 -129.492248)
		(width 0.1143)
		(layer "B.Cu")
		(net "XM_DATA1")
	)
	(segment
		(start 77.374496 -90.77452)
		(end 86.247986 -90.77452)
		(width 0.1143)
		(layer "B.Cu")
		(net "XM_DATA1")
	)
	(segment
		(start 71.590154 -96.559116)
		(end 71.751698 -96.559116)
		(width 0.1143)
		(layer "B.Cu")
		(net "XM_DATA1")
	)
	(segment
		(start 70.01002 -98.13925)
		(end 70.296786 -97.852484)
		(width 0.1143)
		(layer "B.Cu")
		(net "XM_DATA1")
	)
	(segment
		(start 74.874628 -92.055442)
		(end 74.874628 -91.893898)
		(width 0.1143)
		(layer "B.Cu")
		(net "XM_DATA1")
	)
	(segment
		(start 77.051916 -91.0971)
		(end 77.374496 -90.77452)
		(width 0.1143)
		(layer "B.Cu")
		(net "XM_DATA1")
	)
	(segment
		(start 75.521312 -91.247214)
		(end 75.68311 -91.085416)
		(width 0.1143)
		(layer "B.Cu")
		(net "XM_DATA1")
	)
	(segment
		(start 75.19797 -91.7321)
		(end 75.726798 -92.260928)
		(width 0.1143)
		(layer "B.Cu")
		(net "XM_DATA1")
	)
	(segment
		(start 76.05014 -92.09913)
		(end 76.05014 -91.937586)
		(width 0.1143)
		(layer "B.Cu")
		(net "XM_DATA1")
	)
	(segment
		(start 71.751698 -96.559116)
		(end 72.168004 -96.975422)
		(width 0.1143)
		(layer "B.Cu")
		(net "XM_DATA1")
	)
	(segment
		(start 87.05596 -89.9668)
		(end 87.461852 -89.560908)
		(width 0.1143)
		(layer "B.Cu")
		(net "XM_DATA1")
	)
	(segment
		(start 75.080114 -92.907612)
		(end 75.241658 -92.907612)
		(width 0.1143)
		(layer "B.Cu")
		(net "XM_DATA1")
	)
	(segment
		(start 75.844654 -91.085416)
		(end 76.373482 -91.614244)
		(width 0.1143)
		(layer "B.Cu")
		(net "XM_DATA1")
	)
	(segment
		(start 71.844662 -97.298764)
		(end 71.428356 -96.882458)
		(width 0.1143)
		(layer "B.Cu")
		(net "XM_DATA1")
	)
	(segment
		(start 73.096374 -93.672152)
		(end 73.257918 -93.672152)
		(width 0.1143)
		(layer "B.Cu")
		(net "XM_DATA1")
	)
	(segment
		(start 72.329548 -96.975422)
		(end 72.491346 -96.813624)
		(width 0.1143)
		(layer "B.Cu")
		(net "XM_DATA1")
	)
	(segment
		(start 73.463404 -94.685866)
		(end 73.463404 -94.524322)
		(width 0.1143)
		(layer "B.Cu")
		(net "XM_DATA1")
	)
	(segment
		(start 75.036426 -91.7321)
		(end 75.19797 -91.7321)
		(width 0.1143)
		(layer "B.Cu")
		(net "XM_DATA1")
	)
	(segment
		(start 71.52132 -97.622106)
		(end 71.682864 -97.622106)
		(width 0.1143)
		(layer "B.Cu")
		(net "XM_DATA1")
	)
	(segment
		(start 72.07504 -96.07423)
		(end 72.81672 -95.33255)
		(width 0.1143)
		(layer "B.Cu")
		(net "XM_DATA1")
	)
	(segment
		(start 75.241658 -92.907612)
		(end 75.403456 -92.745814)
		(width 0.1143)
		(layer "B.Cu")
		(net "XM_DATA1")
	)
	(segment
		(start 72.81672 -95.33255)
		(end 72.81672 -95.171006)
		(width 0.1143)
		(layer "B.Cu")
		(net "XM_DATA1")
	)
	(segment
		(start 71.105014 -97.2058)
		(end 71.52132 -97.622106)
		(width 0.1143)
		(layer "B.Cu")
		(net "XM_DATA1")
	)
	(segment
		(start 76.534772 -91.614244)
		(end 77.051916 -91.0971)
		(width 0.1143)
		(layer "B.Cu")
		(net "XM_DATA1")
	)
	(segment
		(start 73.904602 -93.025468)
		(end 74.43343 -93.554296)
		(width 0.1143)
		(layer "B.Cu")
		(net "XM_DATA1")
	)
	(segment
		(start 72.07504 -96.235774)
		(end 72.07504 -96.07423)
		(width 0.1143)
		(layer "B.Cu")
		(net "XM_DATA1")
	)
	(segment
		(start 75.68311 -91.085416)
		(end 75.844654 -91.085416)
		(width 0.1143)
		(layer "B.Cu")
		(net "XM_DATA1")
	)
	(segment
		(start 70.781672 -97.529142)
		(end 70.781672 -97.367598)
		(width 0.1143)
		(layer "B.Cu")
		(net "XM_DATA1")
	)
	(segment
		(start 71.428356 -96.720914)
		(end 71.590154 -96.559116)
		(width 0.1143)
		(layer "B.Cu")
		(net "XM_DATA1")
	)
	(segment
		(start 87.055706 -89.9668)
		(end 87.05596 -89.9668)
		(width 0.1143)
		(layer "B.Cu")
		(net "XM_DATA1")
	)
	(segment
		(start 74.756772 -93.392498)
		(end 74.756772 -93.230954)
		(width 0.1143)
		(layer "B.Cu")
		(net "XM_DATA1")
	)
	(segment
		(start 74.389742 -92.378784)
		(end 74.551286 -92.378784)
		(width 0.1143)
		(layer "B.Cu")
		(net "XM_DATA1")
	)
	(segment
		(start 73.463404 -94.524322)
		(end 72.934576 -93.995494)
		(width 0.1143)
		(layer "B.Cu")
		(net "XM_DATA1")
	)
	(segment
		(start 73.58126 -93.34881)
		(end 73.58126 -93.187266)
		(width 0.1143)
		(layer "B.Cu")
		(net "XM_DATA1")
	)
	(segment
		(start 71.682864 -97.622106)
		(end 71.844662 -97.460308)
		(width 0.1143)
		(layer "B.Cu")
		(net "XM_DATA1")
	)
	(segment
		(start 75.726798 -92.260928)
		(end 75.888342 -92.260928)
		(width 0.1143)
		(layer "B.Cu")
		(net "XM_DATA1")
	)
	(segment
		(start 74.756772 -93.230954)
		(end 74.227944 -92.702126)
		(width 0.1143)
		(layer "B.Cu")
		(net "XM_DATA1")
	)
	(segment
		(start 73.301606 -94.847664)
		(end 73.463404 -94.685866)
		(width 0.1143)
		(layer "B.Cu")
		(net "XM_DATA1")
	)
	(segment
		(start 74.594974 -93.554296)
		(end 74.756772 -93.392498)
		(width 0.1143)
		(layer "B.Cu")
		(net "XM_DATA1")
	)
	(segment
		(start 71.844662 -97.460308)
		(end 71.844662 -97.298764)
		(width 0.1143)
		(layer "B.Cu")
		(net "XM_DATA1")
	)
	(segment
		(start 199.142096 -120.733312)
		(end 198.062596 -120.733312)
		(width 0.508)
		(layer "F.Cu")
		(net "P1V5_E_VRG5")
	)
	(segment
		(start 199.205596 -120.796812)
		(end 199.142096 -120.733312)
		(width 0.508)
		(layer "F.Cu")
		(net "P1V5_E_VRG5")
	)
	(segment
		(start 200.090532 -117.856)
		(end 199.136 -118.810532)
		(width 0.3048)
		(layer "F.Cu")
		(net "P1V5_E_VRG5")
	)
	(segment
		(start 199.136 -119.253)
		(end 199.205596 -119.322596)
		(width 0.508)
		(layer "F.Cu")
		(net "P1V5_E_VRG5")
	)
	(segment
		(start 199.136 -118.810532)
		(end 199.136 -119.253)
		(width 0.508)
		(layer "F.Cu")
		(net "P1V5_E_VRG5")
	)
	(segment
		(start 199.205596 -119.322596)
		(end 199.205596 -120.796812)
		(width 0.508)
		(layer "F.Cu")
		(net "P1V5_E_VRG5")
	)
	(segment
		(start 200.090532 -116.112036)
		(end 200.090532 -117.856)
		(width 0.3048)
		(layer "F.Cu")
		(net "P1V5_E_VRG5")
	)
	(via
		(at 199.136 -119.253)
		(size 0.7112)
		(drill 0.3556)
		(layers "F.Cu" "B.Cu")
		(net "P1V5_E_VRG5")
	)
	(segment
		(start 70.13321 -141.16304)
		(end 69.90461 -141.16304)
		(width 0.1143)
		(layer "F.Cu")
		(net "EXP_XM_ADDR_17")
	)
	(segment
		(start 75.786742 -138.893042)
		(end 75.019408 -138.893042)
		(width 0.1143)
		(layer "F.Cu")
		(net "EXP_XM_ADDR_17")
	)
	(segment
		(start 70.70471 -141.04874)
		(end 70.70471 -139.5603)
		(width 0.1143)
		(layer "F.Cu")
		(net "EXP_XM_ADDR_17")
	)
	(segment
		(start 69.79031 -141.04874)
		(end 69.79031 -139.5603)
		(width 0.1143)
		(layer "F.Cu")
		(net "EXP_XM_ADDR_17")
	)
	(segment
		(start 70.24751 -139.5603)
		(end 70.24751 -141.04874)
		(width 0.1143)
		(layer "F.Cu")
		(net "EXP_XM_ADDR_17")
	)
	(segment
		(start 71.04761 -141.16304)
		(end 70.81901 -141.16304)
		(width 0.1143)
		(layer "F.Cu")
		(net "EXP_XM_ADDR_17")
	)
	(segment
		(start 70.81901 -141.16304)
		(end 70.70471 -141.04874)
		(width 0.1143)
		(layer "F.Cu")
		(net "EXP_XM_ADDR_17")
	)
	(segment
		(start 71.27621 -139.446)
		(end 71.16191 -139.5603)
		(width 0.1143)
		(layer "F.Cu")
		(net "EXP_XM_ADDR_17")
	)
	(segment
		(start 69.79031 -139.5603)
		(end 69.67601 -139.446)
		(width 0.1143)
		(layer "F.Cu")
		(net "EXP_XM_ADDR_17")
	)
	(segment
		(start 106.3498 -94.349824)
		(end 105.849674 -93.849698)
		(width 0.1143)
		(layer "F.Cu")
		(net "EXP_XM_ADDR_17")
	)
	(segment
		(start 69.67601 -139.446)
		(end 66.35877 -139.446)
		(width 0.1143)
		(layer "F.Cu")
		(net "EXP_XM_ADDR_17")
	)
	(segment
		(start 93.48597 -98.933)
		(end 93.61297 -98.806)
		(width 0.1143)
		(layer "F.Cu")
		(net "EXP_XM_ADDR_17")
	)
	(segment
		(start 70.59041 -139.446)
		(end 70.36181 -139.446)
		(width 0.1143)
		(layer "F.Cu")
		(net "EXP_XM_ADDR_17")
	)
	(segment
		(start 71.16191 -139.5603)
		(end 71.16191 -141.04874)
		(width 0.1143)
		(layer "F.Cu")
		(net "EXP_XM_ADDR_17")
	)
	(segment
		(start 92.66047 -98.933)
		(end 93.48597 -98.933)
		(width 0.1143)
		(layer "F.Cu")
		(net "EXP_XM_ADDR_17")
	)
	(segment
		(start 74.46645 -139.446)
		(end 71.27621 -139.446)
		(width 0.1143)
		(layer "F.Cu")
		(net "EXP_XM_ADDR_17")
	)
	(segment
		(start 70.36181 -139.446)
		(end 70.24751 -139.5603)
		(width 0.1143)
		(layer "F.Cu")
		(net "EXP_XM_ADDR_17")
	)
	(segment
		(start 70.70471 -139.5603)
		(end 70.59041 -139.446)
		(width 0.1143)
		(layer "F.Cu")
		(net "EXP_XM_ADDR_17")
	)
	(segment
		(start 75.019408 -138.893042)
		(end 74.46645 -139.446)
		(width 0.1143)
		(layer "F.Cu")
		(net "EXP_XM_ADDR_17")
	)
	(segment
		(start 70.24751 -141.04874)
		(end 70.13321 -141.16304)
		(width 0.1143)
		(layer "F.Cu")
		(net "EXP_XM_ADDR_17")
	)
	(segment
		(start 71.16191 -141.04874)
		(end 71.04761 -141.16304)
		(width 0.1143)
		(layer "F.Cu")
		(net "EXP_XM_ADDR_17")
	)
	(segment
		(start 69.90461 -141.16304)
		(end 69.79031 -141.04874)
		(width 0.1143)
		(layer "F.Cu")
		(net "EXP_XM_ADDR_17")
	)
	(via
		(at 66.35877 -139.446)
		(size 0.5588)
		(drill 0.3048)
		(layers "F.Cu" "B.Cu")
		(net "EXP_XM_ADDR_17")
	)
	(via
		(at 93.61297 -98.806)
		(size 0.508)
		(drill 0.254)
		(layers "F.Cu" "B.Cu")
		(net "EXP_XM_ADDR_17")
	)
	(via
		(at 105.849674 -93.849698)
		(size 0.508)
		(drill 0.254)
		(layers "F.Cu" "B.Cu")
		(net "EXP_XM_ADDR_17")
	)
	(via
		(at 66.9798 -140.335)
		(size 0.7112)
		(drill 0.3556)
		(layers "F.Cu" "B.Cu")
		(net "EXP_XM_ADDR_17")
	)
	(segment
		(start 66.9798 -140.06703)
		(end 66.9798 -140.335)
		(width 0.1143)
		(layer "B.Cu")
		(net "EXP_XM_ADDR_17")
	)
	(segment
		(start 66.35877 -139.446)
		(end 66.9798 -140.06703)
		(width 0.1143)
		(layer "B.Cu")
		(net "EXP_XM_ADDR_17")
	)
	(segment
		(start 67.79387 -130.487674)
		(end 67.79387 -132.255514)
		(width 0.127)
		(layer "In2.Cu")
		(net "EXP_XM_ADDR_17")
	)
	(segment
		(start 102.4255 -94.66834)
		(end 101.08184 -96.012)
		(width 0.127)
		(layer "In2.Cu")
		(net "EXP_XM_ADDR_17")
	)
	(segment
		(start 94.237556 -98.062796)
		(end 93.962474 -98.337878)
		(width 0.127)
		(layer "In2.Cu")
		(net "EXP_XM_ADDR_17")
	)
	(segment
		(start 67.79387 -132.255514)
		(end 67.05727 -132.992114)
		(width 0.127)
		(layer "In2.Cu")
		(net "EXP_XM_ADDR_17")
	)
	(segment
		(start 93.77807 -98.640646)
		(end 93.61297 -98.806)
		(width 0.127)
		(layer "In2.Cu")
		(net "EXP_XM_ADDR_17")
	)
	(segment
		(start 86.94293 -99.3648)
		(end 86.94293 -105.004616)
		(width 0.127)
		(layer "In2.Cu")
		(net "EXP_XM_ADDR_17")
	)
	(segment
		(start 87.99195 -98.31578)
		(end 86.94293 -99.3648)
		(width 0.127)
		(layer "In2.Cu")
		(net "EXP_XM_ADDR_17")
	)
	(segment
		(start 93.61297 -98.806)
		(end 93.12275 -98.31578)
		(width 0.127)
		(layer "In2.Cu")
		(net "EXP_XM_ADDR_17")
	)
	(segment
		(start 67.05727 -132.992114)
		(end 67.05727 -133.84022)
		(width 0.127)
		(layer "In2.Cu")
		(net "EXP_XM_ADDR_17")
	)
	(segment
		(start 96.780858 -96.012)
		(end 94.729808 -98.062796)
		(width 0.127)
		(layer "In2.Cu")
		(net "EXP_XM_ADDR_17")
	)
	(segment
		(start 70.04939 -128.2319)
		(end 68.09867 -130.18262)
		(width 0.127)
		(layer "In2.Cu")
		(net "EXP_XM_ADDR_17")
	)
	(segment
		(start 66.35877 -134.53872)
		(end 66.35877 -139.446)
		(width 0.127)
		(layer "In2.Cu")
		(net "EXP_XM_ADDR_17")
	)
	(segment
		(start 94.729808 -98.062796)
		(end 94.237556 -98.062796)
		(width 0.127)
		(layer "In2.Cu")
		(net "EXP_XM_ADDR_17")
	)
	(segment
		(start 105.849674 -93.849698)
		(end 105.653332 -93.849698)
		(width 0.127)
		(layer "In2.Cu")
		(net "EXP_XM_ADDR_17")
	)
	(segment
		(start 93.12275 -98.31578)
		(end 87.99195 -98.31578)
		(width 0.127)
		(layer "In2.Cu")
		(net "EXP_XM_ADDR_17")
	)
	(segment
		(start 68.09867 -130.18262)
		(end 68.09867 -130.182874)
		(width 0.127)
		(layer "In2.Cu")
		(net "EXP_XM_ADDR_17")
	)
	(segment
		(start 102.88651 -94.56674)
		(end 102.78491 -94.66834)
		(width 0.127)
		(layer "In2.Cu")
		(net "EXP_XM_ADDR_17")
	)
	(segment
		(start 86.94293 -105.004616)
		(end 85.450426 -106.49712)
		(width 0.127)
		(layer "In2.Cu")
		(net "EXP_XM_ADDR_17")
	)
	(segment
		(start 101.08184 -96.012)
		(end 96.780858 -96.012)
		(width 0.127)
		(layer "In2.Cu")
		(net "EXP_XM_ADDR_17")
	)
	(segment
		(start 102.78491 -94.66834)
		(end 102.4255 -94.66834)
		(width 0.127)
		(layer "In2.Cu")
		(net "EXP_XM_ADDR_17")
	)
	(segment
		(start 67.05727 -133.84022)
		(end 66.35877 -134.53872)
		(width 0.127)
		(layer "In2.Cu")
		(net "EXP_XM_ADDR_17")
	)
	(segment
		(start 70.04939 -118.217188)
		(end 70.04939 -128.2319)
		(width 0.127)
		(layer "In2.Cu")
		(net "EXP_XM_ADDR_17")
	)
	(segment
		(start 85.450426 -106.49712)
		(end 81.769204 -106.49712)
		(width 0.127)
		(layer "In2.Cu")
		(net "EXP_XM_ADDR_17")
	)
	(segment
		(start 93.962474 -98.456242)
		(end 93.77807 -98.640646)
		(width 0.127)
		(layer "In2.Cu")
		(net "EXP_XM_ADDR_17")
	)
	(segment
		(start 104.93629 -94.56674)
		(end 102.88651 -94.56674)
		(width 0.127)
		(layer "In2.Cu")
		(net "EXP_XM_ADDR_17")
	)
	(segment
		(start 105.653332 -93.849698)
		(end 104.93629 -94.56674)
		(width 0.127)
		(layer "In2.Cu")
		(net "EXP_XM_ADDR_17")
	)
	(segment
		(start 81.769204 -106.49712)
		(end 70.04939 -118.217188)
		(width 0.127)
		(layer "In2.Cu")
		(net "EXP_XM_ADDR_17")
	)
	(segment
		(start 93.962474 -98.337878)
		(end 93.962474 -98.456242)
		(width 0.127)
		(layer "In2.Cu")
		(net "EXP_XM_ADDR_17")
	)
	(segment
		(start 68.09867 -130.182874)
		(end 67.79387 -130.487674)
		(width 0.127)
		(layer "In2.Cu")
		(net "EXP_XM_ADDR_17")
	)
	(segment
		(start 112.40897 -114.0206)
		(end 112.40897 -113.798096)
		(width 0.1016)
		(layer "F.Cu")
		(net "SAS_HDD_TX5_N")
	)
	(segment
		(start 112.879378 -107.518708)
		(end 112.879378 -107.485688)
		(width 0.1016)
		(layer "F.Cu")
		(net "SAS_HDD_TX5_N")
	)
	(segment
		(start 112.55502 -113.488216)
		(end 112.55502 -112.710468)
		(width 0.1016)
		(layer "F.Cu")
		(net "SAS_HDD_TX5_N")
	)
	(segment
		(start 112.86617 -111.959136)
		(end 112.86617 -107.67314)
		(width 0.1016)
		(layer "F.Cu")
		(net "SAS_HDD_TX5_N")
	)
	(segment
		(start 112.482122 -113.62182)
		(end 112.512348 -113.591594)
		(width 0.1016)
		(layer "F.Cu")
		(net "SAS_HDD_TX5_N")
	)
	(arc
		(start 112.40897 -113.798096)
		(mid 112.427987 -113.702673)
		(end 112.482122 -113.62182)
		(width 0.1016)
		(layer "F.Cu")
		(net "SAS_HDD_TX5_N")
	)
	(arc
		(start 112.879378 -107.485688)
		(mid 113.001631 -106.871082)
		(end 113.349786 -106.350054)
		(width 0.1016)
		(layer "F.Cu")
		(net "SAS_HDD_TX5_N")
	)
	(arc
		(start 112.512348 -113.591594)
		(mid 112.543933 -113.544135)
		(end 112.55502 -113.488216)
		(width 0.1016)
		(layer "F.Cu")
		(net "SAS_HDD_TX5_N")
	)
	(arc
		(start 112.810798 -112.091978)
		(mid 112.851742 -112.031074)
		(end 112.86617 -111.959136)
		(width 0.1016)
		(layer "F.Cu")
		(net "SAS_HDD_TX5_N")
	)
	(arc
		(start 112.86617 -107.67314)
		(mid 112.869442 -107.595639)
		(end 112.879378 -107.518708)
		(width 0.1016)
		(layer "F.Cu")
		(net "SAS_HDD_TX5_N")
	)
	(arc
		(start 112.55502 -112.710468)
		(mid 112.621374 -112.375764)
		(end 112.810798 -112.091978)
		(width 0.1016)
		(layer "F.Cu")
		(net "SAS_HDD_TX5_N")
	)
	(segment
		(start 201.408284 -121.666)
		(end 202.202796 -121.666)
		(width 0.254)
		(layer "F.Cu")
		(net "P1V5_E_VFB_R")
	)
	(segment
		(start 201.364596 -121.622312)
		(end 201.408284 -121.666)
		(width 0.254)
		(layer "F.Cu")
		(net "P1V5_E_VFB_R")
	)
	(via
		(at 202.202796 -121.666)
		(size 0.5588)
		(drill 0.3048)
		(layers "F.Cu" "B.Cu")
		(net "P1V5_E_VFB_R")
	)
	(via
		(at 200.914 -118.517162)
		(size 0.7112)
		(drill 0.3556)
		(layers "F.Cu" "B.Cu")
		(net "P1V5_E_VFB_R")
	)
	(segment
		(start 202.202796 -121.666)
		(end 200.914 -120.377204)
		(width 0.254)
		(layer "B.Cu")
		(net "P1V5_E_VFB_R")
	)
	(segment
		(start 200.914 -120.377204)
		(end 200.914 -118.517162)
		(width 0.254)
		(layer "B.Cu")
		(net "P1V5_E_VFB_R")
	)
	(segment
		(start 200.914 -104.775)
		(end 200.914 -118.517162)
		(width 0.254)
		(layer "B.Cu")
		(net "P1V5_E_VFB_R")
	)
	(segment
		(start 199.898 -103.251)
		(end 199.898 -104.4575)
		(width 0.254)
		(layer "B.Cu")
		(net "P1V5_E_VFB_R")
	)
	(segment
		(start 199.898 -104.4575)
		(end 200.5965 -104.4575)
		(width 0.254)
		(layer "B.Cu")
		(net "P1V5_E_VFB_R")
	)
	(segment
		(start 200.5965 -104.4575)
		(end 200.914 -104.775)
		(width 0.254)
		(layer "B.Cu")
		(net "P1V5_E_VFB_R")
	)
	(segment
		(start 108.349796 -95.350076)
		(end 108.356654 -95.350076)
		(width 0.1143)
		(layer "F.Cu")
		(net "EXP_XM_ADDR_10")
	)
	(segment
		(start 56.558942 -135.892032)
		(end 66.712338 -135.892032)
		(width 0.1143)
		(layer "F.Cu")
		(net "EXP_XM_ADDR_10")
	)
	(segment
		(start 108.356654 -95.350076)
		(end 108.82503 -94.8817)
		(width 0.1143)
		(layer "F.Cu")
		(net "EXP_XM_ADDR_10")
	)
	(segment
		(start 66.712338 -135.892032)
		(end 66.84137 -135.763)
		(width 0.1143)
		(layer "F.Cu")
		(net "EXP_XM_ADDR_10")
	)
	(segment
		(start 66.84137 -135.763)
		(end 66.94297 -135.763)
		(width 0.1143)
		(layer "F.Cu")
		(net "EXP_XM_ADDR_10")
	)
	(via
		(at 108.82503 -94.8817)
		(size 0.508)
		(drill 0.254)
		(layers "F.Cu" "B.Cu")
		(net "EXP_XM_ADDR_10")
	)
	(via
		(at 65.786 -136.5758)
		(size 0.7112)
		(drill 0.3556)
		(layers "F.Cu" "B.Cu")
		(net "EXP_XM_ADDR_10")
	)
	(via
		(at 66.94297 -135.763)
		(size 0.5588)
		(drill 0.3048)
		(layers "F.Cu" "B.Cu")
		(net "EXP_XM_ADDR_10")
	)
	(segment
		(start 66.94297 -135.763)
		(end 66.5988 -135.763)
		(width 0.1143)
		(layer "B.Cu")
		(net "EXP_XM_ADDR_10")
	)
	(segment
		(start 66.5988 -135.763)
		(end 65.786 -136.5758)
		(width 0.1143)
		(layer "B.Cu")
		(net "EXP_XM_ADDR_10")
	)
	(segment
		(start 91.07551 -98.69678)
		(end 90.94851 -98.82378)
		(width 0.127)
		(layer "In2.Cu")
		(net "EXP_XM_ADDR_10")
	)
	(segment
		(start 92.47251 -98.82378)
		(end 92.34551 -98.69678)
		(width 0.127)
		(layer "In2.Cu")
		(net "EXP_XM_ADDR_10")
	)
	(segment
		(start 87.539322 -99.632008)
		(end 87.32393 -99.8474)
		(width 0.127)
		(layer "In2.Cu")
		(net "EXP_XM_ADDR_10")
	)
	(segment
		(start 96.936052 -96.395794)
		(end 94.902274 -98.429572)
		(width 0.127)
		(layer "In2.Cu")
		(net "EXP_XM_ADDR_10")
	)
	(segment
		(start 90.94851 -99.505008)
		(end 90.82151 -99.632008)
		(width 0.127)
		(layer "In2.Cu")
		(net "EXP_XM_ADDR_10")
	)
	(segment
		(start 91.96451 -98.82378)
		(end 91.96451 -99.505008)
		(width 0.127)
		(layer "In2.Cu")
		(net "EXP_XM_ADDR_10")
	)
	(segment
		(start 87.91321 -100.3554)
		(end 88.04021 -100.4824)
		(width 0.127)
		(layer "In2.Cu")
		(net "EXP_XM_ADDR_10")
	)
	(segment
		(start 68.47967 -130.340862)
		(end 68.17487 -130.645916)
		(width 0.127)
		(layer "In2.Cu")
		(net "EXP_XM_ADDR_10")
	)
	(segment
		(start 87.32393 -105.162604)
		(end 85.608414 -106.87812)
		(width 0.127)
		(layer "In2.Cu")
		(net "EXP_XM_ADDR_10")
	)
	(segment
		(start 93.319092 -99.454208)
		(end 93.141292 -99.632008)
		(width 0.127)
		(layer "In2.Cu")
		(net "EXP_XM_ADDR_10")
	)
	(segment
		(start 70.43039 -128.389888)
		(end 68.47967 -130.340608)
		(width 0.127)
		(layer "In2.Cu")
		(net "EXP_XM_ADDR_10")
	)
	(segment
		(start 102.99192 -94.82074)
		(end 101.416866 -96.395794)
		(width 0.127)
		(layer "In2.Cu")
		(net "EXP_XM_ADDR_10")
	)
	(segment
		(start 87.45093 -101.3714)
		(end 87.91321 -101.3714)
		(width 0.127)
		(layer "In2.Cu")
		(net "EXP_XM_ADDR_10")
	)
	(segment
		(start 68.47967 -130.340608)
		(end 68.47967 -130.340862)
		(width 0.127)
		(layer "In2.Cu")
		(net "EXP_XM_ADDR_10")
	)
	(segment
		(start 90.44051 -99.632008)
		(end 90.389202 -99.5807)
		(width 0.127)
		(layer "In2.Cu")
		(net "EXP_XM_ADDR_10")
	)
	(segment
		(start 94.285308 -99.34448)
		(end 93.45041 -99.34448)
		(width 0.127)
		(layer "In2.Cu")
		(net "EXP_XM_ADDR_10")
	)
	(segment
		(start 94.902274 -98.727514)
		(end 94.285308 -99.34448)
		(width 0.127)
		(layer "In2.Cu")
		(net "EXP_XM_ADDR_10")
	)
	(segment
		(start 88.04021 -100.7364)
		(end 87.91321 -100.8634)
		(width 0.127)
		(layer "In2.Cu")
		(net "EXP_XM_ADDR_10")
	)
	(segment
		(start 88.911938 -99.632008)
		(end 88.784938 -99.505008)
		(width 0.127)
		(layer "In2.Cu")
		(net "EXP_XM_ADDR_10")
	)
	(segment
		(start 91.83751 -99.632008)
		(end 91.58351 -99.632008)
		(width 0.127)
		(layer "In2.Cu")
		(net "EXP_XM_ADDR_10")
	)
	(segment
		(start 88.04021 -100.4824)
		(end 88.04021 -100.7364)
		(width 0.127)
		(layer "In2.Cu")
		(net "EXP_XM_ADDR_10")
	)
	(segment
		(start 88.276938 -98.82378)
		(end 88.276938 -99.505008)
		(width 0.127)
		(layer "In2.Cu")
		(net "EXP_XM_ADDR_10")
	)
	(segment
		(start 90.82151 -99.632008)
		(end 90.44051 -99.632008)
		(width 0.127)
		(layer "In2.Cu")
		(net "EXP_XM_ADDR_10")
	)
	(segment
		(start 93.141292 -99.632008)
		(end 92.59951 -99.632008)
		(width 0.127)
		(layer "In2.Cu")
		(net "EXP_XM_ADDR_10")
	)
	(segment
		(start 91.32951 -98.69678)
		(end 91.07551 -98.69678)
		(width 0.127)
		(layer "In2.Cu")
		(net "EXP_XM_ADDR_10")
	)
	(segment
		(start 87.32393 -102.0064)
		(end 87.32393 -105.162604)
		(width 0.127)
		(layer "In2.Cu")
		(net "EXP_XM_ADDR_10")
	)
	(segment
		(start 93.45041 -99.34448)
		(end 93.340682 -99.454208)
		(width 0.127)
		(layer "In2.Cu")
		(net "EXP_XM_ADDR_10")
	)
	(segment
		(start 87.45093 -100.3554)
		(end 87.91321 -100.3554)
		(width 0.127)
		(layer "In2.Cu")
		(net "EXP_XM_ADDR_10")
	)
	(segment
		(start 90.389202 -99.5807)
		(end 89.978738 -99.5807)
		(width 0.127)
		(layer "In2.Cu")
		(net "EXP_XM_ADDR_10")
	)
	(segment
		(start 70.43039 -118.375176)
		(end 70.43039 -128.389888)
		(width 0.127)
		(layer "In2.Cu")
		(net "EXP_XM_ADDR_10")
	)
	(segment
		(start 105.86974 -94.82074)
		(end 102.99192 -94.82074)
		(width 0.127)
		(layer "In2.Cu")
		(net "EXP_XM_ADDR_10")
	)
	(segment
		(start 88.276938 -99.505008)
		(end 88.149938 -99.632008)
		(width 0.127)
		(layer "In2.Cu")
		(net "EXP_XM_ADDR_10")
	)
	(segment
		(start 91.45651 -98.82378)
		(end 91.32951 -98.69678)
		(width 0.127)
		(layer "In2.Cu")
		(net "EXP_XM_ADDR_10")
	)
	(segment
		(start 88.403938 -98.69678)
		(end 88.276938 -98.82378)
		(width 0.127)
		(layer "In2.Cu")
		(net "EXP_XM_ADDR_10")
	)
	(segment
		(start 88.149938 -99.632008)
		(end 87.539322 -99.632008)
		(width 0.127)
		(layer "In2.Cu")
		(net "EXP_XM_ADDR_10")
	)
	(segment
		(start 93.340682 -99.454208)
		(end 93.319092 -99.454208)
		(width 0.127)
		(layer "In2.Cu")
		(net "EXP_XM_ADDR_10")
	)
	(segment
		(start 87.91321 -101.8794)
		(end 87.45093 -101.8794)
		(width 0.127)
		(layer "In2.Cu")
		(net "EXP_XM_ADDR_10")
	)
	(segment
		(start 67.43827 -133.424676)
		(end 67.43827 -134.470394)
		(width 0.127)
		(layer "In2.Cu")
		(net "EXP_XM_ADDR_10")
	)
	(segment
		(start 91.58351 -99.632008)
		(end 91.45651 -99.505008)
		(width 0.127)
		(layer "In2.Cu")
		(net "EXP_XM_ADDR_10")
	)
	(segment
		(start 85.608414 -106.87812)
		(end 81.927192 -106.87812)
		(width 0.127)
		(layer "In2.Cu")
		(net "EXP_XM_ADDR_10")
	)
	(segment
		(start 88.784938 -98.82378)
		(end 88.657938 -98.69678)
		(width 0.127)
		(layer "In2.Cu")
		(net "EXP_XM_ADDR_10")
	)
	(segment
		(start 88.04021 -101.4984)
		(end 88.04021 -101.7524)
		(width 0.127)
		(layer "In2.Cu")
		(net "EXP_XM_ADDR_10")
	)
	(segment
		(start 87.91321 -100.8634)
		(end 87.45093 -100.8634)
		(width 0.127)
		(layer "In2.Cu")
		(net "EXP_XM_ADDR_10")
	)
	(segment
		(start 101.416866 -96.395794)
		(end 96.936052 -96.395794)
		(width 0.127)
		(layer "In2.Cu")
		(net "EXP_XM_ADDR_10")
	)
	(segment
		(start 92.34551 -98.69678)
		(end 92.09151 -98.69678)
		(width 0.127)
		(layer "In2.Cu")
		(net "EXP_XM_ADDR_10")
	)
	(segment
		(start 66.94297 -134.965694)
		(end 66.94297 -135.763)
		(width 0.127)
		(layer "In2.Cu")
		(net "EXP_XM_ADDR_10")
	)
	(segment
		(start 67.43827 -134.470394)
		(end 66.94297 -134.965694)
		(width 0.127)
		(layer "In2.Cu")
		(net "EXP_XM_ADDR_10")
	)
	(segment
		(start 87.32393 -100.2284)
		(end 87.45093 -100.3554)
		(width 0.127)
		(layer "In2.Cu")
		(net "EXP_XM_ADDR_10")
	)
	(segment
		(start 87.32393 -101.2444)
		(end 87.45093 -101.3714)
		(width 0.127)
		(layer "In2.Cu")
		(net "EXP_XM_ADDR_10")
	)
	(segment
		(start 88.784938 -99.505008)
		(end 88.784938 -98.82378)
		(width 0.127)
		(layer "In2.Cu")
		(net "EXP_XM_ADDR_10")
	)
	(segment
		(start 105.9307 -94.8817)
		(end 105.86974 -94.82074)
		(width 0.127)
		(layer "In2.Cu")
		(net "EXP_XM_ADDR_10")
	)
	(segment
		(start 68.17487 -130.645916)
		(end 68.17487 -132.688076)
		(width 0.127)
		(layer "In2.Cu")
		(net "EXP_XM_ADDR_10")
	)
	(segment
		(start 92.47251 -99.505008)
		(end 92.47251 -98.82378)
		(width 0.127)
		(layer "In2.Cu")
		(net "EXP_XM_ADDR_10")
	)
	(segment
		(start 87.32393 -100.9904)
		(end 87.32393 -101.2444)
		(width 0.127)
		(layer "In2.Cu")
		(net "EXP_XM_ADDR_10")
	)
	(segment
		(start 89.92743 -99.632008)
		(end 88.911938 -99.632008)
		(width 0.127)
		(layer "In2.Cu")
		(net "EXP_XM_ADDR_10")
	)
	(segment
		(start 87.32393 -99.8474)
		(end 87.32393 -100.2284)
		(width 0.127)
		(layer "In2.Cu")
		(net "EXP_XM_ADDR_10")
	)
	(segment
		(start 92.59951 -99.632008)
		(end 92.47251 -99.505008)
		(width 0.127)
		(layer "In2.Cu")
		(net "EXP_XM_ADDR_10")
	)
	(segment
		(start 81.927192 -106.87812)
		(end 70.43039 -118.375176)
		(width 0.127)
		(layer "In2.Cu")
		(net "EXP_XM_ADDR_10")
	)
	(segment
		(start 91.96451 -99.505008)
		(end 91.83751 -99.632008)
		(width 0.127)
		(layer "In2.Cu")
		(net "EXP_XM_ADDR_10")
	)
	(segment
		(start 88.657938 -98.69678)
		(end 88.403938 -98.69678)
		(width 0.127)
		(layer "In2.Cu")
		(net "EXP_XM_ADDR_10")
	)
	(segment
		(start 94.902274 -98.429572)
		(end 94.902274 -98.727514)
		(width 0.127)
		(layer "In2.Cu")
		(net "EXP_XM_ADDR_10")
	)
	(segment
		(start 87.45093 -100.8634)
		(end 87.32393 -100.9904)
		(width 0.127)
		(layer "In2.Cu")
		(net "EXP_XM_ADDR_10")
	)
	(segment
		(start 90.94851 -98.82378)
		(end 90.94851 -99.505008)
		(width 0.127)
		(layer "In2.Cu")
		(net "EXP_XM_ADDR_10")
	)
	(segment
		(start 92.09151 -98.69678)
		(end 91.96451 -98.82378)
		(width 0.127)
		(layer "In2.Cu")
		(net "EXP_XM_ADDR_10")
	)
	(segment
		(start 87.91321 -101.3714)
		(end 88.04021 -101.4984)
		(width 0.127)
		(layer "In2.Cu")
		(net "EXP_XM_ADDR_10")
	)
	(segment
		(start 68.17487 -132.688076)
		(end 67.43827 -133.424676)
		(width 0.127)
		(layer "In2.Cu")
		(net "EXP_XM_ADDR_10")
	)
	(segment
		(start 87.45093 -101.8794)
		(end 87.32393 -102.0064)
		(width 0.127)
		(layer "In2.Cu")
		(net "EXP_XM_ADDR_10")
	)
	(segment
		(start 89.978738 -99.5807)
		(end 89.92743 -99.632008)
		(width 0.127)
		(layer "In2.Cu")
		(net "EXP_XM_ADDR_10")
	)
	(segment
		(start 91.45651 -99.505008)
		(end 91.45651 -98.82378)
		(width 0.127)
		(layer "In2.Cu")
		(net "EXP_XM_ADDR_10")
	)
	(segment
		(start 108.82503 -94.8817)
		(end 105.9307 -94.8817)
		(width 0.127)
		(layer "In2.Cu")
		(net "EXP_XM_ADDR_10")
	)
	(segment
		(start 88.04021 -101.7524)
		(end 87.91321 -101.8794)
		(width 0.127)
		(layer "In2.Cu")
		(net "EXP_XM_ADDR_10")
	)
	(segment
		(start 113.349786 -107.350306)
		(end 113.349786 -107.350052)
		(width 0.1016)
		(layer "F.Cu")
		(net "SAS_HDD_TX5_P")
	)
	(segment
		(start 112.971072 -113.62182)
		(end 112.940846 -113.591594)
		(width 0.1016)
		(layer "F.Cu")
		(net "SAS_HDD_TX5_P")
	)
	(segment
		(start 113.259362 -107.44073)
		(end 113.349786 -107.350306)
		(width 0.1016)
		(layer "F.Cu")
		(net "SAS_HDD_TX5_P")
	)
	(segment
		(start 113.04397 -114.0206)
		(end 113.04397 -113.798096)
		(width 0.1016)
		(layer "F.Cu")
		(net "SAS_HDD_TX5_P")
	)
	(segment
		(start 112.89792 -113.487962)
		(end 112.89792 -112.710468)
		(width 0.1016)
		(layer "F.Cu")
		(net "SAS_HDD_TX5_P")
	)
	(segment
		(start 113.20907 -111.959136)
		(end 113.20907 -107.67314)
		(width 0.1016)
		(layer "F.Cu")
		(net "SAS_HDD_TX5_P")
	)
	(segment
		(start 113.251742 -107.459018)
		(end 113.259362 -107.44073)
		(width 0.1016)
		(layer "F.Cu")
		(net "SAS_HDD_TX5_P")
	)
	(arc
		(start 113.04397 -113.798096)
		(mid 113.025033 -113.702713)
		(end 112.971072 -113.62182)
		(width 0.1016)
		(layer "F.Cu")
		(net "SAS_HDD_TX5_P")
	)
	(arc
		(start 113.217198 -107.577382)
		(mid 113.231186 -107.517241)
		(end 113.251742 -107.459018)
		(width 0.1016)
		(layer "F.Cu")
		(net "SAS_HDD_TX5_P")
	)
	(arc
		(start 113.053622 -112.334548)
		(mid 113.168656 -112.162293)
		(end 113.20907 -111.959136)
		(width 0.1016)
		(layer "F.Cu")
		(net "SAS_HDD_TX5_P")
	)
	(arc
		(start 112.940846 -113.591594)
		(mid 112.909076 -113.544047)
		(end 112.89792 -113.487962)
		(width 0.1016)
		(layer "F.Cu")
		(net "SAS_HDD_TX5_P")
	)
	(arc
		(start 112.89792 -112.710468)
		(mid 112.938387 -112.507025)
		(end 113.053622 -112.334548)
		(width 0.1016)
		(layer "F.Cu")
		(net "SAS_HDD_TX5_P")
	)
	(arc
		(start 113.20907 -107.67314)
		(mid 113.211075 -107.625086)
		(end 113.217198 -107.577382)
		(width 0.1016)
		(layer "F.Cu")
		(net "SAS_HDD_TX5_P")
	)
	(segment
		(start 96.692974 -55.34279)
		(end 96.350074 -54.99989)
		(width 0.1143)
		(layer "F.Cu")
		(net "ICE0_TDO")
	)
	(segment
		(start 96.120966 -58.484008)
		(end 96.692974 -57.912)
		(width 0.1143)
		(layer "F.Cu")
		(net "ICE0_TDO")
	)
	(segment
		(start 96.120966 -61.468)
		(end 96.120966 -58.484008)
		(width 0.1143)
		(layer "F.Cu")
		(net "ICE0_TDO")
	)
	(segment
		(start 96.692974 -57.912)
		(end 96.692974 -55.34279)
		(width 0.1143)
		(layer "F.Cu")
		(net "ICE0_TDO")
	)
	(segment
		(start 196.094096 -121.659904)
		(end 196.094096 -120.669812)
		(width 0.254)
		(layer "F.Cu")
		(net "AGND_P1V5_E")
	)
	(segment
		(start 196.094096 -120.669812)
		(end 196.094096 -119.627904)
		(width 0.254)
		(layer "F.Cu")
		(net "AGND_P1V5_E")
	)
	(segment
		(start 199.090534 -116.631466)
		(end 199.090534 -116.124736)
		(width 0.254)
		(layer "F.Cu")
		(net "AGND_P1V5_E")
	)
	(segment
		(start 200.348596 -121.622312)
		(end 200.348596 -122.624596)
		(width 0.254)
		(layer "F.Cu")
		(net "AGND_P1V5_E")
	)
	(segment
		(start 207.562196 -118.129812)
		(end 207.562196 -119.335804)
		(width 0.254)
		(layer "F.Cu")
		(net "AGND_P1V5_E")
	)
	(segment
		(start 196.094096 -119.627904)
		(end 199.090534 -116.631466)
		(width 0.254)
		(layer "F.Cu")
		(net "AGND_P1V5_E")
	)
	(segment
		(start 206.317596 -118.129812)
		(end 207.562196 -118.129812)
		(width 0.254)
		(layer "F.Cu")
		(net "AGND_P1V5_E")
	)
	(segment
		(start 207.562196 -119.335804)
		(end 206.883 -120.015)
		(width 0.254)
		(layer "F.Cu")
		(net "AGND_P1V5_E")
	)
	(via
		(at 206.1464 -121.1834)
		(size 0.7112)
		(drill 0.3556)
		(layers "F.Cu" "B.Cu")
		(net "AGND_P1V5_E")
	)
	(via
		(at 206.883 -120.015)
		(size 0.5588)
		(drill 0.3048)
		(layers "F.Cu" "B.Cu")
		(net "AGND_P1V5_E")
	)
	(via
		(at 196.094096 -121.659904)
		(size 0.5588)
		(drill 0.3048)
		(layers "F.Cu" "B.Cu")
		(net "AGND_P1V5_E")
	)
	(via
		(at 200.348596 -122.624596)
		(size 0.5588)
		(drill 0.3048)
		(layers "F.Cu" "B.Cu")
		(net "AGND_P1V5_E")
	)
	(segment
		(start 197.512686 -122.428)
		(end 196.862192 -122.428)
		(width 0.254)
		(layer "B.Cu")
		(net "AGND_P1V5_E")
	)
	(segment
		(start 196.862192 -122.428)
		(end 196.094096 -121.659904)
		(width 0.254)
		(layer "B.Cu")
		(net "AGND_P1V5_E")
	)
	(segment
		(start 200.348596 -122.624596)
		(end 204.705204 -122.624596)
		(width 0.254)
		(layer "B.Cu")
		(net "AGND_P1V5_E")
	)
	(segment
		(start 204.705204 -122.624596)
		(end 206.1464 -121.1834)
		(width 0.254)
		(layer "B.Cu")
		(net "AGND_P1V5_E")
	)
	(segment
		(start 200.348596 -122.624596)
		(end 197.709282 -122.624596)
		(width 0.254)
		(layer "B.Cu")
		(net "AGND_P1V5_E")
	)
	(segment
		(start 206.1464 -121.1834)
		(end 206.883 -120.4468)
		(width 0.254)
		(layer "B.Cu")
		(net "AGND_P1V5_E")
	)
	(segment
		(start 197.709282 -122.624596)
		(end 197.512686 -122.428)
		(width 0.254)
		(layer "B.Cu")
		(net "AGND_P1V5_E")
	)
	(segment
		(start 206.883 -120.4468)
		(end 206.883 -120.015)
		(width 0.254)
		(layer "B.Cu")
		(net "AGND_P1V5_E")
	)
	(segment
		(start 109.349794 -93.349826)
		(end 108.849668 -92.8497)
		(width 0.1143)
		(layer "F.Cu")
		(net "EXP_XM_ADDR_24")
	)
	(via
		(at 108.849668 -92.8497)
		(size 0.508)
		(drill 0.254)
		(layers "F.Cu" "B.Cu")
		(net "EXP_XM_ADDR_24")
	)
	(segment
		(start 109.728 -92.964)
		(end 108.963968 -92.964)
		(width 0.1143)
		(layer "B.Cu")
		(net "EXP_XM_ADDR_24")
	)
	(segment
		(start 108.963968 -92.964)
		(end 108.849668 -92.8497)
		(width 0.1143)
		(layer "B.Cu")
		(net "EXP_XM_ADDR_24")
	)
	(segment
		(start 114.35207 -113.622074)
		(end 114.35207 -112.800892)
		(width 0.1016)
		(layer "F.Cu")
		(net "SAS_HDD_TX4_N")
	)
	(segment
		(start 113.733834 -111.308388)
		(end 113.733834 -106.836972)
		(width 0.1016)
		(layer "F.Cu")
		(net "SAS_HDD_TX4_N")
	)
	(arc
		(start 113.733834 -106.836972)
		(mid 113.893905 -106.03224)
		(end 114.349784 -105.350056)
		(width 0.1016)
		(layer "F.Cu")
		(net "SAS_HDD_TX4_N")
	)
	(arc
		(start 114.18697 -114.0206)
		(mid 114.309143 -113.837755)
		(end 114.35207 -113.622074)
		(width 0.1016)
		(layer "F.Cu")
		(net "SAS_HDD_TX4_N")
	)
	(arc
		(start 114.1476 -112.30737)
		(mid 113.841403 -111.849019)
		(end 113.733834 -111.308388)
		(width 0.1016)
		(layer "F.Cu")
		(net "SAS_HDD_TX4_N")
	)
	(arc
		(start 114.35207 -112.800892)
		(mid 114.298923 -112.533796)
		(end 114.1476 -112.30737)
		(width 0.1016)
		(layer "F.Cu")
		(net "SAS_HDD_TX4_N")
	)
	(segment
		(start 202.634596 -109.22)
		(end 202.184 -109.22)
		(width 0.508)
		(layer "F.Cu")
		(net "P1V5_E_VBST_RR")
	)
	(segment
		(start 202.888596 -109.474)
		(end 202.634596 -109.22)
		(width 0.508)
		(layer "F.Cu")
		(net "P1V5_E_VBST_RR")
	)
	(segment
		(start 202.888596 -110.192312)
		(end 202.888596 -109.474)
		(width 0.508)
		(layer "F.Cu")
		(net "P1V5_E_VBST_RR")
	)
	(segment
		(start 201.618596 -109.785404)
		(end 202.184 -109.22)
		(width 0.508)
		(layer "F.Cu")
		(net "P1V5_E_VBST_RR")
	)
	(segment
		(start 201.618596 -110.255812)
		(end 201.618596 -109.785404)
		(width 0.508)
		(layer "F.Cu")
		(net "P1V5_E_VBST_RR")
	)
	(via
		(at 202.184 -109.22)
		(size 0.7112)
		(drill 0.3556)
		(layers "F.Cu" "B.Cu")
		(net "P1V5_E_VBST_RR")
	)
	(segment
		(start 56.558942 -131.392422)
		(end 61.464444 -131.392422)
		(width 0.1143)
		(layer "F.Cu")
		(net "EXP_XM_ADDR_19")
	)
	(segment
		(start 62.035944 -132.394198)
		(end 62.035944 -131.506722)
		(width 0.1143)
		(layer "F.Cu")
		(net "EXP_XM_ADDR_19")
	)
	(segment
		(start 63.979044 -131.392422)
		(end 64.347344 -131.392422)
		(width 0.1143)
		(layer "F.Cu")
		(net "EXP_XM_ADDR_19")
	)
	(segment
		(start 62.950344 -132.394198)
		(end 62.950344 -131.506722)
		(width 0.1143)
		(layer "F.Cu")
		(net "EXP_XM_ADDR_19")
	)
	(segment
		(start 64.461644 -131.506722)
		(end 64.461644 -131.8514)
		(width 0.1143)
		(layer "F.Cu")
		(net "EXP_XM_ADDR_19")
	)
	(segment
		(start 62.607444 -132.508498)
		(end 62.836044 -132.508498)
		(width 0.1143)
		(layer "F.Cu")
		(net "EXP_XM_ADDR_19")
	)
	(segment
		(start 63.407544 -131.506722)
		(end 63.407544 -132.394198)
		(width 0.1143)
		(layer "F.Cu")
		(net "EXP_XM_ADDR_19")
	)
	(segment
		(start 62.035944 -131.506722)
		(end 62.150244 -131.392422)
		(width 0.1143)
		(layer "F.Cu")
		(net "EXP_XM_ADDR_19")
	)
	(segment
		(start 63.293244 -131.392422)
		(end 63.407544 -131.506722)
		(width 0.1143)
		(layer "F.Cu")
		(net "EXP_XM_ADDR_19")
	)
	(segment
		(start 65.358772 -131.392422)
		(end 65.85458 -131.88823)
		(width 0.1143)
		(layer "F.Cu")
		(net "EXP_XM_ADDR_19")
	)
	(segment
		(start 65.033144 -131.392422)
		(end 65.358772 -131.392422)
		(width 0.1143)
		(layer "F.Cu")
		(net "EXP_XM_ADDR_19")
	)
	(segment
		(start 64.804544 -131.9657)
		(end 64.918844 -131.8514)
		(width 0.1143)
		(layer "F.Cu")
		(net "EXP_XM_ADDR_19")
	)
	(segment
		(start 63.750444 -132.508498)
		(end 63.864744 -132.394198)
		(width 0.1143)
		(layer "F.Cu")
		(net "EXP_XM_ADDR_19")
	)
	(segment
		(start 64.347344 -131.392422)
		(end 64.461644 -131.506722)
		(width 0.1143)
		(layer "F.Cu")
		(net "EXP_XM_ADDR_19")
	)
	(segment
		(start 61.693044 -132.508498)
		(end 61.921644 -132.508498)
		(width 0.1143)
		(layer "F.Cu")
		(net "EXP_XM_ADDR_19")
	)
	(segment
		(start 63.407544 -132.394198)
		(end 63.521844 -132.508498)
		(width 0.1143)
		(layer "F.Cu")
		(net "EXP_XM_ADDR_19")
	)
	(segment
		(start 62.493144 -131.506722)
		(end 62.493144 -132.394198)
		(width 0.1143)
		(layer "F.Cu")
		(net "EXP_XM_ADDR_19")
	)
	(segment
		(start 62.950344 -131.506722)
		(end 63.064644 -131.392422)
		(width 0.1143)
		(layer "F.Cu")
		(net "EXP_XM_ADDR_19")
	)
	(segment
		(start 61.578744 -132.394198)
		(end 61.693044 -132.508498)
		(width 0.1143)
		(layer "F.Cu")
		(net "EXP_XM_ADDR_19")
	)
	(segment
		(start 61.921644 -132.508498)
		(end 62.035944 -132.394198)
		(width 0.1143)
		(layer "F.Cu")
		(net "EXP_XM_ADDR_19")
	)
	(segment
		(start 62.378844 -131.392422)
		(end 62.493144 -131.506722)
		(width 0.1143)
		(layer "F.Cu")
		(net "EXP_XM_ADDR_19")
	)
	(segment
		(start 64.918844 -131.8514)
		(end 64.918844 -131.506722)
		(width 0.1143)
		(layer "F.Cu")
		(net "EXP_XM_ADDR_19")
	)
	(segment
		(start 63.064644 -131.392422)
		(end 63.293244 -131.392422)
		(width 0.1143)
		(layer "F.Cu")
		(net "EXP_XM_ADDR_19")
	)
	(segment
		(start 92.66047 -96.647)
		(end 93.48597 -96.647)
		(width 0.1143)
		(layer "F.Cu")
		(net "EXP_XM_ADDR_19")
	)
	(segment
		(start 65.85458 -131.88823)
		(end 66.19367 -131.88823)
		(width 0.1143)
		(layer "F.Cu")
		(net "EXP_XM_ADDR_19")
	)
	(segment
		(start 61.578744 -131.506722)
		(end 61.578744 -132.394198)
		(width 0.1143)
		(layer "F.Cu")
		(net "EXP_XM_ADDR_19")
	)
	(segment
		(start 103.349806 -94.349824)
		(end 102.84968 -93.849698)
		(width 0.1143)
		(layer "F.Cu")
		(net "EXP_XM_ADDR_19")
	)
	(segment
		(start 61.464444 -131.392422)
		(end 61.578744 -131.506722)
		(width 0.1143)
		(layer "F.Cu")
		(net "EXP_XM_ADDR_19")
	)
	(segment
		(start 63.521844 -132.508498)
		(end 63.750444 -132.508498)
		(width 0.1143)
		(layer "F.Cu")
		(net "EXP_XM_ADDR_19")
	)
	(segment
		(start 62.493144 -132.394198)
		(end 62.607444 -132.508498)
		(width 0.1143)
		(layer "F.Cu")
		(net "EXP_XM_ADDR_19")
	)
	(segment
		(start 63.864744 -131.506722)
		(end 63.979044 -131.392422)
		(width 0.1143)
		(layer "F.Cu")
		(net "EXP_XM_ADDR_19")
	)
	(segment
		(start 62.150244 -131.392422)
		(end 62.378844 -131.392422)
		(width 0.1143)
		(layer "F.Cu")
		(net "EXP_XM_ADDR_19")
	)
	(segment
		(start 63.864744 -132.394198)
		(end 63.864744 -131.506722)
		(width 0.1143)
		(layer "F.Cu")
		(net "EXP_XM_ADDR_19")
	)
	(segment
		(start 62.836044 -132.508498)
		(end 62.950344 -132.394198)
		(width 0.1143)
		(layer "F.Cu")
		(net "EXP_XM_ADDR_19")
	)
	(segment
		(start 64.918844 -131.506722)
		(end 65.033144 -131.392422)
		(width 0.1143)
		(layer "F.Cu")
		(net "EXP_XM_ADDR_19")
	)
	(segment
		(start 64.575944 -131.9657)
		(end 64.804544 -131.9657)
		(width 0.1143)
		(layer "F.Cu")
		(net "EXP_XM_ADDR_19")
	)
	(segment
		(start 64.461644 -131.8514)
		(end 64.575944 -131.9657)
		(width 0.1143)
		(layer "F.Cu")
		(net "EXP_XM_ADDR_19")
	)
	(via
		(at 66.19367 -131.88823)
		(size 0.5588)
		(drill 0.3048)
		(layers "F.Cu" "B.Cu")
		(net "EXP_XM_ADDR_19")
	)
	(via
		(at 67.21221 -132.07238)
		(size 0.7112)
		(drill 0.3556)
		(layers "F.Cu" "B.Cu")
		(net "EXP_XM_ADDR_19")
	)
	(via
		(at 93.48597 -96.647)
		(size 0.508)
		(drill 0.254)
		(layers "F.Cu" "B.Cu")
		(net "EXP_XM_ADDR_19")
	)
	(via
		(at 102.84968 -93.849698)
		(size 0.508)
		(drill 0.254)
		(layers "F.Cu" "B.Cu")
		(net "EXP_XM_ADDR_19")
	)
	(segment
		(start 66.19367 -131.88823)
		(end 66.37782 -132.07238)
		(width 0.1143)
		(layer "B.Cu")
		(net "EXP_XM_ADDR_19")
	)
	(segment
		(start 66.37782 -132.07238)
		(end 67.21221 -132.07238)
		(width 0.1143)
		(layer "B.Cu")
		(net "EXP_XM_ADDR_19")
	)
	(segment
		(start 66.19367 -131.550918)
		(end 66.608452 -131.136136)
		(width 0.127)
		(layer "In2.Cu")
		(net "EXP_XM_ADDR_19")
	)
	(segment
		(start 67.56527 -123.460002)
		(end 66.80327 -123.460002)
		(width 0.127)
		(layer "In2.Cu")
		(net "EXP_XM_ADDR_19")
	)
	(segment
		(start 102.84968 -93.849698)
		(end 101.617272 -93.849698)
		(width 0.127)
		(layer "In2.Cu")
		(net "EXP_XM_ADDR_19")
	)
	(segment
		(start 95.310198 -94.869)
		(end 94.167198 -96.012)
		(width 0.127)
		(layer "In2.Cu")
		(net "EXP_XM_ADDR_19")
	)
	(segment
		(start 96.087946 -94.869)
		(end 96.087692 -94.868746)
		(width 0.127)
		(layer "In2.Cu")
		(net "EXP_XM_ADDR_19")
	)
	(segment
		(start 66.34607 -130.237992)
		(end 66.34607 -129.006092)
		(width 0.127)
		(layer "In2.Cu")
		(net "EXP_XM_ADDR_19")
	)
	(segment
		(start 101.617272 -93.849698)
		(end 100.59797 -94.869)
		(width 0.127)
		(layer "In2.Cu")
		(net "EXP_XM_ADDR_19")
	)
	(segment
		(start 66.608452 -130.500374)
		(end 66.34607 -130.237992)
		(width 0.127)
		(layer "In2.Cu")
		(net "EXP_XM_ADDR_19")
	)
	(segment
		(start 66.78549 -128.752092)
		(end 66.78549 -128.498092)
		(width 0.127)
		(layer "In2.Cu")
		(net "EXP_XM_ADDR_19")
	)
	(segment
		(start 66.34607 -129.006092)
		(end 66.47307 -128.879092)
		(width 0.127)
		(layer "In2.Cu")
		(net "EXP_XM_ADDR_19")
	)
	(segment
		(start 81.827624 -104.478074)
		(end 81.827624 -102.711504)
		(width 0.127)
		(layer "In2.Cu")
		(net "EXP_XM_ADDR_19")
	)
	(segment
		(start 66.67627 -127.49022)
		(end 66.67627 -124.095002)
		(width 0.127)
		(layer "In2.Cu")
		(net "EXP_XM_ADDR_19")
	)
	(segment
		(start 94.167198 -96.012)
		(end 94.12097 -96.012)
		(width 0.127)
		(layer "In2.Cu")
		(net "EXP_XM_ADDR_19")
	)
	(segment
		(start 67.18427 -127.36322)
		(end 67.31127 -127.49022)
		(width 0.127)
		(layer "In2.Cu")
		(net "EXP_XM_ADDR_19")
	)
	(segment
		(start 96.087692 -94.868746)
		(end 95.456248 -94.868746)
		(width 0.127)
		(layer "In2.Cu")
		(net "EXP_XM_ADDR_19")
	)
	(segment
		(start 89.459562 -95.07982)
		(end 91.91879 -95.07982)
		(width 0.127)
		(layer "In2.Cu")
		(net "EXP_XM_ADDR_19")
	)
	(segment
		(start 66.47307 -128.371092)
		(end 66.34607 -128.244092)
		(width 0.127)
		(layer "In2.Cu")
		(net "EXP_XM_ADDR_19")
	)
	(segment
		(start 67.69227 -127.36322)
		(end 67.69227 -123.587002)
		(width 0.127)
		(layer "In2.Cu")
		(net "EXP_XM_ADDR_19")
	)
	(segment
		(start 95.455994 -94.869)
		(end 95.310198 -94.869)
		(width 0.127)
		(layer "In2.Cu")
		(net "EXP_XM_ADDR_19")
	)
	(segment
		(start 95.456248 -94.868746)
		(end 95.455994 -94.869)
		(width 0.127)
		(layer "In2.Cu")
		(net "EXP_XM_ADDR_19")
	)
	(segment
		(start 66.65849 -128.371092)
		(end 66.47307 -128.371092)
		(width 0.127)
		(layer "In2.Cu")
		(net "EXP_XM_ADDR_19")
	)
	(segment
		(start 67.69227 -123.587002)
		(end 67.56527 -123.460002)
		(width 0.127)
		(layer "In2.Cu")
		(net "EXP_XM_ADDR_19")
	)
	(segment
		(start 66.67627 -123.333002)
		(end 66.67627 -119.953024)
		(width 0.127)
		(layer "In2.Cu")
		(net "EXP_XM_ADDR_19")
	)
	(segment
		(start 66.67627 -119.953024)
		(end 81.82737 -104.801924)
		(width 0.127)
		(layer "In2.Cu")
		(net "EXP_XM_ADDR_19")
	)
	(segment
		(start 66.67627 -124.095002)
		(end 66.80327 -123.968002)
		(width 0.127)
		(layer "In2.Cu")
		(net "EXP_XM_ADDR_19")
	)
	(segment
		(start 94.12097 -96.012)
		(end 93.48597 -96.647)
		(width 0.127)
		(layer "In2.Cu")
		(net "EXP_XM_ADDR_19")
	)
	(segment
		(start 81.82737 -104.801924)
		(end 81.82737 -104.478328)
		(width 0.127)
		(layer "In2.Cu")
		(net "EXP_XM_ADDR_19")
	)
	(segment
		(start 67.18427 -124.095002)
		(end 67.18427 -127.36322)
		(width 0.127)
		(layer "In2.Cu")
		(net "EXP_XM_ADDR_19")
	)
	(segment
		(start 81.82737 -104.478328)
		(end 81.827624 -104.478074)
		(width 0.127)
		(layer "In2.Cu")
		(net "EXP_XM_ADDR_19")
	)
	(segment
		(start 66.65849 -128.879092)
		(end 66.78549 -128.752092)
		(width 0.127)
		(layer "In2.Cu")
		(net "EXP_XM_ADDR_19")
	)
	(segment
		(start 100.59797 -94.869)
		(end 96.087946 -94.869)
		(width 0.127)
		(layer "In2.Cu")
		(net "EXP_XM_ADDR_19")
	)
	(segment
		(start 66.80327 -123.460002)
		(end 66.67627 -123.333002)
		(width 0.127)
		(layer "In2.Cu")
		(net "EXP_XM_ADDR_19")
	)
	(segment
		(start 66.47307 -128.879092)
		(end 66.65849 -128.879092)
		(width 0.127)
		(layer "In2.Cu")
		(net "EXP_XM_ADDR_19")
	)
	(segment
		(start 67.31127 -127.49022)
		(end 67.56527 -127.49022)
		(width 0.127)
		(layer "In2.Cu")
		(net "EXP_XM_ADDR_19")
	)
	(segment
		(start 66.19367 -131.88823)
		(end 66.19367 -131.550918)
		(width 0.127)
		(layer "In2.Cu")
		(net "EXP_XM_ADDR_19")
	)
	(segment
		(start 66.34607 -128.244092)
		(end 66.34607 -127.82042)
		(width 0.127)
		(layer "In2.Cu")
		(net "EXP_XM_ADDR_19")
	)
	(segment
		(start 66.34607 -127.82042)
		(end 66.67627 -127.49022)
		(width 0.127)
		(layer "In2.Cu")
		(net "EXP_XM_ADDR_19")
	)
	(segment
		(start 81.827624 -102.711504)
		(end 88.676988 -95.86214)
		(width 0.127)
		(layer "In2.Cu")
		(net "EXP_XM_ADDR_19")
	)
	(segment
		(start 67.05727 -123.968002)
		(end 67.18427 -124.095002)
		(width 0.127)
		(layer "In2.Cu")
		(net "EXP_XM_ADDR_19")
	)
	(segment
		(start 66.78549 -128.498092)
		(end 66.65849 -128.371092)
		(width 0.127)
		(layer "In2.Cu")
		(net "EXP_XM_ADDR_19")
	)
	(segment
		(start 67.56527 -127.49022)
		(end 67.69227 -127.36322)
		(width 0.127)
		(layer "In2.Cu")
		(net "EXP_XM_ADDR_19")
	)
	(segment
		(start 88.676988 -95.86214)
		(end 89.459562 -95.07982)
		(width 0.127)
		(layer "In2.Cu")
		(net "EXP_XM_ADDR_19")
	)
	(segment
		(start 66.80327 -123.968002)
		(end 67.05727 -123.968002)
		(width 0.127)
		(layer "In2.Cu")
		(net "EXP_XM_ADDR_19")
	)
	(segment
		(start 91.91879 -95.07982)
		(end 93.48597 -96.647)
		(width 0.127)
		(layer "In2.Cu")
		(net "EXP_XM_ADDR_19")
	)
	(segment
		(start 66.608452 -131.136136)
		(end 66.608452 -130.500374)
		(width 0.127)
		(layer "In2.Cu")
		(net "EXP_XM_ADDR_19")
	)
	(segment
		(start 114.143536 -106.556556)
		(end 114.349784 -106.350054)
		(width 0.1016)
		(layer "F.Cu")
		(net "SAS_HDD_TX4_P")
	)
	(segment
		(start 114.69497 -113.714022)
		(end 114.69497 -112.800638)
		(width 0.1016)
		(layer "F.Cu")
		(net "SAS_HDD_TX4_P")
	)
	(segment
		(start 113.96599 -108.340906)
		(end 113.96599 -106.9848)
		(width 0.1016)
		(layer "F.Cu")
		(net "SAS_HDD_TX4_P")
	)
	(segment
		(start 114.076734 -111.308134)
		(end 114.076734 -108.608114)
		(width 0.1016)
		(layer "F.Cu")
		(net "SAS_HDD_TX4_P")
	)
	(arc
		(start 114.02187 -108.47578)
		(mid 113.980523 -108.413899)
		(end 113.96599 -108.340906)
		(width 0.1016)
		(layer "F.Cu")
		(net "SAS_HDD_TX4_P")
	)
	(arc
		(start 114.69497 -112.800638)
		(mid 114.615756 -112.402403)
		(end 114.39017 -112.0648)
		(width 0.1016)
		(layer "F.Cu")
		(net "SAS_HDD_TX4_P")
	)
	(arc
		(start 114.076734 -108.608114)
		(mid 114.062484 -108.536476)
		(end 114.02187 -108.47578)
		(width 0.1016)
		(layer "F.Cu")
		(net "SAS_HDD_TX4_P")
	)
	(arc
		(start 113.96599 -106.9848)
		(mid 114.012186 -106.753028)
		(end 114.143536 -106.556556)
		(width 0.1016)
		(layer "F.Cu")
		(net "SAS_HDD_TX4_P")
	)
	(arc
		(start 114.82197 -114.0206)
		(mid 114.727985 -113.879941)
		(end 114.69497 -113.714022)
		(width 0.1016)
		(layer "F.Cu")
		(net "SAS_HDD_TX4_P")
	)
	(arc
		(start 114.39017 -112.0648)
		(mid 114.158204 -111.717639)
		(end 114.076734 -111.308134)
		(width 0.1016)
		(layer "F.Cu")
		(net "SAS_HDD_TX4_P")
	)
	(segment
		(start 202.3745 -120.600216)
		(end 202.3745 -119.634)
		(width 0.254)
		(layer "F.Cu")
		(net "P1V5_E_VFB")
	)
	(segment
		(start 200.348596 -119.818404)
		(end 200.406 -119.761)
		(width 0.254)
		(layer "F.Cu")
		(net "P1V5_E_VFB")
	)
	(segment
		(start 200.348596 -120.733312)
		(end 200.348596 -119.818404)
		(width 0.254)
		(layer "F.Cu")
		(net "P1V5_E_VFB")
	)
	(segment
		(start 201.428096 -120.669812)
		(end 202.444096 -120.669812)
		(width 0.254)
		(layer "F.Cu")
		(net "P1V5_E_VFB")
	)
	(segment
		(start 200.348596 -120.733312)
		(end 201.364596 -120.733312)
		(width 0.254)
		(layer "F.Cu")
		(net "P1V5_E_VFB")
	)
	(segment
		(start 201.364596 -120.733312)
		(end 201.428096 -120.669812)
		(width 0.254)
		(layer "F.Cu")
		(net "P1V5_E_VFB")
	)
	(segment
		(start 202.444096 -120.669812)
		(end 202.3745 -120.600216)
		(width 0.254)
		(layer "F.Cu")
		(net "P1V5_E_VFB")
	)
	(segment
		(start 200.590658 -119.576342)
		(end 200.406 -119.761)
		(width 0.254)
		(layer "F.Cu")
		(net "P1V5_E_VFB")
	)
	(segment
		(start 200.590658 -116.124736)
		(end 200.590658 -119.576342)
		(width 0.254)
		(layer "F.Cu")
		(net "P1V5_E_VFB")
	)
	(via
		(at 200.406 -119.761)
		(size 0.7112)
		(drill 0.3556)
		(layers "F.Cu" "B.Cu")
		(net "P1V5_E_VFB")
	)
	(segment
		(start 101.991922 -85.739732)
		(end 101.087682 -84.835492)
		(width 0.1143)
		(layer "F.Cu")
		(net "EXP_XM_CS_N_0")
	)
	(segment
		(start 103.349806 -86.34984)
		(end 102.739698 -85.739732)
		(width 0.1143)
		(layer "F.Cu")
		(net "EXP_XM_CS_N_0")
	)
	(segment
		(start 59.594242 -143.746982)
		(end 59.594242 -142.906242)
		(width 0.1143)
		(layer "F.Cu")
		(net "EXP_XM_CS_N_0")
	)
	(segment
		(start 59.594242 -142.906242)
		(end 59.436 -142.748)
		(width 0.1143)
		(layer "F.Cu")
		(net "EXP_XM_CS_N_0")
	)
	(segment
		(start 102.739698 -85.739732)
		(end 101.991922 -85.739732)
		(width 0.1143)
		(layer "F.Cu")
		(net "EXP_XM_CS_N_0")
	)
	(segment
		(start 59.436 -141.859)
		(end 59.436 -142.748)
		(width 0.1143)
		(layer "F.Cu")
		(net "EXP_XM_CS_N_0")
	)
	(via
		(at 101.087682 -84.835492)
		(size 0.508)
		(drill 0.254)
		(layers "F.Cu" "B.Cu")
		(net "EXP_XM_CS_N_0")
	)
	(via
		(at 59.436 -141.859)
		(size 0.7112)
		(drill 0.3556)
		(layers "F.Cu" "B.Cu")
		(net "EXP_XM_CS_N_0")
	)
	(via
		(at 59.436 -142.748)
		(size 0.508)
		(drill 0.254)
		(layers "F.Cu" "B.Cu")
		(net "EXP_XM_CS_N_0")
	)
	(segment
		(start 98.409252 -86.106)
		(end 99.895152 -84.6201)
		(width 0.127)
		(layer "In2.Cu")
		(net "EXP_XM_CS_N_0")
	)
	(segment
		(start 59.436 -142.748)
		(end 59.18327 -142.49527)
		(width 0.127)
		(layer "In2.Cu")
		(net "EXP_XM_CS_N_0")
	)
	(segment
		(start 87.903812 -88.011508)
		(end 88.552528 -88.011508)
		(width 0.127)
		(layer "In2.Cu")
		(net "EXP_XM_CS_N_0")
	)
	(segment
		(start 59.18327 -134.293864)
		(end 58.98769 -134.098284)
		(width 0.127)
		(layer "In2.Cu")
		(net "EXP_XM_CS_N_0")
	)
	(segment
		(start 100.50018 -84.835492)
		(end 101.087682 -84.835492)
		(width 0.127)
		(layer "In2.Cu")
		(net "EXP_XM_CS_N_0")
	)
	(segment
		(start 58.48477 -127.95504)
		(end 59.05881 -127.381)
		(width 0.127)
		(layer "In2.Cu")
		(net "EXP_XM_CS_N_0")
	)
	(segment
		(start 59.05881 -127.381)
		(end 59.05881 -116.439696)
		(width 0.127)
		(layer "In2.Cu")
		(net "EXP_XM_CS_N_0")
	)
	(segment
		(start 71.5899 -103.908606)
		(end 71.5899 -101.047042)
		(width 0.127)
		(layer "In2.Cu")
		(net "EXP_XM_CS_N_0")
	)
	(segment
		(start 85.259164 -90.656156)
		(end 87.903812 -88.011508)
		(width 0.127)
		(layer "In2.Cu")
		(net "EXP_XM_CS_N_0")
	)
	(segment
		(start 59.18327 -142.49527)
		(end 59.18327 -134.293864)
		(width 0.127)
		(layer "In2.Cu")
		(net "EXP_XM_CS_N_0")
	)
	(segment
		(start 90.458036 -86.106)
		(end 98.409252 -86.106)
		(width 0.127)
		(layer "In2.Cu")
		(net "EXP_XM_CS_N_0")
	)
	(segment
		(start 82.429604 -93.069156)
		(end 84.842604 -90.656156)
		(width 0.127)
		(layer "In2.Cu")
		(net "EXP_XM_CS_N_0")
	)
	(segment
		(start 58.86577 -130.175)
		(end 58.48477 -129.794)
		(width 0.127)
		(layer "In2.Cu")
		(net "EXP_XM_CS_N_0")
	)
	(segment
		(start 58.98769 -132.97662)
		(end 58.86577 -132.8547)
		(width 0.127)
		(layer "In2.Cu")
		(net "EXP_XM_CS_N_0")
	)
	(segment
		(start 99.895152 -84.6201)
		(end 100.284788 -84.6201)
		(width 0.127)
		(layer "In2.Cu")
		(net "EXP_XM_CS_N_0")
	)
	(segment
		(start 100.284788 -84.6201)
		(end 100.50018 -84.835492)
		(width 0.127)
		(layer "In2.Cu")
		(net "EXP_XM_CS_N_0")
	)
	(segment
		(start 71.5899 -101.047042)
		(end 79.567786 -93.069156)
		(width 0.127)
		(layer "In2.Cu")
		(net "EXP_XM_CS_N_0")
	)
	(segment
		(start 58.98769 -134.098284)
		(end 58.98769 -132.97662)
		(width 0.127)
		(layer "In2.Cu")
		(net "EXP_XM_CS_N_0")
	)
	(segment
		(start 59.05881 -116.439696)
		(end 71.5899 -103.908606)
		(width 0.127)
		(layer "In2.Cu")
		(net "EXP_XM_CS_N_0")
	)
	(segment
		(start 58.86577 -132.8547)
		(end 58.86577 -130.175)
		(width 0.127)
		(layer "In2.Cu")
		(net "EXP_XM_CS_N_0")
	)
	(segment
		(start 84.842604 -90.656156)
		(end 85.259164 -90.656156)
		(width 0.127)
		(layer "In2.Cu")
		(net "EXP_XM_CS_N_0")
	)
	(segment
		(start 58.48477 -129.794)
		(end 58.48477 -127.95504)
		(width 0.127)
		(layer "In2.Cu")
		(net "EXP_XM_CS_N_0")
	)
	(segment
		(start 88.552528 -88.011508)
		(end 90.458036 -86.106)
		(width 0.127)
		(layer "In2.Cu")
		(net "EXP_XM_CS_N_0")
	)
	(segment
		(start 79.567786 -93.069156)
		(end 82.429604 -93.069156)
		(width 0.127)
		(layer "In2.Cu")
		(net "EXP_XM_CS_N_0")
	)
	(segment
		(start 107.54995 -37.399976)
		(end 107.949746 -37.799772)
		(width 0.1143)
		(layer "F.Cu")
		(net "SYS_DBMODE0")
	)
	(via
		(at 107.949746 -37.799772)
		(size 0.508)
		(drill 0.254)
		(layers "F.Cu" "B.Cu")
		(net "SYS_DBMODE0")
	)
	(segment
		(start 107.949746 -37.799772)
		(end 107.96016 -37.810186)
		(width 0.1143)
		(layer "B.Cu")
		(net "SYS_DBMODE0")
	)
	(segment
		(start 108.18876 -38.4937)
		(end 109.20476 -38.4937)
		(width 0.1143)
		(layer "B.Cu")
		(net "SYS_DBMODE0")
	)
	(segment
		(start 107.96016 -37.810186)
		(end 108.18876 -38.4937)
		(width 0.1143)
		(layer "B.Cu")
		(net "SYS_DBMODE0")
	)
	(segment
		(start 107.949746 -37.59962)
		(end 107.949746 -37.799772)
		(width 0.1143)
		(layer "B.Cu")
		(net "SYS_DBMODE0")
	)
	(segment
		(start 107.525566 -36.98748)
		(end 107.949746 -37.59962)
		(width 0.1143)
		(layer "B.Cu")
		(net "SYS_DBMODE0")
	)
	(segment
		(start 208.133188 -122.955812)
		(end 209.169 -121.92)
		(width 0.254)
		(layer "F.Cu")
		(net "P1V5_E_CC")
	)
	(segment
		(start 204.6605 -92.329)
		(end 205.359 -92.329)
		(width 0.127)
		(layer "F.Cu")
		(net "P1V5_E_CC")
	)
	(segment
		(start 205.74 -122.955812)
		(end 208.133188 -122.955812)
		(width 0.254)
		(layer "F.Cu")
		(net "P1V5_E_CC")
	)
	(segment
		(start 205.74 -122.955812)
		(end 205.74 -121.92)
		(width 0.254)
		(layer "F.Cu")
		(net "P1V5_E_CC")
	)
	(via
		(at 205.359 -92.329)
		(size 0.5588)
		(drill 0.3048)
		(layers "F.Cu" "B.Cu")
		(net "P1V5_E_CC")
	)
	(via
		(at 209.169 -121.92)
		(size 0.5588)
		(drill 0.3048)
		(layers "F.Cu" "B.Cu")
		(net "P1V5_E_CC")
	)
	(via
		(at 205.74 -122.955812)
		(size 0.7112)
		(drill 0.3556)
		(layers "F.Cu" "B.Cu")
		(net "P1V5_E_CC")
	)
	(segment
		(start 209.169 -121.92)
		(end 209.169 -118.491)
		(width 0.254)
		(layer "B.Cu")
		(net "P1V5_E_CC")
	)
	(segment
		(start 205.359 -106.299)
		(end 205.359 -92.329)
		(width 0.254)
		(layer "B.Cu")
		(net "P1V5_E_CC")
	)
	(segment
		(start 204.089 -113.411)
		(end 204.089 -107.569)
		(width 0.254)
		(layer "B.Cu")
		(net "P1V5_E_CC")
	)
	(segment
		(start 209.169 -118.491)
		(end 204.089 -113.411)
		(width 0.254)
		(layer "B.Cu")
		(net "P1V5_E_CC")
	)
	(segment
		(start 204.089 -107.569)
		(end 205.359 -106.299)
		(width 0.254)
		(layer "B.Cu")
		(net "P1V5_E_CC")
	)
	(segment
		(start 101.122988 -91.64955)
		(end 99.8601 -92.912438)
		(width 0.1143)
		(layer "F.Cu")
		(net "EXP_XM_ADDR_25")
	)
	(segment
		(start 99.819714 -92.952824)
		(end 99.819714 -92.912438)
		(width 0.1143)
		(layer "F.Cu")
		(net "EXP_XM_ADDR_25")
	)
	(segment
		(start 103.057198 -92.349828)
		(end 102.51567 -91.8083)
		(width 0.1143)
		(layer "F.Cu")
		(net "EXP_XM_ADDR_25")
	)
	(segment
		(start 97.395538 -95.377)
		(end 99.819714 -92.952824)
		(width 0.1143)
		(layer "F.Cu")
		(net "EXP_XM_ADDR_25")
	)
	(segment
		(start 99.8601 -92.912438)
		(end 99.819714 -92.912438)
		(width 0.1143)
		(layer "F.Cu")
		(net "EXP_XM_ADDR_25")
	)
	(segment
		(start 103.349806 -92.349828)
		(end 103.057198 -92.349828)
		(width 0.1143)
		(layer "F.Cu")
		(net "EXP_XM_ADDR_25")
	)
	(segment
		(start 101.91623 -91.64955)
		(end 101.122988 -91.64955)
		(width 0.1143)
		(layer "F.Cu")
		(net "EXP_XM_ADDR_25")
	)
	(segment
		(start 96.34347 -95.377)
		(end 97.395538 -95.377)
		(width 0.1143)
		(layer "F.Cu")
		(net "EXP_XM_ADDR_25")
	)
	(segment
		(start 102.51567 -91.8083)
		(end 102.07498 -91.8083)
		(width 0.1143)
		(layer "F.Cu")
		(net "EXP_XM_ADDR_25")
	)
	(segment
		(start 102.07498 -91.8083)
		(end 101.91623 -91.64955)
		(width 0.1143)
		(layer "F.Cu")
		(net "EXP_XM_ADDR_25")
	)
	(via
		(at 99.819714 -92.912438)
		(size 0.508)
		(drill 0.254)
		(layers "F.Cu" "B.Cu")
		(net "EXP_XM_ADDR_25")
	)
	(segment
		(start 98.171 -91.9734)
		(end 98.5774 -91.9734)
		(width 0.1143)
		(layer "B.Cu")
		(net "EXP_XM_ADDR_25")
	)
	(segment
		(start 98.5774 -91.9734)
		(end 99.516438 -92.912438)
		(width 0.1143)
		(layer "B.Cu")
		(net "EXP_XM_ADDR_25")
	)
	(segment
		(start 99.516438 -92.912438)
		(end 99.819714 -92.912438)
		(width 0.1143)
		(layer "B.Cu")
		(net "EXP_XM_ADDR_25")
	)
	(segment
		(start 115.683538 -112.323118)
		(end 115.61826 -112.25784)
		(width 0.1016)
		(layer "F.Cu")
		(net "SAS_HDD_TX3_N")
	)
	(segment
		(start 114.93881 -110.617254)
		(end 114.93881 -107.383326)
		(width 0.1016)
		(layer "F.Cu")
		(net "SAS_HDD_TX3_N")
	)
	(segment
		(start 116.09197 -113.714022)
		(end 116.09197 -113.3094)
		(width 0.1016)
		(layer "F.Cu")
		(net "SAS_HDD_TX3_N")
	)
	(segment
		(start 115.683284 -112.323118)
		(end 115.683538 -112.323118)
		(width 0.1016)
		(layer "F.Cu")
		(net "SAS_HDD_TX3_N")
	)
	(segment
		(start 114.954304 -107.305602)
		(end 115.350036 -106.350054)
		(width 0.1016)
		(layer "F.Cu")
		(net "SAS_HDD_TX3_N")
	)
	(arc
		(start 115.61826 -112.25784)
		(mid 115.115424 -111.505104)
		(end 114.93881 -110.617254)
		(width 0.1016)
		(layer "F.Cu")
		(net "SAS_HDD_TX3_N")
	)
	(arc
		(start 116.09197 -113.3094)
		(mid 115.985701 -112.775623)
		(end 115.683284 -112.323118)
		(width 0.1016)
		(layer "F.Cu")
		(net "SAS_HDD_TX3_N")
	)
	(arc
		(start 115.96497 -114.0206)
		(mid 116.058955 -113.879941)
		(end 116.09197 -113.714022)
		(width 0.1016)
		(layer "F.Cu")
		(net "SAS_HDD_TX3_N")
	)
	(arc
		(start 114.93881 -107.383326)
		(mid 114.942712 -107.343696)
		(end 114.954304 -107.305602)
		(width 0.1016)
		(layer "F.Cu")
		(net "SAS_HDD_TX3_N")
	)
	(segment
		(start 91.175332 -44.1706)
		(end 91.147392 -44.19854)
		(width 0.1143)
		(layer "F.Cu")
		(net "OSC_REF_CLK")
	)
	(segment
		(start 93.150182 -44.59986)
		(end 92.720922 -44.1706)
		(width 0.1143)
		(layer "F.Cu")
		(net "OSC_REF_CLK")
	)
	(segment
		(start 92.720922 -44.1706)
		(end 91.175332 -44.1706)
		(width 0.1143)
		(layer "F.Cu")
		(net "OSC_REF_CLK")
	)
	(via
		(at 91.147392 -44.19854)
		(size 0.508)
		(drill 0.254)
		(layers "F.Cu" "B.Cu")
		(net "OSC_REF_CLK")
	)
	(segment
		(start 90.26398 -44.577)
		(end 90.768932 -44.577)
		(width 0.1143)
		(layer "B.Cu")
		(net "OSC_REF_CLK")
	)
	(segment
		(start 90.02014 -44.82084)
		(end 90.26398 -44.577)
		(width 0.1143)
		(layer "B.Cu")
		(net "OSC_REF_CLK")
	)
	(segment
		(start 90.768932 -44.577)
		(end 91.147392 -44.19854)
		(width 0.1143)
		(layer "B.Cu")
		(net "OSC_REF_CLK")
	)
	(segment
		(start 163.7665 -112.903)
		(end 162.687 -112.903)
		(width 0.254)
		(layer "F.Cu")
		(net "P1V5_E_PG")
	)
	(segment
		(start 198.289672 -115.323874)
		(end 198.289672 -115.908328)
		(width 0.254)
		(layer "F.Cu")
		(net "P1V5_E_PG")
	)
	(segment
		(start 198.062596 -121.622312)
		(end 197.104 -121.622312)
		(width 0.254)
		(layer "F.Cu")
		(net "P1V5_E_PG")
	)
	(segment
		(start 198.289672 -115.908328)
		(end 197.866 -116.332)
		(width 0.254)
		(layer "F.Cu")
		(net "P1V5_E_PG")
	)
	(via
		(at 162.687 -112.903)
		(size 0.5588)
		(drill 0.3048)
		(layers "F.Cu" "B.Cu")
		(net "P1V5_E_PG")
	)
	(via
		(at 197.104 -121.622312)
		(size 0.5588)
		(drill 0.3048)
		(layers "F.Cu" "B.Cu")
		(net "P1V5_E_PG")
	)
	(via
		(at 197.866 -116.332)
		(size 0.5588)
		(drill 0.3048)
		(layers "F.Cu" "B.Cu")
		(net "P1V5_E_PG")
	)
	(via
		(at 197.786752 -119.58066)
		(size 0.7112)
		(drill 0.3556)
		(layers "F.Cu" "B.Cu")
		(net "P1V5_E_PG")
	)
	(segment
		(start 197.640956 -121.085356)
		(end 197.104 -121.622312)
		(width 0.254)
		(layer "B.Cu")
		(net "P1V5_E_PG")
	)
	(segment
		(start 197.640956 -119.726456)
		(end 197.640956 -121.085356)
		(width 0.254)
		(layer "B.Cu")
		(net "P1V5_E_PG")
	)
	(segment
		(start 197.786752 -119.58066)
		(end 197.866 -119.501412)
		(width 0.254)
		(layer "B.Cu")
		(net "P1V5_E_PG")
	)
	(segment
		(start 197.866 -119.501412)
		(end 197.866 -116.332)
		(width 0.254)
		(layer "B.Cu")
		(net "P1V5_E_PG")
	)
	(segment
		(start 197.786752 -119.58066)
		(end 197.640956 -119.726456)
		(width 0.254)
		(layer "B.Cu")
		(net "P1V5_E_PG")
	)
	(segment
		(start 168.0972 -112.0902)
		(end 168.76395 -112.75695)
		(width 0.254)
		(layer "In2.Cu")
		(net "P1V5_E_PG")
	)
	(segment
		(start 190.60795 -112.75695)
		(end 194.183 -116.332)
		(width 0.254)
		(layer "In2.Cu")
		(net "P1V5_E_PG")
	)
	(segment
		(start 166.37 -112.903)
		(end 167.1828 -112.0902)
		(width 0.254)
		(layer "In2.Cu")
		(net "P1V5_E_PG")
	)
	(segment
		(start 167.1828 -112.0902)
		(end 168.0972 -112.0902)
		(width 0.254)
		(layer "In2.Cu")
		(net "P1V5_E_PG")
	)
	(segment
		(start 162.687 -112.903)
		(end 166.37 -112.903)
		(width 0.254)
		(layer "In2.Cu")
		(net "P1V5_E_PG")
	)
	(segment
		(start 168.76395 -112.75695)
		(end 190.60795 -112.75695)
		(width 0.254)
		(layer "In2.Cu")
		(net "P1V5_E_PG")
	)
	(segment
		(start 194.183 -116.332)
		(end 197.866 -116.332)
		(width 0.254)
		(layer "In2.Cu")
		(net "P1V5_E_PG")
	)
	(segment
		(start 72.29602 -131.70916)
		(end 72.29602 -131.744974)
		(width 0.1143)
		(layer "F.Cu")
		(net "XM_DATA2")
	)
	(segment
		(start 72.612758 -131.392422)
		(end 72.29602 -131.70916)
		(width 0.1143)
		(layer "F.Cu")
		(net "XM_DATA2")
	)
	(segment
		(start 75.786742 -131.392422)
		(end 72.612758 -131.392422)
		(width 0.1143)
		(layer "F.Cu")
		(net "XM_DATA2")
	)
	(segment
		(start 105.349802 -90.349832)
		(end 104.849676 -89.849706)
		(width 0.1143)
		(layer "F.Cu")
		(net "XM_DATA2")
	)
	(segment
		(start 72.29602 -131.744974)
		(end 71.908162 -132.132832)
		(width 0.1143)
		(layer "F.Cu")
		(net "XM_DATA2")
	)
	(via
		(at 71.908162 -132.132832)
		(size 0.5588)
		(drill 0.3048)
		(layers "F.Cu" "B.Cu")
		(net "XM_DATA2")
	)
	(via
		(at 104.849676 -89.849706)
		(size 0.508)
		(drill 0.254)
		(layers "F.Cu" "B.Cu")
		(net "XM_DATA2")
	)
	(via
		(at 79.905352 -91.870784)
		(size 0.7112)
		(drill 0.3556)
		(layers "F.Cu" "B.Cu")
		(net "XM_DATA2")
	)
	(segment
		(start 101.995986 -90.35923)
		(end 99.86137 -90.35923)
		(width 0.1143)
		(layer "B.Cu")
		(net "XM_DATA2")
	)
	(segment
		(start 71.492618 -99.03587)
		(end 72.382634 -99.925632)
		(width 0.1143)
		(layer "B.Cu")
		(net "XM_DATA2")
	)
	(segment
		(start 79.37754 -93.211396)
		(end 79.215996 -93.211396)
		(width 0.1143)
		(layer "B.Cu")
		(net "XM_DATA2")
	)
	(segment
		(start 71.169276 -99.359212)
		(end 71.007732 -99.359212)
		(width 0.1143)
		(layer "B.Cu")
		(net "XM_DATA2")
	)
	(segment
		(start 72.275954 -131.76504)
		(end 71.908162 -132.132832)
		(width 0.1143)
		(layer "B.Cu")
		(net "XM_DATA2")
	)
	(segment
		(start 80.265016 -91.51112)
		(end 79.905352 -91.870784)
		(width 0.1143)
		(layer "B.Cu")
		(net "XM_DATA2")
	)
	(segment
		(start 78.105 -92.261944)
		(end 77.943202 -92.423742)
		(width 0.1143)
		(layer "B.Cu")
		(net "XM_DATA2")
	)
	(segment
		(start 87.361014 -90.7034)
		(end 86.553294 -91.51112)
		(width 0.1143)
		(layer "B.Cu")
		(net "XM_DATA2")
	)
	(segment
		(start 77.943202 -92.423742)
		(end 77.943202 -92.585286)
		(width 0.1143)
		(layer "B.Cu")
		(net "XM_DATA2")
	)
	(segment
		(start 104.172766 -89.436956)
		(end 102.707948 -89.436956)
		(width 0.1143)
		(layer "B.Cu")
		(net "XM_DATA2")
	)
	(segment
		(start 72.160892 -130.379724)
		(end 72.160892 -130.379978)
		(width 0.1143)
		(layer "B.Cu")
		(net "XM_DATA2")
	)
	(segment
		(start 72.705976 -99.60229)
		(end 71.81596 -98.712528)
		(width 0.1143)
		(layer "B.Cu")
		(net "XM_DATA2")
	)
	(segment
		(start 72.382634 -99.925632)
		(end 72.382634 -100.087176)
		(width 0.1143)
		(layer "B.Cu")
		(net "XM_DATA2")
	)
	(segment
		(start 78.266544 -92.261944)
		(end 78.105 -92.261944)
		(width 0.1143)
		(layer "B.Cu")
		(net "XM_DATA2")
	)
	(segment
		(start 71.492618 -98.874326)
		(end 71.492618 -99.03587)
		(width 0.1143)
		(layer "B.Cu")
		(net "XM_DATA2")
	)
	(segment
		(start 104.585516 -89.849706)
		(end 104.172766 -89.436956)
		(width 0.1143)
		(layer "B.Cu")
		(net "XM_DATA2")
	)
	(segment
		(start 86.553294 -91.51112)
		(end 80.265016 -91.51112)
		(width 0.1143)
		(layer "B.Cu")
		(net "XM_DATA2")
	)
	(segment
		(start 77.943202 -92.585286)
		(end 78.892654 -93.534738)
		(width 0.1143)
		(layer "B.Cu")
		(net "XM_DATA2")
	)
	(segment
		(start 76.23048 -94.136464)
		(end 72.139302 -98.227642)
		(width 0.1143)
		(layer "B.Cu")
		(net "XM_DATA2")
	)
	(segment
		(start 102.26929 -90.085926)
		(end 101.995986 -90.35923)
		(width 0.1143)
		(layer "B.Cu")
		(net "XM_DATA2")
	)
	(segment
		(start 92.07246 -90.316558)
		(end 92.072206 -90.316304)
		(width 0.1143)
		(layer "B.Cu")
		(net "XM_DATA2")
	)
	(segment
		(start 78.730856 -93.85808)
		(end 78.569312 -93.85808)
		(width 0.1143)
		(layer "B.Cu")
		(net "XM_DATA2")
	)
	(segment
		(start 72.160892 -130.379978)
		(end 72.275954 -130.49504)
		(width 0.1143)
		(layer "B.Cu")
		(net "XM_DATA2")
	)
	(segment
		(start 77.567028 -94.665038)
		(end 77.567028 -94.826582)
		(width 0.1143)
		(layer "B.Cu")
		(net "XM_DATA2")
	)
	(segment
		(start 76.392024 -94.136464)
		(end 76.23048 -94.136464)
		(width 0.1143)
		(layer "B.Cu")
		(net "XM_DATA2")
	)
	(segment
		(start 79.539338 -92.236798)
		(end 79.539338 -93.049598)
		(width 0.1143)
		(layer "B.Cu")
		(net "XM_DATA2")
	)
	(segment
		(start 71.007732 -99.359212)
		(end 70.74662 -99.620324)
		(width 0.1143)
		(layer "B.Cu")
		(net "XM_DATA2")
	)
	(segment
		(start 72.275954 -130.49504)
		(end 72.275954 -131.76504)
		(width 0.1143)
		(layer "B.Cu")
		(net "XM_DATA2")
	)
	(segment
		(start 76.715366 -93.813122)
		(end 77.567028 -94.665038)
		(width 0.1143)
		(layer "B.Cu")
		(net "XM_DATA2")
	)
	(segment
		(start 102.707948 -89.436956)
		(end 102.26929 -89.875614)
		(width 0.1143)
		(layer "B.Cu")
		(net "XM_DATA2")
	)
	(segment
		(start 77.243686 -94.98838)
		(end 76.392024 -94.136464)
		(width 0.1143)
		(layer "B.Cu")
		(net "XM_DATA2")
	)
	(segment
		(start 79.539338 -93.049598)
		(end 79.37754 -93.211396)
		(width 0.1143)
		(layer "B.Cu")
		(net "XM_DATA2")
	)
	(segment
		(start 73.029318 -99.440492)
		(end 72.86752 -99.60229)
		(width 0.1143)
		(layer "B.Cu")
		(net "XM_DATA2")
	)
	(segment
		(start 73.029318 -99.278948)
		(end 73.029318 -99.440492)
		(width 0.1143)
		(layer "B.Cu")
		(net "XM_DATA2")
	)
	(segment
		(start 77.40523 -94.98838)
		(end 77.243686 -94.98838)
		(width 0.1143)
		(layer "B.Cu")
		(net "XM_DATA2")
	)
	(segment
		(start 77.61986 -92.908628)
		(end 77.458316 -92.908628)
		(width 0.1143)
		(layer "B.Cu")
		(net "XM_DATA2")
	)
	(segment
		(start 70.74662 -99.620324)
		(end 70.74662 -128.965452)
		(width 0.1143)
		(layer "B.Cu")
		(net "XM_DATA2")
	)
	(segment
		(start 79.215996 -93.211396)
		(end 78.266544 -92.261944)
		(width 0.1143)
		(layer "B.Cu")
		(net "XM_DATA2")
	)
	(segment
		(start 72.059292 -100.248974)
		(end 71.169276 -99.359212)
		(width 0.1143)
		(layer "B.Cu")
		(net "XM_DATA2")
	)
	(segment
		(start 70.74662 -128.965452)
		(end 72.160892 -130.379724)
		(width 0.1143)
		(layer "B.Cu")
		(net "XM_DATA2")
	)
	(segment
		(start 72.86752 -99.60229)
		(end 72.705976 -99.60229)
		(width 0.1143)
		(layer "B.Cu")
		(net "XM_DATA2")
	)
	(segment
		(start 99.818698 -90.316558)
		(end 92.07246 -90.316558)
		(width 0.1143)
		(layer "B.Cu")
		(net "XM_DATA2")
	)
	(segment
		(start 78.569312 -93.85808)
		(end 77.61986 -92.908628)
		(width 0.1143)
		(layer "B.Cu")
		(net "XM_DATA2")
	)
	(segment
		(start 72.220836 -100.248974)
		(end 72.059292 -100.248974)
		(width 0.1143)
		(layer "B.Cu")
		(net "XM_DATA2")
	)
	(segment
		(start 77.458316 -92.908628)
		(end 76.715366 -93.651578)
		(width 0.1143)
		(layer "B.Cu")
		(net "XM_DATA2")
	)
	(segment
		(start 79.905352 -91.870784)
		(end 79.539338 -92.236798)
		(width 0.1143)
		(layer "B.Cu")
		(net "XM_DATA2")
	)
	(segment
		(start 92.072206 -90.316304)
		(end 87.748364 -90.316304)
		(width 0.1143)
		(layer "B.Cu")
		(net "XM_DATA2")
	)
	(segment
		(start 71.654416 -98.712528)
		(end 71.492618 -98.874326)
		(width 0.1143)
		(layer "B.Cu")
		(net "XM_DATA2")
	)
	(segment
		(start 72.382634 -100.087176)
		(end 72.220836 -100.248974)
		(width 0.1143)
		(layer "B.Cu")
		(net "XM_DATA2")
	)
	(segment
		(start 87.748364 -90.316304)
		(end 87.361268 -90.7034)
		(width 0.1143)
		(layer "B.Cu")
		(net "XM_DATA2")
	)
	(segment
		(start 71.81596 -98.712528)
		(end 71.654416 -98.712528)
		(width 0.1143)
		(layer "B.Cu")
		(net "XM_DATA2")
	)
	(segment
		(start 104.849676 -89.849706)
		(end 104.585516 -89.849706)
		(width 0.1143)
		(layer "B.Cu")
		(net "XM_DATA2")
	)
	(segment
		(start 72.139302 -98.227642)
		(end 72.139302 -98.389186)
		(width 0.1143)
		(layer "B.Cu")
		(net "XM_DATA2")
	)
	(segment
		(start 78.892654 -93.534738)
		(end 78.892654 -93.696282)
		(width 0.1143)
		(layer "B.Cu")
		(net "XM_DATA2")
	)
	(segment
		(start 76.715366 -93.651578)
		(end 76.715366 -93.813122)
		(width 0.1143)
		(layer "B.Cu")
		(net "XM_DATA2")
	)
	(segment
		(start 78.892654 -93.696282)
		(end 78.730856 -93.85808)
		(width 0.1143)
		(layer "B.Cu")
		(net "XM_DATA2")
	)
	(segment
		(start 87.361268 -90.7034)
		(end 87.361014 -90.7034)
		(width 0.1143)
		(layer "B.Cu")
		(net "XM_DATA2")
	)
	(segment
		(start 72.139302 -98.389186)
		(end 73.029318 -99.278948)
		(width 0.1143)
		(layer "B.Cu")
		(net "XM_DATA2")
	)
	(segment
		(start 99.86137 -90.35923)
		(end 99.818698 -90.316558)
		(width 0.1143)
		(layer "B.Cu")
		(net "XM_DATA2")
	)
	(segment
		(start 102.26929 -89.875614)
		(end 102.26929 -90.085926)
		(width 0.1143)
		(layer "B.Cu")
		(net "XM_DATA2")
	)
	(segment
		(start 77.567028 -94.826582)
		(end 77.40523 -94.98838)
		(width 0.1143)
		(layer "B.Cu")
		(net "XM_DATA2")
	)
	(segment
		(start 105.150158 -37.399976)
		(end 105.549954 -37.799772)
		(width 0.1143)
		(layer "F.Cu")
		(net "SPARE5")
	)
	(via
		(at 105.549954 -37.799772)
		(size 0.508)
		(drill 0.254)
		(layers "F.Cu" "B.Cu")
		(net "SPARE5")
	)
	(segment
		(start 104.883966 -37.133784)
		(end 105.549954 -37.799772)
		(width 0.1143)
		(layer "B.Cu")
		(net "SPARE5")
	)
	(segment
		(start 104.883966 -36.957)
		(end 104.883966 -37.133784)
		(width 0.1143)
		(layer "B.Cu")
		(net "SPARE5")
	)
	(segment
		(start 75.786742 -128.893062)
		(end 71.630032 -128.893062)
		(width 0.1143)
		(layer "F.Cu")
		(net "EXP_XM_OE_N")
	)
	(segment
		(start 71.630032 -128.893062)
		(end 68.97497 -126.238)
		(width 0.1143)
		(layer "F.Cu")
		(net "EXP_XM_OE_N")
	)
	(segment
		(start 102.349808 -85.349842)
		(end 101.849682 -84.849716)
		(width 0.1143)
		(layer "F.Cu")
		(net "EXP_XM_OE_N")
	)
	(segment
		(start 68.97497 -126.238)
		(end 58.17997 -126.238)
		(width 0.1143)
		(layer "F.Cu")
		(net "EXP_XM_OE_N")
	)
	(via
		(at 101.849682 -84.849716)
		(size 0.508)
		(drill 0.254)
		(layers "F.Cu" "B.Cu")
		(net "EXP_XM_OE_N")
	)
	(via
		(at 58.17997 -126.238)
		(size 0.5588)
		(drill 0.3048)
		(layers "F.Cu" "B.Cu")
		(net "EXP_XM_OE_N")
	)
	(via
		(at 58.166 -125.349)
		(size 0.7112)
		(drill 0.3556)
		(layers "F.Cu" "B.Cu")
		(net "EXP_XM_OE_N")
	)
	(segment
		(start 58.166 -125.349)
		(end 58.166 -126.22403)
		(width 0.1143)
		(layer "B.Cu")
		(net "EXP_XM_OE_N")
	)
	(segment
		(start 58.166 -126.22403)
		(end 58.17997 -126.238)
		(width 0.1143)
		(layer "B.Cu")
		(net "EXP_XM_OE_N")
	)
	(segment
		(start 58.67781 -113.420144)
		(end 79.641954 -92.456)
		(width 0.127)
		(layer "In2.Cu")
		(net "EXP_XM_OE_N")
	)
	(segment
		(start 98.251264 -85.725)
		(end 99.737164 -84.2391)
		(width 0.127)
		(layer "In2.Cu")
		(net "EXP_XM_OE_N")
	)
	(segment
		(start 85.101176 -90.275156)
		(end 87.745824 -87.630508)
		(width 0.127)
		(layer "In2.Cu")
		(net "EXP_XM_OE_N")
	)
	(segment
		(start 101.239066 -84.2391)
		(end 101.849682 -84.849716)
		(width 0.127)
		(layer "In2.Cu")
		(net "EXP_XM_OE_N")
	)
	(segment
		(start 58.67781 -125.74016)
		(end 58.67781 -113.420144)
		(width 0.127)
		(layer "In2.Cu")
		(net "EXP_XM_OE_N")
	)
	(segment
		(start 88.39454 -87.630508)
		(end 90.300048 -85.725)
		(width 0.127)
		(layer "In2.Cu")
		(net "EXP_XM_OE_N")
	)
	(segment
		(start 87.745824 -87.630508)
		(end 88.39454 -87.630508)
		(width 0.127)
		(layer "In2.Cu")
		(net "EXP_XM_OE_N")
	)
	(segment
		(start 79.641954 -92.456)
		(end 82.503772 -92.456)
		(width 0.127)
		(layer "In2.Cu")
		(net "EXP_XM_OE_N")
	)
	(segment
		(start 84.684616 -90.275156)
		(end 85.101176 -90.275156)
		(width 0.127)
		(layer "In2.Cu")
		(net "EXP_XM_OE_N")
	)
	(segment
		(start 99.737164 -84.2391)
		(end 101.239066 -84.2391)
		(width 0.127)
		(layer "In2.Cu")
		(net "EXP_XM_OE_N")
	)
	(segment
		(start 90.300048 -85.725)
		(end 98.251264 -85.725)
		(width 0.127)
		(layer "In2.Cu")
		(net "EXP_XM_OE_N")
	)
	(segment
		(start 58.17997 -126.238)
		(end 58.67781 -125.74016)
		(width 0.127)
		(layer "In2.Cu")
		(net "EXP_XM_OE_N")
	)
	(segment
		(start 82.503772 -92.456)
		(end 84.684616 -90.275156)
		(width 0.127)
		(layer "In2.Cu")
		(net "EXP_XM_OE_N")
	)
	(segment
		(start 115.28171 -110.617)
		(end 115.28171 -107.514898)
		(width 0.1016)
		(layer "F.Cu")
		(net "SAS_HDD_TX3_P")
	)
	(segment
		(start 115.926108 -112.080548)
		(end 115.86083 -112.01527)
		(width 0.1016)
		(layer "F.Cu")
		(net "SAS_HDD_TX3_P")
	)
	(segment
		(start 116.43487 -113.62182)
		(end 116.43487 -113.309146)
		(width 0.1016)
		(layer "F.Cu")
		(net "SAS_HDD_TX3_P")
	)
	(arc
		(start 116.43487 -113.309146)
		(mid 116.302651 -112.644259)
		(end 115.926108 -112.080548)
		(width 0.1016)
		(layer "F.Cu")
		(net "SAS_HDD_TX3_P")
	)
	(arc
		(start 116.59997 -114.0206)
		(mid 116.590666 -113.973735)
		(end 116.564156 -113.933986)
		(width 0.1016)
		(layer "F.Cu")
		(net "SAS_HDD_TX3_P")
	)
	(arc
		(start 115.86083 -112.01527)
		(mid 115.432226 -111.373724)
		(end 115.28171 -110.617)
		(width 0.1016)
		(layer "F.Cu")
		(net "SAS_HDD_TX3_P")
	)
	(arc
		(start 115.28171 -107.514898)
		(mid 115.299459 -107.425667)
		(end 115.350036 -107.350052)
		(width 0.1016)
		(layer "F.Cu")
		(net "SAS_HDD_TX3_P")
	)
	(arc
		(start 116.564156 -113.933986)
		(mid 116.468457 -113.790763)
		(end 116.43487 -113.62182)
		(width 0.1016)
		(layer "F.Cu")
		(net "SAS_HDD_TX3_P")
	)
	(segment
		(start 108.35005 -37.399976)
		(end 108.749846 -37.799772)
		(width 0.1143)
		(layer "F.Cu")
		(net "SYS_RST_N_1")
	)
	(via
		(at 109.204506 -37.08908)
		(size 0.7112)
		(drill 0.3556)
		(layers "F.Cu" "B.Cu")
		(net "SYS_RST_N_1")
	)
	(via
		(at 108.749846 -37.799772)
		(size 0.508)
		(drill 0.254)
		(layers "F.Cu" "B.Cu")
		(net "SYS_RST_N_1")
	)
	(segment
		(start 109.234986 -37.0586)
		(end 109.204506 -37.08908)
		(width 0.1143)
		(layer "B.Cu")
		(net "SYS_RST_N_1")
	)
	(segment
		(start 110.142782 -37.008054)
		(end 109.234986 -37.0586)
		(width 0.1143)
		(layer "B.Cu")
		(net "SYS_RST_N_1")
	)
	(segment
		(start 108.749846 -37.799772)
		(end 108.749846 -37.54374)
		(width 0.1143)
		(layer "B.Cu")
		(net "SYS_RST_N_1")
	)
	(segment
		(start 108.749846 -37.54374)
		(end 109.204506 -37.08908)
		(width 0.1143)
		(layer "B.Cu")
		(net "SYS_RST_N_1")
	)
	(segment
		(start 102.071932 -88.079834)
		(end 100.734622 -88.079834)
		(width 0.1143)
		(layer "F.Cu")
		(net "XM_DATA3")
	)
	(segment
		(start 72.863964 -132.391912)
		(end 72.634094 -132.621782)
		(width 0.1143)
		(layer "F.Cu")
		(net "XM_DATA3")
	)
	(segment
		(start 102.510336 -87.962486)
		(end 102.18928 -87.962486)
		(width 0.1143)
		(layer "F.Cu")
		(net "XM_DATA3")
	)
	(segment
		(start 71.70547 -132.621782)
		(end 71.627238 -132.54355)
		(width 0.1143)
		(layer "F.Cu")
		(net "XM_DATA3")
	)
	(segment
		(start 103.349806 -88.349836)
		(end 102.897686 -88.349836)
		(width 0.1143)
		(layer "F.Cu")
		(net "XM_DATA3")
	)
	(segment
		(start 72.634094 -132.621782)
		(end 71.70547 -132.621782)
		(width 0.1143)
		(layer "F.Cu")
		(net "XM_DATA3")
	)
	(segment
		(start 100.727256 -88.0872)
		(end 99.837494 -88.0872)
		(width 0.1143)
		(layer "F.Cu")
		(net "XM_DATA3")
	)
	(segment
		(start 102.18928 -87.962486)
		(end 102.071932 -88.079834)
		(width 0.1143)
		(layer "F.Cu")
		(net "XM_DATA3")
	)
	(segment
		(start 71.627238 -132.54355)
		(end 69.86397 -132.54355)
		(width 0.1143)
		(layer "F.Cu")
		(net "XM_DATA3")
	)
	(segment
		(start 100.734622 -88.079834)
		(end 100.727256 -88.0872)
		(width 0.1143)
		(layer "F.Cu")
		(net "XM_DATA3")
	)
	(segment
		(start 102.897686 -88.349836)
		(end 102.510336 -87.962486)
		(width 0.1143)
		(layer "F.Cu")
		(net "XM_DATA3")
	)
	(segment
		(start 75.786742 -132.391912)
		(end 72.863964 -132.391912)
		(width 0.1143)
		(layer "F.Cu")
		(net "XM_DATA3")
	)
	(via
		(at 69.86397 -131.56184)
		(size 0.7112)
		(drill 0.3556)
		(layers "F.Cu" "B.Cu")
		(net "XM_DATA3")
	)
	(via
		(at 99.837494 -88.0872)
		(size 0.508)
		(drill 0.254)
		(layers "F.Cu" "B.Cu")
		(net "XM_DATA3")
	)
	(via
		(at 69.86397 -132.54355)
		(size 0.5588)
		(drill 0.3048)
		(layers "F.Cu" "B.Cu")
		(net "XM_DATA3")
	)
	(segment
		(start 72.570086 -91.728544)
		(end 72.570086 -91.567)
		(width 0.1143)
		(layer "B.Cu")
		(net "XM_DATA3")
	)
	(segment
		(start 72.884538 -90.42654)
		(end 73.641458 -89.66962)
		(width 0.1143)
		(layer "B.Cu")
		(net "XM_DATA3")
	)
	(segment
		(start 73.641458 -89.66962)
		(end 85.790024 -89.66962)
		(width 0.1143)
		(layer "B.Cu")
		(net "XM_DATA3")
	)
	(segment
		(start 85.790024 -89.66962)
		(end 86.597744 -88.8619)
		(width 0.1143)
		(layer "B.Cu")
		(net "XM_DATA3")
	)
	(segment
		(start 70.297802 -93.013276)
		(end 70.4596 -92.851478)
		(width 0.1143)
		(layer "B.Cu")
		(net "XM_DATA3")
	)
	(segment
		(start 70.4596 -92.851478)
		(end 70.621144 -92.851478)
		(width 0.1143)
		(layer "B.Cu")
		(net "XM_DATA3")
	)
	(segment
		(start 71.761604 -92.537026)
		(end 71.923402 -92.375228)
		(width 0.1143)
		(layer "B.Cu")
		(net "XM_DATA3")
	)
	(segment
		(start 69.651118 -93.65996)
		(end 69.812916 -93.498162)
		(width 0.1143)
		(layer "B.Cu")
		(net "XM_DATA3")
	)
	(segment
		(start 69.327776 -94.144846)
		(end 69.660008 -94.477078)
		(width 0.1143)
		(layer "B.Cu")
		(net "XM_DATA3")
	)
	(segment
		(start 86.597744 -88.8619)
		(end 86.597998 -88.8619)
		(width 0.1143)
		(layer "B.Cu")
		(net "XM_DATA3")
	)
	(segment
		(start 72.399652 -90.911426)
		(end 72.561196 -90.911426)
		(width 0.1143)
		(layer "B.Cu")
		(net "XM_DATA3")
	)
	(segment
		(start 69.86397 -131.56184)
		(end 69.86397 -132.54355)
		(width 0.1143)
		(layer "B.Cu")
		(net "XM_DATA3")
	)
	(segment
		(start 71.923402 -92.375228)
		(end 71.923402 -92.213684)
		(width 0.1143)
		(layer "B.Cu")
		(net "XM_DATA3")
	)
	(segment
		(start 70.621144 -92.851478)
		(end 70.953376 -93.18371)
		(width 0.1143)
		(layer "B.Cu")
		(net "XM_DATA3")
	)
	(segment
		(start 72.561196 -90.911426)
		(end 72.893428 -91.243658)
		(width 0.1143)
		(layer "B.Cu")
		(net "XM_DATA3")
	)
	(segment
		(start 71.11492 -93.18371)
		(end 71.276718 -93.021912)
		(width 0.1143)
		(layer "B.Cu")
		(net "XM_DATA3")
	)
	(segment
		(start 73.21677 -91.08186)
		(end 73.21677 -90.920316)
		(width 0.1143)
		(layer "B.Cu")
		(net "XM_DATA3")
	)
	(segment
		(start 98.861626 -88.0872)
		(end 99.837494 -88.0872)
		(width 0.1143)
		(layer "B.Cu")
		(net "XM_DATA3")
	)
	(segment
		(start 72.237854 -91.073224)
		(end 72.399652 -90.911426)
		(width 0.1143)
		(layer "B.Cu")
		(net "XM_DATA3")
	)
	(segment
		(start 71.276718 -92.860368)
		(end 70.944486 -92.528136)
		(width 0.1143)
		(layer "B.Cu")
		(net "XM_DATA3")
	)
	(segment
		(start 69.166232 -94.144846)
		(end 69.327776 -94.144846)
		(width 0.1143)
		(layer "B.Cu")
		(net "XM_DATA3")
	)
	(segment
		(start 73.054972 -91.243658)
		(end 73.21677 -91.08186)
		(width 0.1143)
		(layer "B.Cu")
		(net "XM_DATA3")
	)
	(segment
		(start 72.246744 -91.890342)
		(end 72.408288 -91.890342)
		(width 0.1143)
		(layer "B.Cu")
		(net "XM_DATA3")
	)
	(segment
		(start 69.97446 -93.498162)
		(end 70.306692 -93.830394)
		(width 0.1143)
		(layer "B.Cu")
		(net "XM_DATA3")
	)
	(segment
		(start 71.60006 -92.537026)
		(end 71.761604 -92.537026)
		(width 0.1143)
		(layer "B.Cu")
		(net "XM_DATA3")
	)
	(segment
		(start 70.953376 -93.18371)
		(end 71.11492 -93.18371)
		(width 0.1143)
		(layer "B.Cu")
		(net "XM_DATA3")
	)
	(segment
		(start 72.408288 -91.890342)
		(end 72.570086 -91.728544)
		(width 0.1143)
		(layer "B.Cu")
		(net "XM_DATA3")
	)
	(segment
		(start 87.074248 -88.38565)
		(end 93.4974 -88.38565)
		(width 0.1143)
		(layer "B.Cu")
		(net "XM_DATA3")
	)
	(segment
		(start 68.90512 -130.120898)
		(end 68.90512 -94.405958)
		(width 0.1143)
		(layer "B.Cu")
		(net "XM_DATA3")
	)
	(segment
		(start 71.59117 -91.881452)
		(end 71.59117 -91.719908)
		(width 0.1143)
		(layer "B.Cu")
		(net "XM_DATA3")
	)
	(segment
		(start 70.630034 -93.668596)
		(end 70.630034 -93.507052)
		(width 0.1143)
		(layer "B.Cu")
		(net "XM_DATA3")
	)
	(segment
		(start 70.297802 -93.17482)
		(end 70.297802 -93.013276)
		(width 0.1143)
		(layer "B.Cu")
		(net "XM_DATA3")
	)
	(segment
		(start 71.267828 -92.204794)
		(end 71.60006 -92.537026)
		(width 0.1143)
		(layer "B.Cu")
		(net "XM_DATA3")
	)
	(segment
		(start 94.107 -87.77605)
		(end 98.550476 -87.77605)
		(width 0.1143)
		(layer "B.Cu")
		(net "XM_DATA3")
	)
	(segment
		(start 71.914512 -91.55811)
		(end 72.246744 -91.890342)
		(width 0.1143)
		(layer "B.Cu")
		(net "XM_DATA3")
	)
	(segment
		(start 71.106284 -92.204794)
		(end 71.267828 -92.204794)
		(width 0.1143)
		(layer "B.Cu")
		(net "XM_DATA3")
	)
	(segment
		(start 93.4974 -88.38565)
		(end 94.107 -87.77605)
		(width 0.1143)
		(layer "B.Cu")
		(net "XM_DATA3")
	)
	(segment
		(start 72.237854 -91.234768)
		(end 72.237854 -91.073224)
		(width 0.1143)
		(layer "B.Cu")
		(net "XM_DATA3")
	)
	(segment
		(start 69.812916 -93.498162)
		(end 69.97446 -93.498162)
		(width 0.1143)
		(layer "B.Cu")
		(net "XM_DATA3")
	)
	(segment
		(start 69.98335 -94.153736)
		(end 69.651118 -93.821504)
		(width 0.1143)
		(layer "B.Cu")
		(net "XM_DATA3")
	)
	(segment
		(start 69.98335 -94.31528)
		(end 69.98335 -94.153736)
		(width 0.1143)
		(layer "B.Cu")
		(net "XM_DATA3")
	)
	(segment
		(start 69.660008 -94.477078)
		(end 69.821552 -94.477078)
		(width 0.1143)
		(layer "B.Cu")
		(net "XM_DATA3")
	)
	(segment
		(start 71.752968 -91.55811)
		(end 71.914512 -91.55811)
		(width 0.1143)
		(layer "B.Cu")
		(net "XM_DATA3")
	)
	(segment
		(start 73.21677 -90.920316)
		(end 72.884538 -90.588084)
		(width 0.1143)
		(layer "B.Cu")
		(net "XM_DATA3")
	)
	(segment
		(start 69.651118 -93.821504)
		(end 69.651118 -93.65996)
		(width 0.1143)
		(layer "B.Cu")
		(net "XM_DATA3")
	)
	(segment
		(start 70.468236 -93.830394)
		(end 70.630034 -93.668596)
		(width 0.1143)
		(layer "B.Cu")
		(net "XM_DATA3")
	)
	(segment
		(start 71.59117 -91.719908)
		(end 71.752968 -91.55811)
		(width 0.1143)
		(layer "B.Cu")
		(net "XM_DATA3")
	)
	(segment
		(start 72.570086 -91.567)
		(end 72.237854 -91.234768)
		(width 0.1143)
		(layer "B.Cu")
		(net "XM_DATA3")
	)
	(segment
		(start 71.923402 -92.213684)
		(end 71.59117 -91.881452)
		(width 0.1143)
		(layer "B.Cu")
		(net "XM_DATA3")
	)
	(segment
		(start 86.597998 -88.8619)
		(end 87.074248 -88.38565)
		(width 0.1143)
		(layer "B.Cu")
		(net "XM_DATA3")
	)
	(segment
		(start 71.276718 -93.021912)
		(end 71.276718 -92.860368)
		(width 0.1143)
		(layer "B.Cu")
		(net "XM_DATA3")
	)
	(segment
		(start 70.944486 -92.366592)
		(end 71.106284 -92.204794)
		(width 0.1143)
		(layer "B.Cu")
		(net "XM_DATA3")
	)
	(segment
		(start 69.86397 -131.079748)
		(end 68.90512 -130.120898)
		(width 0.1143)
		(layer "B.Cu")
		(net "XM_DATA3")
	)
	(segment
		(start 69.86397 -131.56184)
		(end 69.86397 -131.079748)
		(width 0.1143)
		(layer "B.Cu")
		(net "XM_DATA3")
	)
	(segment
		(start 70.630034 -93.507052)
		(end 70.297802 -93.17482)
		(width 0.1143)
		(layer "B.Cu")
		(net "XM_DATA3")
	)
	(segment
		(start 70.306692 -93.830394)
		(end 70.468236 -93.830394)
		(width 0.1143)
		(layer "B.Cu")
		(net "XM_DATA3")
	)
	(segment
		(start 70.944486 -92.528136)
		(end 70.944486 -92.366592)
		(width 0.1143)
		(layer "B.Cu")
		(net "XM_DATA3")
	)
	(segment
		(start 69.821552 -94.477078)
		(end 69.98335 -94.31528)
		(width 0.1143)
		(layer "B.Cu")
		(net "XM_DATA3")
	)
	(segment
		(start 72.893428 -91.243658)
		(end 73.054972 -91.243658)
		(width 0.1143)
		(layer "B.Cu")
		(net "XM_DATA3")
	)
	(segment
		(start 72.884538 -90.588084)
		(end 72.884538 -90.42654)
		(width 0.1143)
		(layer "B.Cu")
		(net "XM_DATA3")
	)
	(segment
		(start 98.550476 -87.77605)
		(end 98.861626 -88.0872)
		(width 0.1143)
		(layer "B.Cu")
		(net "XM_DATA3")
	)
	(segment
		(start 68.90512 -94.405958)
		(end 69.166232 -94.144846)
		(width 0.1143)
		(layer "B.Cu")
		(net "XM_DATA3")
	)
	(segment
		(start 115.734084 -109.8042)
		(end 115.734084 -106.4006)
		(width 0.1016)
		(layer "F.Cu")
		(net "SAS_HDD_TX2_N")
	)
	(segment
		(start 116.041424 -105.658666)
		(end 116.350034 -105.350056)
		(width 0.1016)
		(layer "F.Cu")
		(net "SAS_HDD_TX2_N")
	)
	(segment
		(start 116.037868 -110.518448)
		(end 116.024406 -110.504732)
		(width 0.1016)
		(layer "F.Cu")
		(net "SAS_HDD_TX2_N")
	)
	(segment
		(start 117.74297 -114.0206)
		(end 117.74297 -113.919)
		(width 0.1016)
		(layer "F.Cu")
		(net "SAS_HDD_TX2_N")
	)
	(segment
		(start 117.814852 -113.745518)
		(end 117.816122 -113.744248)
		(width 0.1016)
		(layer "F.Cu")
		(net "SAS_HDD_TX2_N")
	)
	(segment
		(start 117.244368 -111.724948)
		(end 116.037868 -110.518448)
		(width 0.1016)
		(layer "F.Cu")
		(net "SAS_HDD_TX2_N")
	)
	(segment
		(start 117.368066 -111.8489)
		(end 117.244368 -111.724948)
		(width 0.1016)
		(layer "F.Cu")
		(net "SAS_HDD_TX2_N")
	)
	(segment
		(start 117.88902 -113.567972)
		(end 117.88902 -113.1062)
		(width 0.1016)
		(layer "F.Cu")
		(net "SAS_HDD_TX2_N")
	)
	(arc
		(start 117.88902 -113.1062)
		(mid 117.753576 -112.425745)
		(end 117.368066 -111.8489)
		(width 0.1016)
		(layer "F.Cu")
		(net "SAS_HDD_TX2_N")
	)
	(arc
		(start 115.734084 -106.4006)
		(mid 115.813955 -105.99906)
		(end 116.041424 -105.658666)
		(width 0.1016)
		(layer "F.Cu")
		(net "SAS_HDD_TX2_N")
	)
	(arc
		(start 117.816122 -113.744248)
		(mid 117.870054 -113.663343)
		(end 117.88902 -113.567972)
		(width 0.1016)
		(layer "F.Cu")
		(net "SAS_HDD_TX2_N")
	)
	(arc
		(start 116.024406 -110.504732)
		(mid 115.809566 -110.18334)
		(end 115.734084 -109.8042)
		(width 0.1016)
		(layer "F.Cu")
		(net "SAS_HDD_TX2_N")
	)
	(arc
		(start 117.74297 -113.919)
		(mid 117.761647 -113.825103)
		(end 117.814852 -113.745518)
		(width 0.1016)
		(layer "F.Cu")
		(net "SAS_HDD_TX2_N")
	)
	(segment
		(start 94.750128 -56.996838)
		(end 94.750128 -56.599836)
		(width 0.1143)
		(layer "F.Cu")
		(net "ICE1_TMS")
	)
	(segment
		(start 91.929966 -62.6745)
		(end 91.929966 -61.468)
		(width 0.1143)
		(layer "F.Cu")
		(net "ICE1_TMS")
	)
	(segment
		(start 91.929966 -59.817)
		(end 94.750128 -56.996838)
		(width 0.1143)
		(layer "F.Cu")
		(net "ICE1_TMS")
	)
	(segment
		(start 91.929966 -61.468)
		(end 91.929966 -59.817)
		(width 0.1143)
		(layer "F.Cu")
		(net "ICE1_TMS")
	)
	(segment
		(start 199.803258 -167.1955)
		(end 198.890636 -166.282878)
		(width 0.127)
		(layer "F.Cu")
		(net "P3V3_B")
	)
	(segment
		(start 200.279 -165.862)
		(end 199.858122 -166.282878)
		(width 0.127)
		(layer "F.Cu")
		(net "P3V3_B")
	)
	(segment
		(start 200.279 -167.1955)
		(end 199.803258 -167.1955)
		(width 0.127)
		(layer "F.Cu")
		(net "P3V3_B")
	)
	(segment
		(start 199.858122 -166.282878)
		(end 198.890636 -166.282878)
		(width 0.127)
		(layer "F.Cu")
		(net "P3V3_B")
	)
	(segment
		(start 201.295 -167.1955)
		(end 200.279 -167.1955)
		(width 0.127)
		(layer "F.Cu")
		(net "P3V3_B")
	)
	(via
		(at 200.279 -165.862)
		(size 0.7112)
		(drill 0.3556)
		(layers "F.Cu" "B.Cu")
		(net "P3V3_B")
	)
	(segment
		(start 106.3498 -95.350076)
		(end 105.849674 -95.850202)
		(width 0.1143)
		(layer "F.Cu")
		(net "EXP_XM_ADDR_11")
	)
	(segment
		(start 56.558942 -136.392412)
		(end 68.218558 -136.392412)
		(width 0.1143)
		(layer "F.Cu")
		(net "EXP_XM_ADDR_11")
	)
	(segment
		(start 68.218558 -136.392412)
		(end 68.46697 -136.144)
		(width 0.1143)
		(layer "F.Cu")
		(net "EXP_XM_ADDR_11")
	)
	(via
		(at 105.849674 -95.850202)
		(size 0.508)
		(drill 0.254)
		(layers "F.Cu" "B.Cu")
		(net "EXP_XM_ADDR_11")
	)
	(via
		(at 69.6468 -136.4488)
		(size 0.7112)
		(drill 0.3556)
		(layers "F.Cu" "B.Cu")
		(net "EXP_XM_ADDR_11")
	)
	(via
		(at 68.46697 -136.144)
		(size 0.5588)
		(drill 0.3048)
		(layers "F.Cu" "B.Cu")
		(net "EXP_XM_ADDR_11")
	)
	(segment
		(start 68.77177 -136.4488)
		(end 68.46697 -136.144)
		(width 0.1143)
		(layer "B.Cu")
		(net "EXP_XM_ADDR_11")
	)
	(segment
		(start 69.6468 -136.4488)
		(end 68.77177 -136.4488)
		(width 0.1143)
		(layer "B.Cu")
		(net "EXP_XM_ADDR_11")
	)
	(segment
		(start 78.63586 -112.29975)
		(end 78.224126 -111.888016)
		(width 0.127)
		(layer "In2.Cu")
		(net "EXP_XM_ADDR_11")
	)
	(segment
		(start 71.552562 -118.331488)
		(end 71.732394 -118.331488)
		(width 0.127)
		(layer "In2.Cu")
		(net "EXP_XM_ADDR_11")
	)
	(segment
		(start 72.091804 -117.792246)
		(end 72.271382 -117.612668)
		(width 0.127)
		(layer "In2.Cu")
		(net "EXP_XM_ADDR_11")
	)
	(segment
		(start 79.06766 -110.81639)
		(end 82.24393 -107.64012)
		(width 0.127)
		(layer "In2.Cu")
		(net "EXP_XM_ADDR_11")
	)
	(segment
		(start 75.768962 -115.179856)
		(end 75.948794 -115.179856)
		(width 0.127)
		(layer "In2.Cu")
		(net "EXP_XM_ADDR_11")
	)
	(segment
		(start 73.792334 -117.336316)
		(end 73.971912 -117.156738)
		(width 0.127)
		(layer "In2.Cu")
		(net "EXP_XM_ADDR_11")
	)
	(segment
		(start 78.218792 -112.730026)
		(end 78.398624 -112.730026)
		(width 0.127)
		(layer "In2.Cu")
		(net "EXP_XM_ADDR_11")
	)
	(segment
		(start 72.271382 -117.612668)
		(end 72.451214 -117.612668)
		(width 0.127)
		(layer "In2.Cu")
		(net "EXP_XM_ADDR_11")
	)
	(segment
		(start 73.253092 -117.695726)
		(end 72.810624 -117.253258)
		(width 0.127)
		(layer "In2.Cu")
		(net "EXP_XM_ADDR_11")
	)
	(segment
		(start 73.253092 -117.875558)
		(end 73.253092 -117.695726)
		(width 0.127)
		(layer "In2.Cu")
		(net "EXP_XM_ADDR_11")
	)
	(segment
		(start 68.93687 -133.004052)
		(end 68.93687 -130.961892)
		(width 0.127)
		(layer "In2.Cu")
		(net "EXP_XM_ADDR_11")
	)
	(segment
		(start 75.409552 -115.539266)
		(end 74.967084 -115.096798)
		(width 0.127)
		(layer "In2.Cu")
		(net "EXP_XM_ADDR_11")
	)
	(segment
		(start 77.416914 -112.467136)
		(end 77.596492 -112.287558)
		(width 0.127)
		(layer "In2.Cu")
		(net "EXP_XM_ADDR_11")
	)
	(segment
		(start 78.63586 -112.49279)
		(end 78.63586 -112.29975)
		(width 0.127)
		(layer "In2.Cu")
		(net "EXP_XM_ADDR_11")
	)
	(segment
		(start 69.241416 -130.657092)
		(end 71.19239 -128.705864)
		(width 0.127)
		(layer "In2.Cu")
		(net "EXP_XM_ADDR_11")
	)
	(segment
		(start 94.313756 -100.394008)
		(end 95.664274 -99.04349)
		(width 0.127)
		(layer "In2.Cu")
		(net "EXP_XM_ADDR_11")
	)
	(segment
		(start 74.607674 -115.456208)
		(end 75.050142 -115.898676)
		(width 0.127)
		(layer "In2.Cu")
		(net "EXP_XM_ADDR_11")
	)
	(segment
		(start 73.888854 -116.175028)
		(end 74.331322 -116.617496)
		(width 0.127)
		(layer "In2.Cu")
		(net "EXP_XM_ADDR_11")
	)
	(segment
		(start 95.664274 -99.04349)
		(end 95.664274 -98.745548)
		(width 0.127)
		(layer "In2.Cu")
		(net "EXP_XM_ADDR_11")
	)
	(segment
		(start 73.971912 -116.976906)
		(end 73.529444 -116.534438)
		(width 0.127)
		(layer "In2.Cu")
		(net "EXP_XM_ADDR_11")
	)
	(segment
		(start 73.709022 -116.175028)
		(end 73.888854 -116.175028)
		(width 0.127)
		(layer "In2.Cu")
		(net "EXP_XM_ADDR_11")
	)
	(segment
		(start 77.776324 -112.287558)
		(end 78.218792 -112.730026)
		(width 0.127)
		(layer "In2.Cu")
		(net "EXP_XM_ADDR_11")
	)
	(segment
		(start 73.971912 -117.156738)
		(end 73.971912 -116.976906)
		(width 0.127)
		(layer "In2.Cu")
		(net "EXP_XM_ADDR_11")
	)
	(segment
		(start 68.73367 -135.8773)
		(end 68.73367 -134.795768)
		(width 0.127)
		(layer "In2.Cu")
		(net "EXP_XM_ADDR_11")
	)
	(segment
		(start 68.733416 -134.480046)
		(end 68.73367 -134.479792)
		(width 0.127)
		(layer "In2.Cu")
		(net "EXP_XM_ADDR_11")
	)
	(segment
		(start 71.815452 -119.133366)
		(end 71.372984 -118.690898)
		(width 0.127)
		(layer "In2.Cu")
		(net "EXP_XM_ADDR_11")
	)
	(segment
		(start 68.46697 -136.144)
		(end 68.73367 -135.8773)
		(width 0.127)
		(layer "In2.Cu")
		(net "EXP_XM_ADDR_11")
	)
	(segment
		(start 88.08593 -103.41356)
		(end 91.105482 -100.394008)
		(width 0.127)
		(layer "In2.Cu")
		(net "EXP_XM_ADDR_11")
	)
	(segment
		(start 68.733416 -134.795514)
		(end 68.733416 -134.480046)
		(width 0.127)
		(layer "In2.Cu")
		(net "EXP_XM_ADDR_11")
	)
	(segment
		(start 69.130418 -130.768344)
		(end 69.241416 -130.657092)
		(width 0.127)
		(layer "In2.Cu")
		(net "EXP_XM_ADDR_11")
	)
	(segment
		(start 71.372984 -118.690898)
		(end 71.372984 -118.511066)
		(width 0.127)
		(layer "In2.Cu")
		(net "EXP_XM_ADDR_11")
	)
	(segment
		(start 75.409552 -115.719098)
		(end 75.409552 -115.539266)
		(width 0.127)
		(layer "In2.Cu")
		(net "EXP_XM_ADDR_11")
	)
	(segment
		(start 72.893682 -118.055136)
		(end 73.073514 -118.055136)
		(width 0.127)
		(layer "In2.Cu")
		(net "EXP_XM_ADDR_11")
	)
	(segment
		(start 68.73367 -134.479792)
		(end 68.73367 -133.207252)
		(width 0.127)
		(layer "In2.Cu")
		(net "EXP_XM_ADDR_11")
	)
	(segment
		(start 105.430574 -95.431102)
		(end 105.849674 -95.850202)
		(width 0.127)
		(layer "In2.Cu")
		(net "EXP_XM_ADDR_11")
	)
	(segment
		(start 74.248264 -115.635786)
		(end 74.427842 -115.456208)
		(width 0.127)
		(layer "In2.Cu")
		(net "EXP_XM_ADDR_11")
	)
	(segment
		(start 72.354694 -118.773956)
		(end 72.534272 -118.594378)
		(width 0.127)
		(layer "In2.Cu")
		(net "EXP_XM_ADDR_11")
	)
	(segment
		(start 97.252028 -97.157794)
		(end 101.470206 -97.157794)
		(width 0.127)
		(layer "In2.Cu")
		(net "EXP_XM_ADDR_11")
	)
	(segment
		(start 101.470206 -97.157794)
		(end 103.196898 -95.431102)
		(width 0.127)
		(layer "In2.Cu")
		(net "EXP_XM_ADDR_11")
	)
	(segment
		(start 74.690732 -116.258086)
		(end 74.248264 -115.815618)
		(width 0.127)
		(layer "In2.Cu")
		(net "EXP_XM_ADDR_11")
	)
	(segment
		(start 79.067152 -110.81639)
		(end 79.06766 -110.81639)
		(width 0.127)
		(layer "In2.Cu")
		(net "EXP_XM_ADDR_11")
	)
	(segment
		(start 73.612502 -117.336316)
		(end 73.792334 -117.336316)
		(width 0.127)
		(layer "In2.Cu")
		(net "EXP_XM_ADDR_11")
	)
	(segment
		(start 74.511154 -116.617496)
		(end 74.690732 -116.437918)
		(width 0.127)
		(layer "In2.Cu")
		(net "EXP_XM_ADDR_11")
	)
	(segment
		(start 75.948794 -115.179856)
		(end 77.859382 -113.269268)
		(width 0.127)
		(layer "In2.Cu")
		(net "EXP_XM_ADDR_11")
	)
	(segment
		(start 73.073514 -118.055136)
		(end 73.253092 -117.875558)
		(width 0.127)
		(layer "In2.Cu")
		(net "EXP_XM_ADDR_11")
	)
	(segment
		(start 72.810624 -117.073426)
		(end 72.990202 -116.893848)
		(width 0.127)
		(layer "In2.Cu")
		(net "EXP_XM_ADDR_11")
	)
	(segment
		(start 78.224126 -111.888016)
		(end 78.224126 -111.659416)
		(width 0.127)
		(layer "In2.Cu")
		(net "EXP_XM_ADDR_11")
	)
	(segment
		(start 68.73367 -134.795768)
		(end 68.733416 -134.795514)
		(width 0.127)
		(layer "In2.Cu")
		(net "EXP_XM_ADDR_11")
	)
	(segment
		(start 74.690732 -116.437918)
		(end 74.690732 -116.258086)
		(width 0.127)
		(layer "In2.Cu")
		(net "EXP_XM_ADDR_11")
	)
	(segment
		(start 73.529444 -116.354606)
		(end 73.709022 -116.175028)
		(width 0.127)
		(layer "In2.Cu")
		(net "EXP_XM_ADDR_11")
	)
	(segment
		(start 71.372984 -118.511066)
		(end 71.552562 -118.331488)
		(width 0.127)
		(layer "In2.Cu")
		(net "EXP_XM_ADDR_11")
	)
	(segment
		(start 72.174862 -118.773956)
		(end 72.354694 -118.773956)
		(width 0.127)
		(layer "In2.Cu")
		(net "EXP_XM_ADDR_11")
	)
	(segment
		(start 77.596492 -112.287558)
		(end 77.776324 -112.287558)
		(width 0.127)
		(layer "In2.Cu")
		(net "EXP_XM_ADDR_11")
	)
	(segment
		(start 75.146662 -114.737388)
		(end 75.326494 -114.737388)
		(width 0.127)
		(layer "In2.Cu")
		(net "EXP_XM_ADDR_11")
	)
	(segment
		(start 78.398624 -112.730026)
		(end 78.63586 -112.49279)
		(width 0.127)
		(layer "In2.Cu")
		(net "EXP_XM_ADDR_11")
	)
	(segment
		(start 74.248264 -115.815618)
		(end 74.248264 -115.635786)
		(width 0.127)
		(layer "In2.Cu")
		(net "EXP_XM_ADDR_11")
	)
	(segment
		(start 82.24393 -107.64012)
		(end 85.92439 -107.64012)
		(width 0.127)
		(layer "In2.Cu")
		(net "EXP_XM_ADDR_11")
	)
	(segment
		(start 73.529444 -116.534438)
		(end 73.529444 -116.354606)
		(width 0.127)
		(layer "In2.Cu")
		(net "EXP_XM_ADDR_11")
	)
	(segment
		(start 72.451214 -117.612668)
		(end 72.893682 -118.055136)
		(width 0.127)
		(layer "In2.Cu")
		(net "EXP_XM_ADDR_11")
	)
	(segment
		(start 73.170034 -116.893848)
		(end 73.612502 -117.336316)
		(width 0.127)
		(layer "In2.Cu")
		(net "EXP_XM_ADDR_11")
	)
	(segment
		(start 74.967084 -115.096798)
		(end 74.967084 -114.916966)
		(width 0.127)
		(layer "In2.Cu")
		(net "EXP_XM_ADDR_11")
	)
	(segment
		(start 68.73367 -133.207252)
		(end 68.93687 -133.004052)
		(width 0.127)
		(layer "In2.Cu")
		(net "EXP_XM_ADDR_11")
	)
	(segment
		(start 75.050142 -115.898676)
		(end 75.229974 -115.898676)
		(width 0.127)
		(layer "In2.Cu")
		(net "EXP_XM_ADDR_11")
	)
	(segment
		(start 74.331322 -116.617496)
		(end 74.511154 -116.617496)
		(width 0.127)
		(layer "In2.Cu")
		(net "EXP_XM_ADDR_11")
	)
	(segment
		(start 103.196898 -95.431102)
		(end 105.430574 -95.431102)
		(width 0.127)
		(layer "In2.Cu")
		(net "EXP_XM_ADDR_11")
	)
	(segment
		(start 77.416914 -112.646968)
		(end 77.416914 -112.467136)
		(width 0.127)
		(layer "In2.Cu")
		(net "EXP_XM_ADDR_11")
	)
	(segment
		(start 75.326494 -114.737388)
		(end 75.768962 -115.179856)
		(width 0.127)
		(layer "In2.Cu")
		(net "EXP_XM_ADDR_11")
	)
	(segment
		(start 74.427842 -115.456208)
		(end 74.607674 -115.456208)
		(width 0.127)
		(layer "In2.Cu")
		(net "EXP_XM_ADDR_11")
	)
	(segment
		(start 78.224126 -111.659416)
		(end 79.067152 -110.81639)
		(width 0.127)
		(layer "In2.Cu")
		(net "EXP_XM_ADDR_11")
	)
	(segment
		(start 88.08593 -105.47858)
		(end 88.08593 -103.41356)
		(width 0.127)
		(layer "In2.Cu")
		(net "EXP_XM_ADDR_11")
	)
	(segment
		(start 71.19239 -119.93626)
		(end 71.815452 -119.313198)
		(width 0.127)
		(layer "In2.Cu")
		(net "EXP_XM_ADDR_11")
	)
	(segment
		(start 95.664274 -98.745548)
		(end 97.252028 -97.157794)
		(width 0.127)
		(layer "In2.Cu")
		(net "EXP_XM_ADDR_11")
	)
	(segment
		(start 72.534272 -118.594378)
		(end 72.534272 -118.414546)
		(width 0.127)
		(layer "In2.Cu")
		(net "EXP_XM_ADDR_11")
	)
	(segment
		(start 72.091804 -117.972078)
		(end 72.091804 -117.792246)
		(width 0.127)
		(layer "In2.Cu")
		(net "EXP_XM_ADDR_11")
	)
	(segment
		(start 72.534272 -118.414546)
		(end 72.091804 -117.972078)
		(width 0.127)
		(layer "In2.Cu")
		(net "EXP_XM_ADDR_11")
	)
	(segment
		(start 71.815452 -119.313198)
		(end 71.815452 -119.133366)
		(width 0.127)
		(layer "In2.Cu")
		(net "EXP_XM_ADDR_11")
	)
	(segment
		(start 72.810624 -117.253258)
		(end 72.810624 -117.073426)
		(width 0.127)
		(layer "In2.Cu")
		(net "EXP_XM_ADDR_11")
	)
	(segment
		(start 91.105482 -100.394008)
		(end 94.313756 -100.394008)
		(width 0.127)
		(layer "In2.Cu")
		(net "EXP_XM_ADDR_11")
	)
	(segment
		(start 72.990202 -116.893848)
		(end 73.170034 -116.893848)
		(width 0.127)
		(layer "In2.Cu")
		(net "EXP_XM_ADDR_11")
	)
	(segment
		(start 71.19239 -128.705864)
		(end 71.19239 -119.93626)
		(width 0.127)
		(layer "In2.Cu")
		(net "EXP_XM_ADDR_11")
	)
	(segment
		(start 74.967084 -114.916966)
		(end 75.146662 -114.737388)
		(width 0.127)
		(layer "In2.Cu")
		(net "EXP_XM_ADDR_11")
	)
	(segment
		(start 71.732394 -118.331488)
		(end 72.174862 -118.773956)
		(width 0.127)
		(layer "In2.Cu")
		(net "EXP_XM_ADDR_11")
	)
	(segment
		(start 85.92439 -107.64012)
		(end 88.08593 -105.47858)
		(width 0.127)
		(layer "In2.Cu")
		(net "EXP_XM_ADDR_11")
	)
	(segment
		(start 75.229974 -115.898676)
		(end 75.409552 -115.719098)
		(width 0.127)
		(layer "In2.Cu")
		(net "EXP_XM_ADDR_11")
	)
	(segment
		(start 68.93687 -130.961892)
		(end 69.130418 -130.768344)
		(width 0.127)
		(layer "In2.Cu")
		(net "EXP_XM_ADDR_11")
	)
	(segment
		(start 77.859382 -113.089436)
		(end 77.416914 -112.646968)
		(width 0.127)
		(layer "In2.Cu")
		(net "EXP_XM_ADDR_11")
	)
	(segment
		(start 77.859382 -113.269268)
		(end 77.859382 -113.089436)
		(width 0.127)
		(layer "In2.Cu")
		(net "EXP_XM_ADDR_11")
	)
	(segment
		(start 118.23192 -113.542572)
		(end 118.23192 -113.105946)
		(width 0.1016)
		(layer "F.Cu")
		(net "SAS_HDD_TX2_P")
	)
	(segment
		(start 116.197634 -106.502454)
		(end 116.350034 -106.350054)
		(width 0.1016)
		(layer "F.Cu")
		(net "SAS_HDD_TX2_P")
	)
	(segment
		(start 115.96624 -109.571282)
		(end 115.96624 -107.061)
		(width 0.1016)
		(layer "F.Cu")
		(net "SAS_HDD_TX2_P")
	)
	(segment
		(start 118.37797 -114.0206)
		(end 118.37797 -113.895378)
		(width 0.1016)
		(layer "F.Cu")
		(net "SAS_HDD_TX2_P")
	)
	(segment
		(start 117.61089 -111.60633)
		(end 116.242338 -110.237778)
		(width 0.1016)
		(layer "F.Cu")
		(net "SAS_HDD_TX2_P")
	)
	(arc
		(start 116.242338 -110.237778)
		(mid 116.077274 -110.015286)
		(end 115.98402 -109.754416)
		(width 0.1016)
		(layer "F.Cu")
		(net "SAS_HDD_TX2_P")
	)
	(arc
		(start 115.96624 -107.061)
		(mid 115.998435 -106.837524)
		(end 116.092478 -106.632248)
		(width 0.1016)
		(layer "F.Cu")
		(net "SAS_HDD_TX2_P")
	)
	(arc
		(start 118.37797 -113.895378)
		(mid 118.358964 -113.799829)
		(end 118.304818 -113.718848)
		(width 0.1016)
		(layer "F.Cu")
		(net "SAS_HDD_TX2_P")
	)
	(arc
		(start 115.98402 -109.754416)
		(mid 115.97066 -109.663283)
		(end 115.96624 -109.571282)
		(width 0.1016)
		(layer "F.Cu")
		(net "SAS_HDD_TX2_P")
	)
	(arc
		(start 118.304818 -113.718848)
		(mid 118.250886 -113.637943)
		(end 118.23192 -113.542572)
		(width 0.1016)
		(layer "F.Cu")
		(net "SAS_HDD_TX2_P")
	)
	(arc
		(start 116.092478 -106.632248)
		(mid 116.14161 -106.564559)
		(end 116.197634 -106.502454)
		(width 0.1016)
		(layer "F.Cu")
		(net "SAS_HDD_TX2_P")
	)
	(arc
		(start 118.23192 -113.105946)
		(mid 118.070525 -112.294381)
		(end 117.61089 -111.60633)
		(width 0.1016)
		(layer "F.Cu")
		(net "SAS_HDD_TX2_P")
	)
	(segment
		(start 94.387924 -55.578248)
		(end 94.750128 -55.216044)
		(width 0.1143)
		(layer "F.Cu")
		(net "ICE1_TRST#")
	)
	(segment
		(start 92.691966 -58.674)
		(end 94.387924 -56.978042)
		(width 0.1143)
		(layer "F.Cu")
		(net "ICE1_TRST#")
	)
	(segment
		(start 90.786966 -60.325)
		(end 90.786966 -59.708034)
		(width 0.1143)
		(layer "F.Cu")
		(net "ICE1_TRST#")
	)
	(segment
		(start 90.786966 -62.6745)
		(end 90.786966 -60.325)
		(width 0.1143)
		(layer "F.Cu")
		(net "ICE1_TRST#")
	)
	(segment
		(start 90.786966 -59.708034)
		(end 91.821 -58.674)
		(width 0.1143)
		(layer "F.Cu")
		(net "ICE1_TRST#")
	)
	(segment
		(start 94.387924 -56.978042)
		(end 94.387924 -55.578248)
		(width 0.1143)
		(layer "F.Cu")
		(net "ICE1_TRST#")
	)
	(segment
		(start 94.750128 -55.216044)
		(end 94.750128 -54.99989)
		(width 0.1143)
		(layer "F.Cu")
		(net "ICE1_TRST#")
	)
	(segment
		(start 91.821 -58.674)
		(end 92.691966 -58.674)
		(width 0.1143)
		(layer "F.Cu")
		(net "ICE1_TRST#")
	)
	(segment
		(start 195.2625 -169.672)
		(end 195.04025 -169.44975)
		(width 0.127)
		(layer "F.Cu")
		(net "P3V3_STBY_B1")
	)
	(segment
		(start 194.183 -169.672)
		(end 195.2625 -169.672)
		(width 0.127)
		(layer "F.Cu")
		(net "P3V3_STBY_B1")
	)
	(segment
		(start 195.04025 -169.44975)
		(end 195.04025 -167.8305)
		(width 0.127)
		(layer "F.Cu")
		(net "P3V3_STBY_B1")
	)
	(via
		(at 194.183 -169.672)
		(size 0.7112)
		(drill 0.3556)
		(layers "F.Cu" "B.Cu")
		(net "P3V3_STBY_B1")
	)
	(segment
		(start 57.798716 -132.375402)
		(end 57.913016 -132.261102)
		(width 0.1143)
		(layer "F.Cu")
		(net "EXP_XM_ADDR_22")
	)
	(segment
		(start 63.263018 -133.8072)
		(end 63.377318 -133.9215)
		(width 0.1143)
		(layer "F.Cu")
		(net "EXP_XM_ADDR_22")
	)
	(segment
		(start 64.317118 -133.8072)
		(end 64.431418 -133.9215)
		(width 0.1143)
		(layer "F.Cu")
		(net "EXP_XM_ADDR_22")
	)
	(segment
		(start 61.891418 -133.8072)
		(end 61.891418 -132.991098)
		(width 0.1143)
		(layer "F.Cu")
		(net "EXP_XM_ADDR_22")
	)
	(segment
		(start 63.859918 -133.5913)
		(end 63.974218 -133.477)
		(width 0.1143)
		(layer "F.Cu")
		(net "EXP_XM_ADDR_22")
	)
	(segment
		(start 66.53657 -132.53974)
		(end 66.37401 -132.37718)
		(width 0.1143)
		(layer "F.Cu")
		(net "EXP_XM_ADDR_22")
	)
	(segment
		(start 56.558942 -132.892292)
		(end 57.233566 -132.892292)
		(width 0.1143)
		(layer "F.Cu")
		(net "EXP_XM_ADDR_22")
	)
	(segment
		(start 62.691518 -133.9215)
		(end 62.805818 -133.8072)
		(width 0.1143)
		(layer "F.Cu")
		(net "EXP_XM_ADDR_22")
	)
	(segment
		(start 103.349806 -93.349826)
		(end 102.928928 -92.928948)
		(width 0.1143)
		(layer "F.Cu")
		(net "EXP_XM_ADDR_22")
	)
	(segment
		(start 59.056016 -132.261102)
		(end 59.170316 -132.375402)
		(width 0.1143)
		(layer "F.Cu")
		(net "EXP_XM_ADDR_22")
	)
	(segment
		(start 62.005718 -132.876798)
		(end 62.234318 -132.876798)
		(width 0.1143)
		(layer "F.Cu")
		(net "EXP_XM_ADDR_22")
	)
	(segment
		(start 58.713116 -132.695442)
		(end 58.713116 -132.375402)
		(width 0.1143)
		(layer "F.Cu")
		(net "EXP_XM_ADDR_22")
	)
	(segment
		(start 60.405518 -132.876798)
		(end 60.519818 -132.991098)
		(width 0.1143)
		(layer "F.Cu")
		(net "EXP_XM_ADDR_22")
	)
	(segment
		(start 63.377318 -133.9215)
		(end 63.745618 -133.9215)
		(width 0.1143)
		(layer "F.Cu")
		(net "EXP_XM_ADDR_22")
	)
	(segment
		(start 100.87737 -92.6338)
		(end 100.87737 -92.500704)
		(width 0.1143)
		(layer "F.Cu")
		(net "EXP_XM_ADDR_22")
	)
	(segment
		(start 60.519818 -132.991098)
		(end 60.519818 -133.858)
		(width 0.1143)
		(layer "F.Cu")
		(net "EXP_XM_ADDR_22")
	)
	(segment
		(start 58.255916 -132.695442)
		(end 58.370216 -132.809742)
		(width 0.1143)
		(layer "F.Cu")
		(net "EXP_XM_ADDR_22")
	)
	(segment
		(start 66.53657 -132.81406)
		(end 66.53657 -132.53974)
		(width 0.1143)
		(layer "F.Cu")
		(net "EXP_XM_ADDR_22")
	)
	(segment
		(start 62.920118 -132.876798)
		(end 63.148718 -132.876798)
		(width 0.1143)
		(layer "F.Cu")
		(net "EXP_XM_ADDR_22")
	)
	(segment
		(start 100.87737 -92.500704)
		(end 100.867718 -92.491052)
		(width 0.1143)
		(layer "F.Cu")
		(net "EXP_XM_ADDR_22")
	)
	(segment
		(start 62.805818 -133.8072)
		(end 62.805818 -132.991098)
		(width 0.1143)
		(layer "F.Cu")
		(net "EXP_XM_ADDR_22")
	)
	(segment
		(start 63.745618 -133.9215)
		(end 63.859918 -133.8072)
		(width 0.1143)
		(layer "F.Cu")
		(net "EXP_XM_ADDR_22")
	)
	(segment
		(start 57.316116 -132.809742)
		(end 57.684416 -132.809742)
		(width 0.1143)
		(layer "F.Cu")
		(net "EXP_XM_ADDR_22")
	)
	(segment
		(start 58.713116 -132.375402)
		(end 58.827416 -132.261102)
		(width 0.1143)
		(layer "F.Cu")
		(net "EXP_XM_ADDR_22")
	)
	(segment
		(start 63.263018 -132.991098)
		(end 63.263018 -133.8072)
		(width 0.1143)
		(layer "F.Cu")
		(net "EXP_XM_ADDR_22")
	)
	(segment
		(start 60.977018 -132.991098)
		(end 61.091318 -132.876798)
		(width 0.1143)
		(layer "F.Cu")
		(net "EXP_XM_ADDR_22")
	)
	(segment
		(start 61.434218 -132.991098)
		(end 61.434218 -133.8072)
		(width 0.1143)
		(layer "F.Cu")
		(net "EXP_XM_ADDR_22")
	)
	(segment
		(start 61.891418 -132.991098)
		(end 62.005718 -132.876798)
		(width 0.1143)
		(layer "F.Cu")
		(net "EXP_XM_ADDR_22")
	)
	(segment
		(start 59.170316 -132.695442)
		(end 59.351672 -132.876798)
		(width 0.1143)
		(layer "F.Cu")
		(net "EXP_XM_ADDR_22")
	)
	(segment
		(start 66.38925 -132.96138)
		(end 66.53657 -132.81406)
		(width 0.1143)
		(layer "F.Cu")
		(net "EXP_XM_ADDR_22")
	)
	(segment
		(start 101.172518 -92.928948)
		(end 100.87737 -92.6338)
		(width 0.1143)
		(layer "F.Cu")
		(net "EXP_XM_ADDR_22")
	)
	(segment
		(start 63.974218 -133.477)
		(end 64.202818 -133.477)
		(width 0.1143)
		(layer "F.Cu")
		(net "EXP_XM_ADDR_22")
	)
	(segment
		(start 102.928928 -92.928948)
		(end 101.172518 -92.928948)
		(width 0.1143)
		(layer "F.Cu")
		(net "EXP_XM_ADDR_22")
	)
	(segment
		(start 58.598816 -132.809742)
		(end 58.713116 -132.695442)
		(width 0.1143)
		(layer "F.Cu")
		(net "EXP_XM_ADDR_22")
	)
	(segment
		(start 64.431418 -133.9215)
		(end 65.01257 -133.9215)
		(width 0.1143)
		(layer "F.Cu")
		(net "EXP_XM_ADDR_22")
	)
	(segment
		(start 59.351672 -132.876798)
		(end 60.405518 -132.876798)
		(width 0.1143)
		(layer "F.Cu")
		(net "EXP_XM_ADDR_22")
	)
	(segment
		(start 61.777118 -133.9215)
		(end 61.891418 -133.8072)
		(width 0.1143)
		(layer "F.Cu")
		(net "EXP_XM_ADDR_22")
	)
	(segment
		(start 57.798716 -132.695442)
		(end 57.798716 -132.375402)
		(width 0.1143)
		(layer "F.Cu")
		(net "EXP_XM_ADDR_22")
	)
	(segment
		(start 60.977018 -133.858)
		(end 60.977018 -132.991098)
		(width 0.1143)
		(layer "F.Cu")
		(net "EXP_XM_ADDR_22")
	)
	(segment
		(start 58.255916 -132.375402)
		(end 58.255916 -132.695442)
		(width 0.1143)
		(layer "F.Cu")
		(net "EXP_XM_ADDR_22")
	)
	(segment
		(start 62.462918 -133.9215)
		(end 62.691518 -133.9215)
		(width 0.1143)
		(layer "F.Cu")
		(net "EXP_XM_ADDR_22")
	)
	(segment
		(start 61.548518 -133.9215)
		(end 61.777118 -133.9215)
		(width 0.1143)
		(layer "F.Cu")
		(net "EXP_XM_ADDR_22")
	)
	(segment
		(start 59.170316 -132.375402)
		(end 59.170316 -132.695442)
		(width 0.1143)
		(layer "F.Cu")
		(net "EXP_XM_ADDR_22")
	)
	(segment
		(start 62.234318 -132.876798)
		(end 62.348618 -132.991098)
		(width 0.1143)
		(layer "F.Cu")
		(net "EXP_XM_ADDR_22")
	)
	(segment
		(start 62.348618 -132.991098)
		(end 62.348618 -133.8072)
		(width 0.1143)
		(layer "F.Cu")
		(net "EXP_XM_ADDR_22")
	)
	(segment
		(start 57.684416 -132.809742)
		(end 57.798716 -132.695442)
		(width 0.1143)
		(layer "F.Cu")
		(net "EXP_XM_ADDR_22")
	)
	(segment
		(start 60.646818 -133.985)
		(end 60.850018 -133.985)
		(width 0.1143)
		(layer "F.Cu")
		(net "EXP_XM_ADDR_22")
	)
	(segment
		(start 64.202818 -133.477)
		(end 64.317118 -133.5913)
		(width 0.1143)
		(layer "F.Cu")
		(net "EXP_XM_ADDR_22")
	)
	(segment
		(start 58.141616 -132.261102)
		(end 58.255916 -132.375402)
		(width 0.1143)
		(layer "F.Cu")
		(net "EXP_XM_ADDR_22")
	)
	(segment
		(start 63.148718 -132.876798)
		(end 63.263018 -132.991098)
		(width 0.1143)
		(layer "F.Cu")
		(net "EXP_XM_ADDR_22")
	)
	(segment
		(start 64.934084 -132.37718)
		(end 64.434466 -132.876798)
		(width 0.1143)
		(layer "F.Cu")
		(net "EXP_XM_ADDR_22")
	)
	(segment
		(start 62.348618 -133.8072)
		(end 62.462918 -133.9215)
		(width 0.1143)
		(layer "F.Cu")
		(net "EXP_XM_ADDR_22")
	)
	(segment
		(start 61.091318 -132.876798)
		(end 61.319918 -132.876798)
		(width 0.1143)
		(layer "F.Cu")
		(net "EXP_XM_ADDR_22")
	)
	(segment
		(start 58.370216 -132.809742)
		(end 58.598816 -132.809742)
		(width 0.1143)
		(layer "F.Cu")
		(net "EXP_XM_ADDR_22")
	)
	(segment
		(start 60.850018 -133.985)
		(end 60.977018 -133.858)
		(width 0.1143)
		(layer "F.Cu")
		(net "EXP_XM_ADDR_22")
	)
	(segment
		(start 63.859918 -133.8072)
		(end 63.859918 -133.5913)
		(width 0.1143)
		(layer "F.Cu")
		(net "EXP_XM_ADDR_22")
	)
	(segment
		(start 60.519818 -133.858)
		(end 60.646818 -133.985)
		(width 0.1143)
		(layer "F.Cu")
		(net "EXP_XM_ADDR_22")
	)
	(segment
		(start 57.233566 -132.892292)
		(end 57.316116 -132.809742)
		(width 0.1143)
		(layer "F.Cu")
		(net "EXP_XM_ADDR_22")
	)
	(segment
		(start 64.317118 -133.5913)
		(end 64.317118 -133.8072)
		(width 0.1143)
		(layer "F.Cu")
		(net "EXP_XM_ADDR_22")
	)
	(segment
		(start 61.434218 -133.8072)
		(end 61.548518 -133.9215)
		(width 0.1143)
		(layer "F.Cu")
		(net "EXP_XM_ADDR_22")
	)
	(segment
		(start 62.805818 -132.991098)
		(end 62.920118 -132.876798)
		(width 0.1143)
		(layer "F.Cu")
		(net "EXP_XM_ADDR_22")
	)
	(segment
		(start 65.97269 -132.96138)
		(end 66.38925 -132.96138)
		(width 0.1143)
		(layer "F.Cu")
		(net "EXP_XM_ADDR_22")
	)
	(segment
		(start 61.319918 -132.876798)
		(end 61.434218 -132.991098)
		(width 0.1143)
		(layer "F.Cu")
		(net "EXP_XM_ADDR_22")
	)
	(segment
		(start 57.913016 -132.261102)
		(end 58.141616 -132.261102)
		(width 0.1143)
		(layer "F.Cu")
		(net "EXP_XM_ADDR_22")
	)
	(segment
		(start 58.827416 -132.261102)
		(end 59.056016 -132.261102)
		(width 0.1143)
		(layer "F.Cu")
		(net "EXP_XM_ADDR_22")
	)
	(segment
		(start 65.01257 -133.9215)
		(end 65.97269 -132.96138)
		(width 0.1143)
		(layer "F.Cu")
		(net "EXP_XM_ADDR_22")
	)
	(segment
		(start 66.37401 -132.37718)
		(end 64.934084 -132.37718)
		(width 0.1143)
		(layer "F.Cu")
		(net "EXP_XM_ADDR_22")
	)
	(via
		(at 100.867718 -92.491052)
		(size 0.508)
		(drill 0.254)
		(layers "F.Cu" "B.Cu")
		(net "EXP_XM_ADDR_22")
	)
	(via
		(at 64.434466 -132.089398)
		(size 0.7112)
		(drill 0.3556)
		(layers "F.Cu" "B.Cu")
		(net "EXP_XM_ADDR_22")
	)
	(via
		(at 64.434466 -132.876798)
		(size 0.5588)
		(drill 0.3048)
		(layers "F.Cu" "B.Cu")
		(net "EXP_XM_ADDR_22")
	)
	(segment
		(start 64.434466 -132.876798)
		(end 64.434466 -132.089398)
		(width 0.1143)
		(layer "B.Cu")
		(net "EXP_XM_ADDR_22")
	)
	(segment
		(start 98.85045 -92.380308)
		(end 100.756974 -92.380308)
		(width 0.127)
		(layer "In2.Cu")
		(net "EXP_XM_ADDR_22")
	)
	(segment
		(start 88.674448 -93.16974)
		(end 93.918278 -93.16974)
		(width 0.127)
		(layer "In2.Cu")
		(net "EXP_XM_ADDR_22")
	)
	(segment
		(start 79.92237 -104.011984)
		(end 79.92237 -101.921818)
		(width 0.127)
		(layer "In2.Cu")
		(net "EXP_XM_ADDR_22")
	)
	(segment
		(start 95.291402 -92.3671)
		(end 98.837242 -92.3671)
		(width 0.127)
		(layer "In2.Cu")
		(net "EXP_XM_ADDR_22")
	)
	(segment
		(start 94.707202 -92.9513)
		(end 95.291402 -92.3671)
		(width 0.127)
		(layer "In2.Cu")
		(net "EXP_XM_ADDR_22")
	)
	(segment
		(start 100.756974 -92.380308)
		(end 100.867718 -92.491052)
		(width 0.127)
		(layer "In2.Cu")
		(net "EXP_XM_ADDR_22")
	)
	(segment
		(start 64.434466 -126.099824)
		(end 64.69507 -125.83922)
		(width 0.127)
		(layer "In2.Cu")
		(net "EXP_XM_ADDR_22")
	)
	(segment
		(start 79.92237 -101.921818)
		(end 88.674448 -93.16974)
		(width 0.127)
		(layer "In2.Cu")
		(net "EXP_XM_ADDR_22")
	)
	(segment
		(start 98.837242 -92.3671)
		(end 98.85045 -92.380308)
		(width 0.127)
		(layer "In2.Cu")
		(net "EXP_XM_ADDR_22")
	)
	(segment
		(start 64.434466 -132.876798)
		(end 64.434466 -126.099824)
		(width 0.127)
		(layer "In2.Cu")
		(net "EXP_XM_ADDR_22")
	)
	(segment
		(start 64.69507 -119.239284)
		(end 79.92237 -104.011984)
		(width 0.127)
		(layer "In2.Cu")
		(net "EXP_XM_ADDR_22")
	)
	(segment
		(start 64.69507 -125.83922)
		(end 64.69507 -119.239284)
		(width 0.127)
		(layer "In2.Cu")
		(net "EXP_XM_ADDR_22")
	)
	(segment
		(start 93.918278 -93.16974)
		(end 94.136718 -92.9513)
		(width 0.127)
		(layer "In2.Cu")
		(net "EXP_XM_ADDR_22")
	)
	(segment
		(start 94.136718 -92.9513)
		(end 94.707202 -92.9513)
		(width 0.127)
		(layer "In2.Cu")
		(net "EXP_XM_ADDR_22")
	)
	(segment
		(start 115.943126 -45.847)
		(end 116.567966 -45.847)
		(width 0.1143)
		(layer "F.Cu")
		(net "SYS_CORE_TRI#")
	)
	(segment
		(start 115.765326 -46.0248)
		(end 115.943126 -45.847)
		(width 0.1143)
		(layer "F.Cu")
		(net "SYS_CORE_TRI#")
	)
	(segment
		(start 113.949988 -45.39996)
		(end 114.7953 -45.39996)
		(width 0.1143)
		(layer "F.Cu")
		(net "SYS_CORE_TRI#")
	)
	(segment
		(start 115.402106 -46.0248)
		(end 115.765326 -46.0248)
		(width 0.1143)
		(layer "F.Cu")
		(net "SYS_CORE_TRI#")
	)
	(segment
		(start 116.567966 -45.847)
		(end 117.520466 -45.847)
		(width 0.1143)
		(layer "F.Cu")
		(net "SYS_CORE_TRI#")
	)
	(segment
		(start 114.7953 -45.39996)
		(end 114.98834 -45.593)
		(width 0.1143)
		(layer "F.Cu")
		(net "SYS_CORE_TRI#")
	)
	(segment
		(start 114.98834 -45.593)
		(end 114.98834 -45.611034)
		(width 0.1143)
		(layer "F.Cu")
		(net "SYS_CORE_TRI#")
	)
	(segment
		(start 114.98834 -45.611034)
		(end 115.402106 -46.0248)
		(width 0.1143)
		(layer "F.Cu")
		(net "SYS_CORE_TRI#")
	)
	(via
		(at 116.567966 -45.847)
		(size 0.7112)
		(drill 0.3556)
		(layers "F.Cu" "B.Cu")
		(net "SYS_CORE_TRI#")
	)
	(segment
		(start 96.34347 -87.376)
		(end 98.01987 -87.376)
		(width 0.1143)
		(layer "F.Cu")
		(net "EXP_XM_WE_N")
	)
	(segment
		(start 56.558942 -133.893052)
		(end 59.48299 -133.893052)
		(width 0.1143)
		(layer "F.Cu")
		(net "EXP_XM_WE_N")
	)
	(segment
		(start 98.01987 -87.376)
		(end 99.45497 -85.9409)
		(width 0.1143)
		(layer "F.Cu")
		(net "EXP_XM_WE_N")
	)
	(segment
		(start 104.349804 -85.349842)
		(end 103.849678 -84.849716)
		(width 0.1143)
		(layer "F.Cu")
		(net "EXP_XM_WE_N")
	)
	(via
		(at 59.47537 -134.7978)
		(size 0.7112)
		(drill 0.3556)
		(layers "F.Cu" "B.Cu")
		(net "EXP_XM_WE_N")
	)
	(via
		(at 59.48299 -133.893052)
		(size 0.5588)
		(drill 0.3048)
		(layers "F.Cu" "B.Cu")
		(net "EXP_XM_WE_N")
	)
	(via
		(at 99.45497 -85.9409)
		(size 0.508)
		(drill 0.254)
		(layers "F.Cu" "B.Cu")
		(net "EXP_XM_WE_N")
	)
	(via
		(at 103.849678 -84.849716)
		(size 0.508)
		(drill 0.254)
		(layers "F.Cu" "B.Cu")
		(net "EXP_XM_WE_N")
	)
	(segment
		(start 59.47537 -134.7978)
		(end 59.47537 -133.900672)
		(width 0.1143)
		(layer "B.Cu")
		(net "EXP_XM_WE_N")
	)
	(segment
		(start 103.03129 -85.287866)
		(end 103.46944 -84.849716)
		(width 0.1143)
		(layer "B.Cu")
		(net "EXP_XM_WE_N")
	)
	(segment
		(start 100.426774 -85.43925)
		(end 100.75672 -85.43925)
		(width 0.1143)
		(layer "B.Cu")
		(net "EXP_XM_WE_N")
	)
	(segment
		(start 99.45497 -85.9409)
		(end 99.925124 -85.9409)
		(width 0.1143)
		(layer "B.Cu")
		(net "EXP_XM_WE_N")
	)
	(segment
		(start 103.46944 -84.849716)
		(end 103.849678 -84.849716)
		(width 0.1143)
		(layer "B.Cu")
		(net "EXP_XM_WE_N")
	)
	(segment
		(start 100.908104 -85.287866)
		(end 103.03129 -85.287866)
		(width 0.1143)
		(layer "B.Cu")
		(net "EXP_XM_WE_N")
	)
	(segment
		(start 99.925124 -85.9409)
		(end 100.426774 -85.43925)
		(width 0.1143)
		(layer "B.Cu")
		(net "EXP_XM_WE_N")
	)
	(segment
		(start 100.75672 -85.43925)
		(end 100.908104 -85.287866)
		(width 0.1143)
		(layer "B.Cu")
		(net "EXP_XM_WE_N")
	)
	(segment
		(start 59.47537 -133.900672)
		(end 59.48299 -133.893052)
		(width 0.1143)
		(layer "B.Cu")
		(net "EXP_XM_WE_N")
	)
	(segment
		(start 73.049892 -100.801678)
		(end 72.869806 -100.981764)
		(width 0.127)
		(layer "In2.Cu")
		(net "EXP_XM_WE_N")
	)
	(segment
		(start 74.502264 -101.35616)
		(end 74.502264 -101.535484)
		(width 0.127)
		(layer "In2.Cu")
		(net "EXP_XM_WE_N")
	)
	(segment
		(start 58.86577 -128.3462)
		(end 58.86577 -129.5908)
		(width 0.127)
		(layer "In2.Cu")
		(net "EXP_XM_WE_N")
	)
	(segment
		(start 76.02347 -99.72548)
		(end 76.02347 -100.014278)
		(width 0.127)
		(layer "In2.Cu")
		(net "EXP_XM_WE_N")
	)
	(segment
		(start 74.322178 -101.71557)
		(end 74.142854 -101.71557)
		(width 0.127)
		(layer "In2.Cu")
		(net "EXP_XM_WE_N")
	)
	(segment
		(start 73.768712 -100.082858)
		(end 73.588626 -100.262944)
		(width 0.127)
		(layer "In2.Cu")
		(net "EXP_XM_WE_N")
	)
	(segment
		(start 59.24677 -129.9718)
		(end 59.24677 -132.226304)
		(width 0.127)
		(layer "In2.Cu")
		(net "EXP_XM_WE_N")
	)
	(segment
		(start 82.587592 -93.450156)
		(end 79.725774 -93.450156)
		(width 0.127)
		(layer "In2.Cu")
		(net "EXP_XM_WE_N")
	)
	(segment
		(start 85.417152 -91.037156)
		(end 85.000592 -91.037156)
		(width 0.127)
		(layer "In2.Cu")
		(net "EXP_XM_WE_N")
	)
	(segment
		(start 79.725774 -93.450156)
		(end 75.0443 -98.13163)
		(width 0.127)
		(layer "In2.Cu")
		(net "EXP_XM_WE_N")
	)
	(segment
		(start 59.43981 -127.77216)
		(end 58.86577 -128.3462)
		(width 0.127)
		(layer "In2.Cu")
		(net "EXP_XM_WE_N")
	)
	(segment
		(start 59.24677 -132.226304)
		(end 59.44997 -132.429504)
		(width 0.127)
		(layer "In2.Cu")
		(net "EXP_XM_WE_N")
	)
	(segment
		(start 75.0443 -98.13163)
		(end 75.0443 -98.74631)
		(width 0.127)
		(layer "In2.Cu")
		(net "EXP_XM_WE_N")
	)
	(segment
		(start 88.0618 -88.392508)
		(end 85.417152 -91.037156)
		(width 0.127)
		(layer "In2.Cu")
		(net "EXP_XM_WE_N")
	)
	(segment
		(start 74.861674 -100.99675)
		(end 73.948036 -100.082858)
		(width 0.127)
		(layer "In2.Cu")
		(net "EXP_XM_WE_N")
	)
	(segment
		(start 99.45497 -85.9409)
		(end 98.90887 -86.487)
		(width 0.127)
		(layer "In2.Cu")
		(net "EXP_XM_WE_N")
	)
	(segment
		(start 73.064624 -102.973124)
		(end 59.43981 -116.597684)
		(width 0.127)
		(layer "In2.Cu")
		(net "EXP_XM_WE_N")
	)
	(segment
		(start 59.44997 -133.778752)
		(end 59.48299 -133.811772)
		(width 0.127)
		(layer "In2.Cu")
		(net "EXP_XM_WE_N")
	)
	(segment
		(start 73.064624 -102.7938)
		(end 73.064624 -102.973124)
		(width 0.127)
		(layer "In2.Cu")
		(net "EXP_XM_WE_N")
	)
	(segment
		(start 76.02347 -100.014278)
		(end 75.040998 -100.99675)
		(width 0.127)
		(layer "In2.Cu")
		(net "EXP_XM_WE_N")
	)
	(segment
		(start 73.783444 -102.254304)
		(end 73.603358 -102.43439)
		(width 0.127)
		(layer "In2.Cu")
		(net "EXP_XM_WE_N")
	)
	(segment
		(start 98.90887 -86.487)
		(end 90.616024 -86.487)
		(width 0.127)
		(layer "In2.Cu")
		(net "EXP_XM_WE_N")
	)
	(segment
		(start 75.040998 -100.99675)
		(end 74.861674 -100.99675)
		(width 0.127)
		(layer "In2.Cu")
		(net "EXP_XM_WE_N")
	)
	(segment
		(start 85.000592 -91.037156)
		(end 82.587592 -93.450156)
		(width 0.127)
		(layer "In2.Cu")
		(net "EXP_XM_WE_N")
	)
	(segment
		(start 73.603358 -102.43439)
		(end 73.424034 -102.43439)
		(width 0.127)
		(layer "In2.Cu")
		(net "EXP_XM_WE_N")
	)
	(segment
		(start 73.229216 -100.801678)
		(end 73.049892 -100.801678)
		(width 0.127)
		(layer "In2.Cu")
		(net "EXP_XM_WE_N")
	)
	(segment
		(start 72.869806 -100.981764)
		(end 72.869806 -101.161088)
		(width 0.127)
		(layer "In2.Cu")
		(net "EXP_XM_WE_N")
	)
	(segment
		(start 73.588626 -100.262944)
		(end 73.588626 -100.442268)
		(width 0.127)
		(layer "In2.Cu")
		(net "EXP_XM_WE_N")
	)
	(segment
		(start 75.0443 -98.74631)
		(end 76.02347 -99.72548)
		(width 0.127)
		(layer "In2.Cu")
		(net "EXP_XM_WE_N")
	)
	(segment
		(start 88.710516 -88.392508)
		(end 88.0618 -88.392508)
		(width 0.127)
		(layer "In2.Cu")
		(net "EXP_XM_WE_N")
	)
	(segment
		(start 90.616024 -86.487)
		(end 88.710516 -88.392508)
		(width 0.127)
		(layer "In2.Cu")
		(net "EXP_XM_WE_N")
	)
	(segment
		(start 74.142854 -101.71557)
		(end 73.229216 -100.801678)
		(width 0.127)
		(layer "In2.Cu")
		(net "EXP_XM_WE_N")
	)
	(segment
		(start 59.44997 -132.429504)
		(end 59.44997 -133.778752)
		(width 0.127)
		(layer "In2.Cu")
		(net "EXP_XM_WE_N")
	)
	(segment
		(start 72.150986 -101.700584)
		(end 72.150986 -101.879908)
		(width 0.127)
		(layer "In2.Cu")
		(net "EXP_XM_WE_N")
	)
	(segment
		(start 58.86577 -129.5908)
		(end 59.24677 -129.9718)
		(width 0.127)
		(layer "In2.Cu")
		(net "EXP_XM_WE_N")
	)
	(segment
		(start 72.510396 -101.520498)
		(end 72.331072 -101.520498)
		(width 0.127)
		(layer "In2.Cu")
		(net "EXP_XM_WE_N")
	)
	(segment
		(start 72.150986 -101.879908)
		(end 73.064624 -102.7938)
		(width 0.127)
		(layer "In2.Cu")
		(net "EXP_XM_WE_N")
	)
	(segment
		(start 73.783444 -102.07498)
		(end 73.783444 -102.254304)
		(width 0.127)
		(layer "In2.Cu")
		(net "EXP_XM_WE_N")
	)
	(segment
		(start 73.424034 -102.43439)
		(end 72.510396 -101.520498)
		(width 0.127)
		(layer "In2.Cu")
		(net "EXP_XM_WE_N")
	)
	(segment
		(start 72.869806 -101.161088)
		(end 73.783444 -102.07498)
		(width 0.127)
		(layer "In2.Cu")
		(net "EXP_XM_WE_N")
	)
	(segment
		(start 59.48299 -133.811772)
		(end 59.48299 -133.893052)
		(width 0.127)
		(layer "In2.Cu")
		(net "EXP_XM_WE_N")
	)
	(segment
		(start 74.502264 -101.535484)
		(end 74.322178 -101.71557)
		(width 0.127)
		(layer "In2.Cu")
		(net "EXP_XM_WE_N")
	)
	(segment
		(start 72.331072 -101.520498)
		(end 72.150986 -101.700584)
		(width 0.127)
		(layer "In2.Cu")
		(net "EXP_XM_WE_N")
	)
	(segment
		(start 59.43981 -116.597684)
		(end 59.43981 -127.77216)
		(width 0.127)
		(layer "In2.Cu")
		(net "EXP_XM_WE_N")
	)
	(segment
		(start 73.948036 -100.082858)
		(end 73.768712 -100.082858)
		(width 0.127)
		(layer "In2.Cu")
		(net "EXP_XM_WE_N")
	)
	(segment
		(start 73.588626 -100.442268)
		(end 74.502264 -101.35616)
		(width 0.127)
		(layer "In2.Cu")
		(net "EXP_XM_WE_N")
	)
	(segment
		(start 116.963444 -107.262168)
		(end 117.350032 -106.350054)
		(width 0.1016)
		(layer "F.Cu")
		(net "SAS_HDD_TX1_N")
	)
	(segment
		(start 117.599968 -110.023148)
		(end 117.502686 -109.925866)
		(width 0.1016)
		(layer "F.Cu")
		(net "SAS_HDD_TX1_N")
	)
	(segment
		(start 117.599714 -110.023148)
		(end 117.599968 -110.023148)
		(width 0.1016)
		(layer "F.Cu")
		(net "SAS_HDD_TX1_N")
	)
	(segment
		(start 119.581168 -112.004602)
		(end 117.599714 -110.023148)
		(width 0.1016)
		(layer "F.Cu")
		(net "SAS_HDD_TX1_N")
	)
	(segment
		(start 119.66702 -113.668048)
		(end 119.66702 -112.211104)
		(width 0.1016)
		(layer "F.Cu")
		(net "SAS_HDD_TX1_N")
	)
	(segment
		(start 116.947442 -108.584746)
		(end 116.947442 -107.341416)
		(width 0.1016)
		(layer "F.Cu")
		(net "SAS_HDD_TX1_N")
	)
	(arc
		(start 119.52097 -114.0206)
		(mid 119.629049 -113.858848)
		(end 119.66702 -113.668048)
		(width 0.1016)
		(layer "F.Cu")
		(net "SAS_HDD_TX1_N")
	)
	(arc
		(start 119.66702 -112.211104)
		(mid 119.644585 -112.099347)
		(end 119.581168 -112.004602)
		(width 0.1016)
		(layer "F.Cu")
		(net "SAS_HDD_TX1_N")
	)
	(arc
		(start 116.95938 -108.79963)
		(mid 116.950367 -108.692357)
		(end 116.947442 -108.584746)
		(width 0.1016)
		(layer "F.Cu")
		(net "SAS_HDD_TX1_N")
	)
	(arc
		(start 117.502686 -109.925866)
		(mid 117.135528 -109.408822)
		(end 116.95938 -108.79963)
		(width 0.1016)
		(layer "F.Cu")
		(net "SAS_HDD_TX1_N")
	)
	(arc
		(start 116.947442 -107.341416)
		(mid 116.951453 -107.300985)
		(end 116.963444 -107.262168)
		(width 0.1016)
		(layer "F.Cu")
		(net "SAS_HDD_TX1_N")
	)
	(segment
		(start 106.750104 -34.99993)
		(end 106.350308 -34.600134)
		(width 0.1143)
		(layer "F.Cu")
		(net "IOC_UART_1_TX")
	)
	(via
		(at 106.350308 -34.600134)
		(size 0.508)
		(drill 0.254)
		(layers "F.Cu" "B.Cu")
		(net "IOC_UART_1_TX")
	)
	(segment
		(start 106.350308 -33.823148)
		(end 106.350308 -34.600134)
		(width 0.1143)
		(layer "B.Cu")
		(net "IOC_UART_1_TX")
	)
	(segment
		(start 106.18216 -33.655)
		(end 106.350308 -33.823148)
		(width 0.1143)
		(layer "B.Cu")
		(net "IOC_UART_1_TX")
	)
	(segment
		(start 102.349808 -96.350074)
		(end 101.76891 -96.350074)
		(width 0.1143)
		(layer "F.Cu")
		(net "EXP_XM_ADDR_12")
	)
	(segment
		(start 101.76891 -96.350074)
		(end 100.31349 -97.805494)
		(width 0.1143)
		(layer "F.Cu")
		(net "EXP_XM_ADDR_12")
	)
	(segment
		(start 69.793612 -136.892792)
		(end 70.705218 -135.981186)
		(width 0.1143)
		(layer "F.Cu")
		(net "EXP_XM_ADDR_12")
	)
	(segment
		(start 56.558942 -136.892792)
		(end 69.793612 -136.892792)
		(width 0.1143)
		(layer "F.Cu")
		(net "EXP_XM_ADDR_12")
	)
	(segment
		(start 100.31349 -97.805494)
		(end 100.31349 -97.8281)
		(width 0.1143)
		(layer "F.Cu")
		(net "EXP_XM_ADDR_12")
	)
	(segment
		(start 70.705218 -135.981186)
		(end 70.705218 -135.92556)
		(width 0.1143)
		(layer "F.Cu")
		(net "EXP_XM_ADDR_12")
	)
	(via
		(at 100.31349 -97.8281)
		(size 0.508)
		(drill 0.254)
		(layers "F.Cu" "B.Cu")
		(net "EXP_XM_ADDR_12")
	)
	(via
		(at 71.3232 -135.3312)
		(size 0.7112)
		(drill 0.3556)
		(layers "F.Cu" "B.Cu")
		(net "EXP_XM_ADDR_12")
	)
	(via
		(at 70.705218 -135.92556)
		(size 0.5588)
		(drill 0.3048)
		(layers "F.Cu" "B.Cu")
		(net "EXP_XM_ADDR_12")
	)
	(segment
		(start 70.705218 -135.92556)
		(end 71.299578 -135.3312)
		(width 0.1143)
		(layer "B.Cu")
		(net "EXP_XM_ADDR_12")
	)
	(segment
		(start 71.299578 -135.3312)
		(end 71.3232 -135.3312)
		(width 0.1143)
		(layer "B.Cu")
		(net "EXP_XM_ADDR_12")
	)
	(segment
		(start 99.210114 -98.2345)
		(end 99.04349 -98.401886)
		(width 0.127)
		(layer "In2.Cu")
		(net "EXP_XM_ADDR_12")
	)
	(segment
		(start 72.569324 -135.887714)
		(end 71.78802 -135.10641)
		(width 0.127)
		(layer "In2.Cu")
		(net "EXP_XM_ADDR_12")
	)
	(segment
		(start 72.14743 -134.747)
		(end 72.928734 -135.528304)
		(width 0.127)
		(layer "In2.Cu")
		(net "EXP_XM_ADDR_12")
	)
	(segment
		(start 73.67651 -132.196078)
		(end 73.80351 -132.323078)
		(width 0.127)
		(layer "In2.Cu")
		(net "EXP_XM_ADDR_12")
	)
	(segment
		(start 89.60993 -106.110532)
		(end 86.556342 -109.16412)
		(width 0.127)
		(layer "In2.Cu")
		(net "EXP_XM_ADDR_12")
	)
	(segment
		(start 93.801946 -101.918008)
		(end 89.60993 -106.110024)
		(width 0.127)
		(layer "In2.Cu")
		(net "EXP_XM_ADDR_12")
	)
	(segment
		(start 72.86625 -133.848348)
		(end 72.86625 -134.02818)
		(width 0.127)
		(layer "In2.Cu")
		(net "EXP_XM_ADDR_12")
	)
	(segment
		(start 71.608188 -135.10641)
		(end 70.849998 -135.8646)
		(width 0.127)
		(layer "In2.Cu")
		(net "EXP_XM_ADDR_12")
	)
	(segment
		(start 77.55509 -115.946428)
		(end 77.55509 -116.448332)
		(width 0.127)
		(layer "In2.Cu")
		(net "EXP_XM_ADDR_12")
	)
	(segment
		(start 99.04349 -98.401886)
		(end 95.527368 -101.918008)
		(width 0.127)
		(layer "In2.Cu")
		(net "EXP_XM_ADDR_12")
	)
	(segment
		(start 78.165452 -117.554502)
		(end 74.93889 -120.781064)
		(width 0.127)
		(layer "In2.Cu")
		(net "EXP_XM_ADDR_12")
	)
	(segment
		(start 75.82027 -132.450078)
		(end 75.82027 -132.704078)
		(width 0.127)
		(layer "In2.Cu")
		(net "EXP_XM_ADDR_12")
	)
	(segment
		(start 77.55509 -116.448332)
		(end 78.165452 -117.058694)
		(width 0.127)
		(layer "In2.Cu")
		(net "EXP_XM_ADDR_12")
	)
	(segment
		(start 73.67651 -133.038088)
		(end 72.86625 -133.848348)
		(width 0.127)
		(layer "In2.Cu")
		(net "EXP_XM_ADDR_12")
	)
	(segment
		(start 84.337398 -109.16412)
		(end 77.55509 -115.946428)
		(width 0.127)
		(layer "In2.Cu")
		(net "EXP_XM_ADDR_12")
	)
	(segment
		(start 72.86625 -134.02818)
		(end 73.647554 -134.809484)
		(width 0.127)
		(layer "In2.Cu")
		(net "EXP_XM_ADDR_12")
	)
	(segment
		(start 70.766178 -135.8646)
		(end 70.705218 -135.92556)
		(width 0.127)
		(layer "In2.Cu")
		(net "EXP_XM_ADDR_12")
	)
	(segment
		(start 86.556342 -109.16412)
		(end 84.337398 -109.16412)
		(width 0.127)
		(layer "In2.Cu")
		(net "EXP_XM_ADDR_12")
	)
	(segment
		(start 73.80351 -130.799078)
		(end 73.67651 -130.926078)
		(width 0.127)
		(layer "In2.Cu")
		(net "EXP_XM_ADDR_12")
	)
	(segment
		(start 73.67651 -131.180078)
		(end 73.80351 -131.307078)
		(width 0.127)
		(layer "In2.Cu")
		(net "EXP_XM_ADDR_12")
	)
	(segment
		(start 73.80351 -131.307078)
		(end 75.69327 -131.307078)
		(width 0.127)
		(layer "In2.Cu")
		(net "EXP_XM_ADDR_12")
	)
	(segment
		(start 73.288144 -135.168894)
		(end 72.50684 -134.38759)
		(width 0.127)
		(layer "In2.Cu")
		(net "EXP_XM_ADDR_12")
	)
	(segment
		(start 72.928734 -135.708136)
		(end 72.749156 -135.887714)
		(width 0.127)
		(layer "In2.Cu")
		(net "EXP_XM_ADDR_12")
	)
	(segment
		(start 89.60993 -106.110024)
		(end 89.60993 -106.110532)
		(width 0.127)
		(layer "In2.Cu")
		(net "EXP_XM_ADDR_12")
	)
	(segment
		(start 75.69327 -130.799078)
		(end 73.80351 -130.799078)
		(width 0.127)
		(layer "In2.Cu")
		(net "EXP_XM_ADDR_12")
	)
	(segment
		(start 78.165452 -117.058694)
		(end 78.165452 -117.554502)
		(width 0.127)
		(layer "In2.Cu")
		(net "EXP_XM_ADDR_12")
	)
	(segment
		(start 75.82027 -131.688078)
		(end 75.69327 -131.815078)
		(width 0.127)
		(layer "In2.Cu")
		(net "EXP_XM_ADDR_12")
	)
	(segment
		(start 99.90709 -98.2345)
		(end 99.210114 -98.2345)
		(width 0.127)
		(layer "In2.Cu")
		(net "EXP_XM_ADDR_12")
	)
	(segment
		(start 75.69327 -132.831078)
		(end 73.80351 -132.831078)
		(width 0.127)
		(layer "In2.Cu")
		(net "EXP_XM_ADDR_12")
	)
	(segment
		(start 75.69327 -131.815078)
		(end 73.80351 -131.815078)
		(width 0.127)
		(layer "In2.Cu")
		(net "EXP_XM_ADDR_12")
	)
	(segment
		(start 75.82027 -132.704078)
		(end 75.69327 -132.831078)
		(width 0.127)
		(layer "In2.Cu")
		(net "EXP_XM_ADDR_12")
	)
	(segment
		(start 73.67651 -132.958078)
		(end 73.67651 -133.038088)
		(width 0.127)
		(layer "In2.Cu")
		(net "EXP_XM_ADDR_12")
	)
	(segment
		(start 70.849998 -135.8646)
		(end 70.766178 -135.8646)
		(width 0.127)
		(layer "In2.Cu")
		(net "EXP_XM_ADDR_12")
	)
	(segment
		(start 75.82027 -131.434078)
		(end 75.82027 -131.688078)
		(width 0.127)
		(layer "In2.Cu")
		(net "EXP_XM_ADDR_12")
	)
	(segment
		(start 73.80351 -131.815078)
		(end 73.67651 -131.942078)
		(width 0.127)
		(layer "In2.Cu")
		(net "EXP_XM_ADDR_12")
	)
	(segment
		(start 73.80351 -132.831078)
		(end 73.67651 -132.958078)
		(width 0.127)
		(layer "In2.Cu")
		(net "EXP_XM_ADDR_12")
	)
	(segment
		(start 75.82027 -130.418078)
		(end 75.82027 -130.672078)
		(width 0.127)
		(layer "In2.Cu")
		(net "EXP_XM_ADDR_12")
	)
	(segment
		(start 72.327008 -134.38759)
		(end 72.14743 -134.567168)
		(width 0.127)
		(layer "In2.Cu")
		(net "EXP_XM_ADDR_12")
	)
	(segment
		(start 73.67651 -130.164078)
		(end 73.80351 -130.291078)
		(width 0.127)
		(layer "In2.Cu")
		(net "EXP_XM_ADDR_12")
	)
	(segment
		(start 73.67651 -130.926078)
		(end 73.67651 -131.180078)
		(width 0.127)
		(layer "In2.Cu")
		(net "EXP_XM_ADDR_12")
	)
	(segment
		(start 73.80351 -132.323078)
		(end 75.69327 -132.323078)
		(width 0.127)
		(layer "In2.Cu")
		(net "EXP_XM_ADDR_12")
	)
	(segment
		(start 75.69327 -132.323078)
		(end 75.82027 -132.450078)
		(width 0.127)
		(layer "In2.Cu")
		(net "EXP_XM_ADDR_12")
	)
	(segment
		(start 73.647554 -134.989316)
		(end 73.467976 -135.168894)
		(width 0.127)
		(layer "In2.Cu")
		(net "EXP_XM_ADDR_12")
	)
	(segment
		(start 73.80351 -130.291078)
		(end 75.69327 -130.291078)
		(width 0.127)
		(layer "In2.Cu")
		(net "EXP_XM_ADDR_12")
	)
	(segment
		(start 72.749156 -135.887714)
		(end 72.569324 -135.887714)
		(width 0.127)
		(layer "In2.Cu")
		(net "EXP_XM_ADDR_12")
	)
	(segment
		(start 75.69327 -131.307078)
		(end 75.82027 -131.434078)
		(width 0.127)
		(layer "In2.Cu")
		(net "EXP_XM_ADDR_12")
	)
	(segment
		(start 73.467976 -135.168894)
		(end 73.288144 -135.168894)
		(width 0.127)
		(layer "In2.Cu")
		(net "EXP_XM_ADDR_12")
	)
	(segment
		(start 74.93889 -126.753112)
		(end 73.67651 -128.015492)
		(width 0.127)
		(layer "In2.Cu")
		(net "EXP_XM_ADDR_12")
	)
	(segment
		(start 75.69327 -130.291078)
		(end 75.82027 -130.418078)
		(width 0.127)
		(layer "In2.Cu")
		(net "EXP_XM_ADDR_12")
	)
	(segment
		(start 72.14743 -134.567168)
		(end 72.14743 -134.747)
		(width 0.127)
		(layer "In2.Cu")
		(net "EXP_XM_ADDR_12")
	)
	(segment
		(start 74.93889 -120.781064)
		(end 74.93889 -126.753112)
		(width 0.127)
		(layer "In2.Cu")
		(net "EXP_XM_ADDR_12")
	)
	(segment
		(start 95.527368 -101.918008)
		(end 93.801946 -101.918008)
		(width 0.127)
		(layer "In2.Cu")
		(net "EXP_XM_ADDR_12")
	)
	(segment
		(start 73.67651 -131.942078)
		(end 73.67651 -132.196078)
		(width 0.127)
		(layer "In2.Cu")
		(net "EXP_XM_ADDR_12")
	)
	(segment
		(start 100.31349 -97.8281)
		(end 99.90709 -98.2345)
		(width 0.127)
		(layer "In2.Cu")
		(net "EXP_XM_ADDR_12")
	)
	(segment
		(start 72.928734 -135.528304)
		(end 72.928734 -135.708136)
		(width 0.127)
		(layer "In2.Cu")
		(net "EXP_XM_ADDR_12")
	)
	(segment
		(start 73.647554 -134.809484)
		(end 73.647554 -134.989316)
		(width 0.127)
		(layer "In2.Cu")
		(net "EXP_XM_ADDR_12")
	)
	(segment
		(start 75.82027 -130.672078)
		(end 75.69327 -130.799078)
		(width 0.127)
		(layer "In2.Cu")
		(net "EXP_XM_ADDR_12")
	)
	(segment
		(start 73.67651 -128.015492)
		(end 73.67651 -130.164078)
		(width 0.127)
		(layer "In2.Cu")
		(net "EXP_XM_ADDR_12")
	)
	(segment
		(start 71.78802 -135.10641)
		(end 71.608188 -135.10641)
		(width 0.127)
		(layer "In2.Cu")
		(net "EXP_XM_ADDR_12")
	)
	(segment
		(start 72.50684 -134.38759)
		(end 72.327008 -134.38759)
		(width 0.127)
		(layer "In2.Cu")
		(net "EXP_XM_ADDR_12")
	)
	(segment
		(start 95.13824 -45.01134)
		(end 95.13824 -45.011848)
		(width 0.1143)
		(layer "F.Cu")
		(net "POWERLOSS#")
	)
	(segment
		(start 95.13824 -45.011848)
		(end 94.750128 -45.39996)
		(width 0.1143)
		(layer "F.Cu")
		(net "POWERLOSS#")
	)
	(via
		(at 95.13824 -45.01134)
		(size 0.508)
		(drill 0.254)
		(layers "F.Cu" "B.Cu")
		(net "POWERLOSS#")
	)
	(via
		(at 95.993966 -44.196)
		(size 0.7112)
		(drill 0.3556)
		(layers "F.Cu" "B.Cu")
		(net "POWERLOSS#")
	)
	(segment
		(start 95.993966 -44.196)
		(end 95.95358 -44.196)
		(width 0.1143)
		(layer "B.Cu")
		(net "POWERLOSS#")
	)
	(segment
		(start 95.95358 -44.196)
		(end 95.13824 -45.01134)
		(width 0.1143)
		(layer "B.Cu")
		(net "POWERLOSS#")
	)
	(segment
		(start 94.7928 -45.66666)
		(end 94.7928 -45.35678)
		(width 0.1143)
		(layer "B.Cu")
		(net "POWERLOSS#")
	)
	(segment
		(start 94.7928 -45.35678)
		(end 95.13824 -45.01134)
		(width 0.1143)
		(layer "B.Cu")
		(net "POWERLOSS#")
	)
	(segment
		(start 196.1515 -169.672)
		(end 197.1675 -169.672)
		(width 0.127)
		(layer "F.Cu")
		(net "P3V3_STBY_R1")
	)
	(segment
		(start 197.1675 -169.672)
		(end 196.985636 -169.490136)
		(width 0.127)
		(layer "F.Cu")
		(net "P3V3_STBY_R1")
	)
	(segment
		(start 196.1515 -169.672)
		(end 196.1515 -170.7515)
		(width 0.127)
		(layer "F.Cu")
		(net "P3V3_STBY_R1")
	)
	(segment
		(start 196.985636 -169.490136)
		(end 196.985636 -167.267128)
		(width 0.127)
		(layer "F.Cu")
		(net "P3V3_STBY_R1")
	)
	(via
		(at 196.1515 -170.7515)
		(size 0.7112)
		(drill 0.3556)
		(layers "F.Cu" "B.Cu")
		(net "P3V3_STBY_R1")
	)
	(segment
		(start 63.60668 -134.389114)
		(end 65.005966 -134.389114)
		(width 0.1143)
		(layer "F.Cu")
		(net "EXP_XM_ADDR_21")
	)
	(segment
		(start 65.10528 -134.2898)
		(end 65.36817 -134.2898)
		(width 0.1143)
		(layer "F.Cu")
		(net "EXP_XM_ADDR_21")
	)
	(segment
		(start 62.853824 -134.34695)
		(end 63.564516 -134.34695)
		(width 0.1143)
		(layer "F.Cu")
		(net "EXP_XM_ADDR_21")
	)
	(segment
		(start 63.564516 -134.34695)
		(end 63.60668 -134.389114)
		(width 0.1143)
		(layer "F.Cu")
		(net "EXP_XM_ADDR_21")
	)
	(segment
		(start 101.718618 -94.349824)
		(end 101.580442 -94.488)
		(width 0.1143)
		(layer "F.Cu")
		(net "EXP_XM_ADDR_21")
	)
	(segment
		(start 102.349808 -94.349824)
		(end 101.718618 -94.349824)
		(width 0.1143)
		(layer "F.Cu")
		(net "EXP_XM_ADDR_21")
	)
	(segment
		(start 65.005966 -134.389114)
		(end 65.10528 -134.2898)
		(width 0.1143)
		(layer "F.Cu")
		(net "EXP_XM_ADDR_21")
	)
	(segment
		(start 56.558942 -134.392162)
		(end 62.808612 -134.392162)
		(width 0.1143)
		(layer "F.Cu")
		(net "EXP_XM_ADDR_21")
	)
	(segment
		(start 65.36817 -134.2898)
		(end 66.18097 -133.477)
		(width 0.1143)
		(layer "F.Cu")
		(net "EXP_XM_ADDR_21")
	)
	(segment
		(start 62.808612 -134.392162)
		(end 62.853824 -134.34695)
		(width 0.1143)
		(layer "F.Cu")
		(net "EXP_XM_ADDR_21")
	)
	(via
		(at 101.580442 -94.488)
		(size 0.508)
		(drill 0.254)
		(layers "F.Cu" "B.Cu")
		(net "EXP_XM_ADDR_21")
	)
	(via
		(at 66.18097 -133.477)
		(size 0.5588)
		(drill 0.3048)
		(layers "F.Cu" "B.Cu")
		(net "EXP_XM_ADDR_21")
	)
	(via
		(at 66.9036 -134.0866)
		(size 0.7112)
		(drill 0.3556)
		(layers "F.Cu" "B.Cu")
		(net "EXP_XM_ADDR_21")
	)
	(segment
		(start 66.9036 -134.0866)
		(end 66.294 -133.477)
		(width 0.1143)
		(layer "B.Cu")
		(net "EXP_XM_ADDR_21")
	)
	(segment
		(start 66.294 -133.477)
		(end 66.18097 -133.477)
		(width 0.1143)
		(layer "B.Cu")
		(net "EXP_XM_ADDR_21")
	)
	(segment
		(start 95.54845 -95.25)
		(end 100.72497 -95.25)
		(width 0.127)
		(layer "In2.Cu")
		(net "EXP_XM_ADDR_21")
	)
	(segment
		(start 101.48697 -94.488)
		(end 101.580442 -94.488)
		(width 0.127)
		(layer "In2.Cu")
		(net "EXP_XM_ADDR_21")
	)
	(segment
		(start 67.95389 -122.85345)
		(end 67.19189 -122.85345)
		(width 0.127)
		(layer "In2.Cu")
		(net "EXP_XM_ADDR_21")
	)
	(segment
		(start 66.72707 -130.080004)
		(end 66.72707 -129.3495)
		(width 0.127)
		(layer "In2.Cu")
		(net "EXP_XM_ADDR_21")
	)
	(segment
		(start 67.57289 -122.21845)
		(end 67.69989 -122.34545)
		(width 0.127)
		(layer "In2.Cu")
		(net "EXP_XM_ADDR_21")
	)
	(segment
		(start 68.08089 -122.98045)
		(end 67.95389 -122.85345)
		(width 0.127)
		(layer "In2.Cu")
		(net "EXP_XM_ADDR_21")
	)
	(segment
		(start 68.20789 -120.103392)
		(end 68.46189 -120.103392)
		(width 0.127)
		(layer "In2.Cu")
		(net "EXP_XM_ADDR_21")
	)
	(segment
		(start 68.08089 -120.230392)
		(end 68.20789 -120.103392)
		(width 0.127)
		(layer "In2.Cu")
		(net "EXP_XM_ADDR_21")
	)
	(segment
		(start 82.208624 -102.869492)
		(end 88.926416 -96.1517)
		(width 0.127)
		(layer "In2.Cu")
		(net "EXP_XM_ADDR_21")
	)
	(segment
		(start 68.96989 -119.595392)
		(end 68.20789 -119.595392)
		(width 0.127)
		(layer "In2.Cu")
		(net "EXP_XM_ADDR_21")
	)
	(segment
		(start 92.325952 -96.1517)
		(end 93.291152 -97.1169)
		(width 0.127)
		(layer "In2.Cu")
		(net "EXP_XM_ADDR_21")
	)
	(segment
		(start 68.58889 -124.51842)
		(end 68.71589 -124.64542)
		(width 0.127)
		(layer "In2.Cu")
		(net "EXP_XM_ADDR_21")
	)
	(segment
		(start 66.72707 -129.3495)
		(end 68.08089 -127.99568)
		(width 0.127)
		(layer "In2.Cu")
		(net "EXP_XM_ADDR_21")
	)
	(segment
		(start 82.208624 -104.959658)
		(end 82.208624 -102.869492)
		(width 0.127)
		(layer "In2.Cu")
		(net "EXP_XM_ADDR_21")
	)
	(segment
		(start 67.06489 -122.72645)
		(end 67.06489 -120.589802)
		(width 0.127)
		(layer "In2.Cu")
		(net "EXP_XM_ADDR_21")
	)
	(segment
		(start 68.20789 -119.595392)
		(end 68.08089 -119.468392)
		(width 0.127)
		(layer "In2.Cu")
		(net "EXP_XM_ADDR_21")
	)
	(segment
		(start 100.72497 -95.25)
		(end 101.48697 -94.488)
		(width 0.127)
		(layer "In2.Cu")
		(net "EXP_XM_ADDR_21")
	)
	(segment
		(start 68.96989 -124.64542)
		(end 69.09689 -124.51842)
		(width 0.127)
		(layer "In2.Cu")
		(net "EXP_XM_ADDR_21")
	)
	(segment
		(start 68.08089 -119.087392)
		(end 82.208624 -104.959658)
		(width 0.127)
		(layer "In2.Cu")
		(net "EXP_XM_ADDR_21")
	)
	(segment
		(start 67.57289 -120.589802)
		(end 67.57289 -122.21845)
		(width 0.127)
		(layer "In2.Cu")
		(net "EXP_XM_ADDR_21")
	)
	(segment
		(start 67.06489 -120.589802)
		(end 67.19189 -120.462802)
		(width 0.127)
		(layer "In2.Cu")
		(net "EXP_XM_ADDR_21")
	)
	(segment
		(start 67.95389 -122.34545)
		(end 68.08089 -122.21845)
		(width 0.127)
		(layer "In2.Cu")
		(net "EXP_XM_ADDR_21")
	)
	(segment
		(start 93.68155 -97.1169)
		(end 95.54845 -95.25)
		(width 0.127)
		(layer "In2.Cu")
		(net "EXP_XM_ADDR_21")
	)
	(segment
		(start 68.08089 -119.468392)
		(end 68.08089 -119.087392)
		(width 0.127)
		(layer "In2.Cu")
		(net "EXP_XM_ADDR_21")
	)
	(segment
		(start 68.58889 -120.230392)
		(end 68.58889 -124.51842)
		(width 0.127)
		(layer "In2.Cu")
		(net "EXP_XM_ADDR_21")
	)
	(segment
		(start 69.09689 -124.51842)
		(end 69.09689 -119.722392)
		(width 0.127)
		(layer "In2.Cu")
		(net "EXP_XM_ADDR_21")
	)
	(segment
		(start 66.18097 -133.477)
		(end 66.18097 -132.790438)
		(width 0.127)
		(layer "In2.Cu")
		(net "EXP_XM_ADDR_21")
	)
	(segment
		(start 66.18097 -132.790438)
		(end 66.989452 -131.981956)
		(width 0.127)
		(layer "In2.Cu")
		(net "EXP_XM_ADDR_21")
	)
	(segment
		(start 68.08089 -122.21845)
		(end 68.08089 -120.230392)
		(width 0.127)
		(layer "In2.Cu")
		(net "EXP_XM_ADDR_21")
	)
	(segment
		(start 68.46189 -120.103392)
		(end 68.58889 -120.230392)
		(width 0.127)
		(layer "In2.Cu")
		(net "EXP_XM_ADDR_21")
	)
	(segment
		(start 93.291152 -97.1169)
		(end 93.68155 -97.1169)
		(width 0.127)
		(layer "In2.Cu")
		(net "EXP_XM_ADDR_21")
	)
	(segment
		(start 68.08089 -127.99568)
		(end 68.08089 -122.98045)
		(width 0.127)
		(layer "In2.Cu")
		(net "EXP_XM_ADDR_21")
	)
	(segment
		(start 68.71589 -124.64542)
		(end 68.96989 -124.64542)
		(width 0.127)
		(layer "In2.Cu")
		(net "EXP_XM_ADDR_21")
	)
	(segment
		(start 66.989452 -130.342386)
		(end 66.72707 -130.080004)
		(width 0.127)
		(layer "In2.Cu")
		(net "EXP_XM_ADDR_21")
	)
	(segment
		(start 66.989452 -131.981956)
		(end 66.989452 -130.342386)
		(width 0.127)
		(layer "In2.Cu")
		(net "EXP_XM_ADDR_21")
	)
	(segment
		(start 67.69989 -122.34545)
		(end 67.95389 -122.34545)
		(width 0.127)
		(layer "In2.Cu")
		(net "EXP_XM_ADDR_21")
	)
	(segment
		(start 88.926416 -96.1517)
		(end 92.325952 -96.1517)
		(width 0.127)
		(layer "In2.Cu")
		(net "EXP_XM_ADDR_21")
	)
	(segment
		(start 67.19189 -120.462802)
		(end 67.44589 -120.462802)
		(width 0.127)
		(layer "In2.Cu")
		(net "EXP_XM_ADDR_21")
	)
	(segment
		(start 69.09689 -119.722392)
		(end 68.96989 -119.595392)
		(width 0.127)
		(layer "In2.Cu")
		(net "EXP_XM_ADDR_21")
	)
	(segment
		(start 67.44589 -120.462802)
		(end 67.57289 -120.589802)
		(width 0.127)
		(layer "In2.Cu")
		(net "EXP_XM_ADDR_21")
	)
	(segment
		(start 67.19189 -122.85345)
		(end 67.06489 -122.72645)
		(width 0.127)
		(layer "In2.Cu")
		(net "EXP_XM_ADDR_21")
	)
	(segment
		(start 120.00992 -113.834672)
		(end 120.00992 -112.211104)
		(width 0.1016)
		(layer "F.Cu")
		(net "SAS_HDD_TX1_P")
	)
	(segment
		(start 117.290342 -108.586778)
		(end 117.290342 -107.484164)
		(width 0.1016)
		(layer "F.Cu")
		(net "SAS_HDD_TX1_P")
	)
	(segment
		(start 120.044972 -113.957354)
		(end 120.024652 -113.908586)
		(width 0.1016)
		(layer "F.Cu")
		(net "SAS_HDD_TX1_P")
	)
	(segment
		(start 120.15597 -114.0206)
		(end 120.13946 -114.0206)
		(width 0.1016)
		(layer "F.Cu")
		(net "SAS_HDD_TX1_P")
	)
	(segment
		(start 119.823992 -111.762032)
		(end 117.745256 -109.683296)
		(width 0.1016)
		(layer "F.Cu")
		(net "SAS_HDD_TX1_P")
	)
	(segment
		(start 117.300248 -108.761022)
		(end 117.290342 -108.586778)
		(width 0.1016)
		(layer "F.Cu")
		(net "SAS_HDD_TX1_P")
	)
	(arc
		(start 120.00992 -112.211104)
		(mid 119.961599 -111.968086)
		(end 119.823992 -111.762032)
		(width 0.1016)
		(layer "F.Cu")
		(net "SAS_HDD_TX1_P")
	)
	(arc
		(start 117.290342 -107.484164)
		(mid 117.307671 -107.411534)
		(end 117.350032 -107.350052)
		(width 0.1016)
		(layer "F.Cu")
		(net "SAS_HDD_TX1_P")
	)
	(arc
		(start 120.024652 -113.908586)
		(mid 120.013639 -113.872356)
		(end 120.00992 -113.834672)
		(width 0.1016)
		(layer "F.Cu")
		(net "SAS_HDD_TX1_P")
	)
	(arc
		(start 117.745256 -109.683296)
		(mid 117.444605 -109.259874)
		(end 117.300248 -108.761022)
		(width 0.1016)
		(layer "F.Cu")
		(net "SAS_HDD_TX1_P")
	)
	(arc
		(start 120.13946 -114.0206)
		(mid 120.082626 -114.003321)
		(end 120.044972 -113.957354)
		(width 0.1016)
		(layer "F.Cu")
		(net "SAS_HDD_TX1_P")
	)
	(segment
		(start 108.35005 -34.07029)
		(end 108.35005 -34.19983)
		(width 0.1143)
		(layer "F.Cu")
		(net "SYS_DBMODE3")
	)
	(segment
		(start 112.34166 -27.94)
		(end 112.293654 -27.94)
		(width 0.1143)
		(layer "F.Cu")
		(net "SYS_DBMODE3")
	)
	(segment
		(start 108.035344 -32.232346)
		(end 108.0135 -32.25419)
		(width 0.1143)
		(layer "F.Cu")
		(net "SYS_DBMODE3")
	)
	(segment
		(start 111.550704 -28.68295)
		(end 109.43209 -28.68295)
		(width 0.1143)
		(layer "F.Cu")
		(net "SYS_DBMODE3")
	)
	(segment
		(start 107.569 -30.54604)
		(end 107.569 -30.988)
		(width 0.1143)
		(layer "F.Cu")
		(net "SYS_DBMODE3")
	)
	(segment
		(start 108.0135 -32.25419)
		(end 108.0135 -33.73374)
		(width 0.1143)
		(layer "F.Cu")
		(net "SYS_DBMODE3")
	)
	(segment
		(start 107.569 -30.988)
		(end 107.569 -31.22168)
		(width 0.1143)
		(layer "F.Cu")
		(net "SYS_DBMODE3")
	)
	(segment
		(start 107.569 -31.22168)
		(end 108.035344 -31.688024)
		(width 0.1143)
		(layer "F.Cu")
		(net "SYS_DBMODE3")
	)
	(segment
		(start 108.035344 -31.688024)
		(end 108.035344 -32.232346)
		(width 0.1143)
		(layer "F.Cu")
		(net "SYS_DBMODE3")
	)
	(segment
		(start 113.3475 -27.94)
		(end 112.34166 -27.94)
		(width 0.1143)
		(layer "F.Cu")
		(net "SYS_DBMODE3")
	)
	(segment
		(start 108.0135 -33.73374)
		(end 108.35005 -34.07029)
		(width 0.1143)
		(layer "F.Cu")
		(net "SYS_DBMODE3")
	)
	(segment
		(start 109.43209 -28.68295)
		(end 107.569 -30.54604)
		(width 0.1143)
		(layer "F.Cu")
		(net "SYS_DBMODE3")
	)
	(segment
		(start 112.293654 -27.94)
		(end 111.550704 -28.68295)
		(width 0.1143)
		(layer "F.Cu")
		(net "SYS_DBMODE3")
	)
	(via
		(at 107.569 -30.988)
		(size 0.7112)
		(drill 0.3556)
		(layers "F.Cu" "B.Cu")
		(net "SYS_DBMODE3")
	)
	(segment
		(start 74.488294 -133.893052)
		(end 74.04862 -133.453378)
		(width 0.1143)
		(layer "F.Cu")
		(net "XM_DATA4")
	)
	(segment
		(start 75.786742 -133.893052)
		(end 74.488294 -133.893052)
		(width 0.1143)
		(layer "F.Cu")
		(net "XM_DATA4")
	)
	(segment
		(start 107.349798 -91.34983)
		(end 106.849672 -90.849704)
		(width 0.1143)
		(layer "F.Cu")
		(net "XM_DATA4")
	)
	(via
		(at 106.849672 -90.849704)
		(size 0.508)
		(drill 0.254)
		(layers "F.Cu" "B.Cu")
		(net "XM_DATA4")
	)
	(via
		(at 85.3948 -93.03385)
		(size 0.7112)
		(drill 0.3556)
		(layers "F.Cu" "B.Cu")
		(net "XM_DATA4")
	)
	(via
		(at 74.04862 -133.453378)
		(size 0.5588)
		(drill 0.3048)
		(layers "F.Cu" "B.Cu")
		(net "XM_DATA4")
	)
	(segment
		(start 71.85152 -128.506728)
		(end 71.85152 -104.15905)
		(width 0.1143)
		(layer "B.Cu")
		(net "XM_DATA4")
	)
	(segment
		(start 76.095606 -98.230944)
		(end 76.095606 -98.0694)
		(width 0.1143)
		(layer "B.Cu")
		(net "XM_DATA4")
	)
	(segment
		(start 77.388974 -96.776032)
		(end 77.550772 -96.614234)
		(width 0.1143)
		(layer "B.Cu")
		(net "XM_DATA4")
	)
	(segment
		(start 77.503528 -98.345498)
		(end 76.74229 -97.58426)
		(width 0.1143)
		(layer "B.Cu")
		(net "XM_DATA4")
	)
	(segment
		(start 75.563476 -100.28555)
		(end 74.802238 -99.524312)
		(width 0.1143)
		(layer "B.Cu")
		(net "XM_DATA4")
	)
	(segment
		(start 77.503528 -98.507042)
		(end 77.503528 -98.345498)
		(width 0.1143)
		(layer "B.Cu")
		(net "XM_DATA4")
	)
	(segment
		(start 77.34173 -98.66884)
		(end 77.503528 -98.507042)
		(width 0.1143)
		(layer "B.Cu")
		(net "XM_DATA4")
	)
	(segment
		(start 102.707186 -91.40825)
		(end 103.723186 -90.39225)
		(width 0.1143)
		(layer "B.Cu")
		(net "XM_DATA4")
	)
	(segment
		(start 78.473554 -97.375472)
		(end 78.635098 -97.375472)
		(width 0.1143)
		(layer "B.Cu")
		(net "XM_DATA4")
	)
	(segment
		(start 77.712316 -96.614234)
		(end 78.473554 -97.375472)
		(width 0.1143)
		(layer "B.Cu")
		(net "XM_DATA4")
	)
	(segment
		(start 73.650856 -130.306572)
		(end 73.266046 -129.921762)
		(width 0.1143)
		(layer "B.Cu")
		(net "XM_DATA4")
	)
	(segment
		(start 76.21016 -99.638866)
		(end 75.448922 -98.877628)
		(width 0.1143)
		(layer "B.Cu")
		(net "XM_DATA4")
	)
	(segment
		(start 106.35869 -90.39225)
		(end 106.816144 -90.849704)
		(width 0.1143)
		(layer "B.Cu")
		(net "XM_DATA4")
	)
	(segment
		(start 76.21016 -99.80041)
		(end 76.21016 -99.638866)
		(width 0.1143)
		(layer "B.Cu")
		(net "XM_DATA4")
	)
	(segment
		(start 88.574372 -91.421458)
		(end 88.688672 -91.535758)
		(width 0.1143)
		(layer "B.Cu")
		(net "XM_DATA4")
	)
	(segment
		(start 76.74229 -97.422716)
		(end 76.904088 -97.260918)
		(width 0.1143)
		(layer "B.Cu")
		(net "XM_DATA4")
	)
	(segment
		(start 75.886818 -99.962208)
		(end 76.048362 -99.962208)
		(width 0.1143)
		(layer "B.Cu")
		(net "XM_DATA4")
	)
	(segment
		(start 82.97672 -93.03385)
		(end 85.3948 -93.03385)
		(width 0.1143)
		(layer "B.Cu")
		(net "XM_DATA4")
	)
	(segment
		(start 85.3948 -93.03385)
		(end 86.593426 -93.03385)
		(width 0.1143)
		(layer "B.Cu")
		(net "XM_DATA4")
	)
	(segment
		(start 76.095606 -98.0694)
		(end 76.257404 -97.907602)
		(width 0.1143)
		(layer "B.Cu")
		(net "XM_DATA4")
	)
	(segment
		(start 75.448922 -98.716084)
		(end 75.61072 -98.554286)
		(width 0.1143)
		(layer "B.Cu")
		(net "XM_DATA4")
	)
	(segment
		(start 75.448922 -98.877628)
		(end 75.448922 -98.716084)
		(width 0.1143)
		(layer "B.Cu")
		(net "XM_DATA4")
	)
	(segment
		(start 74.04862 -133.453378)
		(end 73.650856 -133.055614)
		(width 0.1143)
		(layer "B.Cu")
		(net "XM_DATA4")
	)
	(segment
		(start 76.856844 -98.992182)
		(end 76.095606 -98.230944)
		(width 0.1143)
		(layer "B.Cu")
		(net "XM_DATA4")
	)
	(segment
		(start 103.723186 -90.39225)
		(end 106.35869 -90.39225)
		(width 0.1143)
		(layer "B.Cu")
		(net "XM_DATA4")
	)
	(segment
		(start 74.802238 -99.524312)
		(end 74.802238 -99.362768)
		(width 0.1143)
		(layer "B.Cu")
		(net "XM_DATA4")
	)
	(segment
		(start 77.988414 -98.022156)
		(end 78.150212 -97.860358)
		(width 0.1143)
		(layer "B.Cu")
		(net "XM_DATA4")
	)
	(segment
		(start 77.550772 -96.614234)
		(end 77.712316 -96.614234)
		(width 0.1143)
		(layer "B.Cu")
		(net "XM_DATA4")
	)
	(segment
		(start 74.802238 -99.362768)
		(end 74.964036 -99.20097)
		(width 0.1143)
		(layer "B.Cu")
		(net "XM_DATA4")
	)
	(segment
		(start 75.563476 -100.447094)
		(end 75.563476 -100.28555)
		(width 0.1143)
		(layer "B.Cu")
		(net "XM_DATA4")
	)
	(segment
		(start 78.635098 -97.375472)
		(end 82.97672 -93.03385)
		(width 0.1143)
		(layer "B.Cu")
		(net "XM_DATA4")
	)
	(segment
		(start 89.031572 -92.64142)
		(end 89.145872 -92.52712)
		(width 0.1143)
		(layer "B.Cu")
		(net "XM_DATA4")
	)
	(segment
		(start 89.145872 -91.535758)
		(end 89.260172 -91.421458)
		(width 0.1143)
		(layer "B.Cu")
		(net "XM_DATA4")
	)
	(segment
		(start 88.688672 -91.535758)
		(end 88.688672 -92.52712)
		(width 0.1143)
		(layer "B.Cu")
		(net "XM_DATA4")
	)
	(segment
		(start 78.150212 -97.698814)
		(end 77.388974 -96.937576)
		(width 0.1143)
		(layer "B.Cu")
		(net "XM_DATA4")
	)
	(segment
		(start 89.260172 -91.421458)
		(end 98.56978 -91.421458)
		(width 0.1143)
		(layer "B.Cu")
		(net "XM_DATA4")
	)
	(segment
		(start 76.695046 -99.315524)
		(end 76.856844 -99.153726)
		(width 0.1143)
		(layer "B.Cu")
		(net "XM_DATA4")
	)
	(segment
		(start 106.816144 -90.849704)
		(end 106.849672 -90.849704)
		(width 0.1143)
		(layer "B.Cu")
		(net "XM_DATA4")
	)
	(segment
		(start 78.150212 -97.860358)
		(end 78.150212 -97.698814)
		(width 0.1143)
		(layer "B.Cu")
		(net "XM_DATA4")
	)
	(segment
		(start 77.388974 -96.937576)
		(end 77.388974 -96.776032)
		(width 0.1143)
		(layer "B.Cu")
		(net "XM_DATA4")
	)
	(segment
		(start 89.145872 -92.52712)
		(end 89.145872 -91.535758)
		(width 0.1143)
		(layer "B.Cu")
		(net "XM_DATA4")
	)
	(segment
		(start 73.266046 -129.921254)
		(end 71.85152 -128.506728)
		(width 0.1143)
		(layer "B.Cu")
		(net "XM_DATA4")
	)
	(segment
		(start 76.856844 -99.153726)
		(end 76.856844 -98.992182)
		(width 0.1143)
		(layer "B.Cu")
		(net "XM_DATA4")
	)
	(segment
		(start 74.964036 -99.20097)
		(end 75.12558 -99.20097)
		(width 0.1143)
		(layer "B.Cu")
		(net "XM_DATA4")
	)
	(segment
		(start 76.048362 -99.962208)
		(end 76.21016 -99.80041)
		(width 0.1143)
		(layer "B.Cu")
		(net "XM_DATA4")
	)
	(segment
		(start 77.065632 -97.260918)
		(end 77.82687 -98.022156)
		(width 0.1143)
		(layer "B.Cu")
		(net "XM_DATA4")
	)
	(segment
		(start 76.257404 -97.907602)
		(end 76.418948 -97.907602)
		(width 0.1143)
		(layer "B.Cu")
		(net "XM_DATA4")
	)
	(segment
		(start 87.818976 -91.8083)
		(end 87.81923 -91.8083)
		(width 0.1143)
		(layer "B.Cu")
		(net "XM_DATA4")
	)
	(segment
		(start 75.772264 -98.554286)
		(end 76.533502 -99.315524)
		(width 0.1143)
		(layer "B.Cu")
		(net "XM_DATA4")
	)
	(segment
		(start 88.802972 -92.64142)
		(end 89.031572 -92.64142)
		(width 0.1143)
		(layer "B.Cu")
		(net "XM_DATA4")
	)
	(segment
		(start 98.56978 -91.421458)
		(end 99.449382 -92.30106)
		(width 0.1143)
		(layer "B.Cu")
		(net "XM_DATA4")
	)
	(segment
		(start 99.449382 -92.30106)
		(end 100.473764 -92.30106)
		(width 0.1143)
		(layer "B.Cu")
		(net "XM_DATA4")
	)
	(segment
		(start 71.85152 -104.15905)
		(end 75.563476 -100.447094)
		(width 0.1143)
		(layer "B.Cu")
		(net "XM_DATA4")
	)
	(segment
		(start 101.366574 -91.40825)
		(end 102.707186 -91.40825)
		(width 0.1143)
		(layer "B.Cu")
		(net "XM_DATA4")
	)
	(segment
		(start 76.418948 -97.907602)
		(end 77.180186 -98.66884)
		(width 0.1143)
		(layer "B.Cu")
		(net "XM_DATA4")
	)
	(segment
		(start 77.82687 -98.022156)
		(end 77.988414 -98.022156)
		(width 0.1143)
		(layer "B.Cu")
		(net "XM_DATA4")
	)
	(segment
		(start 88.206072 -91.421458)
		(end 88.574372 -91.421458)
		(width 0.1143)
		(layer "B.Cu")
		(net "XM_DATA4")
	)
	(segment
		(start 87.81923 -91.8083)
		(end 88.206072 -91.421458)
		(width 0.1143)
		(layer "B.Cu")
		(net "XM_DATA4")
	)
	(segment
		(start 100.473764 -92.30106)
		(end 101.366574 -91.40825)
		(width 0.1143)
		(layer "B.Cu")
		(net "XM_DATA4")
	)
	(segment
		(start 88.688672 -92.52712)
		(end 88.802972 -92.64142)
		(width 0.1143)
		(layer "B.Cu")
		(net "XM_DATA4")
	)
	(segment
		(start 76.533502 -99.315524)
		(end 76.695046 -99.315524)
		(width 0.1143)
		(layer "B.Cu")
		(net "XM_DATA4")
	)
	(segment
		(start 75.12558 -99.20097)
		(end 75.886818 -99.962208)
		(width 0.1143)
		(layer "B.Cu")
		(net "XM_DATA4")
	)
	(segment
		(start 86.593426 -93.03385)
		(end 87.818976 -91.8083)
		(width 0.1143)
		(layer "B.Cu")
		(net "XM_DATA4")
	)
	(segment
		(start 73.650856 -133.055614)
		(end 73.650856 -130.306572)
		(width 0.1143)
		(layer "B.Cu")
		(net "XM_DATA4")
	)
	(segment
		(start 76.74229 -97.58426)
		(end 76.74229 -97.422716)
		(width 0.1143)
		(layer "B.Cu")
		(net "XM_DATA4")
	)
	(segment
		(start 75.61072 -98.554286)
		(end 75.772264 -98.554286)
		(width 0.1143)
		(layer "B.Cu")
		(net "XM_DATA4")
	)
	(segment
		(start 73.266046 -129.921762)
		(end 73.266046 -129.921254)
		(width 0.1143)
		(layer "B.Cu")
		(net "XM_DATA4")
	)
	(segment
		(start 77.180186 -98.66884)
		(end 77.34173 -98.66884)
		(width 0.1143)
		(layer "B.Cu")
		(net "XM_DATA4")
	)
	(segment
		(start 76.904088 -97.260918)
		(end 77.065632 -97.260918)
		(width 0.1143)
		(layer "B.Cu")
		(net "XM_DATA4")
	)
	(segment
		(start 106.750104 -33.399984)
		(end 106.67111 -33.32099)
		(width 0.1143)
		(layer "F.Cu")
		(net "SYS_DBMODE4")
	)
	(segment
		(start 109.22635 -28.31465)
		(end 108.585 -28.956)
		(width 0.1143)
		(layer "F.Cu")
		(net "SYS_DBMODE4")
	)
	(segment
		(start 109.93501 -28.31465)
		(end 109.22635 -28.31465)
		(width 0.1143)
		(layer "F.Cu")
		(net "SYS_DBMODE4")
	)
	(segment
		(start 110.37316 -27.8765)
		(end 109.93501 -28.31465)
		(width 0.1143)
		(layer "F.Cu")
		(net "SYS_DBMODE4")
	)
	(segment
		(start 107.442 -30.152086)
		(end 107.442 -29.845)
		(width 0.1143)
		(layer "F.Cu")
		(net "SYS_DBMODE4")
	)
	(segment
		(start 108.331 -28.956)
		(end 107.823 -29.464)
		(width 0.1143)
		(layer "F.Cu")
		(net "SYS_DBMODE4")
	)
	(segment
		(start 108.585 -28.956)
		(end 108.331 -28.956)
		(width 0.1143)
		(layer "F.Cu")
		(net "SYS_DBMODE4")
	)
	(segment
		(start 106.82986 -30.764226)
		(end 107.442 -30.152086)
		(width 0.1143)
		(layer "F.Cu")
		(net "SYS_DBMODE4")
	)
	(segment
		(start 106.67111 -33.32099)
		(end 106.67111 -32.082486)
		(width 0.1143)
		(layer "F.Cu")
		(net "SYS_DBMODE4")
	)
	(segment
		(start 106.67111 -32.082486)
		(end 106.82986 -31.923736)
		(width 0.1143)
		(layer "F.Cu")
		(net "SYS_DBMODE4")
	)
	(segment
		(start 106.82986 -31.923736)
		(end 106.82986 -30.764226)
		(width 0.1143)
		(layer "F.Cu")
		(net "SYS_DBMODE4")
	)
	(segment
		(start 107.442 -29.845)
		(end 107.823 -29.464)
		(width 0.1143)
		(layer "F.Cu")
		(net "SYS_DBMODE4")
	)
	(via
		(at 107.823 -29.464)
		(size 0.7112)
		(drill 0.3556)
		(layers "F.Cu" "B.Cu")
		(net "SYS_DBMODE4")
	)
	(segment
		(start 300.03496 -176.240186)
		(end 300.430184 -176.63541)
		(width 0.1143)
		(layer "F.Cu")
		(net "ADC_P1V5_E_BMC")
	)
	(via
		(at 315.722 -181.737)
		(size 0.7112)
		(drill 0.3556)
		(layers "F.Cu" "B.Cu")
		(net "ADC_P1V5_E_BMC")
	)
	(via
		(at 300.430184 -176.63541)
		(size 0.508)
		(drill 0.254)
		(layers "F.Cu" "B.Cu")
		(net "ADC_P1V5_E_BMC")
	)
	(segment
		(start 317.0555 -181.737)
		(end 315.722 -181.737)
		(width 0.1143)
		(layer "B.Cu")
		(net "ADC_P1V5_E_BMC")
	)
	(segment
		(start 313.182 -181.737)
		(end 308.25313 -176.80813)
		(width 0.1143)
		(layer "B.Cu")
		(net "ADC_P1V5_E_BMC")
	)
	(segment
		(start 315.722 -181.737)
		(end 313.182 -181.737)
		(width 0.1143)
		(layer "B.Cu")
		(net "ADC_P1V5_E_BMC")
	)
	(segment
		(start 300.842934 -177.04816)
		(end 300.430184 -176.63541)
		(width 0.1143)
		(layer "B.Cu")
		(net "ADC_P1V5_E_BMC")
	)
	(segment
		(start 302.26 -176.80813)
		(end 302.01997 -177.04816)
		(width 0.1143)
		(layer "B.Cu")
		(net "ADC_P1V5_E_BMC")
	)
	(segment
		(start 302.01997 -177.04816)
		(end 300.842934 -177.04816)
		(width 0.1143)
		(layer "B.Cu")
		(net "ADC_P1V5_E_BMC")
	)
	(segment
		(start 308.25313 -176.80813)
		(end 302.26 -176.80813)
		(width 0.1143)
		(layer "B.Cu")
		(net "ADC_P1V5_E_BMC")
	)
	(segment
		(start 93.80601 -105.283)
		(end 94.04985 -105.03916)
		(width 0.1143)
		(layer "F.Cu")
		(net "SAS_SMART_TX")
	)
	(segment
		(start 92.72397 -105.283)
		(end 93.80601 -105.283)
		(width 0.1143)
		(layer "F.Cu")
		(net "SAS_SMART_TX")
	)
	(segment
		(start 94.18701 -104.902)
		(end 94.04985 -105.03916)
		(width 0.1143)
		(layer "F.Cu")
		(net "SAS_SMART_TX")
	)
	(segment
		(start 95.26397 -104.902)
		(end 94.18701 -104.902)
		(width 0.1143)
		(layer "F.Cu")
		(net "SAS_SMART_TX")
	)
	(segment
		(start 241.9223 -118.6053)
		(end 241.9223 -147.4343)
		(width 0.1143)
		(layer "F.Cu")
		(net "SAS_SMART_TX")
	)
	(segment
		(start 241.9223 -147.4343)
		(end 243.205 -148.717)
		(width 0.1143)
		(layer "F.Cu")
		(net "SAS_SMART_TX")
	)
	(via
		(at 95.1484 -105.03916)
		(size 0.7112)
		(drill 0.3556)
		(layers "F.Cu" "B.Cu")
		(net "SAS_SMART_TX")
	)
	(via
		(at 243.205 -148.717)
		(size 0.5588)
		(drill 0.3048)
		(layers "F.Cu" "B.Cu")
		(net "SAS_SMART_TX")
	)
	(via
		(at 94.04985 -105.03916)
		(size 0.5588)
		(drill 0.3048)
		(layers "F.Cu" "B.Cu")
		(net "SAS_SMART_TX")
	)
	(segment
		(start 95.1484 -105.03916)
		(end 94.04985 -105.03916)
		(width 0.1143)
		(layer "B.Cu")
		(net "SAS_SMART_TX")
	)
	(segment
		(start 169.6339 -150.5839)
		(end 168.8846 -151.3332)
		(width 0.127)
		(layer "In2.Cu")
		(net "SAS_SMART_TX")
	)
	(segment
		(start 83.780884 -126.754382)
		(end 81.145634 -126.754382)
		(width 0.127)
		(layer "In2.Cu")
		(net "SAS_SMART_TX")
	)
	(segment
		(start 211.201 -148.717)
		(end 209.3341 -150.5839)
		(width 0.127)
		(layer "In2.Cu")
		(net "SAS_SMART_TX")
	)
	(segment
		(start 89.995502 -132.969)
		(end 83.780884 -126.754382)
		(width 0.127)
		(layer "In2.Cu")
		(net "SAS_SMART_TX")
	)
	(segment
		(start 93.37167 -105.839768)
		(end 94.04985 -105.161588)
		(width 0.127)
		(layer "In2.Cu")
		(net "SAS_SMART_TX")
	)
	(segment
		(start 128.497838 -151.3332)
		(end 128.472438 -151.3078)
		(width 0.127)
		(layer "In2.Cu")
		(net "SAS_SMART_TX")
	)
	(segment
		(start 91.31046 -133.22046)
		(end 91.059 -132.969)
		(width 0.127)
		(layer "In2.Cu")
		(net "SAS_SMART_TX")
	)
	(segment
		(start 94.04985 -105.161588)
		(end 94.04985 -105.03916)
		(width 0.127)
		(layer "In2.Cu")
		(net "SAS_SMART_TX")
	)
	(segment
		(start 95.037148 -136.804146)
		(end 91.453462 -133.22046)
		(width 0.127)
		(layer "In2.Cu")
		(net "SAS_SMART_TX")
	)
	(segment
		(start 84.468716 -116.712746)
		(end 87.64143 -113.540032)
		(width 0.127)
		(layer "In2.Cu")
		(net "SAS_SMART_TX")
	)
	(segment
		(start 87.64143 -112.42294)
		(end 93.37167 -106.6927)
		(width 0.127)
		(layer "In2.Cu")
		(net "SAS_SMART_TX")
	)
	(segment
		(start 110.325916 -151.3078)
		(end 95.822262 -136.804146)
		(width 0.127)
		(layer "In2.Cu")
		(net "SAS_SMART_TX")
	)
	(segment
		(start 79.17307 -124.781818)
		(end 79.17307 -120.446546)
		(width 0.127)
		(layer "In2.Cu")
		(net "SAS_SMART_TX")
	)
	(segment
		(start 91.059 -132.969)
		(end 89.995502 -132.969)
		(width 0.127)
		(layer "In2.Cu")
		(net "SAS_SMART_TX")
	)
	(segment
		(start 93.37167 -106.6927)
		(end 93.37167 -105.839768)
		(width 0.127)
		(layer "In2.Cu")
		(net "SAS_SMART_TX")
	)
	(segment
		(start 168.8846 -151.3332)
		(end 128.497838 -151.3332)
		(width 0.127)
		(layer "In2.Cu")
		(net "SAS_SMART_TX")
	)
	(segment
		(start 209.3341 -150.5839)
		(end 169.6339 -150.5839)
		(width 0.127)
		(layer "In2.Cu")
		(net "SAS_SMART_TX")
	)
	(segment
		(start 91.453462 -133.22046)
		(end 91.31046 -133.22046)
		(width 0.127)
		(layer "In2.Cu")
		(net "SAS_SMART_TX")
	)
	(segment
		(start 82.90687 -116.712746)
		(end 84.468716 -116.712746)
		(width 0.127)
		(layer "In2.Cu")
		(net "SAS_SMART_TX")
	)
	(segment
		(start 243.205 -148.717)
		(end 211.201 -148.717)
		(width 0.127)
		(layer "In2.Cu")
		(net "SAS_SMART_TX")
	)
	(segment
		(start 81.145634 -126.754382)
		(end 79.17307 -124.781818)
		(width 0.127)
		(layer "In2.Cu")
		(net "SAS_SMART_TX")
	)
	(segment
		(start 95.822262 -136.804146)
		(end 95.037148 -136.804146)
		(width 0.127)
		(layer "In2.Cu")
		(net "SAS_SMART_TX")
	)
	(segment
		(start 87.64143 -113.540032)
		(end 87.64143 -112.42294)
		(width 0.127)
		(layer "In2.Cu")
		(net "SAS_SMART_TX")
	)
	(segment
		(start 128.472438 -151.3078)
		(end 110.325916 -151.3078)
		(width 0.127)
		(layer "In2.Cu")
		(net "SAS_SMART_TX")
	)
	(segment
		(start 79.17307 -120.446546)
		(end 82.90687 -116.712746)
		(width 0.127)
		(layer "In2.Cu")
		(net "SAS_SMART_TX")
	)
	(segment
		(start 70.57898 -135.43661)
		(end 70.14337 -135.001)
		(width 0.1143)
		(layer "F.Cu")
		(net "XM_DATA6")
	)
	(segment
		(start 102.349808 -87.349838)
		(end 101.861112 -87.838534)
		(width 0.1143)
		(layer "F.Cu")
		(net "XM_DATA6")
	)
	(segment
		(start 70.14337 -135.001)
		(end 69.99097 -135.001)
		(width 0.1143)
		(layer "F.Cu")
		(net "XM_DATA6")
	)
	(segment
		(start 73.47712 -135.892032)
		(end 73.021698 -135.43661)
		(width 0.1143)
		(layer "F.Cu")
		(net "XM_DATA6")
	)
	(segment
		(start 101.15042 -87.838534)
		(end 100.97897 -87.667084)
		(width 0.1143)
		(layer "F.Cu")
		(net "XM_DATA6")
	)
	(segment
		(start 101.861112 -87.838534)
		(end 101.15042 -87.838534)
		(width 0.1143)
		(layer "F.Cu")
		(net "XM_DATA6")
	)
	(segment
		(start 75.786742 -135.892032)
		(end 73.47712 -135.892032)
		(width 0.1143)
		(layer "F.Cu")
		(net "XM_DATA6")
	)
	(segment
		(start 73.021698 -135.43661)
		(end 70.57898 -135.43661)
		(width 0.1143)
		(layer "F.Cu")
		(net "XM_DATA6")
	)
	(via
		(at 69.99097 -135.001)
		(size 0.5588)
		(drill 0.3048)
		(layers "F.Cu" "B.Cu")
		(net "XM_DATA6")
	)
	(via
		(at 100.97897 -87.667084)
		(size 0.508)
		(drill 0.254)
		(layers "F.Cu" "B.Cu")
		(net "XM_DATA6")
	)
	(via
		(at 69.00037 -134.16534)
		(size 0.7112)
		(drill 0.3556)
		(layers "F.Cu" "B.Cu")
		(net "XM_DATA6")
	)
	(segment
		(start 69.06133 -93.20784)
		(end 69.223128 -93.046042)
		(width 0.1143)
		(layer "B.Cu")
		(net "XM_DATA6")
	)
	(segment
		(start 70.354698 -91.914472)
		(end 70.516496 -91.752674)
		(width 0.1143)
		(layer "B.Cu")
		(net "XM_DATA6")
	)
	(segment
		(start 68.37553 -93.168724)
		(end 68.537328 -93.006926)
		(width 0.1143)
		(layer "B.Cu")
		(net "XM_DATA6")
	)
	(segment
		(start 69.54647 -92.561156)
		(end 69.708014 -92.561156)
		(width 0.1143)
		(layer "B.Cu")
		(net "XM_DATA6")
	)
	(segment
		(start 69.184012 -92.360242)
		(end 69.345556 -92.360242)
		(width 0.1143)
		(layer "B.Cu")
		(net "XM_DATA6")
	)
	(segment
		(start 70.315582 -91.227656)
		(end 73.417938 -88.1253)
		(width 0.1143)
		(layer "B.Cu")
		(net "XM_DATA6")
	)
	(segment
		(start 68.537328 -93.006926)
		(end 68.698872 -93.006926)
		(width 0.1143)
		(layer "B.Cu")
		(net "XM_DATA6")
	)
	(segment
		(start 70.516496 -91.752674)
		(end 70.516496 -91.59113)
		(width 0.1143)
		(layer "B.Cu")
		(net "XM_DATA6")
	)
	(segment
		(start 69.223128 -92.884498)
		(end 69.022214 -92.683584)
		(width 0.1143)
		(layer "B.Cu")
		(net "XM_DATA6")
	)
	(segment
		(start 68.576444 -93.692726)
		(end 68.576444 -93.531182)
		(width 0.1143)
		(layer "B.Cu")
		(net "XM_DATA6")
	)
	(segment
		(start 86.29269 -88.1253)
		(end 86.76894 -87.64905)
		(width 0.1143)
		(layer "B.Cu")
		(net "XM_DATA6")
	)
	(segment
		(start 69.00037 -134.16534)
		(end 69.83603 -135.001)
		(width 0.1143)
		(layer "B.Cu")
		(net "XM_DATA6")
	)
	(segment
		(start 70.516496 -91.59113)
		(end 70.315582 -91.390216)
		(width 0.1143)
		(layer "B.Cu")
		(net "XM_DATA6")
	)
	(segment
		(start 69.708014 -92.561156)
		(end 69.869812 -92.399358)
		(width 0.1143)
		(layer "B.Cu")
		(net "XM_DATA6")
	)
	(segment
		(start 68.37553 -93.330268)
		(end 68.37553 -93.168724)
		(width 0.1143)
		(layer "B.Cu")
		(net "XM_DATA6")
	)
	(segment
		(start 68.698872 -93.006926)
		(end 68.899786 -93.20784)
		(width 0.1143)
		(layer "B.Cu")
		(net "XM_DATA6")
	)
	(segment
		(start 68.16852 -94.10065)
		(end 68.576444 -93.692726)
		(width 0.1143)
		(layer "B.Cu")
		(net "XM_DATA6")
	)
	(segment
		(start 69.668898 -92.0369)
		(end 69.668898 -91.875356)
		(width 0.1143)
		(layer "B.Cu")
		(net "XM_DATA6")
	)
	(segment
		(start 68.576444 -93.531182)
		(end 68.37553 -93.330268)
		(width 0.1143)
		(layer "B.Cu")
		(net "XM_DATA6")
	)
	(segment
		(start 69.869812 -92.399358)
		(end 69.869812 -92.237814)
		(width 0.1143)
		(layer "B.Cu")
		(net "XM_DATA6")
	)
	(segment
		(start 69.668898 -91.875356)
		(end 69.830696 -91.713558)
		(width 0.1143)
		(layer "B.Cu")
		(net "XM_DATA6")
	)
	(segment
		(start 70.193154 -91.914472)
		(end 70.354698 -91.914472)
		(width 0.1143)
		(layer "B.Cu")
		(net "XM_DATA6")
	)
	(segment
		(start 100.36302 -87.14105)
		(end 100.889054 -87.667084)
		(width 0.1143)
		(layer "B.Cu")
		(net "XM_DATA6")
	)
	(segment
		(start 69.869812 -92.237814)
		(end 69.668898 -92.0369)
		(width 0.1143)
		(layer "B.Cu")
		(net "XM_DATA6")
	)
	(segment
		(start 100.889054 -87.667084)
		(end 100.97897 -87.667084)
		(width 0.1143)
		(layer "B.Cu")
		(net "XM_DATA6")
	)
	(segment
		(start 69.345556 -92.360242)
		(end 69.54647 -92.561156)
		(width 0.1143)
		(layer "B.Cu")
		(net "XM_DATA6")
	)
	(segment
		(start 68.899786 -93.20784)
		(end 69.06133 -93.20784)
		(width 0.1143)
		(layer "B.Cu")
		(net "XM_DATA6")
	)
	(segment
		(start 98.856038 -87.03945)
		(end 98.957638 -87.14105)
		(width 0.1143)
		(layer "B.Cu")
		(net "XM_DATA6")
	)
	(segment
		(start 69.99224 -91.713558)
		(end 70.193154 -91.914472)
		(width 0.1143)
		(layer "B.Cu")
		(net "XM_DATA6")
	)
	(segment
		(start 69.00037 -134.16534)
		(end 68.16852 -133.33349)
		(width 0.1143)
		(layer "B.Cu")
		(net "XM_DATA6")
	)
	(segment
		(start 93.68155 -87.03945)
		(end 98.856038 -87.03945)
		(width 0.1143)
		(layer "B.Cu")
		(net "XM_DATA6")
	)
	(segment
		(start 69.223128 -93.046042)
		(end 69.223128 -92.884498)
		(width 0.1143)
		(layer "B.Cu")
		(net "XM_DATA6")
	)
	(segment
		(start 68.16852 -133.33349)
		(end 68.16852 -94.10065)
		(width 0.1143)
		(layer "B.Cu")
		(net "XM_DATA6")
	)
	(segment
		(start 69.830696 -91.713558)
		(end 69.99224 -91.713558)
		(width 0.1143)
		(layer "B.Cu")
		(net "XM_DATA6")
	)
	(segment
		(start 98.957638 -87.14105)
		(end 100.36302 -87.14105)
		(width 0.1143)
		(layer "B.Cu")
		(net "XM_DATA6")
	)
	(segment
		(start 73.417938 -88.1253)
		(end 86.29269 -88.1253)
		(width 0.1143)
		(layer "B.Cu")
		(net "XM_DATA6")
	)
	(segment
		(start 69.022214 -92.52204)
		(end 69.184012 -92.360242)
		(width 0.1143)
		(layer "B.Cu")
		(net "XM_DATA6")
	)
	(segment
		(start 93.07195 -87.64905)
		(end 93.68155 -87.03945)
		(width 0.1143)
		(layer "B.Cu")
		(net "XM_DATA6")
	)
	(segment
		(start 69.83603 -135.001)
		(end 69.99097 -135.001)
		(width 0.1143)
		(layer "B.Cu")
		(net "XM_DATA6")
	)
	(segment
		(start 86.76894 -87.64905)
		(end 93.07195 -87.64905)
		(width 0.1143)
		(layer "B.Cu")
		(net "XM_DATA6")
	)
	(segment
		(start 70.315582 -91.390216)
		(end 70.315582 -91.227656)
		(width 0.1143)
		(layer "B.Cu")
		(net "XM_DATA6")
	)
	(segment
		(start 69.022214 -92.683584)
		(end 69.022214 -92.52204)
		(width 0.1143)
		(layer "B.Cu")
		(net "XM_DATA6")
	)
	(segment
		(start 116.713 -28.7655)
		(end 117.602 -29.6545)
		(width 0.1143)
		(layer "F.Cu")
		(net "SYS_HALT1#")
	)
	(segment
		(start 117.602 -29.845)
		(end 116.967 -30.48)
		(width 0.1143)
		(layer "F.Cu")
		(net "SYS_HALT1#")
	)
	(segment
		(start 116.36375 -31.21025)
		(end 111.471964 -31.21025)
		(width 0.1143)
		(layer "F.Cu")
		(net "SYS_HALT1#")
	)
	(segment
		(start 116.967 -30.607)
		(end 116.36375 -31.21025)
		(width 0.1143)
		(layer "F.Cu")
		(net "SYS_HALT1#")
	)
	(segment
		(start 116.967 -30.48)
		(end 116.967 -30.607)
		(width 0.1143)
		(layer "F.Cu")
		(net "SYS_HALT1#")
	)
	(segment
		(start 110.750096 -31.932118)
		(end 110.750096 -33.399984)
		(width 0.1143)
		(layer "F.Cu")
		(net "SYS_HALT1#")
	)
	(segment
		(start 117.602 -29.6545)
		(end 117.602 -29.845)
		(width 0.1143)
		(layer "F.Cu")
		(net "SYS_HALT1#")
	)
	(segment
		(start 111.471964 -31.21025)
		(end 110.750096 -31.932118)
		(width 0.1143)
		(layer "F.Cu")
		(net "SYS_HALT1#")
	)
	(segment
		(start 37.527484 -200.764648)
		(end 38.15715 -200.764648)
		(width 0.1143)
		(layer "F.Cu")
		(net "ADC_P1V5_E")
	)
	(segment
		(start 35.827716 -199.06488)
		(end 37.527484 -200.764648)
		(width 0.1143)
		(layer "F.Cu")
		(net "ADC_P1V5_E")
	)
	(via
		(at 329.184 -186.182)
		(size 0.7112)
		(drill 0.3556)
		(layers "F.Cu" "B.Cu")
		(net "ADC_P1V5_E")
	)
	(via
		(at 38.15715 -200.764648)
		(size 0.5588)
		(drill 0.3048)
		(layers "F.Cu" "B.Cu")
		(net "ADC_P1V5_E")
	)
	(via
		(at 330.324714 -186.179714)
		(size 0.508)
		(drill 0.254)
		(layers "F.Cu" "B.Cu")
		(net "ADC_P1V5_E")
	)
	(segment
		(start 321.429634 -186.39155)
		(end 328.97445 -186.39155)
		(width 0.1143)
		(layer "B.Cu")
		(net "ADC_P1V5_E")
	)
	(segment
		(start 318.9605 -181.737)
		(end 317.9445 -181.737)
		(width 0.1143)
		(layer "B.Cu")
		(net "ADC_P1V5_E")
	)
	(segment
		(start 317.9445 -182.753)
		(end 317.9445 -181.737)
		(width 0.1143)
		(layer "B.Cu")
		(net "ADC_P1V5_E")
	)
	(segment
		(start 328.97445 -186.39155)
		(end 329.184 -186.182)
		(width 0.1143)
		(layer "B.Cu")
		(net "ADC_P1V5_E")
	)
	(segment
		(start 318.9605 -182.753)
		(end 318.9605 -183.922416)
		(width 0.1143)
		(layer "B.Cu")
		(net "ADC_P1V5_E")
	)
	(segment
		(start 318.9605 -183.922416)
		(end 321.429634 -186.39155)
		(width 0.1143)
		(layer "B.Cu")
		(net "ADC_P1V5_E")
	)
	(segment
		(start 329.184 -186.182)
		(end 330.322428 -186.182)
		(width 0.1143)
		(layer "B.Cu")
		(net "ADC_P1V5_E")
	)
	(segment
		(start 318.9605 -181.737)
		(end 318.9605 -182.753)
		(width 0.1143)
		(layer "B.Cu")
		(net "ADC_P1V5_E")
	)
	(segment
		(start 330.322428 -186.182)
		(end 330.324714 -186.179714)
		(width 0.1143)
		(layer "B.Cu")
		(net "ADC_P1V5_E")
	)
	(segment
		(start 274.531582 -239.268)
		(end 273.763232 -240.03635)
		(width 0.127)
		(layer "In2.Cu")
		(net "ADC_P1V5_E")
	)
	(segment
		(start 256.544064 -227.162868)
		(end 256.544064 -226.752404)
		(width 0.127)
		(layer "In2.Cu")
		(net "ADC_P1V5_E")
	)
	(segment
		(start 263.340596 -240.03635)
		(end 257.175 -233.870754)
		(width 0.127)
		(layer "In2.Cu")
		(net "ADC_P1V5_E")
	)
	(segment
		(start 257.175 -227.793804)
		(end 256.544064 -227.162868)
		(width 0.127)
		(layer "In2.Cu")
		(net "ADC_P1V5_E")
	)
	(segment
		(start 330.324714 -186.179714)
		(end 330.324714 -186.184286)
		(width 0.127)
		(layer "In2.Cu")
		(net "ADC_P1V5_E")
	)
	(segment
		(start 38.273482 -200.88098)
		(end 38.15715 -200.764648)
		(width 0.127)
		(layer "In2.Cu")
		(net "ADC_P1V5_E")
	)
	(segment
		(start 328.549 -187.96)
		(end 328.549 -206.694532)
		(width 0.127)
		(layer "In2.Cu")
		(net "ADC_P1V5_E")
	)
	(segment
		(start 231.87152 -189.2808)
		(end 214.717884 -206.434436)
		(width 0.127)
		(layer "In2.Cu")
		(net "ADC_P1V5_E")
	)
	(segment
		(start 257.4163 -194.632072)
		(end 252.065028 -189.2808)
		(width 0.127)
		(layer "In2.Cu")
		(net "ADC_P1V5_E")
	)
	(segment
		(start 330.324714 -186.184286)
		(end 328.549 -187.96)
		(width 0.127)
		(layer "In2.Cu")
		(net "ADC_P1V5_E")
	)
	(segment
		(start 214.717884 -206.434436)
		(end 149.919436 -206.434436)
		(width 0.127)
		(layer "In2.Cu")
		(net "ADC_P1V5_E")
	)
	(segment
		(start 144.36598 -200.88098)
		(end 38.273482 -200.88098)
		(width 0.127)
		(layer "In2.Cu")
		(net "ADC_P1V5_E")
	)
	(segment
		(start 328.549 -206.694532)
		(end 295.975532 -239.268)
		(width 0.127)
		(layer "In2.Cu")
		(net "ADC_P1V5_E")
	)
	(segment
		(start 252.065028 -189.2808)
		(end 231.87152 -189.2808)
		(width 0.127)
		(layer "In2.Cu")
		(net "ADC_P1V5_E")
	)
	(segment
		(start 257.4163 -225.880168)
		(end 257.4163 -194.632072)
		(width 0.127)
		(layer "In2.Cu")
		(net "ADC_P1V5_E")
	)
	(segment
		(start 295.975532 -239.268)
		(end 274.531582 -239.268)
		(width 0.127)
		(layer "In2.Cu")
		(net "ADC_P1V5_E")
	)
	(segment
		(start 256.544064 -226.752404)
		(end 257.4163 -225.880168)
		(width 0.127)
		(layer "In2.Cu")
		(net "ADC_P1V5_E")
	)
	(segment
		(start 149.919436 -206.434436)
		(end 144.36598 -200.88098)
		(width 0.127)
		(layer "In2.Cu")
		(net "ADC_P1V5_E")
	)
	(segment
		(start 273.763232 -240.03635)
		(end 263.340596 -240.03635)
		(width 0.127)
		(layer "In2.Cu")
		(net "ADC_P1V5_E")
	)
	(segment
		(start 257.175 -233.870754)
		(end 257.175 -227.793804)
		(width 0.127)
		(layer "In2.Cu")
		(net "ADC_P1V5_E")
	)
	(segment
		(start 98.46056 -96.998536)
		(end 98.46056 -97.53473)
		(width 0.1143)
		(layer "F.Cu")
		(net "EXP_XM_ADDR_13")
	)
	(segment
		(start 102.90683 -95.350076)
		(end 102.51948 -94.962726)
		(width 0.1143)
		(layer "F.Cu")
		(net "EXP_XM_ADDR_13")
	)
	(segment
		(start 102.51948 -94.962726)
		(end 101.032564 -94.962726)
		(width 0.1143)
		(layer "F.Cu")
		(net "EXP_XM_ADDR_13")
	)
	(segment
		(start 99.959922 -95.499174)
		(end 98.46056 -96.998536)
		(width 0.1143)
		(layer "F.Cu")
		(net "EXP_XM_ADDR_13")
	)
	(segment
		(start 103.349806 -95.350076)
		(end 102.90683 -95.350076)
		(width 0.1143)
		(layer "F.Cu")
		(net "EXP_XM_ADDR_13")
	)
	(segment
		(start 101.032564 -94.962726)
		(end 100.496116 -95.499174)
		(width 0.1143)
		(layer "F.Cu")
		(net "EXP_XM_ADDR_13")
	)
	(segment
		(start 69.003672 -137.391902)
		(end 69.06387 -137.4521)
		(width 0.1143)
		(layer "F.Cu")
		(net "EXP_XM_ADDR_13")
	)
	(segment
		(start 56.558942 -137.391902)
		(end 69.003672 -137.391902)
		(width 0.1143)
		(layer "F.Cu")
		(net "EXP_XM_ADDR_13")
	)
	(segment
		(start 69.06387 -137.4521)
		(end 69.233034 -137.4521)
		(width 0.1143)
		(layer "F.Cu")
		(net "EXP_XM_ADDR_13")
	)
	(segment
		(start 98.46056 -97.53473)
		(end 98.36531 -97.62998)
		(width 0.1143)
		(layer "F.Cu")
		(net "EXP_XM_ADDR_13")
	)
	(segment
		(start 100.496116 -95.499174)
		(end 99.959922 -95.499174)
		(width 0.1143)
		(layer "F.Cu")
		(net "EXP_XM_ADDR_13")
	)
	(via
		(at 98.36531 -97.62998)
		(size 0.508)
		(drill 0.254)
		(layers "F.Cu" "B.Cu")
		(net "EXP_XM_ADDR_13")
	)
	(via
		(at 70.612 -138.0998)
		(size 0.7112)
		(drill 0.3556)
		(layers "F.Cu" "B.Cu")
		(net "EXP_XM_ADDR_13")
	)
	(via
		(at 69.233034 -137.4521)
		(size 0.5588)
		(drill 0.3048)
		(layers "F.Cu" "B.Cu")
		(net "EXP_XM_ADDR_13")
	)
	(segment
		(start 70.612 -138.0998)
		(end 69.880734 -138.0998)
		(width 0.1143)
		(layer "B.Cu")
		(net "EXP_XM_ADDR_13")
	)
	(segment
		(start 69.880734 -138.0998)
		(end 69.233034 -137.4521)
		(width 0.1143)
		(layer "B.Cu")
		(net "EXP_XM_ADDR_13")
	)
	(segment
		(start 82.135726 -109.00664)
		(end 82.135726 -108.826808)
		(width 0.127)
		(layer "In2.Cu")
		(net "EXP_XM_ADDR_13")
	)
	(segment
		(start 94.629732 -101.156008)
		(end 98.15576 -97.62998)
		(width 0.127)
		(layer "In2.Cu")
		(net "EXP_XM_ADDR_13")
	)
	(segment
		(start 81.203292 -110.949486)
		(end 80.698086 -110.44428)
		(width 0.127)
		(layer "In2.Cu")
		(net "EXP_XM_ADDR_13")
	)
	(segment
		(start 82.640932 -109.511846)
		(end 82.135726 -109.00664)
		(width 0.127)
		(layer "In2.Cu")
		(net "EXP_XM_ADDR_13")
	)
	(segment
		(start 69.233034 -137.4521)
		(end 69.49567 -137.189464)
		(width 0.127)
		(layer "In2.Cu")
		(net "EXP_XM_ADDR_13")
	)
	(segment
		(start 80.698086 -110.264448)
		(end 80.877664 -110.08487)
		(width 0.127)
		(layer "In2.Cu")
		(net "EXP_XM_ADDR_13")
	)
	(segment
		(start 81.922112 -110.410498)
		(end 81.922112 -110.230666)
		(width 0.127)
		(layer "In2.Cu")
		(net "EXP_XM_ADDR_13")
	)
	(segment
		(start 98.15576 -97.62998)
		(end 98.36531 -97.62998)
		(width 0.127)
		(layer "In2.Cu")
		(net "EXP_XM_ADDR_13")
	)
	(segment
		(start 90.735404 -102.021894)
		(end 91.587828 -102.874318)
		(width 0.127)
		(layer "In2.Cu")
		(net "EXP_XM_ADDR_13")
	)
	(segment
		(start 83.000342 -109.152436)
		(end 83.180174 -109.152436)
		(width 0.127)
		(layer "In2.Cu")
		(net "EXP_XM_ADDR_13")
	)
	(segment
		(start 69.69887 -133.61162)
		(end 70.36181 -132.94868)
		(width 0.127)
		(layer "In2.Cu")
		(net "EXP_XM_ADDR_13")
	)
	(segment
		(start 88.84793 -103.729536)
		(end 89.117932 -103.459534)
		(width 0.127)
		(layer "In2.Cu")
		(net "EXP_XM_ADDR_13")
	)
	(segment
		(start 80.843882 -111.308896)
		(end 81.023714 -111.308896)
		(width 0.127)
		(layer "In2.Cu")
		(net "EXP_XM_ADDR_13")
	)
	(segment
		(start 70.36181 -132.94868)
		(end 70.36181 -130.615182)
		(width 0.127)
		(layer "In2.Cu")
		(net "EXP_XM_ADDR_13")
	)
	(segment
		(start 89.657174 -102.920292)
		(end 89.836752 -102.740714)
		(width 0.127)
		(layer "In2.Cu")
		(net "EXP_XM_ADDR_13")
	)
	(segment
		(start 82.315304 -108.64723)
		(end 82.495136 -108.64723)
		(width 0.127)
		(layer "In2.Cu")
		(net "EXP_XM_ADDR_13")
	)
	(segment
		(start 89.117932 -103.459534)
		(end 89.297764 -103.459534)
		(width 0.127)
		(layer "In2.Cu")
		(net "EXP_XM_ADDR_13")
	)
	(segment
		(start 79.979266 -110.983268)
		(end 80.158844 -110.80369)
		(width 0.127)
		(layer "In2.Cu")
		(net "EXP_XM_ADDR_13")
	)
	(segment
		(start 91.947238 -102.69474)
		(end 91.947238 -102.514908)
		(width 0.127)
		(layer "In2.Cu")
		(net "EXP_XM_ADDR_13")
	)
	(segment
		(start 91.228418 -103.41356)
		(end 91.228418 -103.233728)
		(width 0.127)
		(layer "In2.Cu")
		(net "EXP_XM_ADDR_13")
	)
	(segment
		(start 86.240366 -108.40212)
		(end 88.84793 -105.794556)
		(width 0.127)
		(layer "In2.Cu")
		(net "EXP_XM_ADDR_13")
	)
	(segment
		(start 91.094814 -101.662484)
		(end 91.094814 -101.482652)
		(width 0.127)
		(layer "In2.Cu")
		(net "EXP_XM_ADDR_13")
	)
	(segment
		(start 90.509598 -104.13238)
		(end 90.509598 -103.952548)
		(width 0.127)
		(layer "In2.Cu")
		(net "EXP_XM_ADDR_13")
	)
	(segment
		(start 88.84793 -105.794556)
		(end 88.84793 -103.729536)
		(width 0.127)
		(layer "In2.Cu")
		(net "EXP_XM_ADDR_13")
	)
	(segment
		(start 82.135726 -108.826808)
		(end 82.315304 -108.64723)
		(width 0.127)
		(layer "In2.Cu")
		(net "EXP_XM_ADDR_13")
	)
	(segment
		(start 69.49567 -134.795768)
		(end 69.69887 -134.592568)
		(width 0.127)
		(layer "In2.Cu")
		(net "EXP_XM_ADDR_13")
	)
	(segment
		(start 90.375994 -102.201472)
		(end 90.555572 -102.021894)
		(width 0.127)
		(layer "In2.Cu")
		(net "EXP_XM_ADDR_13")
	)
	(segment
		(start 91.094814 -101.482652)
		(end 91.421458 -101.156008)
		(width 0.127)
		(layer "In2.Cu")
		(net "EXP_XM_ADDR_13")
	)
	(segment
		(start 80.698086 -110.44428)
		(end 80.698086 -110.264448)
		(width 0.127)
		(layer "In2.Cu")
		(net "EXP_XM_ADDR_13")
	)
	(segment
		(start 82.281522 -109.871256)
		(end 82.461354 -109.871256)
		(width 0.127)
		(layer "In2.Cu")
		(net "EXP_XM_ADDR_13")
	)
	(segment
		(start 71.52005 -129.456434)
		(end 71.954644 -129.021586)
		(width 0.127)
		(layer "In2.Cu")
		(net "EXP_XM_ADDR_13")
	)
	(segment
		(start 91.421458 -101.156008)
		(end 94.629732 -101.156008)
		(width 0.127)
		(layer "In2.Cu")
		(net "EXP_XM_ADDR_13")
	)
	(segment
		(start 80.877664 -110.08487)
		(end 81.057496 -110.08487)
		(width 0.127)
		(layer "In2.Cu")
		(net "EXP_XM_ADDR_13")
	)
	(segment
		(start 81.742534 -110.590076)
		(end 81.922112 -110.410498)
		(width 0.127)
		(layer "In2.Cu")
		(net "EXP_XM_ADDR_13")
	)
	(segment
		(start 90.869008 -103.593138)
		(end 91.04884 -103.593138)
		(width 0.127)
		(layer "In2.Cu")
		(net "EXP_XM_ADDR_13")
	)
	(segment
		(start 81.023714 -111.308896)
		(end 81.203292 -111.129318)
		(width 0.127)
		(layer "In2.Cu")
		(net "EXP_XM_ADDR_13")
	)
	(segment
		(start 89.657174 -103.100124)
		(end 89.657174 -102.920292)
		(width 0.127)
		(layer "In2.Cu")
		(net "EXP_XM_ADDR_13")
	)
	(segment
		(start 90.375994 -102.381304)
		(end 90.375994 -102.201472)
		(width 0.127)
		(layer "In2.Cu")
		(net "EXP_XM_ADDR_13")
	)
	(segment
		(start 71.95439 -128.389888)
		(end 71.95439 -120.37822)
		(width 0.127)
		(layer "In2.Cu")
		(net "EXP_XM_ADDR_13")
	)
	(segment
		(start 71.95439 -120.37822)
		(end 80.484472 -111.848138)
		(width 0.127)
		(layer "In2.Cu")
		(net "EXP_XM_ADDR_13")
	)
	(segment
		(start 91.947238 -102.514908)
		(end 91.094814 -101.662484)
		(width 0.127)
		(layer "In2.Cu")
		(net "EXP_XM_ADDR_13")
	)
	(segment
		(start 71.954644 -129.021586)
		(end 71.954644 -128.390142)
		(width 0.127)
		(layer "In2.Cu")
		(net "EXP_XM_ADDR_13")
	)
	(segment
		(start 90.150188 -104.311958)
		(end 90.33002 -104.311958)
		(width 0.127)
		(layer "In2.Cu")
		(net "EXP_XM_ADDR_13")
	)
	(segment
		(start 89.297764 -103.459534)
		(end 90.150188 -104.311958)
		(width 0.127)
		(layer "In2.Cu")
		(net "EXP_XM_ADDR_13")
	)
	(segment
		(start 81.057496 -110.08487)
		(end 81.562702 -110.590076)
		(width 0.127)
		(layer "In2.Cu")
		(net "EXP_XM_ADDR_13")
	)
	(segment
		(start 71.230236 -129.746502)
		(end 71.52005 -129.456434)
		(width 0.127)
		(layer "In2.Cu")
		(net "EXP_XM_ADDR_13")
	)
	(segment
		(start 69.49567 -137.189464)
		(end 69.49567 -134.795768)
		(width 0.127)
		(layer "In2.Cu")
		(net "EXP_XM_ADDR_13")
	)
	(segment
		(start 90.509598 -103.952548)
		(end 89.657174 -103.100124)
		(width 0.127)
		(layer "In2.Cu")
		(net "EXP_XM_ADDR_13")
	)
	(segment
		(start 90.016584 -102.740714)
		(end 90.869008 -103.593138)
		(width 0.127)
		(layer "In2.Cu")
		(net "EXP_XM_ADDR_13")
	)
	(segment
		(start 81.922112 -110.230666)
		(end 81.416906 -109.72546)
		(width 0.127)
		(layer "In2.Cu")
		(net "EXP_XM_ADDR_13")
	)
	(segment
		(start 91.587828 -102.874318)
		(end 91.76766 -102.874318)
		(width 0.127)
		(layer "In2.Cu")
		(net "EXP_XM_ADDR_13")
	)
	(segment
		(start 82.495136 -108.64723)
		(end 83.000342 -109.152436)
		(width 0.127)
		(layer "In2.Cu")
		(net "EXP_XM_ADDR_13")
	)
	(segment
		(start 70.36181 -130.615182)
		(end 71.230236 -129.746502)
		(width 0.127)
		(layer "In2.Cu")
		(net "EXP_XM_ADDR_13")
	)
	(segment
		(start 71.954644 -128.390142)
		(end 71.95439 -128.389888)
		(width 0.127)
		(layer "In2.Cu")
		(net "EXP_XM_ADDR_13")
	)
	(segment
		(start 80.484472 -111.848138)
		(end 80.484472 -111.668306)
		(width 0.127)
		(layer "In2.Cu")
		(net "EXP_XM_ADDR_13")
	)
	(segment
		(start 81.562702 -110.590076)
		(end 81.742534 -110.590076)
		(width 0.127)
		(layer "In2.Cu")
		(net "EXP_XM_ADDR_13")
	)
	(segment
		(start 79.979266 -111.1631)
		(end 79.979266 -110.983268)
		(width 0.127)
		(layer "In2.Cu")
		(net "EXP_XM_ADDR_13")
	)
	(segment
		(start 90.33002 -104.311958)
		(end 90.509598 -104.13238)
		(width 0.127)
		(layer "In2.Cu")
		(net "EXP_XM_ADDR_13")
	)
	(segment
		(start 91.04884 -103.593138)
		(end 91.228418 -103.41356)
		(width 0.127)
		(layer "In2.Cu")
		(net "EXP_XM_ADDR_13")
	)
	(segment
		(start 80.338676 -110.80369)
		(end 80.843882 -111.308896)
		(width 0.127)
		(layer "In2.Cu")
		(net "EXP_XM_ADDR_13")
	)
	(segment
		(start 91.76766 -102.874318)
		(end 91.947238 -102.69474)
		(width 0.127)
		(layer "In2.Cu")
		(net "EXP_XM_ADDR_13")
	)
	(segment
		(start 82.461354 -109.871256)
		(end 82.640932 -109.691678)
		(width 0.127)
		(layer "In2.Cu")
		(net "EXP_XM_ADDR_13")
	)
	(segment
		(start 81.416906 -109.72546)
		(end 81.416906 -109.545628)
		(width 0.127)
		(layer "In2.Cu")
		(net "EXP_XM_ADDR_13")
	)
	(segment
		(start 69.69887 -134.592568)
		(end 69.69887 -133.61162)
		(width 0.127)
		(layer "In2.Cu")
		(net "EXP_XM_ADDR_13")
	)
	(segment
		(start 81.596484 -109.36605)
		(end 81.776316 -109.36605)
		(width 0.127)
		(layer "In2.Cu")
		(net "EXP_XM_ADDR_13")
	)
	(segment
		(start 81.203292 -111.129318)
		(end 81.203292 -110.949486)
		(width 0.127)
		(layer "In2.Cu")
		(net "EXP_XM_ADDR_13")
	)
	(segment
		(start 81.416906 -109.545628)
		(end 81.596484 -109.36605)
		(width 0.127)
		(layer "In2.Cu")
		(net "EXP_XM_ADDR_13")
	)
	(segment
		(start 80.484472 -111.668306)
		(end 79.979266 -111.1631)
		(width 0.127)
		(layer "In2.Cu")
		(net "EXP_XM_ADDR_13")
	)
	(segment
		(start 80.158844 -110.80369)
		(end 80.338676 -110.80369)
		(width 0.127)
		(layer "In2.Cu")
		(net "EXP_XM_ADDR_13")
	)
	(segment
		(start 83.180174 -109.152436)
		(end 83.93049 -108.40212)
		(width 0.127)
		(layer "In2.Cu")
		(net "EXP_XM_ADDR_13")
	)
	(segment
		(start 82.640932 -109.691678)
		(end 82.640932 -109.511846)
		(width 0.127)
		(layer "In2.Cu")
		(net "EXP_XM_ADDR_13")
	)
	(segment
		(start 81.776316 -109.36605)
		(end 82.281522 -109.871256)
		(width 0.127)
		(layer "In2.Cu")
		(net "EXP_XM_ADDR_13")
	)
	(segment
		(start 91.228418 -103.233728)
		(end 90.375994 -102.381304)
		(width 0.127)
		(layer "In2.Cu")
		(net "EXP_XM_ADDR_13")
	)
	(segment
		(start 90.555572 -102.021894)
		(end 90.735404 -102.021894)
		(width 0.127)
		(layer "In2.Cu")
		(net "EXP_XM_ADDR_13")
	)
	(segment
		(start 89.836752 -102.740714)
		(end 90.016584 -102.740714)
		(width 0.127)
		(layer "In2.Cu")
		(net "EXP_XM_ADDR_13")
	)
	(segment
		(start 83.93049 -108.40212)
		(end 86.240366 -108.40212)
		(width 0.127)
		(layer "In2.Cu")
		(net "EXP_XM_ADDR_13")
	)
	(segment
		(start 113.754154 -46.657006)
		(end 113.411254 -46.999906)
		(width 0.1143)
		(layer "F.Cu")
		(net "MEM_CLK_SEL")
	)
	(segment
		(start 116.449094 -48.2092)
		(end 116.161566 -48.2092)
		(width 0.1143)
		(layer "F.Cu")
		(net "MEM_CLK_SEL")
	)
	(segment
		(start 113.411254 -46.999906)
		(end 113.150142 -46.999906)
		(width 0.1143)
		(layer "F.Cu")
		(net "MEM_CLK_SEL")
	)
	(segment
		(start 116.459 -48.199294)
		(end 116.449094 -48.2092)
		(width 0.1143)
		(layer "F.Cu")
		(net "MEM_CLK_SEL")
	)
	(segment
		(start 116.466366 -48.199294)
		(end 116.459 -48.199294)
		(width 0.1143)
		(layer "F.Cu")
		(net "MEM_CLK_SEL")
	)
	(segment
		(start 117.393466 -48.133)
		(end 117.317266 -48.2092)
		(width 0.1143)
		(layer "F.Cu")
		(net "MEM_CLK_SEL")
	)
	(segment
		(start 116.476272 -48.2092)
		(end 116.466366 -48.199294)
		(width 0.1143)
		(layer "F.Cu")
		(net "MEM_CLK_SEL")
	)
	(segment
		(start 114.609372 -46.657006)
		(end 113.754154 -46.657006)
		(width 0.1143)
		(layer "F.Cu")
		(net "MEM_CLK_SEL")
	)
	(segment
		(start 117.317266 -48.2092)
		(end 116.476272 -48.2092)
		(width 0.1143)
		(layer "F.Cu")
		(net "MEM_CLK_SEL")
	)
	(segment
		(start 116.161566 -48.2092)
		(end 114.609372 -46.657006)
		(width 0.1143)
		(layer "F.Cu")
		(net "MEM_CLK_SEL")
	)
	(via
		(at 116.466366 -48.199294)
		(size 0.7112)
		(drill 0.3556)
		(layers "F.Cu" "B.Cu")
		(net "MEM_CLK_SEL")
	)
	(segment
		(start 299.634656 -176.639982)
		(end 299.634656 -176.648364)
		(width 0.1143)
		(layer "F.Cu")
		(net "ADC_P0V9_E_BMC")
	)
	(segment
		(start 299.23486 -176.240186)
		(end 299.634656 -176.639982)
		(width 0.1143)
		(layer "F.Cu")
		(net "ADC_P0V9_E_BMC")
	)
	(via
		(at 313.817 -180.721)
		(size 0.7112)
		(drill 0.3556)
		(layers "F.Cu" "B.Cu")
		(net "ADC_P0V9_E_BMC")
	)
	(via
		(at 299.634656 -176.648364)
		(size 0.508)
		(drill 0.254)
		(layers "F.Cu" "B.Cu")
		(net "ADC_P0V9_E_BMC")
	)
	(segment
		(start 312.928 -180.721)
		(end 313.817 -180.721)
		(width 0.1143)
		(layer "B.Cu")
		(net "ADC_P0V9_E_BMC")
	)
	(segment
		(start 308.51983 -176.31283)
		(end 312.928 -180.721)
		(width 0.1143)
		(layer "B.Cu")
		(net "ADC_P0V9_E_BMC")
	)
	(segment
		(start 301.491396 -176.31283)
		(end 308.51983 -176.31283)
		(width 0.1143)
		(layer "B.Cu")
		(net "ADC_P0V9_E_BMC")
	)
	(segment
		(start 299.634656 -176.648364)
		(end 299.811186 -176.471834)
		(width 0.1143)
		(layer "B.Cu")
		(net "ADC_P0V9_E_BMC")
	)
	(segment
		(start 299.811186 -176.471834)
		(end 300.009814 -176.471834)
		(width 0.1143)
		(layer "B.Cu")
		(net "ADC_P0V9_E_BMC")
	)
	(segment
		(start 313.817 -180.721)
		(end 317.5635 -180.721)
		(width 0.1143)
		(layer "B.Cu")
		(net "ADC_P0V9_E_BMC")
	)
	(segment
		(start 301.401226 -176.22266)
		(end 301.491396 -176.31283)
		(width 0.1143)
		(layer "B.Cu")
		(net "ADC_P0V9_E_BMC")
	)
	(segment
		(start 300.258988 -176.22266)
		(end 301.401226 -176.22266)
		(width 0.1143)
		(layer "B.Cu")
		(net "ADC_P0V9_E_BMC")
	)
	(segment
		(start 300.009814 -176.471834)
		(end 300.258988 -176.22266)
		(width 0.1143)
		(layer "B.Cu")
		(net "ADC_P0V9_E_BMC")
	)
	(segment
		(start 67.86245 -132.62864)
		(end 67.97675 -132.74294)
		(width 0.1143)
		(layer "F.Cu")
		(net "EXP_XM_ADDR_20")
	)
	(segment
		(start 67.236848 -133.485382)
		(end 67.236848 -133.646926)
		(width 0.1143)
		(layer "F.Cu")
		(net "EXP_XM_ADDR_20")
	)
	(segment
		(start 66.35369 -135.39724)
		(end 67.85483 -133.8961)
		(width 0.1143)
		(layer "F.Cu")
		(net "EXP_XM_ADDR_20")
	)
	(segment
		(start 67.52209 -132.51434)
		(end 67.63639 -132.62864)
		(width 0.1143)
		(layer "F.Cu")
		(net "EXP_XM_ADDR_20")
	)
	(segment
		(start 67.005454 -134.062216)
		(end 66.913506 -133.970268)
		(width 0.1143)
		(layer "F.Cu")
		(net "EXP_XM_ADDR_20")
	)
	(segment
		(start 66.913506 -133.970268)
		(end 66.751962 -133.970268)
		(width 0.1143)
		(layer "F.Cu")
		(net "EXP_XM_ADDR_20")
	)
	(segment
		(start 62.829186 -134.892542)
		(end 63.006478 -134.71525)
		(width 0.1143)
		(layer "F.Cu")
		(net "EXP_XM_ADDR_20")
	)
	(segment
		(start 67.85483 -133.8961)
		(end 67.86499 -133.8961)
		(width 0.1143)
		(layer "F.Cu")
		(net "EXP_XM_ADDR_20")
	)
	(segment
		(start 68.34505 -131.27736)
		(end 68.25107 -131.18338)
		(width 0.1143)
		(layer "F.Cu")
		(net "EXP_XM_ADDR_20")
	)
	(segment
		(start 68.25107 -131.18338)
		(end 67.64909 -131.18338)
		(width 0.1143)
		(layer "F.Cu")
		(net "EXP_XM_ADDR_20")
	)
	(segment
		(start 63.411862 -134.71525)
		(end 63.454026 -134.757414)
		(width 0.1143)
		(layer "F.Cu")
		(net "EXP_XM_ADDR_20")
	)
	(segment
		(start 66.751962 -133.970268)
		(end 66.590164 -134.132066)
		(width 0.1143)
		(layer "F.Cu")
		(net "EXP_XM_ADDR_20")
	)
	(segment
		(start 67.328796 -133.738874)
		(end 67.328796 -133.900418)
		(width 0.1143)
		(layer "F.Cu")
		(net "EXP_XM_ADDR_20")
	)
	(segment
		(start 102.349808 -93.349826)
		(end 100.706936 -93.349826)
		(width 0.1143)
		(layer "F.Cu")
		(net "EXP_XM_ADDR_20")
	)
	(segment
		(start 66.266822 -134.616952)
		(end 66.105278 -134.616952)
		(width 0.1143)
		(layer "F.Cu")
		(net "EXP_XM_ADDR_20")
	)
	(segment
		(start 65.844166 -134.878064)
		(end 65.03797 -134.878064)
		(width 0.1143)
		(layer "F.Cu")
		(net "EXP_XM_ADDR_20")
	)
	(segment
		(start 63.006478 -134.71525)
		(end 63.411862 -134.71525)
		(width 0.1143)
		(layer "F.Cu")
		(net "EXP_XM_ADDR_20")
	)
	(segment
		(start 67.86245 -133.08584)
		(end 67.63639 -133.08584)
		(width 0.1143)
		(layer "F.Cu")
		(net "EXP_XM_ADDR_20")
	)
	(segment
		(start 63.773304 -134.757414)
		(end 64.41313 -135.39724)
		(width 0.1143)
		(layer "F.Cu")
		(net "EXP_XM_ADDR_20")
	)
	(segment
		(start 67.236848 -133.646926)
		(end 67.328796 -133.738874)
		(width 0.1143)
		(layer "F.Cu")
		(net "EXP_XM_ADDR_20")
	)
	(segment
		(start 56.558942 -134.892542)
		(end 62.829186 -134.892542)
		(width 0.1143)
		(layer "F.Cu")
		(net "EXP_XM_ADDR_20")
	)
	(segment
		(start 66.682112 -134.547102)
		(end 66.520314 -134.7089)
		(width 0.1143)
		(layer "F.Cu")
		(net "EXP_XM_ADDR_20")
	)
	(segment
		(start 67.86499 -133.8961)
		(end 68.34505 -133.41604)
		(width 0.1143)
		(layer "F.Cu")
		(net "EXP_XM_ADDR_20")
	)
	(segment
		(start 66.590164 -134.29361)
		(end 66.682112 -134.385558)
		(width 0.1143)
		(layer "F.Cu")
		(net "EXP_XM_ADDR_20")
	)
	(segment
		(start 68.34505 -133.41604)
		(end 68.34505 -131.27736)
		(width 0.1143)
		(layer "F.Cu")
		(net "EXP_XM_ADDR_20")
	)
	(segment
		(start 66.520314 -134.7089)
		(end 66.35877 -134.7089)
		(width 0.1143)
		(layer "F.Cu")
		(net "EXP_XM_ADDR_20")
	)
	(segment
		(start 66.682112 -134.385558)
		(end 66.682112 -134.547102)
		(width 0.1143)
		(layer "F.Cu")
		(net "EXP_XM_ADDR_20")
	)
	(segment
		(start 67.52209 -131.31038)
		(end 67.52209 -132.51434)
		(width 0.1143)
		(layer "F.Cu")
		(net "EXP_XM_ADDR_20")
	)
	(segment
		(start 66.590164 -134.132066)
		(end 66.590164 -134.29361)
		(width 0.1143)
		(layer "F.Cu")
		(net "EXP_XM_ADDR_20")
	)
	(segment
		(start 67.166998 -134.062216)
		(end 67.005454 -134.062216)
		(width 0.1143)
		(layer "F.Cu")
		(net "EXP_XM_ADDR_20")
	)
	(segment
		(start 63.454026 -134.757414)
		(end 63.773304 -134.757414)
		(width 0.1143)
		(layer "F.Cu")
		(net "EXP_XM_ADDR_20")
	)
	(segment
		(start 67.97675 -132.97154)
		(end 67.86245 -133.08584)
		(width 0.1143)
		(layer "F.Cu")
		(net "EXP_XM_ADDR_20")
	)
	(segment
		(start 67.328796 -133.900418)
		(end 67.166998 -134.062216)
		(width 0.1143)
		(layer "F.Cu")
		(net "EXP_XM_ADDR_20")
	)
	(segment
		(start 66.105278 -134.616952)
		(end 65.844166 -134.878064)
		(width 0.1143)
		(layer "F.Cu")
		(net "EXP_XM_ADDR_20")
	)
	(segment
		(start 67.63639 -132.62864)
		(end 67.86245 -132.62864)
		(width 0.1143)
		(layer "F.Cu")
		(net "EXP_XM_ADDR_20")
	)
	(segment
		(start 67.63639 -133.08584)
		(end 67.236848 -133.485382)
		(width 0.1143)
		(layer "F.Cu")
		(net "EXP_XM_ADDR_20")
	)
	(segment
		(start 67.97675 -132.74294)
		(end 67.97675 -132.97154)
		(width 0.1143)
		(layer "F.Cu")
		(net "EXP_XM_ADDR_20")
	)
	(segment
		(start 100.706936 -93.349826)
		(end 100.54717 -93.19006)
		(width 0.1143)
		(layer "F.Cu")
		(net "EXP_XM_ADDR_20")
	)
	(segment
		(start 64.41313 -135.39724)
		(end 66.35369 -135.39724)
		(width 0.1143)
		(layer "F.Cu")
		(net "EXP_XM_ADDR_20")
	)
	(segment
		(start 67.64909 -131.18338)
		(end 67.52209 -131.31038)
		(width 0.1143)
		(layer "F.Cu")
		(net "EXP_XM_ADDR_20")
	)
	(segment
		(start 66.35877 -134.7089)
		(end 66.266822 -134.616952)
		(width 0.1143)
		(layer "F.Cu")
		(net "EXP_XM_ADDR_20")
	)
	(via
		(at 100.54717 -93.19006)
		(size 0.508)
		(drill 0.254)
		(layers "F.Cu" "B.Cu")
		(net "EXP_XM_ADDR_20")
	)
	(via
		(at 65.03797 -134.878064)
		(size 0.5588)
		(drill 0.3048)
		(layers "F.Cu" "B.Cu")
		(net "EXP_XM_ADDR_20")
	)
	(via
		(at 64.980566 -134.092696)
		(size 0.7112)
		(drill 0.3556)
		(layers "F.Cu" "B.Cu")
		(net "EXP_XM_ADDR_20")
	)
	(segment
		(start 64.98209 -134.09422)
		(end 64.980566 -134.092696)
		(width 0.1143)
		(layer "B.Cu")
		(net "EXP_XM_ADDR_20")
	)
	(segment
		(start 64.98209 -134.822184)
		(end 64.98209 -134.09422)
		(width 0.1143)
		(layer "B.Cu")
		(net "EXP_XM_ADDR_20")
	)
	(segment
		(start 65.03797 -134.878064)
		(end 64.98209 -134.822184)
		(width 0.1143)
		(layer "B.Cu")
		(net "EXP_XM_ADDR_20")
	)
	(segment
		(start 88.990424 -93.93174)
		(end 94.234254 -93.93174)
		(width 0.127)
		(layer "In2.Cu")
		(net "EXP_XM_ADDR_20")
	)
	(segment
		(start 65.30467 -133.11378)
		(end 65.310766 -133.107684)
		(width 0.127)
		(layer "In2.Cu")
		(net "EXP_XM_ADDR_20")
	)
	(segment
		(start 97.517204 -93.725492)
		(end 100.011738 -93.725492)
		(width 0.127)
		(layer "In2.Cu")
		(net "EXP_XM_ADDR_20")
	)
	(segment
		(start 94.234254 -93.93174)
		(end 94.440502 -93.725492)
		(width 0.127)
		(layer "In2.Cu")
		(net "EXP_XM_ADDR_20")
	)
	(segment
		(start 97.009204 -93.1291)
		(end 97.263204 -93.1291)
		(width 0.127)
		(layer "In2.Cu")
		(net "EXP_XM_ADDR_20")
	)
	(segment
		(start 65.20307 -126.409196)
		(end 65.45707 -126.155196)
		(width 0.127)
		(layer "In2.Cu")
		(net "EXP_XM_ADDR_20")
	)
	(segment
		(start 95.866204 -93.2561)
		(end 95.993204 -93.1291)
		(width 0.127)
		(layer "In2.Cu")
		(net "EXP_XM_ADDR_20")
	)
	(segment
		(start 65.20307 -132.325872)
		(end 65.20307 -126.409196)
		(width 0.127)
		(layer "In2.Cu")
		(net "EXP_XM_ADDR_20")
	)
	(segment
		(start 96.882204 -93.598492)
		(end 96.882204 -93.2561)
		(width 0.127)
		(layer "In2.Cu")
		(net "EXP_XM_ADDR_20")
	)
	(segment
		(start 65.310766 -132.433568)
		(end 65.20307 -132.325872)
		(width 0.127)
		(layer "In2.Cu")
		(net "EXP_XM_ADDR_20")
	)
	(segment
		(start 95.739204 -93.725492)
		(end 95.866204 -93.598492)
		(width 0.127)
		(layer "In2.Cu")
		(net "EXP_XM_ADDR_20")
	)
	(segment
		(start 80.68437 -104.32796)
		(end 80.68437 -102.237794)
		(width 0.127)
		(layer "In2.Cu")
		(net "EXP_XM_ADDR_20")
	)
	(segment
		(start 100.011738 -93.725492)
		(end 100.54717 -93.19006)
		(width 0.127)
		(layer "In2.Cu")
		(net "EXP_XM_ADDR_20")
	)
	(segment
		(start 96.755204 -93.725492)
		(end 96.882204 -93.598492)
		(width 0.127)
		(layer "In2.Cu")
		(net "EXP_XM_ADDR_20")
	)
	(segment
		(start 65.03797 -134.878064)
		(end 65.03797 -133.623812)
		(width 0.127)
		(layer "In2.Cu")
		(net "EXP_XM_ADDR_20")
	)
	(segment
		(start 97.263204 -93.1291)
		(end 97.390204 -93.2561)
		(width 0.127)
		(layer "In2.Cu")
		(net "EXP_XM_ADDR_20")
	)
	(segment
		(start 65.45707 -119.55526)
		(end 80.68437 -104.32796)
		(width 0.127)
		(layer "In2.Cu")
		(net "EXP_XM_ADDR_20")
	)
	(segment
		(start 65.45707 -126.155196)
		(end 65.45707 -119.55526)
		(width 0.127)
		(layer "In2.Cu")
		(net "EXP_XM_ADDR_20")
	)
	(segment
		(start 96.501204 -93.725492)
		(end 96.755204 -93.725492)
		(width 0.127)
		(layer "In2.Cu")
		(net "EXP_XM_ADDR_20")
	)
	(segment
		(start 96.374204 -93.598492)
		(end 96.501204 -93.725492)
		(width 0.127)
		(layer "In2.Cu")
		(net "EXP_XM_ADDR_20")
	)
	(segment
		(start 95.993204 -93.1291)
		(end 96.247204 -93.1291)
		(width 0.127)
		(layer "In2.Cu")
		(net "EXP_XM_ADDR_20")
	)
	(segment
		(start 80.68437 -102.237794)
		(end 88.990424 -93.93174)
		(width 0.127)
		(layer "In2.Cu")
		(net "EXP_XM_ADDR_20")
	)
	(segment
		(start 97.390204 -93.598492)
		(end 97.517204 -93.725492)
		(width 0.127)
		(layer "In2.Cu")
		(net "EXP_XM_ADDR_20")
	)
	(segment
		(start 97.390204 -93.2561)
		(end 97.390204 -93.598492)
		(width 0.127)
		(layer "In2.Cu")
		(net "EXP_XM_ADDR_20")
	)
	(segment
		(start 95.866204 -93.598492)
		(end 95.866204 -93.2561)
		(width 0.127)
		(layer "In2.Cu")
		(net "EXP_XM_ADDR_20")
	)
	(segment
		(start 96.882204 -93.2561)
		(end 97.009204 -93.1291)
		(width 0.127)
		(layer "In2.Cu")
		(net "EXP_XM_ADDR_20")
	)
	(segment
		(start 65.03797 -133.623812)
		(end 65.30467 -133.357112)
		(width 0.127)
		(layer "In2.Cu")
		(net "EXP_XM_ADDR_20")
	)
	(segment
		(start 65.310766 -133.107684)
		(end 65.310766 -132.433568)
		(width 0.127)
		(layer "In2.Cu")
		(net "EXP_XM_ADDR_20")
	)
	(segment
		(start 94.440502 -93.725492)
		(end 95.739204 -93.725492)
		(width 0.127)
		(layer "In2.Cu")
		(net "EXP_XM_ADDR_20")
	)
	(segment
		(start 96.247204 -93.1291)
		(end 96.374204 -93.2561)
		(width 0.127)
		(layer "In2.Cu")
		(net "EXP_XM_ADDR_20")
	)
	(segment
		(start 65.30467 -133.357112)
		(end 65.30467 -133.11378)
		(width 0.127)
		(layer "In2.Cu")
		(net "EXP_XM_ADDR_20")
	)
	(segment
		(start 96.374204 -93.2561)
		(end 96.374204 -93.598492)
		(width 0.127)
		(layer "In2.Cu")
		(net "EXP_XM_ADDR_20")
	)
	(segment
		(start 22.619716 -202.74788)
		(end 21.641816 -202.74788)
		(width 0.1143)
		(layer "F.Cu")
		(net "ADC_P0V9_E")
	)
	(via
		(at 330.6572 -184.708546)
		(size 0.7112)
		(drill 0.3556)
		(layers "F.Cu" "B.Cu")
		(net "ADC_P0V9_E")
	)
	(via
		(at 21.641816 -202.74788)
		(size 0.5588)
		(drill 0.3048)
		(layers "F.Cu" "B.Cu")
		(net "ADC_P0V9_E")
	)
	(via
		(at 331.978 -186.055)
		(size 0.508)
		(drill 0.254)
		(layers "F.Cu" "B.Cu")
		(net "ADC_P0V9_E")
	)
	(segment
		(start 321.9577 -182.5752)
		(end 321.9577 -182.0037)
		(width 0.1143)
		(layer "B.Cu")
		(net "ADC_P0V9_E")
	)
	(segment
		(start 328.1045 -183.9595)
		(end 325.374 -183.9595)
		(width 0.1143)
		(layer "B.Cu")
		(net "ADC_P0V9_E")
	)
	(segment
		(start 331.978 -185.846974)
		(end 330.839572 -184.708546)
		(width 0.1143)
		(layer "B.Cu")
		(net "ADC_P0V9_E")
	)
	(segment
		(start 324.358 -183.9595)
		(end 323.342 -183.9595)
		(width 0.1143)
		(layer "B.Cu")
		(net "ADC_P0V9_E")
	)
	(segment
		(start 320.929 -180.975)
		(end 318.7065 -180.975)
		(width 0.1143)
		(layer "B.Cu")
		(net "ADC_P0V9_E")
	)
	(segment
		(start 330.839572 -184.708546)
		(end 330.6572 -184.708546)
		(width 0.1143)
		(layer "B.Cu")
		(net "ADC_P0V9_E")
	)
	(segment
		(start 318.7065 -180.975)
		(end 318.4525 -180.721)
		(width 0.1143)
		(layer "B.Cu")
		(net "ADC_P0V9_E")
	)
	(segment
		(start 330.6572 -184.708546)
		(end 328.853546 -184.708546)
		(width 0.1143)
		(layer "B.Cu")
		(net "ADC_P0V9_E")
	)
	(segment
		(start 325.374 -183.9595)
		(end 324.358 -183.9595)
		(width 0.1143)
		(layer "B.Cu")
		(net "ADC_P0V9_E")
	)
	(segment
		(start 331.978 -186.055)
		(end 331.978 -185.846974)
		(width 0.1143)
		(layer "B.Cu")
		(net "ADC_P0V9_E")
	)
	(segment
		(start 323.342 -183.9595)
		(end 321.9577 -182.5752)
		(width 0.1143)
		(layer "B.Cu")
		(net "ADC_P0V9_E")
	)
	(segment
		(start 328.853546 -184.708546)
		(end 328.1045 -183.9595)
		(width 0.1143)
		(layer "B.Cu")
		(net "ADC_P0V9_E")
	)
	(segment
		(start 321.9577 -182.0037)
		(end 320.929 -180.975)
		(width 0.1143)
		(layer "B.Cu")
		(net "ADC_P0V9_E")
	)
	(segment
		(start 255.417828 -226.800664)
		(end 255.417828 -233.191558)
		(width 0.127)
		(layer "In2.Cu")
		(net "ADC_P0V9_E")
	)
	(segment
		(start 329.74026 -206.26578)
		(end 329.740006 -206.265526)
		(width 0.127)
		(layer "In2.Cu")
		(net "ADC_P0V9_E")
	)
	(segment
		(start 329.740006 -206.265526)
		(end 329.740006 -188.292994)
		(width 0.127)
		(layer "In2.Cu")
		(net "ADC_P0V9_E")
	)
	(segment
		(start 329.740006 -188.292994)
		(end 331.978 -186.055)
		(width 0.127)
		(layer "In2.Cu")
		(net "ADC_P0V9_E")
	)
	(segment
		(start 251.749052 -190.0428)
		(end 256.6543 -194.948048)
		(width 0.127)
		(layer "In2.Cu")
		(net "ADC_P0V9_E")
	)
	(segment
		(start 274.079208 -240.79835)
		(end 274.847558 -240.03)
		(width 0.127)
		(layer "In2.Cu")
		(net "ADC_P0V9_E")
	)
	(segment
		(start 329.74026 -206.581248)
		(end 329.74026 -206.26578)
		(width 0.127)
		(layer "In2.Cu")
		(net "ADC_P0V9_E")
	)
	(segment
		(start 21.641816 -202.74788)
		(end 22.746716 -201.64298)
		(width 0.127)
		(layer "In2.Cu")
		(net "ADC_P0V9_E")
	)
	(segment
		(start 144.050004 -201.64298)
		(end 151.00046 -208.593436)
		(width 0.127)
		(layer "In2.Cu")
		(net "ADC_P0V9_E")
	)
	(segment
		(start 255.417828 -233.191558)
		(end 263.02462 -240.79835)
		(width 0.127)
		(layer "In2.Cu")
		(net "ADC_P0V9_E")
	)
	(segment
		(start 213.63686 -208.593436)
		(end 232.187496 -190.0428)
		(width 0.127)
		(layer "In2.Cu")
		(net "ADC_P0V9_E")
	)
	(segment
		(start 22.746716 -201.64298)
		(end 144.050004 -201.64298)
		(width 0.127)
		(layer "In2.Cu")
		(net "ADC_P0V9_E")
	)
	(segment
		(start 274.847558 -240.03)
		(end 296.291508 -240.03)
		(width 0.127)
		(layer "In2.Cu")
		(net "ADC_P0V9_E")
	)
	(segment
		(start 256.6543 -225.564192)
		(end 255.417828 -226.800664)
		(width 0.127)
		(layer "In2.Cu")
		(net "ADC_P0V9_E")
	)
	(segment
		(start 263.02462 -240.79835)
		(end 274.079208 -240.79835)
		(width 0.127)
		(layer "In2.Cu")
		(net "ADC_P0V9_E")
	)
	(segment
		(start 296.291508 -240.03)
		(end 329.74026 -206.581248)
		(width 0.127)
		(layer "In2.Cu")
		(net "ADC_P0V9_E")
	)
	(segment
		(start 151.00046 -208.593436)
		(end 213.63686 -208.593436)
		(width 0.127)
		(layer "In2.Cu")
		(net "ADC_P0V9_E")
	)
	(segment
		(start 232.187496 -190.0428)
		(end 251.749052 -190.0428)
		(width 0.127)
		(layer "In2.Cu")
		(net "ADC_P0V9_E")
	)
	(segment
		(start 256.6543 -194.948048)
		(end 256.6543 -225.564192)
		(width 0.127)
		(layer "In2.Cu")
		(net "ADC_P0V9_E")
	)
	(segment
		(start 106.3498 -84.349844)
		(end 105.849674 -83.849718)
		(width 0.1143)
		(layer "F.Cu")
		(net "EXP_BLINK_IN")
	)
	(via
		(at 105.849674 -83.849718)
		(size 0.508)
		(drill 0.254)
		(layers "F.Cu" "B.Cu")
		(net "EXP_BLINK_IN")
	)
	(via
		(at 105.04297 -81.788)
		(size 0.7112)
		(drill 0.3556)
		(layers "F.Cu" "B.Cu")
		(net "EXP_BLINK_IN")
	)
	(segment
		(start 105.849674 -83.849718)
		(end 105.76306 -83.849718)
		(width 0.1143)
		(layer "B.Cu")
		(net "EXP_BLINK_IN")
	)
	(segment
		(start 105.29697 -82.042)
		(end 105.04297 -81.788)
		(width 0.1143)
		(layer "B.Cu")
		(net "EXP_BLINK_IN")
	)
	(segment
		(start 105.76306 -83.849718)
		(end 105.479342 -83.566)
		(width 0.1143)
		(layer "B.Cu")
		(net "EXP_BLINK_IN")
	)
	(segment
		(start 105.479342 -83.002882)
		(end 105.352342 -82.875882)
		(width 0.1143)
		(layer "B.Cu")
		(net "EXP_BLINK_IN")
	)
	(segment
		(start 105.29697 -82.82051)
		(end 105.29697 -82.042)
		(width 0.1143)
		(layer "B.Cu")
		(net "EXP_BLINK_IN")
	)
	(segment
		(start 105.479342 -83.566)
		(end 105.479342 -83.002882)
		(width 0.1143)
		(layer "B.Cu")
		(net "EXP_BLINK_IN")
	)
	(segment
		(start 105.352342 -82.875882)
		(end 105.29697 -82.82051)
		(width 0.1143)
		(layer "B.Cu")
		(net "EXP_BLINK_IN")
	)
	(segment
		(start 98.171 -60.325)
		(end 97.95002 -60.10402)
		(width 0.1143)
		(layer "F.Cu")
		(net "ICE1_TDO")
	)
	(segment
		(start 97.95002 -60.10402)
		(end 97.95002 -56.599836)
		(width 0.1143)
		(layer "F.Cu")
		(net "ICE1_TDO")
	)
	(segment
		(start 316.521592 -178.689)
		(end 316.185296 -178.352704)
		(width 0.1143)
		(layer "F.Cu")
		(net "ADC_P1V5_C_BMC")
	)
	(segment
		(start 309.861204 -177.8)
		(end 308.083204 -176.022)
		(width 0.1143)
		(layer "F.Cu")
		(net "ADC_P1V5_C_BMC")
	)
	(segment
		(start 302.465486 -175.440086)
		(end 301.634906 -175.440086)
		(width 0.1143)
		(layer "F.Cu")
		(net "ADC_P1V5_C_BMC")
	)
	(segment
		(start 308.083204 -176.022)
		(end 303.0474 -176.022)
		(width 0.1143)
		(layer "F.Cu")
		(net "ADC_P1V5_C_BMC")
	)
	(segment
		(start 315.632592 -177.8)
		(end 309.861204 -177.8)
		(width 0.1143)
		(layer "F.Cu")
		(net "ADC_P1V5_C_BMC")
	)
	(segment
		(start 303.0474 -176.022)
		(end 302.465486 -175.440086)
		(width 0.1143)
		(layer "F.Cu")
		(net "ADC_P1V5_C_BMC")
	)
	(segment
		(start 317.5635 -178.689)
		(end 316.521592 -178.689)
		(width 0.1143)
		(layer "F.Cu")
		(net "ADC_P1V5_C_BMC")
	)
	(segment
		(start 316.185296 -178.352704)
		(end 315.632592 -177.8)
		(width 0.1143)
		(layer "F.Cu")
		(net "ADC_P1V5_C_BMC")
	)
	(via
		(at 316.185296 -178.352704)
		(size 0.7112)
		(drill 0.3556)
		(layers "F.Cu" "B.Cu")
		(net "ADC_P1V5_C_BMC")
	)
	(segment
		(start 195.961 -165.9255)
		(end 194.056 -165.9255)
		(width 0.127)
		(layer "F.Cu")
		(net "P3V3_PG_R")
	)
	(segment
		(start 197.0405 -163.703)
		(end 195.834 -163.703)
		(width 0.127)
		(layer "F.Cu")
		(net "P3V3_PG_R")
	)
	(segment
		(start 197.0405 -164.846)
		(end 195.961 -165.9255)
		(width 0.127)
		(layer "F.Cu")
		(net "P3V3_PG_R")
	)
	(segment
		(start 197.0405 -164.846)
		(end 197.0405 -163.703)
		(width 0.127)
		(layer "F.Cu")
		(net "P3V3_PG_R")
	)
	(via
		(at 195.834 -163.703)
		(size 0.7112)
		(drill 0.3556)
		(layers "F.Cu" "B.Cu")
		(net "P3V3_PG_R")
	)
	(segment
		(start 31.3817 -149.834346)
		(end 31.3817 -149.453346)
		(width 0.1143)
		(layer "F.Cu")
		(net "SAS_HDD_LED5")
	)
	(segment
		(start 16.386048 -170.107356)
		(end 16.386048 -165.282372)
		(width 0.1143)
		(layer "F.Cu")
		(net "SAS_HDD_LED5")
	)
	(segment
		(start 16.98244 -164.68598)
		(end 19.177 -162.49142)
		(width 0.1143)
		(layer "F.Cu")
		(net "SAS_HDD_LED5")
	)
	(segment
		(start 31.496 -148.3487)
		(end 31.7627 -148.082)
		(width 0.1143)
		(layer "F.Cu")
		(net "SAS_HDD_LED5")
	)
	(segment
		(start 108.349796 -84.349844)
		(end 107.84967 -83.849718)
		(width 0.1143)
		(layer "F.Cu")
		(net "SAS_HDD_LED5")
	)
	(segment
		(start 16.386048 -165.282372)
		(end 16.98244 -164.68598)
		(width 0.1143)
		(layer "F.Cu")
		(net "SAS_HDD_LED5")
	)
	(segment
		(start 31.3817 -149.453346)
		(end 31.496 -149.339046)
		(width 0.1143)
		(layer "F.Cu")
		(net "SAS_HDD_LED5")
	)
	(segment
		(start 31.496 -149.339046)
		(end 31.496 -148.3487)
		(width 0.1143)
		(layer "F.Cu")
		(net "SAS_HDD_LED5")
	)
	(segment
		(start 19.177 -162.49142)
		(end 19.177 -162.0393)
		(width 0.1143)
		(layer "F.Cu")
		(net "SAS_HDD_LED5")
	)
	(segment
		(start 19.177 -162.0393)
		(end 31.3817 -149.834346)
		(width 0.1143)
		(layer "F.Cu")
		(net "SAS_HDD_LED5")
	)
	(via
		(at 16.98244 -164.68598)
		(size 0.7112)
		(drill 0.3556)
		(layers "F.Cu" "B.Cu")
		(net "SAS_HDD_LED5")
	)
	(via
		(at 107.84967 -83.849718)
		(size 0.508)
		(drill 0.254)
		(layers "F.Cu" "B.Cu")
		(net "SAS_HDD_LED5")
	)
	(via
		(at 31.7627 -148.082)
		(size 0.5588)
		(drill 0.3048)
		(layers "F.Cu" "B.Cu")
		(net "SAS_HDD_LED5")
	)
	(segment
		(start 48.641 -134.84606)
		(end 46.736 -136.75106)
		(width 0.127)
		(layer "In5.Cu")
		(net "SAS_HDD_LED5")
	)
	(segment
		(start 108.25607 -80.598264)
		(end 106.842306 -79.1845)
		(width 0.127)
		(layer "In5.Cu")
		(net "SAS_HDD_LED5")
	)
	(segment
		(start 106.842306 -79.1845)
		(end 100.137976 -79.1845)
		(width 0.127)
		(layer "In5.Cu")
		(net "SAS_HDD_LED5")
	)
	(segment
		(start 107.84967 -83.849718)
		(end 107.84967 -82.12074)
		(width 0.127)
		(layer "In5.Cu")
		(net "SAS_HDD_LED5")
	)
	(segment
		(start 32.131 -148.4503)
		(end 31.7627 -148.082)
		(width 0.127)
		(layer "In5.Cu")
		(net "SAS_HDD_LED5")
	)
	(segment
		(start 107.84967 -82.12074)
		(end 108.25607 -81.71434)
		(width 0.127)
		(layer "In5.Cu")
		(net "SAS_HDD_LED5")
	)
	(segment
		(start 46.736 -136.75106)
		(end 46.736 -138.111484)
		(width 0.127)
		(layer "In5.Cu")
		(net "SAS_HDD_LED5")
	)
	(segment
		(start 36.397184 -148.4503)
		(end 32.131 -148.4503)
		(width 0.127)
		(layer "In5.Cu")
		(net "SAS_HDD_LED5")
	)
	(segment
		(start 48.641 -130.681476)
		(end 48.641 -134.84606)
		(width 0.127)
		(layer "In5.Cu")
		(net "SAS_HDD_LED5")
	)
	(segment
		(start 46.736 -138.111484)
		(end 36.397184 -148.4503)
		(width 0.127)
		(layer "In5.Cu")
		(net "SAS_HDD_LED5")
	)
	(segment
		(start 108.25607 -81.71434)
		(end 108.25607 -80.598264)
		(width 0.127)
		(layer "In5.Cu")
		(net "SAS_HDD_LED5")
	)
	(segment
		(start 100.137976 -79.1845)
		(end 48.641 -130.681476)
		(width 0.127)
		(layer "In5.Cu")
		(net "SAS_HDD_LED5")
	)
	(segment
		(start 98.01098 -62.8777)
		(end 98.01098 -62.06998)
		(width 0.1143)
		(layer "F.Cu")
		(net "IOC_VREF_SET")
	)
	(segment
		(start 97.493074 -56.14289)
		(end 97.150174 -55.79999)
		(width 0.1143)
		(layer "F.Cu")
		(net "IOC_VREF_SET")
	)
	(segment
		(start 98.01098 -62.06998)
		(end 97.663 -61.722)
		(width 0.1143)
		(layer "F.Cu")
		(net "IOC_VREF_SET")
	)
	(segment
		(start 97.493074 -61.552074)
		(end 97.493074 -56.14289)
		(width 0.1143)
		(layer "F.Cu")
		(net "IOC_VREF_SET")
	)
	(segment
		(start 97.663 -61.722)
		(end 97.493074 -61.552074)
		(width 0.1143)
		(layer "F.Cu")
		(net "IOC_VREF_SET")
	)
	(via
		(at 97.663 -61.722)
		(size 0.7112)
		(drill 0.3556)
		(layers "F.Cu" "B.Cu")
		(net "IOC_VREF_SET")
	)
	(segment
		(start 332.359 -179.07)
		(end 333.629 -180.34)
		(width 0.1143)
		(layer "F.Cu")
		(net "ADC_P1V5_C")
	)
	(segment
		(start 35.827716 -201.09688)
		(end 35.898836 -201.168)
		(width 0.1143)
		(layer "F.Cu")
		(net "ADC_P1V5_C")
	)
	(segment
		(start 35.827716 -202.13828)
		(end 35.827716 -201.09688)
		(width 0.1143)
		(layer "F.Cu")
		(net "ADC_P1V5_C")
	)
	(segment
		(start 325.5645 -179.07)
		(end 332.359 -179.07)
		(width 0.1143)
		(layer "F.Cu")
		(net "ADC_P1V5_C")
	)
	(segment
		(start 323.342 -179.2605)
		(end 319.024 -179.2605)
		(width 0.1143)
		(layer "F.Cu")
		(net "ADC_P1V5_C")
	)
	(segment
		(start 35.898836 -201.168)
		(end 36.83 -201.168)
		(width 0.1143)
		(layer "F.Cu")
		(net "ADC_P1V5_C")
	)
	(segment
		(start 325.374 -179.2605)
		(end 325.5645 -179.07)
		(width 0.1143)
		(layer "F.Cu")
		(net "ADC_P1V5_C")
	)
	(segment
		(start 319.024 -179.2605)
		(end 318.4525 -178.689)
		(width 0.1143)
		(layer "F.Cu")
		(net "ADC_P1V5_C")
	)
	(segment
		(start 324.358 -179.2605)
		(end 325.374 -179.2605)
		(width 0.1143)
		(layer "F.Cu")
		(net "ADC_P1V5_C")
	)
	(segment
		(start 324.358 -179.2605)
		(end 323.342 -179.2605)
		(width 0.1143)
		(layer "F.Cu")
		(net "ADC_P1V5_C")
	)
	(via
		(at 36.83 -201.168)
		(size 0.7112)
		(drill 0.3556)
		(layers "F.Cu" "B.Cu")
		(net "ADC_P1V5_C")
	)
	(via
		(at 333.629 -180.34)
		(size 0.5588)
		(drill 0.3048)
		(layers "F.Cu" "B.Cu")
		(net "ADC_P1V5_C")
	)
	(via
		(at 35.827716 -202.13828)
		(size 0.5588)
		(drill 0.3048)
		(layers "F.Cu" "B.Cu")
		(net "ADC_P1V5_C")
	)
	(segment
		(start 35.827716 -202.13828)
		(end 144.006316 -202.13828)
		(width 0.127)
		(layer "In2.Cu")
		(net "ADC_P1V5_C")
	)
	(segment
		(start 263.182354 -241.179604)
		(end 263.182608 -241.17935)
		(width 0.127)
		(layer "In2.Cu")
		(net "ADC_P1V5_C")
	)
	(segment
		(start 332.047088 -186.5249)
		(end 332.172818 -186.5249)
		(width 0.127)
		(layer "In2.Cu")
		(net "ADC_P1V5_C")
	)
	(segment
		(start 262.866886 -241.179604)
		(end 263.182354 -241.179604)
		(width 0.127)
		(layer "In2.Cu")
		(net "ADC_P1V5_C")
	)
	(segment
		(start 275.005546 -240.411)
		(end 296.449496 -240.411)
		(width 0.127)
		(layer "In2.Cu")
		(net "ADC_P1V5_C")
	)
	(segment
		(start 256.2733 -219.812362)
		(end 255.27 -220.815662)
		(width 0.127)
		(layer "In2.Cu")
		(net "ADC_P1V5_C")
	)
	(segment
		(start 333.629 -185.068718)
		(end 333.629 -180.34)
		(width 0.127)
		(layer "In2.Cu")
		(net "ADC_P1V5_C")
	)
	(segment
		(start 255.036828 -233.349546)
		(end 262.866886 -241.179604)
		(width 0.127)
		(layer "In2.Cu")
		(net "ADC_P1V5_C")
	)
	(segment
		(start 330.3905 -188.181488)
		(end 332.047088 -186.5249)
		(width 0.127)
		(layer "In2.Cu")
		(net "ADC_P1V5_C")
	)
	(segment
		(start 255.27 -226.409504)
		(end 255.036828 -226.642676)
		(width 0.127)
		(layer "In2.Cu")
		(net "ADC_P1V5_C")
	)
	(segment
		(start 255.27 -220.815662)
		(end 255.27 -226.409504)
		(width 0.127)
		(layer "In2.Cu")
		(net "ADC_P1V5_C")
	)
	(segment
		(start 251.591064 -190.4238)
		(end 256.2733 -195.106036)
		(width 0.127)
		(layer "In2.Cu")
		(net "ADC_P1V5_C")
	)
	(segment
		(start 150.842472 -208.974436)
		(end 213.794848 -208.974436)
		(width 0.127)
		(layer "In2.Cu")
		(net "ADC_P1V5_C")
	)
	(segment
		(start 274.237196 -241.17935)
		(end 275.005546 -240.411)
		(width 0.127)
		(layer "In2.Cu")
		(net "ADC_P1V5_C")
	)
	(segment
		(start 256.2733 -195.106036)
		(end 256.2733 -219.812362)
		(width 0.127)
		(layer "In2.Cu")
		(net "ADC_P1V5_C")
	)
	(segment
		(start 144.006316 -202.13828)
		(end 150.842472 -208.974436)
		(width 0.127)
		(layer "In2.Cu")
		(net "ADC_P1V5_C")
	)
	(segment
		(start 213.794848 -208.974436)
		(end 232.345484 -190.4238)
		(width 0.127)
		(layer "In2.Cu")
		(net "ADC_P1V5_C")
	)
	(segment
		(start 232.345484 -190.4238)
		(end 251.591064 -190.4238)
		(width 0.127)
		(layer "In2.Cu")
		(net "ADC_P1V5_C")
	)
	(segment
		(start 255.036828 -226.642676)
		(end 255.036828 -233.349546)
		(width 0.127)
		(layer "In2.Cu")
		(net "ADC_P1V5_C")
	)
	(segment
		(start 296.449496 -240.411)
		(end 330.3905 -206.469996)
		(width 0.127)
		(layer "In2.Cu")
		(net "ADC_P1V5_C")
	)
	(segment
		(start 332.172818 -186.5249)
		(end 333.629 -185.068718)
		(width 0.127)
		(layer "In2.Cu")
		(net "ADC_P1V5_C")
	)
	(segment
		(start 263.182608 -241.17935)
		(end 274.237196 -241.17935)
		(width 0.127)
		(layer "In2.Cu")
		(net "ADC_P1V5_C")
	)
	(segment
		(start 330.3905 -206.469996)
		(end 330.3905 -188.181488)
		(width 0.127)
		(layer "In2.Cu")
		(net "ADC_P1V5_C")
	)
	(segment
		(start 218.948 -101.346)
		(end 218.943174 -101.350826)
		(width 0.3048)
		(layer "F.Cu")
		(net "TPS74801_P1V5_C_IN")
	)
	(segment
		(start 218.93784 -100.70084)
		(end 217.555318 -100.70084)
		(width 0.3048)
		(layer "F.Cu")
		(net "TPS74801_P1V5_C_IN")
	)
	(segment
		(start 217.555318 -102.000812)
		(end 219.182188 -102.000812)
		(width 0.3048)
		(layer "F.Cu")
		(net "TPS74801_P1V5_C_IN")
	)
	(segment
		(start 216.380568 -98.007932)
		(end 216.5985 -97.79)
		(width 0.3048)
		(layer "F.Cu")
		(net "TPS74801_P1V5_C_IN")
	)
	(segment
		(start 218.948 -100.711)
		(end 218.93784 -100.70084)
		(width 0.3048)
		(layer "F.Cu")
		(net "TPS74801_P1V5_C_IN")
	)
	(segment
		(start 218.943174 -101.350826)
		(end 217.555318 -101.350826)
		(width 0.3048)
		(layer "F.Cu")
		(net "TPS74801_P1V5_C_IN")
	)
	(segment
		(start 216.380568 -99.52609)
		(end 216.380568 -98.007932)
		(width 0.3048)
		(layer "F.Cu")
		(net "TPS74801_P1V5_C_IN")
	)
	(via
		(at 220.599 -99.06)
		(size 0.7112)
		(drill 0.3556)
		(layers "F.Cu" "B.Cu")
		(net "TPS74801_P1V5_C_IN")
	)
	(segment
		(start 116.350034 -88.349836)
		(end 116.261134 -88.349836)
		(width 0.1143)
		(layer "F.Cu")
		(net "EXP_TEST_MUX31")
	)
	(segment
		(start 116.261134 -88.349836)
		(end 115.77955 -88.83142)
		(width 0.1143)
		(layer "F.Cu")
		(net "EXP_TEST_MUX31")
	)
	(segment
		(start 115.77955 -88.83142)
		(end 115.77955 -88.85936)
		(width 0.1143)
		(layer "F.Cu")
		(net "EXP_TEST_MUX31")
	)
	(via
		(at 115.77955 -88.85936)
		(size 0.508)
		(drill 0.254)
		(layers "F.Cu" "B.Cu")
		(net "EXP_TEST_MUX31")
	)
	(segment
		(start 115.75161 -88.85936)
		(end 115.77955 -88.85936)
		(width 0.1143)
		(layer "B.Cu")
		(net "EXP_TEST_MUX31")
	)
	(segment
		(start 114.94897 -89.6366)
		(end 114.97437 -89.6366)
		(width 0.1143)
		(layer "B.Cu")
		(net "EXP_TEST_MUX31")
	)
	(segment
		(start 114.97437 -89.6366)
		(end 115.75161 -88.85936)
		(width 0.1143)
		(layer "B.Cu")
		(net "EXP_TEST_MUX31")
	)
	(segment
		(start 298.43476 -176.240186)
		(end 298.829984 -176.63541)
		(width 0.1143)
		(layer "F.Cu")
		(net "ADC_P0V955_C_BMC")
	)
	(via
		(at 298.829984 -176.63541)
		(size 0.508)
		(drill 0.254)
		(layers "F.Cu" "B.Cu")
		(net "ADC_P0V955_C_BMC")
	)
	(via
		(at 315.722 -179.705)
		(size 0.7112)
		(drill 0.3556)
		(layers "F.Cu" "B.Cu")
		(net "ADC_P0V955_C_BMC")
	)
	(segment
		(start 312.674 -179.705)
		(end 315.722 -179.705)
		(width 0.1143)
		(layer "B.Cu")
		(net "ADC_P0V955_C_BMC")
	)
	(segment
		(start 309.056532 -176.149)
		(end 309.118 -176.149)
		(width 0.1143)
		(layer "B.Cu")
		(net "ADC_P0V955_C_BMC")
	)
	(segment
		(start 302.88738 -175.90262)
		(end 302.977296 -175.90262)
		(width 0.1143)
		(layer "B.Cu")
		(net "ADC_P0V955_C_BMC")
	)
	(segment
		(start 298.97959 -176.63541)
		(end 299.371766 -176.243234)
		(width 0.0889)
		(layer "B.Cu")
		(net "ADC_P0V955_C_BMC")
	)
	(segment
		(start 302.977296 -175.90262)
		(end 303.062386 -175.81753)
		(width 0.1143)
		(layer "B.Cu")
		(net "ADC_P0V955_C_BMC")
	)
	(segment
		(start 299.371766 -176.243234)
		(end 299.879258 -176.243234)
		(width 0.0889)
		(layer "B.Cu")
		(net "ADC_P0V955_C_BMC")
	)
	(segment
		(start 317.5635 -179.705)
		(end 315.722 -179.705)
		(width 0.1143)
		(layer "B.Cu")
		(net "ADC_P0V955_C_BMC")
	)
	(segment
		(start 298.829984 -176.63541)
		(end 298.97959 -176.63541)
		(width 0.0889)
		(layer "B.Cu")
		(net "ADC_P0V955_C_BMC")
	)
	(segment
		(start 309.118 -176.149)
		(end 312.674 -179.705)
		(width 0.1143)
		(layer "B.Cu")
		(net "ADC_P0V955_C_BMC")
	)
	(segment
		(start 303.062386 -175.81753)
		(end 308.725062 -175.81753)
		(width 0.1143)
		(layer "B.Cu")
		(net "ADC_P0V955_C_BMC")
	)
	(segment
		(start 299.879258 -176.243234)
		(end 300.219872 -175.90262)
		(width 0.0889)
		(layer "B.Cu")
		(net "ADC_P0V955_C_BMC")
	)
	(segment
		(start 308.725062 -175.81753)
		(end 309.056532 -176.149)
		(width 0.1143)
		(layer "B.Cu")
		(net "ADC_P0V955_C_BMC")
	)
	(segment
		(start 300.219872 -175.90262)
		(end 302.88738 -175.90262)
		(width 0.0889)
		(layer "B.Cu")
		(net "ADC_P0V955_C_BMC")
	)
	(segment
		(start 208.915 -103.5685)
		(end 209.931 -103.5685)
		(width 0.254)
		(layer "F.Cu")
		(net "TPS74801_1V5_C_FB")
	)
	(segment
		(start 210.947 -103.4415)
		(end 211.087716 -103.300784)
		(width 0.254)
		(layer "F.Cu")
		(net "TPS74801_1V5_C_FB")
	)
	(segment
		(start 208.915 -103.5685)
		(end 208.8515 -103.505)
		(width 0.254)
		(layer "F.Cu")
		(net "TPS74801_1V5_C_FB")
	)
	(segment
		(start 208.8515 -103.505)
		(end 207.899 -103.505)
		(width 0.254)
		(layer "F.Cu")
		(net "TPS74801_1V5_C_FB")
	)
	(segment
		(start 210.058 -103.4415)
		(end 210.947 -103.4415)
		(width 0.254)
		(layer "F.Cu")
		(net "TPS74801_1V5_C_FB")
	)
	(segment
		(start 211.087716 -103.300784)
		(end 212.605874 -103.300784)
		(width 0.254)
		(layer "F.Cu")
		(net "TPS74801_1V5_C_FB")
	)
	(segment
		(start 209.931 -103.5685)
		(end 210.058 -103.4415)
		(width 0.254)
		(layer "F.Cu")
		(net "TPS74801_1V5_C_FB")
	)
	(via
		(at 207.899 -103.505)
		(size 0.7112)
		(drill 0.3556)
		(layers "F.Cu" "B.Cu")
		(net "TPS74801_1V5_C_FB")
	)
	(segment
		(start 90.750136 -44.59986)
		(end 90.75928 -44.59986)
		(width 0.1143)
		(layer "F.Cu")
		(net "RTRIM")
	)
	(segment
		(start 90.75928 -44.59986)
		(end 91.149932 -44.990512)
		(width 0.1143)
		(layer "F.Cu")
		(net "RTRIM")
	)
	(via
		(at 91.149932 -44.990512)
		(size 0.508)
		(drill 0.254)
		(layers "F.Cu" "B.Cu")
		(net "RTRIM")
	)
	(via
		(at 91.929966 -44.196)
		(size 0.7112)
		(drill 0.3556)
		(layers "F.Cu" "B.Cu")
		(net "RTRIM")
	)
	(segment
		(start 91.149932 -45.672248)
		(end 91.149932 -44.990512)
		(width 0.1143)
		(layer "B.Cu")
		(net "RTRIM")
	)
	(segment
		(start 91.149932 -44.976034)
		(end 91.929966 -44.196)
		(width 0.1143)
		(layer "B.Cu")
		(net "RTRIM")
	)
	(segment
		(start 91.149932 -44.990512)
		(end 91.149932 -44.976034)
		(width 0.1143)
		(layer "B.Cu")
		(net "RTRIM")
	)
	(segment
		(start 91.12504 -45.69714)
		(end 91.149932 -45.672248)
		(width 0.1143)
		(layer "B.Cu")
		(net "RTRIM")
	)
	(segment
		(start 22.226016 -200.71588)
		(end 21.032216 -201.90968)
		(width 0.1143)
		(layer "F.Cu")
		(net "ADC_P0V955_C")
	)
	(segment
		(start 22.619716 -200.71588)
		(end 22.226016 -200.71588)
		(width 0.1143)
		(layer "F.Cu")
		(net "ADC_P0V955_C")
	)
	(via
		(at 21.032216 -201.90968)
		(size 0.5588)
		(drill 0.3048)
		(layers "F.Cu" "B.Cu")
		(net "ADC_P0V955_C")
	)
	(via
		(at 328.803 -182.88)
		(size 0.7112)
		(drill 0.3556)
		(layers "F.Cu" "B.Cu")
		(net "ADC_P0V955_C")
	)
	(via
		(at 331.978 -185.1914)
		(size 0.508)
		(drill 0.254)
		(layers "F.Cu" "B.Cu")
		(net "ADC_P0V955_C")
	)
	(segment
		(start 323.342 -182.8165)
		(end 323.1515 -182.8165)
		(width 0.1143)
		(layer "B.Cu")
		(net "ADC_P0V955_C")
	)
	(segment
		(start 322.938648 -182.603902)
		(end 322.937378 -182.603902)
		(width 0.1143)
		(layer "B.Cu")
		(net "ADC_P0V955_C")
	)
	(segment
		(start 322.937378 -182.603902)
		(end 322.326 -181.992524)
		(width 0.1143)
		(layer "B.Cu")
		(net "ADC_P0V955_C")
	)
	(segment
		(start 323.1515 -182.8165)
		(end 322.938648 -182.603902)
		(width 0.1143)
		(layer "B.Cu")
		(net "ADC_P0V955_C")
	)
	(segment
		(start 322.326 -180.848)
		(end 321.183 -179.705)
		(width 0.1143)
		(layer "B.Cu")
		(net "ADC_P0V955_C")
	)
	(segment
		(start 329.666854 -182.88)
		(end 328.803 -182.88)
		(width 0.1143)
		(layer "B.Cu")
		(net "ADC_P0V955_C")
	)
	(segment
		(start 324.358 -182.8165)
		(end 323.342 -182.8165)
		(width 0.1143)
		(layer "B.Cu")
		(net "ADC_P0V955_C")
	)
	(segment
		(start 331.978 -185.191146)
		(end 329.666854 -182.88)
		(width 0.1143)
		(layer "B.Cu")
		(net "ADC_P0V955_C")
	)
	(segment
		(start 325.4375 -182.88)
		(end 328.803 -182.88)
		(width 0.1143)
		(layer "B.Cu")
		(net "ADC_P0V955_C")
	)
	(segment
		(start 322.326 -181.992524)
		(end 322.326 -180.848)
		(width 0.1143)
		(layer "B.Cu")
		(net "ADC_P0V955_C")
	)
	(segment
		(start 325.374 -182.8165)
		(end 325.4375 -182.88)
		(width 0.1143)
		(layer "B.Cu")
		(net "ADC_P0V955_C")
	)
	(segment
		(start 331.978 -185.1914)
		(end 331.978 -185.191146)
		(width 0.1143)
		(layer "B.Cu")
		(net "ADC_P0V955_C")
	)
	(segment
		(start 324.358 -182.8165)
		(end 325.374 -182.8165)
		(width 0.1143)
		(layer "B.Cu")
		(net "ADC_P0V955_C")
	)
	(segment
		(start 321.183 -179.705)
		(end 318.4525 -179.705)
		(width 0.1143)
		(layer "B.Cu")
		(net "ADC_P0V955_C")
	)
	(segment
		(start 256.163064 -227.320856)
		(end 256.667 -227.824792)
		(width 0.127)
		(layer "In2.Cu")
		(net "ADC_P0V955_C")
	)
	(segment
		(start 232.029508 -189.6618)
		(end 251.90704 -189.6618)
		(width 0.127)
		(layer "In2.Cu")
		(net "ADC_P0V955_C")
	)
	(segment
		(start 329.359006 -187.810394)
		(end 331.978 -185.1914)
		(width 0.127)
		(layer "In2.Cu")
		(net "ADC_P0V955_C")
	)
	(segment
		(start 251.90704 -189.6618)
		(end 257.0353 -194.79006)
		(width 0.127)
		(layer "In2.Cu")
		(net "ADC_P0V955_C")
	)
	(segment
		(start 329.359006 -206.423514)
		(end 329.359006 -187.810394)
		(width 0.127)
		(layer "In2.Cu")
		(net "ADC_P0V955_C")
	)
	(segment
		(start 256.163064 -226.594416)
		(end 256.163064 -227.320856)
		(width 0.127)
		(layer "In2.Cu")
		(net "ADC_P0V955_C")
	)
	(segment
		(start 257.0353 -225.72218)
		(end 256.163064 -226.594416)
		(width 0.127)
		(layer "In2.Cu")
		(net "ADC_P0V955_C")
	)
	(segment
		(start 214.875872 -206.815436)
		(end 232.029508 -189.6618)
		(width 0.127)
		(layer "In2.Cu")
		(net "ADC_P0V955_C")
	)
	(segment
		(start 256.667 -227.824792)
		(end 256.667 -233.901742)
		(width 0.127)
		(layer "In2.Cu")
		(net "ADC_P0V955_C")
	)
	(segment
		(start 149.761448 -206.815436)
		(end 214.875872 -206.815436)
		(width 0.127)
		(layer "In2.Cu")
		(net "ADC_P0V955_C")
	)
	(segment
		(start 273.92122 -240.41735)
		(end 274.68957 -239.649)
		(width 0.127)
		(layer "In2.Cu")
		(net "ADC_P0V955_C")
	)
	(segment
		(start 21.032216 -201.90968)
		(end 21.679916 -201.26198)
		(width 0.127)
		(layer "In2.Cu")
		(net "ADC_P0V955_C")
	)
	(segment
		(start 257.0353 -194.79006)
		(end 257.0353 -225.72218)
		(width 0.127)
		(layer "In2.Cu")
		(net "ADC_P0V955_C")
	)
	(segment
		(start 296.13352 -239.649)
		(end 329.359006 -206.423514)
		(width 0.127)
		(layer "In2.Cu")
		(net "ADC_P0V955_C")
	)
	(segment
		(start 263.182608 -240.41735)
		(end 273.92122 -240.41735)
		(width 0.127)
		(layer "In2.Cu")
		(net "ADC_P0V955_C")
	)
	(segment
		(start 144.207992 -201.26198)
		(end 149.761448 -206.815436)
		(width 0.127)
		(layer "In2.Cu")
		(net "ADC_P0V955_C")
	)
	(segment
		(start 21.679916 -201.26198)
		(end 144.207992 -201.26198)
		(width 0.127)
		(layer "In2.Cu")
		(net "ADC_P0V955_C")
	)
	(segment
		(start 256.667 -233.901742)
		(end 263.182608 -240.41735)
		(width 0.127)
		(layer "In2.Cu")
		(net "ADC_P0V955_C")
	)
	(segment
		(start 274.68957 -239.649)
		(end 296.13352 -239.649)
		(width 0.127)
		(layer "In2.Cu")
		(net "ADC_P0V955_C")
	)
	(segment
		(start 220.9165 -102.22865)
		(end 220.9165 -102.743)
		(width 0.1143)
		(layer "F.Cu")
		(net "PWRGD_P1V5_C_PG")
	)
	(segment
		(start 239.776 -110.236)
		(end 234.7595 -105.2195)
		(width 0.1143)
		(layer "F.Cu")
		(net "PWRGD_P1V5_C_PG")
	)
	(segment
		(start 234.7595 -105.2195)
		(end 227.229162 -105.2195)
		(width 0.1143)
		(layer "F.Cu")
		(net "PWRGD_P1V5_C_PG")
	)
	(segment
		(start 227.229162 -105.2195)
		(end 225.806 -103.796338)
		(width 0.1143)
		(layer "F.Cu")
		(net "PWRGD_P1V5_C_PG")
	)
	(segment
		(start 221.1705 -101.97465)
		(end 220.9165 -102.22865)
		(width 0.1143)
		(layer "F.Cu")
		(net "PWRGD_P1V5_C_PG")
	)
	(segment
		(start 225.806 -103.688388)
		(end 224.092262 -101.97465)
		(width 0.1143)
		(layer "F.Cu")
		(net "PWRGD_P1V5_C_PG")
	)
	(segment
		(start 76.6572 -23.9522)
		(end 76.708 -23.9522)
		(width 0.1143)
		(layer "F.Cu")
		(net "PWRGD_P1V5_C_PG")
	)
	(segment
		(start 76.327 -23.622)
		(end 76.6572 -23.9522)
		(width 0.1143)
		(layer "F.Cu")
		(net "PWRGD_P1V5_C_PG")
	)
	(segment
		(start 76.327 -23.1775)
		(end 76.327 -23.622)
		(width 0.1143)
		(layer "F.Cu")
		(net "PWRGD_P1V5_C_PG")
	)
	(segment
		(start 220.218 -102.743)
		(end 220.9165 -102.743)
		(width 0.1143)
		(layer "F.Cu")
		(net "PWRGD_P1V5_C_PG")
	)
	(segment
		(start 76.708 -24.765)
		(end 76.708 -23.9522)
		(width 0.1143)
		(layer "F.Cu")
		(net "PWRGD_P1V5_C_PG")
	)
	(segment
		(start 224.092262 -101.97465)
		(end 221.1705 -101.97465)
		(width 0.1143)
		(layer "F.Cu")
		(net "PWRGD_P1V5_C_PG")
	)
	(segment
		(start 217.555318 -102.650798)
		(end 220.125798 -102.650798)
		(width 0.1143)
		(layer "F.Cu")
		(net "PWRGD_P1V5_C_PG")
	)
	(segment
		(start 225.806 -103.796338)
		(end 225.806 -103.688388)
		(width 0.1143)
		(layer "F.Cu")
		(net "PWRGD_P1V5_C_PG")
	)
	(segment
		(start 220.125798 -102.650798)
		(end 220.218 -102.743)
		(width 0.1143)
		(layer "F.Cu")
		(net "PWRGD_P1V5_C_PG")
	)
	(via
		(at 247.651778 -49.3522)
		(size 0.508)
		(drill 0.254)
		(layers "F.Cu" "B.Cu")
		(net "PWRGD_P1V5_C_PG")
	)
	(via
		(at 239.776 -110.236)
		(size 0.5588)
		(drill 0.3048)
		(layers "F.Cu" "B.Cu")
		(net "PWRGD_P1V5_C_PG")
	)
	(via
		(at 76.708 -23.9522)
		(size 0.5588)
		(drill 0.3048)
		(layers "F.Cu" "B.Cu")
		(net "PWRGD_P1V5_C_PG")
	)
	(via
		(at 76.708 -24.765)
		(size 0.7112)
		(drill 0.3556)
		(layers "F.Cu" "B.Cu")
		(net "PWRGD_P1V5_C_PG")
	)
	(segment
		(start 249.64898 -110.236)
		(end 250.43638 -111.0234)
		(width 0.127)
		(layer "In2.Cu")
		(net "PWRGD_P1V5_C_PG")
	)
	(segment
		(start 239.776 -110.236)
		(end 249.64898 -110.236)
		(width 0.127)
		(layer "In2.Cu")
		(net "PWRGD_P1V5_C_PG")
	)
	(segment
		(start 254.001778 -111.0234)
		(end 263.6647 -101.360478)
		(width 0.127)
		(layer "In2.Cu")
		(net "PWRGD_P1V5_C_PG")
	)
	(segment
		(start 263.6647 -85.2297)
		(end 247.651778 -69.216778)
		(width 0.127)
		(layer "In2.Cu")
		(net "PWRGD_P1V5_C_PG")
	)
	(segment
		(start 250.43638 -111.0234)
		(end 254.001778 -111.0234)
		(width 0.127)
		(layer "In2.Cu")
		(net "PWRGD_P1V5_C_PG")
	)
	(segment
		(start 247.651778 -69.216778)
		(end 247.651778 -49.3522)
		(width 0.127)
		(layer "In2.Cu")
		(net "PWRGD_P1V5_C_PG")
	)
	(segment
		(start 263.6647 -101.360478)
		(end 263.6647 -85.2297)
		(width 0.127)
		(layer "In2.Cu")
		(net "PWRGD_P1V5_C_PG")
	)
	(segment
		(start 84.3534 -20.356068)
		(end 84.3534 -22.138132)
		(width 0.127)
		(layer "In5.Cu")
		(net "PWRGD_P1V5_C_PG")
	)
	(segment
		(start 247.651778 -49.3522)
		(end 246.8372 -48.537622)
		(width 0.127)
		(layer "In5.Cu")
		(net "PWRGD_P1V5_C_PG")
	)
	(segment
		(start 203.581 -38.354)
		(end 203.201524 -38.354)
		(width 0.127)
		(layer "In5.Cu")
		(net "PWRGD_P1V5_C_PG")
	)
	(segment
		(start 243.9416 -45.2628)
		(end 210.4898 -45.2628)
		(width 0.127)
		(layer "In5.Cu")
		(net "PWRGD_P1V5_C_PG")
	)
	(segment
		(start 83.26247 -23.229062)
		(end 77.431138 -23.229062)
		(width 0.127)
		(layer "In5.Cu")
		(net "PWRGD_P1V5_C_PG")
	)
	(segment
		(start 95.2627 -17.1577)
		(end 90.037412 -17.1577)
		(width 0.127)
		(layer "In5.Cu")
		(net "PWRGD_P1V5_C_PG")
	)
	(segment
		(start 77.431138 -23.229062)
		(end 76.708 -23.9522)
		(width 0.127)
		(layer "In5.Cu")
		(net "PWRGD_P1V5_C_PG")
	)
	(segment
		(start 145.17878 -36.7538)
		(end 126.385828 -17.960848)
		(width 0.127)
		(layer "In5.Cu")
		(net "PWRGD_P1V5_C_PG")
	)
	(segment
		(start 203.125324 -38.2778)
		(end 175.883062 -38.2778)
		(width 0.127)
		(layer "In5.Cu")
		(net "PWRGD_P1V5_C_PG")
	)
	(segment
		(start 126.385828 -17.960848)
		(end 96.065848 -17.960848)
		(width 0.127)
		(layer "In5.Cu")
		(net "PWRGD_P1V5_C_PG")
	)
	(segment
		(start 89.415112 -17.78)
		(end 86.929468 -17.78)
		(width 0.127)
		(layer "In5.Cu")
		(net "PWRGD_P1V5_C_PG")
	)
	(segment
		(start 246.8372 -48.537622)
		(end 246.8372 -48.1584)
		(width 0.127)
		(layer "In5.Cu")
		(net "PWRGD_P1V5_C_PG")
	)
	(segment
		(start 84.3534 -22.138132)
		(end 83.26247 -23.229062)
		(width 0.127)
		(layer "In5.Cu")
		(net "PWRGD_P1V5_C_PG")
	)
	(segment
		(start 96.065848 -17.960848)
		(end 95.2627 -17.1577)
		(width 0.127)
		(layer "In5.Cu")
		(net "PWRGD_P1V5_C_PG")
	)
	(segment
		(start 175.883062 -38.2778)
		(end 174.359062 -36.7538)
		(width 0.127)
		(layer "In5.Cu")
		(net "PWRGD_P1V5_C_PG")
	)
	(segment
		(start 90.037412 -17.1577)
		(end 89.415112 -17.78)
		(width 0.127)
		(layer "In5.Cu")
		(net "PWRGD_P1V5_C_PG")
	)
	(segment
		(start 86.929468 -17.78)
		(end 84.3534 -20.356068)
		(width 0.127)
		(layer "In5.Cu")
		(net "PWRGD_P1V5_C_PG")
	)
	(segment
		(start 210.4898 -45.2628)
		(end 203.581 -38.354)
		(width 0.127)
		(layer "In5.Cu")
		(net "PWRGD_P1V5_C_PG")
	)
	(segment
		(start 203.201524 -38.354)
		(end 203.125324 -38.2778)
		(width 0.127)
		(layer "In5.Cu")
		(net "PWRGD_P1V5_C_PG")
	)
	(segment
		(start 246.8372 -48.1584)
		(end 243.9416 -45.2628)
		(width 0.127)
		(layer "In5.Cu")
		(net "PWRGD_P1V5_C_PG")
	)
	(segment
		(start 174.359062 -36.7538)
		(end 145.17878 -36.7538)
		(width 0.127)
		(layer "In5.Cu")
		(net "PWRGD_P1V5_C_PG")
	)
	(segment
		(start 109.860842 -83.938872)
		(end 109.860842 -83.891882)
		(width 0.1143)
		(layer "F.Cu")
		(net "EXP_ADC_IN0")
	)
	(segment
		(start 110.271814 -84.349844)
		(end 109.860842 -83.938872)
		(width 0.1143)
		(layer "F.Cu")
		(net "EXP_ADC_IN0")
	)
	(segment
		(start 110.349792 -84.349844)
		(end 110.271814 -84.349844)
		(width 0.1143)
		(layer "F.Cu")
		(net "EXP_ADC_IN0")
	)
	(via
		(at 110.27537 -83.058)
		(size 0.7112)
		(drill 0.3556)
		(layers "F.Cu" "B.Cu")
		(net "EXP_ADC_IN0")
	)
	(via
		(at 109.860842 -83.891882)
		(size 0.508)
		(drill 0.254)
		(layers "F.Cu" "B.Cu")
		(net "EXP_ADC_IN0")
	)
	(segment
		(start 109.813852 -83.891882)
		(end 109.352842 -83.430872)
		(width 0.1143)
		(layer "B.Cu")
		(net "EXP_ADC_IN0")
	)
	(segment
		(start 109.361224 -83.058)
		(end 110.27537 -83.058)
		(width 0.1143)
		(layer "B.Cu")
		(net "EXP_ADC_IN0")
	)
	(segment
		(start 109.352842 -83.430872)
		(end 109.352842 -83.066382)
		(width 0.1143)
		(layer "B.Cu")
		(net "EXP_ADC_IN0")
	)
	(segment
		(start 109.352842 -83.066382)
		(end 109.361224 -83.058)
		(width 0.1143)
		(layer "B.Cu")
		(net "EXP_ADC_IN0")
	)
	(segment
		(start 109.860842 -83.891882)
		(end 109.813852 -83.891882)
		(width 0.1143)
		(layer "B.Cu")
		(net "EXP_ADC_IN0")
	)
	(segment
		(start 91.559634 -44.59986)
		(end 91.957144 -44.99737)
		(width 0.1143)
		(layer "F.Cu")
		(net "RTRIM#")
	)
	(segment
		(start 91.549982 -44.59986)
		(end 91.559634 -44.59986)
		(width 0.1143)
		(layer "F.Cu")
		(net "RTRIM#")
	)
	(via
		(at 93.149166 -44.196)
		(size 0.7112)
		(drill 0.3556)
		(layers "F.Cu" "B.Cu")
		(net "RTRIM#")
	)
	(via
		(at 91.957144 -44.99737)
		(size 0.508)
		(drill 0.254)
		(layers "F.Cu" "B.Cu")
		(net "RTRIM#")
	)
	(segment
		(start 91.957144 -44.99737)
		(end 92.017596 -44.99737)
		(width 0.1143)
		(layer "B.Cu")
		(net "RTRIM#")
	)
	(segment
		(start 92.01404 -45.054266)
		(end 91.957144 -44.99737)
		(width 0.1143)
		(layer "B.Cu")
		(net "RTRIM#")
	)
	(segment
		(start 92.017596 -44.99737)
		(end 92.818966 -44.196)
		(width 0.1143)
		(layer "B.Cu")
		(net "RTRIM#")
	)
	(segment
		(start 92.01404 -45.69714)
		(end 92.01404 -45.054266)
		(width 0.1143)
		(layer "B.Cu")
		(net "RTRIM#")
	)
	(segment
		(start 92.818966 -44.196)
		(end 93.149166 -44.196)
		(width 0.1143)
		(layer "B.Cu")
		(net "RTRIM#")
	)
	(segment
		(start 113.349786 -86.34984)
		(end 112.84966 -85.849714)
		(width 0.1143)
		(layer "F.Cu")
		(net "EXP_LED19")
	)
	(via
		(at 112.84966 -85.849714)
		(size 0.508)
		(drill 0.254)
		(layers "F.Cu" "B.Cu")
		(net "EXP_LED19")
	)
	(segment
		(start 112.851946 -85.852)
		(end 112.84966 -85.849714)
		(width 0.1143)
		(layer "B.Cu")
		(net "EXP_LED19")
	)
	(segment
		(start 113.93297 -85.852)
		(end 112.851946 -85.852)
		(width 0.1143)
		(layer "B.Cu")
		(net "EXP_LED19")
	)
	(via
		(at 219.583 -104.394)
		(size 0.7112)
		(drill 0.3556)
		(layers "F.Cu" "B.Cu")
		(net "TPS74801_1V5_C_BIAS")
	)
	(segment
		(start 112.775238 -75.946)
		(end 111.860838 -75.0316)
		(width 0.1143)
		(layer "F.Cu")
		(net "EXP_BLINK_OUT")
	)
	(segment
		(start 106.34472 -77.673454)
		(end 107.310174 -76.708)
		(width 0.1143)
		(layer "F.Cu")
		(net "EXP_BLINK_OUT")
	)
	(segment
		(start 105.65257 -78.905354)
		(end 105.913174 -78.64475)
		(width 0.1143)
		(layer "F.Cu")
		(net "EXP_BLINK_OUT")
	)
	(segment
		(start 107.310174 -76.708)
		(end 108.59897 -76.708)
		(width 0.1143)
		(layer "F.Cu")
		(net "EXP_BLINK_OUT")
	)
	(segment
		(start 105.349802 -80.48371)
		(end 105.65257 -80.180942)
		(width 0.1143)
		(layer "F.Cu")
		(net "EXP_BLINK_OUT")
	)
	(segment
		(start 109.74197 -75.565)
		(end 110.109 -75.565)
		(width 0.1143)
		(layer "F.Cu")
		(net "EXP_BLINK_OUT")
	)
	(segment
		(start 105.349802 -82.349848)
		(end 105.349802 -80.48371)
		(width 0.1143)
		(layer "F.Cu")
		(net "EXP_BLINK_OUT")
	)
	(segment
		(start 112.820958 -75.946)
		(end 112.775238 -75.946)
		(width 0.1143)
		(layer "F.Cu")
		(net "EXP_BLINK_OUT")
	)
	(segment
		(start 105.65257 -80.180942)
		(end 105.65257 -78.905354)
		(width 0.1143)
		(layer "F.Cu")
		(net "EXP_BLINK_OUT")
	)
	(segment
		(start 111.5568 -74.8792)
		(end 111.5568 -74.8157)
		(width 0.1143)
		(layer "F.Cu")
		(net "EXP_BLINK_OUT")
	)
	(segment
		(start 108.59897 -76.708)
		(end 109.74197 -75.565)
		(width 0.1143)
		(layer "F.Cu")
		(net "EXP_BLINK_OUT")
	)
	(segment
		(start 111.7854 -75.0316)
		(end 111.5695 -74.8157)
		(width 0.1143)
		(layer "F.Cu")
		(net "EXP_BLINK_OUT")
	)
	(segment
		(start 105.913174 -78.64475)
		(end 106.028744 -78.64475)
		(width 0.1143)
		(layer "F.Cu")
		(net "EXP_BLINK_OUT")
	)
	(segment
		(start 110.871 -75.565)
		(end 111.5568 -74.8792)
		(width 0.1143)
		(layer "F.Cu")
		(net "EXP_BLINK_OUT")
	)
	(segment
		(start 106.34472 -78.328774)
		(end 106.34472 -77.673454)
		(width 0.1143)
		(layer "F.Cu")
		(net "EXP_BLINK_OUT")
	)
	(segment
		(start 110.109 -75.565)
		(end 110.871 -75.565)
		(width 0.1143)
		(layer "F.Cu")
		(net "EXP_BLINK_OUT")
	)
	(segment
		(start 106.028744 -78.64475)
		(end 106.34472 -78.328774)
		(width 0.1143)
		(layer "F.Cu")
		(net "EXP_BLINK_OUT")
	)
	(segment
		(start 111.5695 -74.8157)
		(end 111.5568 -74.8157)
		(width 0.1143)
		(layer "F.Cu")
		(net "EXP_BLINK_OUT")
	)
	(segment
		(start 111.860838 -75.0316)
		(end 111.7854 -75.0316)
		(width 0.1143)
		(layer "F.Cu")
		(net "EXP_BLINK_OUT")
	)
	(via
		(at 110.109 -75.565)
		(size 0.7112)
		(drill 0.3556)
		(layers "F.Cu" "B.Cu")
		(net "EXP_BLINK_OUT")
	)
	(via
		(at 111.5568 -74.8157)
		(size 0.5588)
		(drill 0.3048)
		(layers "F.Cu" "B.Cu")
		(net "EXP_BLINK_OUT")
	)
	(segment
		(start 111.5695 -74.8157)
		(end 111.5568 -74.8157)
		(width 0.1143)
		(layer "B.Cu")
		(net "EXP_BLINK_OUT")
	)
	(segment
		(start 112.78997 -74.9935)
		(end 111.7473 -74.9935)
		(width 0.1143)
		(layer "B.Cu")
		(net "EXP_BLINK_OUT")
	)
	(segment
		(start 111.7473 -74.9935)
		(end 111.5695 -74.8157)
		(width 0.1143)
		(layer "B.Cu")
		(net "EXP_BLINK_OUT")
	)
	(segment
		(start 112.34166 -26.924)
		(end 111.57966 -26.162)
		(width 0.1143)
		(layer "F.Cu")
		(net "SYS_DBMODE1")
	)
	(segment
		(start 107.19816 -29.95041)
		(end 105.950004 -31.198566)
		(width 0.1143)
		(layer "F.Cu")
		(net "SYS_DBMODE1")
	)
	(segment
		(start 108.75899 -27.35199)
		(end 108.75899 -27.89301)
		(width 0.1143)
		(layer "F.Cu")
		(net "SYS_DBMODE1")
	)
	(segment
		(start 108.75899 -27.89301)
		(end 108.458 -28.194)
		(width 0.1143)
		(layer "F.Cu")
		(net "SYS_DBMODE1")
	)
	(segment
		(start 108.458 -28.194)
		(end 107.91698 -28.194)
		(width 0.1143)
		(layer "F.Cu")
		(net "SYS_DBMODE1")
	)
	(segment
		(start 107.19816 -28.91282)
		(end 107.19816 -29.95041)
		(width 0.1143)
		(layer "F.Cu")
		(net "SYS_DBMODE1")
	)
	(segment
		(start 109.94898 -26.162)
		(end 108.75899 -27.35199)
		(width 0.1143)
		(layer "F.Cu")
		(net "SYS_DBMODE1")
	)
	(segment
		(start 113.3475 -26.924)
		(end 112.34166 -26.924)
		(width 0.1143)
		(layer "F.Cu")
		(net "SYS_DBMODE1")
	)
	(segment
		(start 111.57966 -26.162)
		(end 109.94898 -26.162)
		(width 0.1143)
		(layer "F.Cu")
		(net "SYS_DBMODE1")
	)
	(segment
		(start 107.91698 -28.194)
		(end 107.19816 -28.91282)
		(width 0.1143)
		(layer "F.Cu")
		(net "SYS_DBMODE1")
	)
	(segment
		(start 105.950004 -31.198566)
		(end 105.950004 -33.399984)
		(width 0.1143)
		(layer "F.Cu")
		(net "SYS_DBMODE1")
	)
	(segment
		(start 94.750128 -48.599852)
		(end 95.149924 -48.999648)
		(width 0.1143)
		(layer "F.Cu")
		(net "ICE1_TDI")
	)
	(via
		(at 95.149924 -48.999648)
		(size 0.508)
		(drill 0.254)
		(layers "F.Cu" "B.Cu")
		(net "ICE1_TDI")
	)
	(segment
		(start 95.26016 -50.165)
		(end 95.26016 -49.109884)
		(width 0.1143)
		(layer "B.Cu")
		(net "ICE1_TDI")
	)
	(segment
		(start 95.26016 -49.109884)
		(end 95.149924 -48.999648)
		(width 0.1143)
		(layer "B.Cu")
		(net "ICE1_TDI")
	)
	(segment
		(start 95.231966 -50.193194)
		(end 95.26016 -50.165)
		(width 0.1143)
		(layer "B.Cu")
		(net "ICE1_TDI")
	)
	(segment
		(start 94.533466 -51.7525)
		(end 95.231966 -51.054)
		(width 0.1143)
		(layer "B.Cu")
		(net "ICE1_TDI")
	)
	(segment
		(start 95.231966 -51.054)
		(end 95.231966 -50.193194)
		(width 0.1143)
		(layer "B.Cu")
		(net "ICE1_TDI")
	)
	(segment
		(start 94.342966 -51.7525)
		(end 94.533466 -51.7525)
		(width 0.1143)
		(layer "B.Cu")
		(net "ICE1_TDI")
	)
	(via
		(at 218.694 -108.966)
		(size 0.7112)
		(drill 0.3556)
		(layers "F.Cu" "B.Cu")
		(net "TPS74801_1V5_C_EN")
	)
	(segment
		(start 103.349806 -98.35007)
		(end 102.84968 -98.850196)
		(width 0.1143)
		(layer "F.Cu")
		(net "EXP_TACH_IN0")
	)
	(via
		(at 102.84968 -98.850196)
		(size 0.508)
		(drill 0.254)
		(layers "F.Cu" "B.Cu")
		(net "EXP_TACH_IN0")
	)
	(segment
		(start 99.68992 -101.268022)
		(end 100.234242 -100.7237)
		(width 0.1143)
		(layer "B.Cu")
		(net "EXP_TACH_IN0")
	)
	(segment
		(start 100.234242 -100.7237)
		(end 100.3681 -100.7237)
		(width 0.1143)
		(layer "B.Cu")
		(net "EXP_TACH_IN0")
	)
	(segment
		(start 101.403658 -99.688142)
		(end 102.011734 -99.688142)
		(width 0.1143)
		(layer "B.Cu")
		(net "EXP_TACH_IN0")
	)
	(segment
		(start 96.66097 -103.378)
		(end 97.81667 -102.2223)
		(width 0.1143)
		(layer "B.Cu")
		(net "EXP_TACH_IN0")
	)
	(segment
		(start 98.858324 -102.2223)
		(end 99.68992 -101.390704)
		(width 0.1143)
		(layer "B.Cu")
		(net "EXP_TACH_IN0")
	)
	(segment
		(start 100.3681 -100.7237)
		(end 101.403658 -99.688142)
		(width 0.1143)
		(layer "B.Cu")
		(net "EXP_TACH_IN0")
	)
	(segment
		(start 99.68992 -101.390704)
		(end 99.68992 -101.268022)
		(width 0.1143)
		(layer "B.Cu")
		(net "EXP_TACH_IN0")
	)
	(segment
		(start 102.011734 -99.688142)
		(end 102.84968 -98.850196)
		(width 0.1143)
		(layer "B.Cu")
		(net "EXP_TACH_IN0")
	)
	(segment
		(start 97.81667 -102.2223)
		(end 98.858324 -102.2223)
		(width 0.1143)
		(layer "B.Cu")
		(net "EXP_TACH_IN0")
	)
	(segment
		(start 103.064818 -55.79999)
		(end 103.401368 -55.46344)
		(width 0.1143)
		(layer "F.Cu")
		(net "LSI_JTAG_EN_N")
	)
	(segment
		(start 102.750112 -55.79999)
		(end 103.064818 -55.79999)
		(width 0.1143)
		(layer "F.Cu")
		(net "LSI_JTAG_EN_N")
	)
	(segment
		(start 106.429556 -60.911486)
		(end 106.47807 -60.96)
		(width 0.1143)
		(layer "F.Cu")
		(net "LSI_JTAG_EN_N")
	)
	(segment
		(start 109.443266 -63.336424)
		(end 110.217966 -64.111124)
		(width 0.1143)
		(layer "F.Cu")
		(net "LSI_JTAG_EN_N")
	)
	(segment
		(start 106.47807 -60.96)
		(end 106.5784 -60.96)
		(width 0.1143)
		(layer "F.Cu")
		(net "LSI_JTAG_EN_N")
	)
	(segment
		(start 108.066078 -61.152786)
		(end 109.443266 -62.529974)
		(width 0.1143)
		(layer "F.Cu")
		(net "LSI_JTAG_EN_N")
	)
	(segment
		(start 105.536238 -60.911486)
		(end 106.429556 -60.911486)
		(width 0.1143)
		(layer "F.Cu")
		(net "LSI_JTAG_EN_N")
	)
	(segment
		(start 103.401368 -55.46344)
		(end 103.689404 -55.46344)
		(width 0.1143)
		(layer "F.Cu")
		(net "LSI_JTAG_EN_N")
	)
	(segment
		(start 110.217966 -64.111124)
		(end 110.217966 -65.4431)
		(width 0.1143)
		(layer "F.Cu")
		(net "LSI_JTAG_EN_N")
	)
	(segment
		(start 106.771186 -61.152786)
		(end 108.066078 -61.152786)
		(width 0.1143)
		(layer "F.Cu")
		(net "LSI_JTAG_EN_N")
	)
	(segment
		(start 109.443266 -62.529974)
		(end 109.443266 -63.336424)
		(width 0.1143)
		(layer "F.Cu")
		(net "LSI_JTAG_EN_N")
	)
	(segment
		(start 103.994966 -55.769002)
		(end 103.994966 -59.370214)
		(width 0.1143)
		(layer "F.Cu")
		(net "LSI_JTAG_EN_N")
	)
	(segment
		(start 106.5784 -60.96)
		(end 106.771186 -61.152786)
		(width 0.1143)
		(layer "F.Cu")
		(net "LSI_JTAG_EN_N")
	)
	(segment
		(start 103.689404 -55.46344)
		(end 103.994966 -55.769002)
		(width 0.1143)
		(layer "F.Cu")
		(net "LSI_JTAG_EN_N")
	)
	(segment
		(start 103.994966 -59.370214)
		(end 105.536238 -60.911486)
		(width 0.1143)
		(layer "F.Cu")
		(net "LSI_JTAG_EN_N")
	)
	(via
		(at 106.47807 -60.96)
		(size 0.7112)
		(drill 0.3556)
		(layers "F.Cu" "B.Cu")
		(net "LSI_JTAG_EN_N")
	)
	(segment
		(start 213.780624 -99.52609)
		(end 210.90509 -99.52609)
		(width 0.3048)
		(layer "F.Cu")
		(net "P1V5_C")
	)
	(segment
		(start 101.950012 -34.99993)
		(end 101.940614 -34.99993)
		(width 0.3048)
		(layer "F.Cu")
		(net "P1V5_C")
	)
	(segment
		(start 325.374 -180.1495)
		(end 325.673974 -180.1495)
		(width 0.508)
		(layer "F.Cu")
		(net "P1V5_C")
	)
	(segment
		(start 325.93153 -179.891944)
		(end 326.547988 -179.891944)
		(width 0.508)
		(layer "F.Cu")
		(net "P1V5_C")
	)
	(segment
		(start 103.96474 -36.185348)
		(end 103.96474 -36.8173)
		(width 0.2032)
		(layer "F.Cu")
		(net "P1V5_C")
	)
	(segment
		(start 212.605874 -101.350826)
		(end 210.951826 -101.350826)
		(width 0.3048)
		(layer "F.Cu")
		(net "P1V5_C")
	)
	(segment
		(start 96.350074 -37.399976)
		(end 95.950278 -37.00018)
		(width 0.3048)
		(layer "F.Cu")
		(net "P1V5_C")
	)
	(segment
		(start 212.605874 -102.000812)
		(end 210.712812 -102.000812)
		(width 0.3048)
		(layer "F.Cu")
		(net "P1V5_C")
	)
	(segment
		(start 99.549966 -35.80003)
		(end 99.15017 -35.400234)
		(width 0.3048)
		(layer "F.Cu")
		(net "P1V5_C")
	)
	(segment
		(start 103.166418 -37.012118)
		(end 103.15194 -36.99764)
		(width 0.2032)
		(layer "F.Cu")
		(net "P1V5_C")
	)
	(segment
		(start 212.605874 -100.70084)
		(end 210.95716 -100.70084)
		(width 0.3048)
		(layer "F.Cu")
		(net "P1V5_C")
	)
	(segment
		(start 327.120504 -180.46446)
		(end 327.142348 -180.46446)
		(width 0.508)
		(layer "F.Cu")
		(net "P1V5_C")
	)
	(segment
		(start 97.150174 -35.80003)
		(end 97.150174 -35.796474)
		(width 0.3048)
		(layer "F.Cu")
		(net "P1V5_C")
	)
	(segment
		(start 103.769922 -37.012118)
		(end 103.166418 -37.012118)
		(width 0.2032)
		(layer "F.Cu")
		(net "P1V5_C")
	)
	(segment
		(start 101.150166 -37.399976)
		(end 100.75037 -37.00018)
		(width 0.3048)
		(layer "F.Cu")
		(net "P1V5_C")
	)
	(segment
		(start 325.673974 -180.1495)
		(end 325.93153 -179.891944)
		(width 0.508)
		(layer "F.Cu")
		(net "P1V5_C")
	)
	(segment
		(start 103.96474 -36.8173)
		(end 103.769922 -37.012118)
		(width 0.2032)
		(layer "F.Cu")
		(net "P1V5_C")
	)
	(segment
		(start 326.547988 -179.891944)
		(end 327.120504 -180.46446)
		(width 0.508)
		(layer "F.Cu")
		(net "P1V5_C")
	)
	(segment
		(start 97.95002 -37.399976)
		(end 97.550224 -37.00018)
		(width 0.3048)
		(layer "F.Cu")
		(net "P1V5_C")
	)
	(segment
		(start 101.940614 -34.99993)
		(end 101.544882 -34.604198)
		(width 0.3048)
		(layer "F.Cu")
		(net "P1V5_C")
	)
	(segment
		(start 104.350058 -35.80003)
		(end 103.96474 -36.185348)
		(width 0.2032)
		(layer "F.Cu")
		(net "P1V5_C")
	)
	(segment
		(start 102.750112 -37.399976)
		(end 102.350316 -37.00018)
		(width 0.3048)
		(layer "F.Cu")
		(net "P1V5_C")
	)
	(segment
		(start 99.549966 -37.399976)
		(end 99.15017 -37.00018)
		(width 0.3048)
		(layer "F.Cu")
		(net "P1V5_C")
	)
	(segment
		(start 97.150174 -35.796474)
		(end 96.75368 -35.39998)
		(width 0.3048)
		(layer "F.Cu")
		(net "P1V5_C")
	)
	(via
		(at 210.693 -94.869)
		(size 0.7112)
		(drill 0.4064)
		(layers "F.Cu" "B.Cu")
		(net "P1V5_C")
	)
	(via
		(at 236.347 -55.626)
		(size 0.7112)
		(drill 0.4064)
		(layers "F.Cu" "B.Cu")
		(net "P1V5_C")
	)
	(via
		(at 99.15017 -37.00018)
		(size 0.508)
		(drill 0.254)
		(layers "F.Cu" "B.Cu")
		(net "P1V5_C")
	)
	(via
		(at 102.350316 -37.00018)
		(size 0.508)
		(drill 0.254)
		(layers "F.Cu" "B.Cu")
		(net "P1V5_C")
	)
	(via
		(at 210.693 -96.52)
		(size 0.7112)
		(drill 0.4064)
		(layers "F.Cu" "B.Cu")
		(net "P1V5_C")
	)
	(via
		(at 237.871 -57.277)
		(size 0.7112)
		(drill 0.4064)
		(layers "F.Cu" "B.Cu")
		(net "P1V5_C")
	)
	(via
		(at 99.15017 -35.400234)
		(size 0.508)
		(drill 0.254)
		(layers "F.Cu" "B.Cu")
		(net "P1V5_C")
	)
	(via
		(at 95.950278 -37.00018)
		(size 0.508)
		(drill 0.254)
		(layers "F.Cu" "B.Cu")
		(net "P1V5_C")
	)
	(via
		(at 100.75037 -37.00018)
		(size 0.508)
		(drill 0.254)
		(layers "F.Cu" "B.Cu")
		(net "P1V5_C")
	)
	(via
		(at 327.142348 -180.46446)
		(size 0.508)
		(drill 0.254)
		(layers "F.Cu" "B.Cu")
		(net "P1V5_C")
	)
	(via
		(at 103.15194 -36.99764)
		(size 0.508)
		(drill 0.254)
		(layers "F.Cu" "B.Cu")
		(net "P1V5_C")
	)
	(via
		(at 237.871 -55.626)
		(size 0.7112)
		(drill 0.4064)
		(layers "F.Cu" "B.Cu")
		(net "P1V5_C")
	)
	(via
		(at 236.347 -58.928)
		(size 0.7112)
		(drill 0.4064)
		(layers "F.Cu" "B.Cu")
		(net "P1V5_C")
	)
	(via
		(at 101.544882 -34.604198)
		(size 0.508)
		(drill 0.254)
		(layers "F.Cu" "B.Cu")
		(net "P1V5_C")
	)
	(via
		(at 319.532 -141.0716)
		(size 0.5588)
		(drill 0.3048)
		(layers "F.Cu" "B.Cu")
		(net "P1V5_C")
	)
	(via
		(at 97.550224 -37.00018)
		(size 0.508)
		(drill 0.254)
		(layers "F.Cu" "B.Cu")
		(net "P1V5_C")
	)
	(via
		(at 240.21288 -121.48312)
		(size 0.7112)
		(drill 0.3556)
		(layers "F.Cu" "B.Cu")
		(net "P1V5_C")
	)
	(via
		(at 96.75368 -35.39998)
		(size 0.508)
		(drill 0.254)
		(layers "F.Cu" "B.Cu")
		(net "P1V5_C")
	)
	(via
		(at 210.693 -97.917)
		(size 0.7112)
		(drill 0.4064)
		(layers "F.Cu" "B.Cu")
		(net "P1V5_C")
	)
	(via
		(at 236.347 -57.277)
		(size 0.7112)
		(drill 0.4064)
		(layers "F.Cu" "B.Cu")
		(net "P1V5_C")
	)
	(via
		(at 237.871 -58.928)
		(size 0.7112)
		(drill 0.4064)
		(layers "F.Cu" "B.Cu")
		(net "P1V5_C")
	)
	(segment
		(start 303.591722 -122.174)
		(end 309.9562 -128.538478)
		(width 0.508)
		(layer "B.Cu")
		(net "P1V5_C")
	)
	(segment
		(start 240.21288 -121.3612)
		(end 240.21288 -121.48312)
		(width 0.508)
		(layer "B.Cu")
		(net "P1V5_C")
	)
	(segment
		(start 99.468686 -37.69868)
		(end 99.468686 -37.318696)
		(width 0.3556)
		(layer "B.Cu")
		(net "P1V5_C")
	)
	(segment
		(start 100.591366 -37.159184)
		(end 100.75037 -37.00018)
		(width 0.3556)
		(layer "B.Cu")
		(net "P1V5_C")
	)
	(segment
		(start 311.027572 -129.907538)
		(end 311.04205 -129.907538)
		(width 0.508)
		(layer "B.Cu")
		(net "P1V5_C")
	)
	(segment
		(start 240.21288 -121.48312)
		(end 241.16411 -122.43435)
		(width 0.508)
		(layer "B.Cu")
		(net "P1V5_C")
	)
	(segment
		(start 311.04205 -129.907538)
		(end 314.611512 -133.477)
		(width 0.508)
		(layer "B.Cu")
		(net "P1V5_C")
	)
	(segment
		(start 210.7692 -103.7082)
		(end 216.4842 -109.4232)
		(width 0.508)
		(layer "B.Cu")
		(net "P1V5_C")
	)
	(segment
		(start 216.4842 -109.4232)
		(end 230.305356 -109.4232)
		(width 0.508)
		(layer "B.Cu")
		(net "P1V5_C")
	)
	(segment
		(start 236.07522 -115.193064)
		(end 236.07522 -117.22354)
		(width 0.508)
		(layer "B.Cu")
		(net "P1V5_C")
	)
	(segment
		(start 319.46215 -141.00175)
		(end 319.532 -141.0716)
		(width 0.508)
		(layer "B.Cu")
		(net "P1V5_C")
	)
	(segment
		(start 100.591366 -37.719)
		(end 100.591366 -37.159184)
		(width 0.3556)
		(layer "B.Cu")
		(net "P1V5_C")
	)
	(segment
		(start 319.46215 -134.911592)
		(end 319.46215 -141.00175)
		(width 0.508)
		(layer "B.Cu")
		(net "P1V5_C")
	)
	(segment
		(start 309.9562 -128.836166)
		(end 311.027572 -129.907538)
		(width 0.508)
		(layer "B.Cu")
		(net "P1V5_C")
	)
	(segment
		(start 95.26016 -37.4396)
		(end 95.42526 -37.2745)
		(width 0.3556)
		(layer "B.Cu")
		(net "P1V5_C")
	)
	(segment
		(start 309.9562 -128.538478)
		(end 309.9562 -128.836166)
		(width 0.508)
		(layer "B.Cu")
		(net "P1V5_C")
	)
	(segment
		(start 241.16411 -122.43435)
		(end 295.77665 -122.43435)
		(width 0.508)
		(layer "B.Cu")
		(net "P1V5_C")
	)
	(segment
		(start 210.7692 -97.9932)
		(end 210.7692 -103.7082)
		(width 0.508)
		(layer "B.Cu")
		(net "P1V5_C")
	)
	(segment
		(start 99.468686 -37.318696)
		(end 99.15017 -37.00018)
		(width 0.3556)
		(layer "B.Cu")
		(net "P1V5_C")
	)
	(segment
		(start 236.07522 -117.22354)
		(end 240.21288 -121.3612)
		(width 0.508)
		(layer "B.Cu")
		(net "P1V5_C")
	)
	(segment
		(start 318.027558 -133.477)
		(end 319.46215 -134.911592)
		(width 0.508)
		(layer "B.Cu")
		(net "P1V5_C")
	)
	(segment
		(start 296.037 -122.174)
		(end 303.591722 -122.174)
		(width 0.508)
		(layer "B.Cu")
		(net "P1V5_C")
	)
	(segment
		(start 295.77665 -122.43435)
		(end 296.037 -122.174)
		(width 0.508)
		(layer "B.Cu")
		(net "P1V5_C")
	)
	(segment
		(start 95.675958 -37.2745)
		(end 95.950278 -37.00018)
		(width 0.3556)
		(layer "B.Cu")
		(net "P1V5_C")
	)
	(segment
		(start 210.693 -97.917)
		(end 210.7692 -97.9932)
		(width 0.508)
		(layer "B.Cu")
		(net "P1V5_C")
	)
	(segment
		(start 103.59898 -36.5506)
		(end 103.15194 -36.99764)
		(width 0.3048)
		(layer "B.Cu")
		(net "P1V5_C")
	)
	(segment
		(start 314.611512 -133.477)
		(end 318.027558 -133.477)
		(width 0.508)
		(layer "B.Cu")
		(net "P1V5_C")
	)
	(segment
		(start 103.89616 -36.5506)
		(end 103.59898 -36.5506)
		(width 0.3048)
		(layer "B.Cu")
		(net "P1V5_C")
	)
	(segment
		(start 95.42526 -37.2745)
		(end 95.675958 -37.2745)
		(width 0.3556)
		(layer "B.Cu")
		(net "P1V5_C")
	)
	(segment
		(start 230.305356 -109.4232)
		(end 236.07522 -115.193064)
		(width 0.508)
		(layer "B.Cu")
		(net "P1V5_C")
	)
	(segment
		(start 326.0852 -167.765222)
		(end 326.517 -168.197022)
		(width 0.508)
		(layer "In2.Cu")
		(net "P1V5_C")
	)
	(segment
		(start 323.514974 -154.686)
		(end 323.620892 -154.686)
		(width 0.508)
		(layer "In2.Cu")
		(net "P1V5_C")
	)
	(segment
		(start 319.532 -141.0716)
		(end 319.532 -150.703026)
		(width 0.508)
		(layer "In2.Cu")
		(net "P1V5_C")
	)
	(segment
		(start 326.4408 -163.545774)
		(end 326.4408 -164.114226)
		(width 0.508)
		(layer "In2.Cu")
		(net "P1V5_C")
	)
	(segment
		(start 326.0852 -164.469826)
		(end 326.0852 -167.765222)
		(width 0.508)
		(layer "In2.Cu")
		(net "P1V5_C")
	)
	(segment
		(start 323.620892 -154.686)
		(end 325.65975 -156.724858)
		(width 0.508)
		(layer "In2.Cu")
		(net "P1V5_C")
	)
	(segment
		(start 319.532 -150.703026)
		(end 323.514974 -154.686)
		(width 0.508)
		(layer "In2.Cu")
		(net "P1V5_C")
	)
	(segment
		(start 326.517 -168.197022)
		(end 326.517 -179.839112)
		(width 0.508)
		(layer "In2.Cu")
		(net "P1V5_C")
	)
	(segment
		(start 325.65975 -156.724858)
		(end 325.65975 -162.764724)
		(width 0.508)
		(layer "In2.Cu")
		(net "P1V5_C")
	)
	(segment
		(start 326.517 -179.839112)
		(end 327.142348 -180.46446)
		(width 0.508)
		(layer "In2.Cu")
		(net "P1V5_C")
	)
	(segment
		(start 325.65975 -162.764724)
		(end 326.4408 -163.545774)
		(width 0.508)
		(layer "In2.Cu")
		(net "P1V5_C")
	)
	(segment
		(start 326.4408 -164.114226)
		(end 326.0852 -164.469826)
		(width 0.508)
		(layer "In2.Cu")
		(net "P1V5_C")
	)
	(segment
		(start 112.350042 -37.397944)
		(end 112.752886 -36.9951)
		(width 0.1143)
		(layer "F.Cu")
		(net "UART_SERCLK")
	)
	(segment
		(start 112.350042 -37.399976)
		(end 112.350042 -37.397944)
		(width 0.1143)
		(layer "F.Cu")
		(net "UART_SERCLK")
	)
	(via
		(at 112.752886 -36.9951)
		(size 0.508)
		(drill 0.254)
		(layers "F.Cu" "B.Cu")
		(net "UART_SERCLK")
	)
	(segment
		(start 116.745004 -35.42665)
		(end 116.389404 -35.78225)
		(width 0.1143)
		(layer "B.Cu")
		(net "UART_SERCLK")
	)
	(segment
		(start 118.790466 -30.988)
		(end 118.218966 -31.5595)
		(width 0.1143)
		(layer "B.Cu")
		(net "UART_SERCLK")
	)
	(segment
		(start 115.836192 -35.78225)
		(end 115.296442 -36.322)
		(width 0.1143)
		(layer "B.Cu")
		(net "UART_SERCLK")
	)
	(segment
		(start 113.64849 -36.322)
		(end 112.97539 -36.9951)
		(width 0.1143)
		(layer "B.Cu")
		(net "UART_SERCLK")
	)
	(segment
		(start 118.218966 -33.956752)
		(end 116.749068 -35.42665)
		(width 0.1143)
		(layer "B.Cu")
		(net "UART_SERCLK")
	)
	(segment
		(start 118.218966 -32.258)
		(end 118.218966 -33.956752)
		(width 0.1143)
		(layer "B.Cu")
		(net "UART_SERCLK")
	)
	(segment
		(start 112.97539 -36.9951)
		(end 112.752886 -36.9951)
		(width 0.1143)
		(layer "B.Cu")
		(net "UART_SERCLK")
	)
	(segment
		(start 116.749068 -35.42665)
		(end 116.745004 -35.42665)
		(width 0.1143)
		(layer "B.Cu")
		(net "UART_SERCLK")
	)
	(segment
		(start 118.218966 -31.5595)
		(end 118.218966 -32.258)
		(width 0.1143)
		(layer "B.Cu")
		(net "UART_SERCLK")
	)
	(segment
		(start 115.296442 -36.322)
		(end 113.64849 -36.322)
		(width 0.1143)
		(layer "B.Cu")
		(net "UART_SERCLK")
	)
	(segment
		(start 116.389404 -35.78225)
		(end 115.836192 -35.78225)
		(width 0.1143)
		(layer "B.Cu")
		(net "UART_SERCLK")
	)
	(segment
		(start 215.773 -109.9185)
		(end 215.773 -108.966)
		(width 0.254)
		(layer "F.Cu")
		(net "TPS74801_1V5_C_SS")
	)
	(segment
		(start 213.780624 -106.973624)
		(end 215.773 -108.966)
		(width 0.254)
		(layer "F.Cu")
		(net "TPS74801_1V5_C_SS")
	)
	(segment
		(start 213.780624 -104.475534)
		(end 213.780624 -106.973624)
		(width 0.254)
		(layer "F.Cu")
		(net "TPS74801_1V5_C_SS")
	)
	(via
		(at 215.773 -108.966)
		(size 0.7112)
		(drill 0.3556)
		(layers "F.Cu" "B.Cu")
		(net "TPS74801_1V5_C_SS")
	)
	(segment
		(start 53.501544 -75.94981)
		(end 53.52669 -75.94981)
		(width 0.1016)
		(layer "F.Cu")
		(net "MINI_RX_P_23")
	)
	(segment
		(start 53.598572 -75.19416)
		(end 53.311298 -74.906886)
		(width 0.1016)
		(layer "F.Cu")
		(net "MINI_RX_P_23")
	)
	(segment
		(start 53.399944 -77.08011)
		(end 53.399944 -76.05141)
		(width 0.1016)
		(layer "F.Cu")
		(net "MINI_RX_P_23")
	)
	(segment
		(start 53.62829 -75.84821)
		(end 53.62829 -75.266042)
		(width 0.1016)
		(layer "F.Cu")
		(net "MINI_RX_P_23")
	)
	(via
		(at 53.311298 -74.906886)
		(size 0.5588)
		(drill 0.3048)
		(layers "F.Cu" "B.Cu")
		(net "MINI_RX_P_23")
	)
	(arc
		(start 53.62829 -75.266042)
		(mid 53.620571 -75.227147)
		(end 53.598572 -75.19416)
		(width 0.1016)
		(layer "F.Cu")
		(net "MINI_RX_P_23")
	)
	(arc
		(start 53.399944 -76.05141)
		(mid 53.429702 -75.979568)
		(end 53.501544 -75.94981)
		(width 0.1016)
		(layer "F.Cu")
		(net "MINI_RX_P_23")
	)
	(arc
		(start 53.52669 -75.94981)
		(mid 53.598532 -75.920052)
		(end 53.62829 -75.84821)
		(width 0.1016)
		(layer "F.Cu")
		(net "MINI_RX_P_23")
	)
	(segment
		(start 53.28793 -76.316586)
		(end 53.546502 -76.058014)
		(width 0.1016)
		(layer "B.Cu")
		(net "MINI_RX_P_23")
	)
	(segment
		(start 53.598572 -75.19416)
		(end 53.311298 -74.906886)
		(width 0.1016)
		(layer "B.Cu")
		(net "MINI_RX_P_23")
	)
	(segment
		(start 53.62829 -75.860656)
		(end 53.62829 -75.266042)
		(width 0.1016)
		(layer "B.Cu")
		(net "MINI_RX_P_23")
	)
	(arc
		(start 53.546502 -76.058014)
		(mid 53.607058 -75.96748)
		(end 53.62829 -75.860656)
		(width 0.1016)
		(layer "B.Cu")
		(net "MINI_RX_P_23")
	)
	(arc
		(start 53.62829 -75.266042)
		(mid 53.620571 -75.227147)
		(end 53.598572 -75.19416)
		(width 0.1016)
		(layer "B.Cu")
		(net "MINI_RX_P_23")
	)
	(segment
		(start 93.072966 -62.6745)
		(end 93.072966 -60.452)
		(width 0.1143)
		(layer "F.Cu")
		(net "ICE1_TCK")
	)
	(segment
		(start 95.104966 -56.244998)
		(end 95.549974 -55.79999)
		(width 0.1143)
		(layer "F.Cu")
		(net "ICE1_TCK")
	)
	(segment
		(start 95.104966 -57.404)
		(end 95.104966 -56.244998)
		(width 0.1143)
		(layer "F.Cu")
		(net "ICE1_TCK")
	)
	(segment
		(start 93.072966 -59.436)
		(end 95.104966 -57.404)
		(width 0.1143)
		(layer "F.Cu")
		(net "ICE1_TCK")
	)
	(segment
		(start 93.072966 -60.452)
		(end 93.072966 -59.436)
		(width 0.1143)
		(layer "F.Cu")
		(net "ICE1_TCK")
	)
	(segment
		(start 253.307596 -51.962812)
		(end 251.714 -51.962812)
		(width 0.1143)
		(layer "F.Cu")
		(net "IOC_EEPROM_WP")
	)
	(segment
		(start 250.704096 -51.962812)
		(end 251.714 -51.962812)
		(width 0.1143)
		(layer "F.Cu")
		(net "IOC_EEPROM_WP")
	)
	(via
		(at 251.714 -51.962812)
		(size 0.7112)
		(drill 0.3556)
		(layers "F.Cu" "B.Cu")
		(net "IOC_EEPROM_WP")
	)
	(segment
		(start 51.228498 -75.84821)
		(end 51.228498 -75.266042)
		(width 0.1016)
		(layer "F.Cu")
		(net "MINI_RX_P_22")
	)
	(segment
		(start 51.19878 -75.19416)
		(end 50.911506 -74.906886)
		(width 0.1016)
		(layer "F.Cu")
		(net "MINI_RX_P_22")
	)
	(segment
		(start 51.101498 -75.94981)
		(end 51.126898 -75.94981)
		(width 0.1016)
		(layer "F.Cu")
		(net "MINI_RX_P_22")
	)
	(segment
		(start 50.999898 -77.08011)
		(end 50.999898 -76.05141)
		(width 0.1016)
		(layer "F.Cu")
		(net "MINI_RX_P_22")
	)
	(via
		(at 50.911506 -74.906886)
		(size 0.5588)
		(drill 0.3048)
		(layers "F.Cu" "B.Cu")
		(net "MINI_RX_P_22")
	)
	(arc
		(start 51.228498 -75.266042)
		(mid 51.220779 -75.227147)
		(end 51.19878 -75.19416)
		(width 0.1016)
		(layer "F.Cu")
		(net "MINI_RX_P_22")
	)
	(arc
		(start 50.999898 -76.05141)
		(mid 51.029656 -75.979568)
		(end 51.101498 -75.94981)
		(width 0.1016)
		(layer "F.Cu")
		(net "MINI_RX_P_22")
	)
	(arc
		(start 51.126898 -75.94981)
		(mid 51.19874 -75.920052)
		(end 51.228498 -75.84821)
		(width 0.1016)
		(layer "F.Cu")
		(net "MINI_RX_P_22")
	)
	(segment
		(start 51.19878 -75.19416)
		(end 50.911506 -74.906886)
		(width 0.1016)
		(layer "B.Cu")
		(net "MINI_RX_P_22")
	)
	(segment
		(start 50.87493 -76.316586)
		(end 51.151536 -76.03998)
		(width 0.1016)
		(layer "B.Cu")
		(net "MINI_RX_P_22")
	)
	(segment
		(start 51.228498 -75.854052)
		(end 51.228498 -75.266042)
		(width 0.1016)
		(layer "B.Cu")
		(net "MINI_RX_P_22")
	)
	(arc
		(start 51.151536 -76.03998)
		(mid 51.208481 -75.954661)
		(end 51.228498 -75.854052)
		(width 0.1016)
		(layer "B.Cu")
		(net "MINI_RX_P_22")
	)
	(arc
		(start 51.228498 -75.266042)
		(mid 51.220779 -75.227147)
		(end 51.19878 -75.19416)
		(width 0.1016)
		(layer "B.Cu")
		(net "MINI_RX_P_22")
	)
	(segment
		(start 101.411532 -98.740468)
		(end 102.18928 -97.96272)
		(width 0.1143)
		(layer "F.Cu")
		(net "EXP_TACH_IN1")
	)
	(segment
		(start 101.411532 -99.093528)
		(end 101.411532 -98.740468)
		(width 0.1143)
		(layer "F.Cu")
		(net "EXP_TACH_IN1")
	)
	(segment
		(start 102.18928 -97.96272)
		(end 102.60203 -97.96272)
		(width 0.1143)
		(layer "F.Cu")
		(net "EXP_TACH_IN1")
	)
	(segment
		(start 103.214678 -97.350072)
		(end 103.349806 -97.350072)
		(width 0.1143)
		(layer "F.Cu")
		(net "EXP_TACH_IN1")
	)
	(segment
		(start 98.751644 -100.38715)
		(end 100.11791 -100.38715)
		(width 0.1143)
		(layer "F.Cu")
		(net "EXP_TACH_IN1")
	)
	(segment
		(start 100.11791 -100.38715)
		(end 101.411532 -99.093528)
		(width 0.1143)
		(layer "F.Cu")
		(net "EXP_TACH_IN1")
	)
	(segment
		(start 96.647 -99.822)
		(end 98.186494 -99.822)
		(width 0.1143)
		(layer "F.Cu")
		(net "EXP_TACH_IN1")
	)
	(segment
		(start 98.186494 -99.822)
		(end 98.751644 -100.38715)
		(width 0.1143)
		(layer "F.Cu")
		(net "EXP_TACH_IN1")
	)
	(segment
		(start 102.60203 -97.96272)
		(end 103.214678 -97.350072)
		(width 0.1143)
		(layer "F.Cu")
		(net "EXP_TACH_IN1")
	)
	(segment
		(start 106.94416 -29.845)
		(end 106.94416 -28.645866)
		(width 0.1143)
		(layer "F.Cu")
		(net "SYS_ERR_0")
	)
	(segment
		(start 109.875066 -25.7937)
		(end 110.217966 -25.4508)
		(width 0.1143)
		(layer "F.Cu")
		(net "SYS_ERR_0")
	)
	(segment
		(start 105.613454 -31.175706)
		(end 106.94416 -29.845)
		(width 0.1143)
		(layer "F.Cu")
		(net "SYS_ERR_0")
	)
	(segment
		(start 105.950004 -34.19983)
		(end 105.613454 -33.86328)
		(width 0.1143)
		(layer "F.Cu")
		(net "SYS_ERR_0")
	)
	(segment
		(start 111.360966 -25.527)
		(end 110.344966 -25.527)
		(width 0.1143)
		(layer "F.Cu")
		(net "SYS_ERR_0")
	)
	(segment
		(start 109.796326 -25.7937)
		(end 109.875066 -25.7937)
		(width 0.1143)
		(layer "F.Cu")
		(net "SYS_ERR_0")
	)
	(segment
		(start 110.217966 -25.4508)
		(end 110.217966 -25.4)
		(width 0.1143)
		(layer "F.Cu")
		(net "SYS_ERR_0")
	)
	(segment
		(start 110.344966 -25.527)
		(end 110.217966 -25.4)
		(width 0.1143)
		(layer "F.Cu")
		(net "SYS_ERR_0")
	)
	(segment
		(start 105.613454 -33.86328)
		(end 105.613454 -31.175706)
		(width 0.1143)
		(layer "F.Cu")
		(net "SYS_ERR_0")
	)
	(segment
		(start 106.94416 -28.645866)
		(end 109.796326 -25.7937)
		(width 0.1143)
		(layer "F.Cu")
		(net "SYS_ERR_0")
	)
	(via
		(at 110.217966 -25.4)
		(size 0.5588)
		(drill 0.3048)
		(layers "F.Cu" "B.Cu")
		(net "SYS_ERR_0")
	)
	(via
		(at 111.360966 -25.527)
		(size 0.7112)
		(drill 0.3556)
		(layers "F.Cu" "B.Cu")
		(net "SYS_ERR_0")
	)
	(segment
		(start 110.217966 -25.4)
		(end 111.513366 -25.4)
		(width 0.1143)
		(layer "B.Cu")
		(net "SYS_ERR_0")
	)
	(segment
		(start 253.307596 -53.232812)
		(end 251.714 -53.232812)
		(width 0.1143)
		(layer "F.Cu")
		(net "IOC_EEPROM_SCL")
	)
	(segment
		(start 250.704096 -53.232812)
		(end 251.714 -53.232812)
		(width 0.1143)
		(layer "F.Cu")
		(net "IOC_EEPROM_SCL")
	)
	(via
		(at 251.714 -53.232812)
		(size 0.7112)
		(drill 0.3556)
		(layers "F.Cu" "B.Cu")
		(net "IOC_EEPROM_SCL")
	)
	(segment
		(start 260.773672 -234.061)
		(end 258.233672 -231.521)
		(width 0.254)
		(layer "F.Cu")
		(net "P1V53_STBY_PG")
	)
	(segment
		(start 279.659334 -220.40215)
		(end 279.304242 -220.757242)
		(width 0.254)
		(layer "F.Cu")
		(net "P1V53_STBY_PG")
	)
	(segment
		(start 281.10815 -220.40215)
		(end 279.659334 -220.40215)
		(width 0.254)
		(layer "F.Cu")
		(net "P1V53_STBY_PG")
	)
	(segment
		(start 262.1788 -234.061)
		(end 260.773672 -234.061)
		(width 0.254)
		(layer "F.Cu")
		(net "P1V53_STBY_PG")
	)
	(segment
		(start 258.1275 -231.521)
		(end 256.9845 -230.378)
		(width 0.254)
		(layer "F.Cu")
		(net "P1V53_STBY_PG")
	)
	(segment
		(start 278.439372 -221.433136)
		(end 278.628348 -221.433136)
		(width 0.254)
		(layer "F.Cu")
		(net "P1V53_STBY_PG")
	)
	(segment
		(start 258.233672 -231.521)
		(end 258.1275 -231.521)
		(width 0.254)
		(layer "F.Cu")
		(net "P1V53_STBY_PG")
	)
	(segment
		(start 278.628348 -221.433136)
		(end 279.304242 -220.757242)
		(width 0.254)
		(layer "F.Cu")
		(net "P1V53_STBY_PG")
	)
	(via
		(at 262.1788 -234.061)
		(size 0.5588)
		(drill 0.3048)
		(layers "F.Cu" "B.Cu")
		(net "P1V53_STBY_PG")
	)
	(via
		(at 279.273 -219.964)
		(size 0.7112)
		(drill 0.3556)
		(layers "F.Cu" "B.Cu")
		(net "P1V53_STBY_PG")
	)
	(via
		(at 279.304242 -220.757242)
		(size 0.5588)
		(drill 0.3048)
		(layers "F.Cu" "B.Cu")
		(net "P1V53_STBY_PG")
	)
	(segment
		(start 279.273 -219.964)
		(end 279.273 -220.726)
		(width 0.254)
		(layer "B.Cu")
		(net "P1V53_STBY_PG")
	)
	(segment
		(start 279.273 -220.726)
		(end 279.304242 -220.757242)
		(width 0.254)
		(layer "B.Cu")
		(net "P1V53_STBY_PG")
	)
	(segment
		(start 279.304242 -231.108758)
		(end 279.304242 -220.757242)
		(width 0.254)
		(layer "In2.Cu")
		(net "P1V53_STBY_PG")
	)
	(segment
		(start 276.352 -234.061)
		(end 279.304242 -231.108758)
		(width 0.254)
		(layer "In2.Cu")
		(net "P1V53_STBY_PG")
	)
	(segment
		(start 262.1788 -234.061)
		(end 276.352 -234.061)
		(width 0.254)
		(layer "In2.Cu")
		(net "P1V53_STBY_PG")
	)
	(segment
		(start 44.82846 -75.84821)
		(end 44.82846 -75.266042)
		(width 0.1016)
		(layer "F.Cu")
		(net "MINI_RX_P_21")
	)
	(segment
		(start 44.59986 -77.08011)
		(end 44.59986 -76.05141)
		(width 0.1016)
		(layer "F.Cu")
		(net "MINI_RX_P_21")
	)
	(segment
		(start 44.798742 -75.19416)
		(end 44.511468 -74.906886)
		(width 0.1016)
		(layer "F.Cu")
		(net "MINI_RX_P_21")
	)
	(segment
		(start 44.70146 -75.94981)
		(end 44.72686 -75.94981)
		(width 0.1016)
		(layer "F.Cu")
		(net "MINI_RX_P_21")
	)
	(via
		(at 44.511468 -74.906886)
		(size 0.5588)
		(drill 0.3048)
		(layers "F.Cu" "B.Cu")
		(net "MINI_RX_P_21")
	)
	(arc
		(start 44.72686 -75.94981)
		(mid 44.798702 -75.920052)
		(end 44.82846 -75.84821)
		(width 0.1016)
		(layer "F.Cu")
		(net "MINI_RX_P_21")
	)
	(arc
		(start 44.82846 -75.266042)
		(mid 44.820741 -75.227147)
		(end 44.798742 -75.19416)
		(width 0.1016)
		(layer "F.Cu")
		(net "MINI_RX_P_21")
	)
	(arc
		(start 44.59986 -76.05141)
		(mid 44.629618 -75.979568)
		(end 44.70146 -75.94981)
		(width 0.1016)
		(layer "F.Cu")
		(net "MINI_RX_P_21")
	)
	(segment
		(start 44.82846 -76.704698)
		(end 44.82846 -75.266042)
		(width 0.1016)
		(layer "B.Cu")
		(net "MINI_RX_P_21")
	)
	(segment
		(start 44.52493 -77.205586)
		(end 44.68876 -77.041756)
		(width 0.1016)
		(layer "B.Cu")
		(net "MINI_RX_P_21")
	)
	(segment
		(start 44.798742 -75.19416)
		(end 44.511468 -74.906886)
		(width 0.1016)
		(layer "B.Cu")
		(net "MINI_RX_P_21")
	)
	(arc
		(start 44.68876 -77.041756)
		(mid 44.792172 -76.887128)
		(end 44.82846 -76.704698)
		(width 0.1016)
		(layer "B.Cu")
		(net "MINI_RX_P_21")
	)
	(arc
		(start 44.82846 -75.266042)
		(mid 44.820741 -75.227147)
		(end 44.798742 -75.19416)
		(width 0.1016)
		(layer "B.Cu")
		(net "MINI_RX_P_21")
	)
	(segment
		(start 261.118096 -54.375812)
		(end 261.118096 -53.232812)
		(width 0.1143)
		(layer "F.Cu")
		(net "IOC_EEPROM_A2")
	)
	(segment
		(start 258.387596 -53.232812)
		(end 259.949188 -53.232812)
		(width 0.1143)
		(layer "F.Cu")
		(net "IOC_EEPROM_A2")
	)
	(segment
		(start 261.118096 -53.232812)
		(end 259.949188 -53.232812)
		(width 0.1143)
		(layer "F.Cu")
		(net "IOC_EEPROM_A2")
	)
	(via
		(at 259.949188 -53.232812)
		(size 0.7112)
		(drill 0.3556)
		(layers "F.Cu" "B.Cu")
		(net "IOC_EEPROM_A2")
	)
	(segment
		(start 54.09819 -75.94981)
		(end 54.07279 -75.94981)
		(width 0.1016)
		(layer "F.Cu")
		(net "MINI_RX_N_23")
	)
	(segment
		(start 54.000908 -75.19416)
		(end 54.288182 -74.906886)
		(width 0.1016)
		(layer "F.Cu")
		(net "MINI_RX_N_23")
	)
	(segment
		(start 53.97119 -75.84821)
		(end 53.97119 -75.266042)
		(width 0.1016)
		(layer "F.Cu")
		(net "MINI_RX_N_23")
	)
	(segment
		(start 54.19979 -77.08011)
		(end 54.19979 -76.05141)
		(width 0.1016)
		(layer "F.Cu")
		(net "MINI_RX_N_23")
	)
	(via
		(at 54.288182 -74.906886)
		(size 0.5588)
		(drill 0.3048)
		(layers "F.Cu" "B.Cu")
		(net "MINI_RX_N_23")
	)
	(arc
		(start 54.19979 -76.05141)
		(mid 54.170032 -75.979568)
		(end 54.09819 -75.94981)
		(width 0.1016)
		(layer "F.Cu")
		(net "MINI_RX_N_23")
	)
	(arc
		(start 53.97119 -75.266042)
		(mid 53.978909 -75.227147)
		(end 54.000908 -75.19416)
		(width 0.1016)
		(layer "F.Cu")
		(net "MINI_RX_N_23")
	)
	(arc
		(start 54.07279 -75.94981)
		(mid 54.000948 -75.920052)
		(end 53.97119 -75.84821)
		(width 0.1016)
		(layer "F.Cu")
		(net "MINI_RX_N_23")
	)
	(segment
		(start 53.97119 -75.745086)
		(end 53.97119 -75.266042)
		(width 0.1016)
		(layer "B.Cu")
		(net "MINI_RX_N_23")
	)
	(segment
		(start 54.000908 -75.19416)
		(end 54.288182 -74.906886)
		(width 0.1016)
		(layer "B.Cu")
		(net "MINI_RX_N_23")
	)
	(segment
		(start 54.30393 -76.316586)
		(end 54.1401 -76.152502)
		(width 0.1016)
		(layer "B.Cu")
		(net "MINI_RX_N_23")
	)
	(arc
		(start 54.1401 -76.152502)
		(mid 54.015118 -75.965593)
		(end 53.97119 -75.745086)
		(width 0.1016)
		(layer "B.Cu")
		(net "MINI_RX_N_23")
	)
	(arc
		(start 53.97119 -75.266042)
		(mid 53.978909 -75.227147)
		(end 54.000908 -75.19416)
		(width 0.1016)
		(layer "B.Cu")
		(net "MINI_RX_N_23")
	)
	(segment
		(start 106.3498 -96.350074)
		(end 105.849674 -96.8502)
		(width 0.1143)
		(layer "F.Cu")
		(net "EXP_TACH_IN2")
	)
	(via
		(at 105.849674 -96.8502)
		(size 0.508)
		(drill 0.254)
		(layers "F.Cu" "B.Cu")
		(net "EXP_TACH_IN2")
	)
	(segment
		(start 103.15702 -96.41205)
		(end 105.028492 -96.41205)
		(width 0.1143)
		(layer "B.Cu")
		(net "EXP_TACH_IN2")
	)
	(segment
		(start 105.463594 -96.847152)
		(end 105.469436 -96.8502)
		(width 0.1143)
		(layer "B.Cu")
		(net "EXP_TACH_IN2")
	)
	(segment
		(start 105.469436 -96.8502)
		(end 105.849674 -96.8502)
		(width 0.1143)
		(layer "B.Cu")
		(net "EXP_TACH_IN2")
	)
	(segment
		(start 105.028492 -96.41205)
		(end 105.463594 -96.847152)
		(width 0.1143)
		(layer "B.Cu")
		(net "EXP_TACH_IN2")
	)
	(segment
		(start 103.01097 -96.266)
		(end 103.15702 -96.41205)
		(width 0.1143)
		(layer "B.Cu")
		(net "EXP_TACH_IN2")
	)
	(segment
		(start 110.750096 -34.99993)
		(end 110.3503 -34.600134)
		(width 0.1143)
		(layer "F.Cu")
		(net "IOC_UART_1_RX")
	)
	(via
		(at 110.3503 -34.600134)
		(size 0.508)
		(drill 0.254)
		(layers "F.Cu" "B.Cu")
		(net "IOC_UART_1_RX")
	)
	(segment
		(start 112.59566 -30.0355)
		(end 110.75416 -31.877)
		(width 0.1143)
		(layer "B.Cu")
		(net "IOC_UART_1_RX")
	)
	(segment
		(start 110.259876 -31.877)
		(end 109.865668 -32.271208)
		(width 0.1143)
		(layer "B.Cu")
		(net "IOC_UART_1_RX")
	)
	(segment
		(start 110.75416 -31.877)
		(end 110.259876 -31.877)
		(width 0.1143)
		(layer "B.Cu")
		(net "IOC_UART_1_RX")
	)
	(segment
		(start 109.865668 -32.271208)
		(end 109.865668 -32.639)
		(width 0.1143)
		(layer "B.Cu")
		(net "IOC_UART_1_RX")
	)
	(segment
		(start 109.99216 -32.765492)
		(end 109.99216 -33.655)
		(width 0.1143)
		(layer "B.Cu")
		(net "IOC_UART_1_RX")
	)
	(segment
		(start 109.99216 -34.241994)
		(end 109.99216 -33.655)
		(width 0.1143)
		(layer "B.Cu")
		(net "IOC_UART_1_RX")
	)
	(segment
		(start 109.865668 -32.639)
		(end 109.99216 -32.765492)
		(width 0.1143)
		(layer "B.Cu")
		(net "IOC_UART_1_RX")
	)
	(segment
		(start 112.59566 -29.972)
		(end 112.59566 -30.0355)
		(width 0.1143)
		(layer "B.Cu")
		(net "IOC_UART_1_RX")
	)
	(segment
		(start 110.3503 -34.600134)
		(end 109.99216 -34.241994)
		(width 0.1143)
		(layer "B.Cu")
		(net "IOC_UART_1_RX")
	)
	(segment
		(start 253.307596 -54.502812)
		(end 251.714 -54.502812)
		(width 0.1143)
		(layer "F.Cu")
		(net "IOC_EEPROM_SDA")
	)
	(segment
		(start 251.714 -54.502812)
		(end 250.704096 -54.502812)
		(width 0.1143)
		(layer "F.Cu")
		(net "IOC_EEPROM_SDA")
	)
	(via
		(at 251.714 -54.502812)
		(size 0.7112)
		(drill 0.3556)
		(layers "F.Cu" "B.Cu")
		(net "IOC_EEPROM_SDA")
	)
	(segment
		(start 51.571398 -75.84821)
		(end 51.571398 -75.266042)
		(width 0.1016)
		(layer "F.Cu")
		(net "MINI_RX_N_22")
	)
	(segment
		(start 51.601116 -75.19416)
		(end 51.88839 -74.906886)
		(width 0.1016)
		(layer "F.Cu")
		(net "MINI_RX_N_22")
	)
	(segment
		(start 51.799998 -77.08011)
		(end 51.799998 -76.05141)
		(width 0.1016)
		(layer "F.Cu")
		(net "MINI_RX_N_22")
	)
	(segment
		(start 51.698398 -75.94981)
		(end 51.672998 -75.94981)
		(width 0.1016)
		(layer "F.Cu")
		(net "MINI_RX_N_22")
	)
	(via
		(at 51.88839 -74.906886)
		(size 0.5588)
		(drill 0.3048)
		(layers "F.Cu" "B.Cu")
		(net "MINI_RX_N_22")
	)
	(arc
		(start 51.672998 -75.94981)
		(mid 51.601156 -75.920052)
		(end 51.571398 -75.84821)
		(width 0.1016)
		(layer "F.Cu")
		(net "MINI_RX_N_22")
	)
	(arc
		(start 51.571398 -75.266042)
		(mid 51.579117 -75.227147)
		(end 51.601116 -75.19416)
		(width 0.1016)
		(layer "F.Cu")
		(net "MINI_RX_N_22")
	)
	(arc
		(start 51.799998 -76.05141)
		(mid 51.77024 -75.979568)
		(end 51.698398 -75.94981)
		(width 0.1016)
		(layer "F.Cu")
		(net "MINI_RX_N_22")
	)
	(segment
		(start 51.571398 -75.851766)
		(end 51.571398 -75.266042)
		(width 0.1016)
		(layer "B.Cu")
		(net "MINI_RX_N_22")
	)
	(segment
		(start 51.601116 -75.19416)
		(end 51.88839 -74.906886)
		(width 0.1016)
		(layer "B.Cu")
		(net "MINI_RX_N_22")
	)
	(arc
		(start 51.76393 -76.316586)
		(mid 51.621433 -76.103325)
		(end 51.571398 -75.851766)
		(width 0.1016)
		(layer "B.Cu")
		(net "MINI_RX_N_22")
	)
	(arc
		(start 51.571398 -75.266042)
		(mid 51.579117 -75.227147)
		(end 51.601116 -75.19416)
		(width 0.1016)
		(layer "B.Cu")
		(net "MINI_RX_N_22")
	)
	(segment
		(start 109.246924 -95.350076)
		(end 108.839 -95.758)
		(width 0.1143)
		(layer "F.Cu")
		(net "EXP_TACH_IN3")
	)
	(segment
		(start 109.349794 -95.350076)
		(end 109.246924 -95.350076)
		(width 0.1143)
		(layer "F.Cu")
		(net "EXP_TACH_IN3")
	)
	(via
		(at 108.839 -95.758)
		(size 0.508)
		(drill 0.254)
		(layers "F.Cu" "B.Cu")
		(net "EXP_TACH_IN3")
	)
	(segment
		(start 107.696 -95.758)
		(end 108.839 -95.758)
		(width 0.1143)
		(layer "B.Cu")
		(net "EXP_TACH_IN3")
	)
	(segment
		(start 258.387596 -51.962812)
		(end 260.076188 -51.962812)
		(width 0.1143)
		(layer "F.Cu")
		(net "IOC_EEPROM_A1")
	)
	(segment
		(start 260.076188 -51.962812)
		(end 261.118096 -51.962812)
		(width 0.1143)
		(layer "F.Cu")
		(net "IOC_EEPROM_A1")
	)
	(via
		(at 260.076188 -51.962812)
		(size 0.7112)
		(drill 0.3556)
		(layers "F.Cu" "B.Cu")
		(net "IOC_EEPROM_A1")
	)
	(segment
		(start 45.29836 -75.94981)
		(end 45.27296 -75.94981)
		(width 0.1016)
		(layer "F.Cu")
		(net "MINI_RX_N_21")
	)
	(segment
		(start 45.201078 -75.19416)
		(end 45.488352 -74.906886)
		(width 0.1016)
		(layer "F.Cu")
		(net "MINI_RX_N_21")
	)
	(segment
		(start 45.39996 -77.08011)
		(end 45.39996 -76.05141)
		(width 0.1016)
		(layer "F.Cu")
		(net "MINI_RX_N_21")
	)
	(segment
		(start 45.17136 -75.84821)
		(end 45.17136 -75.266042)
		(width 0.1016)
		(layer "F.Cu")
		(net "MINI_RX_N_21")
	)
	(via
		(at 45.488352 -74.906886)
		(size 0.5588)
		(drill 0.3048)
		(layers "F.Cu" "B.Cu")
		(net "MINI_RX_N_21")
	)
	(arc
		(start 45.39996 -76.05141)
		(mid 45.370202 -75.979568)
		(end 45.29836 -75.94981)
		(width 0.1016)
		(layer "F.Cu")
		(net "MINI_RX_N_21")
	)
	(arc
		(start 45.17136 -75.266042)
		(mid 45.179079 -75.227147)
		(end 45.201078 -75.19416)
		(width 0.1016)
		(layer "F.Cu")
		(net "MINI_RX_N_21")
	)
	(arc
		(start 45.27296 -75.94981)
		(mid 45.201118 -75.920052)
		(end 45.17136 -75.84821)
		(width 0.1016)
		(layer "F.Cu")
		(net "MINI_RX_N_21")
	)
	(segment
		(start 45.201078 -75.19416)
		(end 45.488352 -74.906886)
		(width 0.1016)
		(layer "B.Cu")
		(net "MINI_RX_N_21")
	)
	(segment
		(start 45.54093 -77.205586)
		(end 45.404024 -77.068426)
		(width 0.1016)
		(layer "B.Cu")
		(net "MINI_RX_N_21")
	)
	(segment
		(start 45.17136 -76.507086)
		(end 45.17136 -75.266042)
		(width 0.1016)
		(layer "B.Cu")
		(net "MINI_RX_N_21")
	)
	(arc
		(start 45.17136 -75.266042)
		(mid 45.179079 -75.227147)
		(end 45.201078 -75.19416)
		(width 0.1016)
		(layer "B.Cu")
		(net "MINI_RX_N_21")
	)
	(arc
		(start 45.404024 -77.068426)
		(mid 45.231855 -76.810896)
		(end 45.17136 -76.507086)
		(width 0.1016)
		(layer "B.Cu")
		(net "MINI_RX_N_21")
	)
	(segment
		(start 105.349802 -96.350074)
		(end 104.849676 -96.8502)
		(width 0.1143)
		(layer "F.Cu")
		(net "EXP_PWM_OUT0")
	)
	(via
		(at 104.849676 -96.8502)
		(size 0.508)
		(drill 0.254)
		(layers "F.Cu" "B.Cu")
		(net "EXP_PWM_OUT0")
	)
	(segment
		(start 101.86797 -96.901)
		(end 101.91877 -96.8502)
		(width 0.1143)
		(layer "B.Cu")
		(net "EXP_PWM_OUT0")
	)
	(segment
		(start 101.91877 -96.8502)
		(end 104.849676 -96.8502)
		(width 0.1143)
		(layer "B.Cu")
		(net "EXP_PWM_OUT0")
	)
	(segment
		(start 111.549942 -34.99993)
		(end 111.150146 -34.600134)
		(width 0.1143)
		(layer "F.Cu")
		(net "SPARE0")
	)
	(via
		(at 111.150146 -34.600134)
		(size 0.508)
		(drill 0.254)
		(layers "F.Cu" "B.Cu")
		(net "SPARE0")
	)
	(segment
		(start 111.38916 -33.655)
		(end 111.38916 -34.36112)
		(width 0.1143)
		(layer "B.Cu")
		(net "SPARE0")
	)
	(segment
		(start 111.38916 -34.36112)
		(end 111.150146 -34.600134)
		(width 0.1143)
		(layer "B.Cu")
		(net "SPARE0")
	)
	(segment
		(start 258.387596 -50.692812)
		(end 260.076188 -50.692812)
		(width 0.1143)
		(layer "F.Cu")
		(net "IOC_EEPROM_A0")
	)
	(segment
		(start 260.076188 -50.692812)
		(end 261.118096 -50.692812)
		(width 0.1143)
		(layer "F.Cu")
		(net "IOC_EEPROM_A0")
	)
	(via
		(at 260.076188 -50.692812)
		(size 0.7112)
		(drill 0.3556)
		(layers "F.Cu" "B.Cu")
		(net "IOC_EEPROM_A0")
	)
	(segment
		(start 42.771314 -75.84821)
		(end 42.771314 -75.113642)
		(width 0.1016)
		(layer "F.Cu")
		(net "MINI_RX_N_20")
	)
	(segment
		(start 42.898314 -75.94981)
		(end 42.872914 -75.94981)
		(width 0.1016)
		(layer "F.Cu")
		(net "MINI_RX_N_20")
	)
	(segment
		(start 42.801032 -75.04176)
		(end 43.088306 -74.754486)
		(width 0.1016)
		(layer "F.Cu")
		(net "MINI_RX_N_20")
	)
	(segment
		(start 42.999914 -77.08011)
		(end 42.999914 -76.05141)
		(width 0.1016)
		(layer "F.Cu")
		(net "MINI_RX_N_20")
	)
	(via
		(at 43.088306 -74.754486)
		(size 0.5588)
		(drill 0.3048)
		(layers "F.Cu" "B.Cu")
		(net "MINI_RX_N_20")
	)
	(arc
		(start 42.872914 -75.94981)
		(mid 42.801072 -75.920052)
		(end 42.771314 -75.84821)
		(width 0.1016)
		(layer "F.Cu")
		(net "MINI_RX_N_20")
	)
	(arc
		(start 42.771314 -75.113642)
		(mid 42.779033 -75.074747)
		(end 42.801032 -75.04176)
		(width 0.1016)
		(layer "F.Cu")
		(net "MINI_RX_N_20")
	)
	(arc
		(start 42.999914 -76.05141)
		(mid 42.970156 -75.979568)
		(end 42.898314 -75.94981)
		(width 0.1016)
		(layer "F.Cu")
		(net "MINI_RX_N_20")
	)
	(segment
		(start 42.771314 -76.344526)
		(end 42.771314 -75.113642)
		(width 0.1016)
		(layer "B.Cu")
		(net "MINI_RX_N_20")
	)
	(segment
		(start 42.801032 -75.04176)
		(end 43.088306 -74.754486)
		(width 0.1016)
		(layer "B.Cu")
		(net "MINI_RX_N_20")
	)
	(arc
		(start 43.12793 -77.205586)
		(mid 42.863961 -76.810528)
		(end 42.771314 -76.344526)
		(width 0.1016)
		(layer "B.Cu")
		(net "MINI_RX_N_20")
	)
	(arc
		(start 42.771314 -75.113642)
		(mid 42.779033 -75.074747)
		(end 42.801032 -75.04176)
		(width 0.1016)
		(layer "B.Cu")
		(net "MINI_RX_N_20")
	)
	(segment
		(start 42.199814 -77.08011)
		(end 42.199814 -76.05141)
		(width 0.1016)
		(layer "F.Cu")
		(net "MINI_RX_P_20")
	)
	(segment
		(start 42.301414 -75.94981)
		(end 42.326814 -75.94981)
		(width 0.1016)
		(layer "F.Cu")
		(net "MINI_RX_P_20")
	)
	(segment
		(start 42.398696 -75.04176)
		(end 42.111422 -74.754486)
		(width 0.1016)
		(layer "F.Cu")
		(net "MINI_RX_P_20")
	)
	(segment
		(start 42.428414 -75.84821)
		(end 42.428414 -75.113642)
		(width 0.1016)
		(layer "F.Cu")
		(net "MINI_RX_P_20")
	)
	(via
		(at 42.111422 -74.754486)
		(size 0.5588)
		(drill 0.3048)
		(layers "F.Cu" "B.Cu")
		(net "MINI_RX_P_20")
	)
	(arc
		(start 42.199814 -76.05141)
		(mid 42.229572 -75.979568)
		(end 42.301414 -75.94981)
		(width 0.1016)
		(layer "F.Cu")
		(net "MINI_RX_P_20")
	)
	(arc
		(start 42.428414 -75.113642)
		(mid 42.420695 -75.074747)
		(end 42.398696 -75.04176)
		(width 0.1016)
		(layer "F.Cu")
		(net "MINI_RX_P_20")
	)
	(arc
		(start 42.326814 -75.94981)
		(mid 42.398656 -75.920052)
		(end 42.428414 -75.84821)
		(width 0.1016)
		(layer "F.Cu")
		(net "MINI_RX_P_20")
	)
	(segment
		(start 42.428414 -76.571094)
		(end 42.428414 -75.113642)
		(width 0.1016)
		(layer "B.Cu")
		(net "MINI_RX_P_20")
	)
	(segment
		(start 42.11193 -77.205586)
		(end 42.203624 -77.113892)
		(width 0.1016)
		(layer "B.Cu")
		(net "MINI_RX_P_20")
	)
	(segment
		(start 42.398696 -75.04176)
		(end 42.111422 -74.754486)
		(width 0.1016)
		(layer "B.Cu")
		(net "MINI_RX_P_20")
	)
	(arc
		(start 42.203624 -77.113892)
		(mid 42.369972 -76.86484)
		(end 42.428414 -76.571094)
		(width 0.1016)
		(layer "B.Cu")
		(net "MINI_RX_P_20")
	)
	(arc
		(start 42.428414 -75.113642)
		(mid 42.420695 -75.074747)
		(end 42.398696 -75.04176)
		(width 0.1016)
		(layer "B.Cu")
		(net "MINI_RX_P_20")
	)
	(segment
		(start 96.882966 -62.2935)
		(end 96.882966 -60.325)
		(width 0.1143)
		(layer "F.Cu")
		(net "ICE0_TCK")
	)
	(segment
		(start 96.882966 -58.573416)
		(end 97.150174 -58.306208)
		(width 0.1143)
		(layer "F.Cu")
		(net "ICE0_TCK")
	)
	(segment
		(start 96.501966 -62.6745)
		(end 96.882966 -62.2935)
		(width 0.1143)
		(layer "F.Cu")
		(net "ICE0_TCK")
	)
	(segment
		(start 96.882966 -60.325)
		(end 96.882966 -58.573416)
		(width 0.1143)
		(layer "F.Cu")
		(net "ICE0_TCK")
	)
	(segment
		(start 97.150174 -58.306208)
		(end 97.150174 -56.599836)
		(width 0.1143)
		(layer "F.Cu")
		(net "ICE0_TCK")
	)
	(segment
		(start 109.981492 -31.807658)
		(end 109.949996 -31.776162)
		(width 0.1143)
		(layer "F.Cu")
		(net "SPARE1")
	)
	(segment
		(start 109.949996 -32.2072)
		(end 109.97946 -32.177736)
		(width 0.1143)
		(layer "F.Cu")
		(net "SPARE1")
	)
	(segment
		(start 109.949996 -31.326836)
		(end 109.86516 -31.242)
		(width 0.1143)
		(layer "F.Cu")
		(net "SPARE1")
	)
	(segment
		(start 109.949996 -31.776162)
		(end 109.949996 -31.326836)
		(width 0.1143)
		(layer "F.Cu")
		(net "SPARE1")
	)
	(segment
		(start 109.949996 -33.399984)
		(end 109.949996 -32.2072)
		(width 0.1143)
		(layer "F.Cu")
		(net "SPARE1")
	)
	(segment
		(start 109.97946 -32.157162)
		(end 109.981492 -32.15513)
		(width 0.1143)
		(layer "F.Cu")
		(net "SPARE1")
	)
	(segment
		(start 109.97946 -32.177736)
		(end 109.97946 -32.157162)
		(width 0.1143)
		(layer "F.Cu")
		(net "SPARE1")
	)
	(segment
		(start 109.981492 -32.15513)
		(end 109.981492 -31.807658)
		(width 0.1143)
		(layer "F.Cu")
		(net "SPARE1")
	)
	(via
		(at 109.86516 -31.242)
		(size 0.508)
		(drill 0.254)
		(layers "F.Cu" "B.Cu")
		(net "SPARE1")
	)
	(segment
		(start 109.99216 -31.115)
		(end 109.86516 -31.242)
		(width 0.1143)
		(layer "B.Cu")
		(net "SPARE1")
	)
	(segment
		(start 109.99216 -30.226)
		(end 109.99216 -31.115)
		(width 0.1143)
		(layer "B.Cu")
		(net "SPARE1")
	)
	(segment
		(start 114.349784 -85.349842)
		(end 113.849658 -84.849716)
		(width 0.1143)
		(layer "F.Cu")
		(net "EXP_TEST_MUX24")
	)
	(via
		(at 113.849658 -84.849716)
		(size 0.508)
		(drill 0.254)
		(layers "F.Cu" "B.Cu")
		(net "EXP_TEST_MUX24")
	)
	(segment
		(start 113.849658 -84.433664)
		(end 113.849658 -84.849716)
		(width 0.1143)
		(layer "B.Cu")
		(net "EXP_TEST_MUX24")
	)
	(segment
		(start 113.55197 -81.661)
		(end 114.262408 -82.371438)
		(width 0.1143)
		(layer "B.Cu")
		(net "EXP_TEST_MUX24")
	)
	(segment
		(start 114.262408 -82.371438)
		(end 114.262408 -84.020914)
		(width 0.1143)
		(layer "B.Cu")
		(net "EXP_TEST_MUX24")
	)
	(segment
		(start 114.262408 -84.020914)
		(end 113.849658 -84.433664)
		(width 0.1143)
		(layer "B.Cu")
		(net "EXP_TEST_MUX24")
	)
	(segment
		(start 212.598 -169.164)
		(end 216.68613 -165.07587)
		(width 0.1143)
		(layer "F.Cu")
		(net "JTAG_IOC_TDO")
	)
	(segment
		(start 29.083 -135.128)
		(end 29.083 -150.241)
		(width 0.1143)
		(layer "F.Cu")
		(net "JTAG_IOC_TDO")
	)
	(segment
		(start 212.09 -182.626)
		(end 212.09 -181.737)
		(width 0.1143)
		(layer "F.Cu")
		(net "JTAG_IOC_TDO")
	)
	(segment
		(start 218.1352 -163.08324)
		(end 218.1352 -163.6268)
		(width 0.1143)
		(layer "F.Cu")
		(net "JTAG_IOC_TDO")
	)
	(segment
		(start 218.1352 -163.6268)
		(end 216.68613 -165.07587)
		(width 0.1143)
		(layer "F.Cu")
		(net "JTAG_IOC_TDO")
	)
	(segment
		(start 13.208 -166.116)
		(end 13.208 -166.497)
		(width 0.1143)
		(layer "F.Cu")
		(net "JTAG_IOC_TDO")
	)
	(segment
		(start 212.09 -181.737)
		(end 212.598 -181.229)
		(width 0.1143)
		(layer "F.Cu")
		(net "JTAG_IOC_TDO")
	)
	(segment
		(start 34.417 -129.794)
		(end 29.083 -135.128)
		(width 0.1143)
		(layer "F.Cu")
		(net "JTAG_IOC_TDO")
	)
	(segment
		(start 29.083 -150.241)
		(end 13.208 -166.116)
		(width 0.1143)
		(layer "F.Cu")
		(net "JTAG_IOC_TDO")
	)
	(segment
		(start 212.598 -181.229)
		(end 212.598 -169.164)
		(width 0.1143)
		(layer "F.Cu")
		(net "JTAG_IOC_TDO")
	)
	(via
		(at 13.208 -166.497)
		(size 0.5588)
		(drill 0.3048)
		(layers "F.Cu" "B.Cu")
		(net "JTAG_IOC_TDO")
	)
	(via
		(at 216.68613 -165.07587)
		(size 0.7112)
		(drill 0.3556)
		(layers "F.Cu" "B.Cu")
		(net "JTAG_IOC_TDO")
	)
	(via
		(at 34.417 -129.794)
		(size 0.5588)
		(drill 0.3048)
		(layers "F.Cu" "B.Cu")
		(net "JTAG_IOC_TDO")
	)
	(via
		(at 212.09 -182.626)
		(size 0.5588)
		(drill 0.3048)
		(layers "F.Cu" "B.Cu")
		(net "JTAG_IOC_TDO")
	)
	(via
		(at 96.901 -75.438)
		(size 0.5588)
		(drill 0.3048)
		(layers "F.Cu" "B.Cu")
		(net "JTAG_IOC_TDO")
	)
	(segment
		(start 97.409 -75.438)
		(end 96.901 -75.438)
		(width 0.1143)
		(layer "B.Cu")
		(net "JTAG_IOC_TDO")
	)
	(segment
		(start 106.236008 -61.341)
		(end 111.252 -66.356992)
		(width 0.1143)
		(layer "B.Cu")
		(net "JTAG_IOC_TDO")
	)
	(segment
		(start 106.38409 -70.85711)
		(end 103.8352 -73.406)
		(width 0.1143)
		(layer "B.Cu")
		(net "JTAG_IOC_TDO")
	)
	(segment
		(start 105.010966 -61.0235)
		(end 105.328466 -61.341)
		(width 0.1143)
		(layer "B.Cu")
		(net "JTAG_IOC_TDO")
	)
	(segment
		(start 109.35589 -70.85711)
		(end 106.38409 -70.85711)
		(width 0.1143)
		(layer "B.Cu")
		(net "JTAG_IOC_TDO")
	)
	(segment
		(start 99.441 -73.406)
		(end 97.409 -75.438)
		(width 0.1143)
		(layer "B.Cu")
		(net "JTAG_IOC_TDO")
	)
	(segment
		(start 111.252 -68.961)
		(end 109.35589 -70.85711)
		(width 0.1143)
		(layer "B.Cu")
		(net "JTAG_IOC_TDO")
	)
	(segment
		(start 103.8352 -73.406)
		(end 99.441 -73.406)
		(width 0.1143)
		(layer "B.Cu")
		(net "JTAG_IOC_TDO")
	)
	(segment
		(start 105.328466 -61.341)
		(end 106.236008 -61.341)
		(width 0.1143)
		(layer "B.Cu")
		(net "JTAG_IOC_TDO")
	)
	(segment
		(start 111.252 -66.356992)
		(end 111.252 -68.961)
		(width 0.1143)
		(layer "B.Cu")
		(net "JTAG_IOC_TDO")
	)
	(segment
		(start 170.053 -185.928)
		(end 162.56 -178.435)
		(width 0.127)
		(layer "In2.Cu")
		(net "JTAG_IOC_TDO")
	)
	(segment
		(start 162.56 -178.435)
		(end 66.421 -178.435)
		(width 0.127)
		(layer "In2.Cu")
		(net "JTAG_IOC_TDO")
	)
	(segment
		(start 35.306 -166.497)
		(end 13.208 -166.497)
		(width 0.127)
		(layer "In2.Cu")
		(net "JTAG_IOC_TDO")
	)
	(segment
		(start 46.863 -171.196)
		(end 40.005 -171.196)
		(width 0.127)
		(layer "In2.Cu")
		(net "JTAG_IOC_TDO")
	)
	(segment
		(start 66.421 -178.435)
		(end 64.389 -176.403)
		(width 0.127)
		(layer "In2.Cu")
		(net "JTAG_IOC_TDO")
	)
	(segment
		(start 209.169 -185.928)
		(end 170.053 -185.928)
		(width 0.127)
		(layer "In2.Cu")
		(net "JTAG_IOC_TDO")
	)
	(segment
		(start 64.389 -176.403)
		(end 52.07 -176.403)
		(width 0.127)
		(layer "In2.Cu")
		(net "JTAG_IOC_TDO")
	)
	(segment
		(start 40.005 -171.196)
		(end 35.306 -166.497)
		(width 0.127)
		(layer "In2.Cu")
		(net "JTAG_IOC_TDO")
	)
	(segment
		(start 212.09 -183.007)
		(end 209.169 -185.928)
		(width 0.127)
		(layer "In2.Cu")
		(net "JTAG_IOC_TDO")
	)
	(segment
		(start 52.07 -176.403)
		(end 46.863 -171.196)
		(width 0.127)
		(layer "In2.Cu")
		(net "JTAG_IOC_TDO")
	)
	(segment
		(start 212.09 -182.626)
		(end 212.09 -183.007)
		(width 0.127)
		(layer "In2.Cu")
		(net "JTAG_IOC_TDO")
	)
	(segment
		(start 87.817198 -83.1723)
		(end 85.177376 -83.1723)
		(width 0.127)
		(layer "In5.Cu")
		(net "JTAG_IOC_TDO")
	)
	(segment
		(start 43.398694 -122.846846)
		(end 36.45154 -129.794)
		(width 0.127)
		(layer "In5.Cu")
		(net "JTAG_IOC_TDO")
	)
	(segment
		(start 77.978 -94.556072)
		(end 49.687226 -122.846846)
		(width 0.127)
		(layer "In5.Cu")
		(net "JTAG_IOC_TDO")
	)
	(segment
		(start 96.901 -75.438)
		(end 95.551498 -75.438)
		(width 0.127)
		(layer "In5.Cu")
		(net "JTAG_IOC_TDO")
	)
	(segment
		(start 85.177376 -83.1723)
		(end 77.978 -90.371676)
		(width 0.127)
		(layer "In5.Cu")
		(net "JTAG_IOC_TDO")
	)
	(segment
		(start 49.687226 -122.846846)
		(end 43.398694 -122.846846)
		(width 0.127)
		(layer "In5.Cu")
		(net "JTAG_IOC_TDO")
	)
	(segment
		(start 77.978 -90.371676)
		(end 77.978 -94.556072)
		(width 0.127)
		(layer "In5.Cu")
		(net "JTAG_IOC_TDO")
	)
	(segment
		(start 95.551498 -75.438)
		(end 87.817198 -83.1723)
		(width 0.127)
		(layer "In5.Cu")
		(net "JTAG_IOC_TDO")
	)
	(segment
		(start 36.45154 -129.794)
		(end 34.417 -129.794)
		(width 0.127)
		(layer "In5.Cu")
		(net "JTAG_IOC_TDO")
	)
	(segment
		(start 105.525316 -64.694054)
		(end 105.525316 -65.049146)
		(width 0.1143)
		(layer "F.Cu")
		(net "LSI_TN")
	)
	(segment
		(start 104.2416 -61.3156)
		(end 102.413562 -59.487562)
		(width 0.1143)
		(layer "F.Cu")
		(net "LSI_TN")
	)
	(segment
		(start 105.588816 -64.630554)
		(end 105.525316 -64.694054)
		(width 0.1143)
		(layer "F.Cu")
		(net "LSI_TN")
	)
	(segment
		(start 104.2416 -61.497464)
		(end 104.2416 -61.5442)
		(width 0.1143)
		(layer "F.Cu")
		(net "LSI_TN")
	)
	(segment
		(start 104.2416 -61.5442)
		(end 104.814116 -62.116716)
		(width 0.1143)
		(layer "F.Cu")
		(net "LSI_TN")
	)
	(segment
		(start 105.588816 -66.662554)
		(end 105.48112 -66.77025)
		(width 0.1143)
		(layer "F.Cu")
		(net "LSI_TN")
	)
	(segment
		(start 104.814116 -62.116716)
		(end 104.814116 -62.294516)
		(width 0.1143)
		(layer "F.Cu")
		(net "LSI_TN")
	)
	(segment
		(start 104.814116 -62.294516)
		(end 105.588816 -63.069216)
		(width 0.1143)
		(layer "F.Cu")
		(net "LSI_TN")
	)
	(segment
		(start 102.413562 -59.487562)
		(end 102.413562 -55.33644)
		(width 0.1143)
		(layer "F.Cu")
		(net "LSI_TN")
	)
	(segment
		(start 105.48112 -66.77025)
		(end 105.37825 -66.77025)
		(width 0.1143)
		(layer "F.Cu")
		(net "LSI_TN")
	)
	(segment
		(start 104.2416 -61.497464)
		(end 104.2416 -61.3156)
		(width 0.1143)
		(layer "F.Cu")
		(net "LSI_TN")
	)
	(segment
		(start 105.525316 -65.049146)
		(end 105.588816 -65.112646)
		(width 0.1143)
		(layer "F.Cu")
		(net "LSI_TN")
	)
	(segment
		(start 105.588816 -63.069216)
		(end 105.588816 -64.630554)
		(width 0.1143)
		(layer "F.Cu")
		(net "LSI_TN")
	)
	(segment
		(start 105.588816 -65.112646)
		(end 105.588816 -66.662554)
		(width 0.1143)
		(layer "F.Cu")
		(net "LSI_TN")
	)
	(segment
		(start 102.413562 -55.33644)
		(end 102.750112 -54.99989)
		(width 0.1143)
		(layer "F.Cu")
		(net "LSI_TN")
	)
	(segment
		(start 105.37825 -66.77025)
		(end 104.775 -67.3735)
		(width 0.1143)
		(layer "F.Cu")
		(net "LSI_TN")
	)
	(via
		(at 104.2416 -61.497464)
		(size 0.7112)
		(drill 0.3556)
		(layers "F.Cu" "B.Cu")
		(net "LSI_TN")
	)
	(segment
		(start 91.68257 -126.086362)
		(end 91.73337 -126.035562)
		(width 0.1143)
		(layer "F.Cu")
		(net "EXP_GPIO_0")
	)
	(segment
		(start 89.125552 -127.296418)
		(end 89.633552 -126.788418)
		(width 0.1143)
		(layer "F.Cu")
		(net "EXP_GPIO_0")
	)
	(segment
		(start 89.633552 -126.788418)
		(end 91.157552 -126.788418)
		(width 0.1143)
		(layer "F.Cu")
		(net "EXP_GPIO_0")
	)
	(segment
		(start 102.349808 -102.350062)
		(end 101.849682 -102.850188)
		(width 0.1143)
		(layer "F.Cu")
		(net "EXP_GPIO_0")
	)
	(segment
		(start 89.125552 -131.570476)
		(end 89.125552 -127.296418)
		(width 0.1143)
		(layer "F.Cu")
		(net "EXP_GPIO_0")
	)
	(segment
		(start 91.68257 -126.2634)
		(end 91.68257 -126.086362)
		(width 0.1143)
		(layer "F.Cu")
		(net "EXP_GPIO_0")
	)
	(segment
		(start 91.157552 -126.788418)
		(end 91.68257 -126.2634)
		(width 0.1143)
		(layer "F.Cu")
		(net "EXP_GPIO_0")
	)
	(via
		(at 91.73337 -126.035562)
		(size 0.508)
		(drill 0.254)
		(layers "F.Cu" "B.Cu")
		(net "EXP_GPIO_0")
	)
	(via
		(at 101.849682 -102.850188)
		(size 0.508)
		(drill 0.254)
		(layers "F.Cu" "B.Cu")
		(net "EXP_GPIO_0")
	)
	(via
		(at 93.02877 -116.0018)
		(size 0.7112)
		(drill 0.3556)
		(layers "F.Cu" "B.Cu")
		(net "EXP_GPIO_0")
	)
	(segment
		(start 101.849682 -103.61676)
		(end 101.849682 -102.850188)
		(width 0.1143)
		(layer "B.Cu")
		(net "EXP_GPIO_0")
	)
	(segment
		(start 91.70797 -117.3226)
		(end 91.70797 -126.010162)
		(width 0.1143)
		(layer "B.Cu")
		(net "EXP_GPIO_0")
	)
	(segment
		(start 96.339406 -109.127036)
		(end 101.849682 -103.61676)
		(width 0.1143)
		(layer "B.Cu")
		(net "EXP_GPIO_0")
	)
	(segment
		(start 91.70797 -126.010162)
		(end 91.73337 -126.035562)
		(width 0.1143)
		(layer "B.Cu")
		(net "EXP_GPIO_0")
	)
	(segment
		(start 96.339406 -112.691164)
		(end 96.339406 -109.127036)
		(width 0.1143)
		(layer "B.Cu")
		(net "EXP_GPIO_0")
	)
	(segment
		(start 93.02877 -116.0018)
		(end 91.70797 -117.3226)
		(width 0.1143)
		(layer "B.Cu")
		(net "EXP_GPIO_0")
	)
	(segment
		(start 93.02877 -116.0018)
		(end 96.339406 -112.691164)
		(width 0.1143)
		(layer "B.Cu")
		(net "EXP_GPIO_0")
	)
	(segment
		(start 113.3475 -29.083)
		(end 111.887 -29.083)
		(width 0.1143)
		(layer "F.Cu")
		(net "SYS_HALT0#")
	)
	(segment
		(start 108.276644 -31.587948)
		(end 108.13415 -31.445454)
		(width 0.1143)
		(layer "F.Cu")
		(net "SYS_HALT0#")
	)
	(segment
		(start 108.276644 -32.332422)
		(end 108.276644 -31.587948)
		(width 0.1143)
		(layer "F.Cu")
		(net "SYS_HALT0#")
	)
	(segment
		(start 108.13415 -31.445454)
		(end 108.13415 -30.501844)
		(width 0.1143)
		(layer "F.Cu")
		(net "SYS_HALT0#")
	)
	(segment
		(start 109.425994 -29.21)
		(end 111.76 -29.21)
		(width 0.1143)
		(layer "F.Cu")
		(net "SYS_HALT0#")
	)
	(segment
		(start 108.2548 -32.354266)
		(end 108.276644 -32.332422)
		(width 0.1143)
		(layer "F.Cu")
		(net "SYS_HALT0#")
	)
	(segment
		(start 108.13415 -30.501844)
		(end 109.425994 -29.21)
		(width 0.1143)
		(layer "F.Cu")
		(net "SYS_HALT0#")
	)
	(segment
		(start 108.2548 -33.304734)
		(end 108.2548 -32.354266)
		(width 0.1143)
		(layer "F.Cu")
		(net "SYS_HALT0#")
	)
	(segment
		(start 108.35005 -33.399984)
		(end 108.2548 -33.304734)
		(width 0.1143)
		(layer "F.Cu")
		(net "SYS_HALT0#")
	)
	(segment
		(start 111.887 -29.083)
		(end 111.76 -29.21)
		(width 0.1143)
		(layer "F.Cu")
		(net "SYS_HALT0#")
	)
	(segment
		(start 113.24717 -78.5368)
		(end 113.360962 -78.650592)
		(width 0.1143)
		(layer "F.Cu")
		(net "EXP_TEST_MUX32")
	)
	(segment
		(start 113.360962 -78.981808)
		(end 115.350036 -80.970882)
		(width 0.1143)
		(layer "F.Cu")
		(net "EXP_TEST_MUX32")
	)
	(segment
		(start 113.360962 -78.650592)
		(end 113.360962 -78.981808)
		(width 0.1143)
		(layer "F.Cu")
		(net "EXP_TEST_MUX32")
	)
	(segment
		(start 115.350036 -80.970882)
		(end 115.350036 -82.349848)
		(width 0.1143)
		(layer "F.Cu")
		(net "EXP_TEST_MUX32")
	)
	(segment
		(start 109.391196 -31.56839)
		(end 109.391196 -31.568644)
		(width 0.1143)
		(layer "F.Cu")
		(net "SYS_DBMODE2")
	)
	(segment
		(start 109.149642 -31.810198)
		(end 109.149642 -31.821882)
		(width 0.1143)
		(layer "F.Cu")
		(net "SYS_DBMODE2")
	)
	(segment
		(start 109.14126 -32.177736)
		(end 109.15015 -32.186626)
		(width 0.1143)
		(layer "F.Cu")
		(net "SYS_DBMODE2")
	)
	(segment
		(start 115.5065 -29.845)
		(end 115.5065 -29.464)
		(width 0.1143)
		(layer "F.Cu")
		(net "SYS_DBMODE2")
	)
	(segment
		(start 109.45241 -31.507176)
		(end 109.391196 -31.56839)
		(width 0.1143)
		(layer "F.Cu")
		(net "SYS_DBMODE2")
	)
	(segment
		(start 115.57 -29.4005)
		(end 115.57 -28.7655)
		(width 0.1143)
		(layer "F.Cu")
		(net "SYS_DBMODE2")
	)
	(segment
		(start 113.411 -30.607)
		(end 114.935 -30.607)
		(width 0.1143)
		(layer "F.Cu")
		(net "SYS_DBMODE2")
	)
	(segment
		(start 109.149642 -31.821882)
		(end 109.14126 -31.830264)
		(width 0.1143)
		(layer "F.Cu")
		(net "SYS_DBMODE2")
	)
	(segment
		(start 109.45241 -31.070804)
		(end 109.45241 -31.507176)
		(width 0.1143)
		(layer "F.Cu")
		(net "SYS_DBMODE2")
	)
	(segment
		(start 110.14202 -30.82925)
		(end 109.693964 -30.82925)
		(width 0.1143)
		(layer "F.Cu")
		(net "SYS_DBMODE2")
	)
	(segment
		(start 115.5065 -30.0355)
		(end 115.5065 -29.845)
		(width 0.1143)
		(layer "F.Cu")
		(net "SYS_DBMODE2")
	)
	(segment
		(start 109.391196 -31.568644)
		(end 109.149642 -31.810198)
		(width 0.1143)
		(layer "F.Cu")
		(net "SYS_DBMODE2")
	)
	(segment
		(start 114.935 -30.607)
		(end 115.5065 -30.0355)
		(width 0.1143)
		(layer "F.Cu")
		(net "SYS_DBMODE2")
	)
	(segment
		(start 109.14126 -31.830264)
		(end 109.14126 -32.177736)
		(width 0.1143)
		(layer "F.Cu")
		(net "SYS_DBMODE2")
	)
	(segment
		(start 113.411 -30.607)
		(end 110.364524 -30.607)
		(width 0.1143)
		(layer "F.Cu")
		(net "SYS_DBMODE2")
	)
	(segment
		(start 115.5065 -29.464)
		(end 115.57 -29.4005)
		(width 0.1143)
		(layer "F.Cu")
		(net "SYS_DBMODE2")
	)
	(segment
		(start 110.364524 -30.607)
		(end 110.14202 -30.82925)
		(width 0.1143)
		(layer "F.Cu")
		(net "SYS_DBMODE2")
	)
	(segment
		(start 109.15015 -32.186626)
		(end 109.15015 -33.399984)
		(width 0.1143)
		(layer "F.Cu")
		(net "SYS_DBMODE2")
	)
	(segment
		(start 109.693964 -30.82925)
		(end 109.45241 -31.070804)
		(width 0.1143)
		(layer "F.Cu")
		(net "SYS_DBMODE2")
	)
	(via
		(at 113.411 -30.607)
		(size 0.7112)
		(drill 0.3556)
		(layers "F.Cu" "B.Cu")
		(net "SYS_DBMODE2")
	)
	(segment
		(start 109.97057 -78.6638)
		(end 109.97057 -79.0956)
		(width 0.1143)
		(layer "F.Cu")
		(net "EXP_TEST_MUX25")
	)
	(segment
		(start 112.908842 -81.579212)
		(end 112.908842 -82.875882)
		(width 0.1143)
		(layer "F.Cu")
		(net "EXP_TEST_MUX25")
	)
	(segment
		(start 109.97057 -79.0956)
		(end 111.82731 -80.95234)
		(width 0.1143)
		(layer "F.Cu")
		(net "EXP_TEST_MUX25")
	)
	(segment
		(start 113.349786 -83.316826)
		(end 113.349786 -83.349846)
		(width 0.1143)
		(layer "F.Cu")
		(net "EXP_TEST_MUX25")
	)
	(segment
		(start 112.28197 -80.95234)
		(end 112.908842 -81.579212)
		(width 0.1143)
		(layer "F.Cu")
		(net "EXP_TEST_MUX25")
	)
	(segment
		(start 111.82731 -80.95234)
		(end 112.28197 -80.95234)
		(width 0.1143)
		(layer "F.Cu")
		(net "EXP_TEST_MUX25")
	)
	(segment
		(start 112.908842 -82.875882)
		(end 113.349786 -83.316826)
		(width 0.1143)
		(layer "F.Cu")
		(net "EXP_TEST_MUX25")
	)
	(segment
		(start 104.350058 -56.599836)
		(end 104.350058 -58.730388)
		(width 0.1143)
		(layer "F.Cu")
		(net "LSI_IDDT")
	)
	(segment
		(start 105.4354 -59.9186)
		(end 105.4354 -59.81573)
		(width 0.1143)
		(layer "F.Cu")
		(net "LSI_IDDT")
	)
	(segment
		(start 104.350058 -58.730388)
		(end 104.842818 -59.223148)
		(width 0.1143)
		(layer "F.Cu")
		(net "LSI_IDDT")
	)
	(segment
		(start 105.4354 -59.81573)
		(end 104.842818 -59.223148)
		(width 0.1143)
		(layer "F.Cu")
		(net "LSI_IDDT")
	)
	(via
		(at 104.842818 -59.223148)
		(size 0.508)
		(drill 0.254)
		(layers "F.Cu" "B.Cu")
		(net "LSI_IDDT")
	)
	(via
		(at 105.4354 -59.9186)
		(size 0.7112)
		(drill 0.3556)
		(layers "F.Cu" "B.Cu")
		(net "LSI_IDDT")
	)
	(segment
		(start 104.163114 -59.223148)
		(end 104.842818 -59.223148)
		(width 0.1143)
		(layer "B.Cu")
		(net "LSI_IDDT")
	)
	(segment
		(start 103.359966 -58.4835)
		(end 103.423466 -58.4835)
		(width 0.1143)
		(layer "B.Cu")
		(net "LSI_IDDT")
	)
	(segment
		(start 103.423466 -58.4835)
		(end 104.163114 -59.223148)
		(width 0.1143)
		(layer "B.Cu")
		(net "LSI_IDDT")
	)
	(segment
		(start 111.03737 -77.925168)
		(end 111.287052 -78.17485)
		(width 0.1143)
		(layer "F.Cu")
		(net "EXP_TEST_MUX33")
	)
	(segment
		(start 115.350036 -82.897726)
		(end 115.350036 -83.349846)
		(width 0.1143)
		(layer "F.Cu")
		(net "EXP_TEST_MUX33")
	)
	(segment
		(start 111.743744 -78.17485)
		(end 112.05972 -78.490826)
		(width 0.1143)
		(layer "F.Cu")
		(net "EXP_TEST_MUX33")
	)
	(segment
		(start 114.12728 -80.294226)
		(end 114.962686 -81.129632)
		(width 0.1143)
		(layer "F.Cu")
		(net "EXP_TEST_MUX33")
	)
	(segment
		(start 112.822736 -79.67599)
		(end 113.543588 -79.67599)
		(width 0.1143)
		(layer "F.Cu")
		(net "EXP_TEST_MUX33")
	)
	(segment
		(start 114.12728 -80.259682)
		(end 114.12728 -80.294226)
		(width 0.1143)
		(layer "F.Cu")
		(net "EXP_TEST_MUX33")
	)
	(segment
		(start 112.05972 -78.912974)
		(end 112.822736 -79.67599)
		(width 0.1143)
		(layer "F.Cu")
		(net "EXP_TEST_MUX33")
	)
	(segment
		(start 113.543588 -79.67599)
		(end 114.12728 -80.259682)
		(width 0.1143)
		(layer "F.Cu")
		(net "EXP_TEST_MUX33")
	)
	(segment
		(start 114.962686 -82.510376)
		(end 115.350036 -82.897726)
		(width 0.1143)
		(layer "F.Cu")
		(net "EXP_TEST_MUX33")
	)
	(segment
		(start 112.05972 -78.490826)
		(end 112.05972 -78.912974)
		(width 0.1143)
		(layer "F.Cu")
		(net "EXP_TEST_MUX33")
	)
	(segment
		(start 111.03737 -77.5462)
		(end 111.03737 -77.925168)
		(width 0.1143)
		(layer "F.Cu")
		(net "EXP_TEST_MUX33")
	)
	(segment
		(start 114.962686 -81.129632)
		(end 114.962686 -82.510376)
		(width 0.1143)
		(layer "F.Cu")
		(net "EXP_TEST_MUX33")
	)
	(segment
		(start 111.287052 -78.17485)
		(end 111.743744 -78.17485)
		(width 0.1143)
		(layer "F.Cu")
		(net "EXP_TEST_MUX33")
	)
	(segment
		(start 107.08386 -33.2486)
		(end 107.08386 -32.639)
		(width 0.1143)
		(layer "F.Cu")
		(net "SPARE2")
	)
	(segment
		(start 107.093004 -33.600644)
		(end 107.093004 -33.257744)
		(width 0.1143)
		(layer "F.Cu")
		(net "SPARE2")
	)
	(segment
		(start 107.54995 -34.05759)
		(end 107.093004 -33.600644)
		(width 0.1143)
		(layer "F.Cu")
		(net "SPARE2")
	)
	(segment
		(start 107.54995 -34.19983)
		(end 107.54995 -34.05759)
		(width 0.1143)
		(layer "F.Cu")
		(net "SPARE2")
	)
	(segment
		(start 107.093004 -33.257744)
		(end 107.08386 -33.2486)
		(width 0.1143)
		(layer "F.Cu")
		(net "SPARE2")
	)
	(via
		(at 107.08386 -32.639)
		(size 0.508)
		(drill 0.254)
		(layers "F.Cu" "B.Cu")
		(net "SPARE2")
	)
	(segment
		(start 107.07116 -31.369)
		(end 107.07116 -32.6263)
		(width 0.1143)
		(layer "B.Cu")
		(net "SPARE2")
	)
	(segment
		(start 107.07116 -32.6263)
		(end 107.08386 -32.639)
		(width 0.1143)
		(layer "B.Cu")
		(net "SPARE2")
	)
	(segment
		(start 116.350034 -86.34984)
		(end 116.85016 -85.849714)
		(width 0.1143)
		(layer "F.Cu")
		(net "EXP_TEST_MUX26")
	)
	(via
		(at 116.85016 -85.849714)
		(size 0.508)
		(drill 0.254)
		(layers "F.Cu" "B.Cu")
		(net "EXP_TEST_MUX26")
	)
	(segment
		(start 117.412008 -86.411562)
		(end 116.85016 -85.849714)
		(width 0.1143)
		(layer "B.Cu")
		(net "EXP_TEST_MUX26")
	)
	(segment
		(start 118.073932 -86.411562)
		(end 117.412008 -86.411562)
		(width 0.1143)
		(layer "B.Cu")
		(net "EXP_TEST_MUX26")
	)
	(segment
		(start 118.68277 -87.0204)
		(end 118.073932 -86.411562)
		(width 0.1143)
		(layer "B.Cu")
		(net "EXP_TEST_MUX26")
	)
	(segment
		(start 116.659406 -42.96156)
		(end 116.657882 -42.96156)
		(width 0.1143)
		(layer "F.Cu")
		(net "CP_DONE")
	)
	(segment
		(start 116.657882 -42.96156)
		(end 116.15293 -42.96156)
		(width 0.1143)
		(layer "F.Cu")
		(net "CP_DONE")
	)
	(segment
		(start 115.314476 -43.800014)
		(end 113.949988 -43.800014)
		(width 0.1143)
		(layer "F.Cu")
		(net "CP_DONE")
	)
	(segment
		(start 117.520466 -42.037)
		(end 117.520466 -42.1005)
		(width 0.1143)
		(layer "F.Cu")
		(net "CP_DONE")
	)
	(segment
		(start 117.520466 -42.1005)
		(end 116.659406 -42.96156)
		(width 0.1143)
		(layer "F.Cu")
		(net "CP_DONE")
	)
	(segment
		(start 116.15293 -42.96156)
		(end 115.314476 -43.800014)
		(width 0.1143)
		(layer "F.Cu")
		(net "CP_DONE")
	)
	(via
		(at 116.657882 -42.96156)
		(size 0.7112)
		(drill 0.3556)
		(layers "F.Cu" "B.Cu")
		(net "CP_DONE")
	)
	(segment
		(start 103.349806 -101.350064)
		(end 102.84968 -101.85019)
		(width 0.1143)
		(layer "F.Cu")
		(net "EXP_GPIO_2")
	)
	(segment
		(start 89.925652 -131.570476)
		(end 89.925652 -129.163318)
		(width 0.1143)
		(layer "F.Cu")
		(net "EXP_GPIO_2")
	)
	(segment
		(start 90.31097 -128.778)
		(end 90.69197 -128.778)
		(width 0.1143)
		(layer "F.Cu")
		(net "EXP_GPIO_2")
	)
	(segment
		(start 89.925652 -129.163318)
		(end 90.31097 -128.778)
		(width 0.1143)
		(layer "F.Cu")
		(net "EXP_GPIO_2")
	)
	(via
		(at 102.84968 -101.85019)
		(size 0.508)
		(drill 0.254)
		(layers "F.Cu" "B.Cu")
		(net "EXP_GPIO_2")
	)
	(via
		(at 93.9546 -113.520728)
		(size 0.7112)
		(drill 0.3556)
		(layers "F.Cu" "B.Cu")
		(net "EXP_GPIO_2")
	)
	(via
		(at 90.69197 -128.778)
		(size 0.508)
		(drill 0.254)
		(layers "F.Cu" "B.Cu")
		(net "EXP_GPIO_2")
	)
	(segment
		(start 91.26982 -128.20015)
		(end 91.26982 -116.205508)
		(width 0.1143)
		(layer "B.Cu")
		(net "EXP_GPIO_2")
	)
	(segment
		(start 101.411532 -103.533956)
		(end 101.411532 -102.704392)
		(width 0.1143)
		(layer "B.Cu")
		(net "EXP_GPIO_2")
	)
	(segment
		(start 101.710236 -102.405688)
		(end 102.294182 -102.405688)
		(width 0.1143)
		(layer "B.Cu")
		(net "EXP_GPIO_2")
	)
	(segment
		(start 90.69197 -128.778)
		(end 91.26982 -128.20015)
		(width 0.1143)
		(layer "B.Cu")
		(net "EXP_GPIO_2")
	)
	(segment
		(start 102.294182 -102.405688)
		(end 102.84968 -101.85019)
		(width 0.1143)
		(layer "B.Cu")
		(net "EXP_GPIO_2")
	)
	(segment
		(start 93.9546 -113.520728)
		(end 95.92437 -111.550958)
		(width 0.1143)
		(layer "B.Cu")
		(net "EXP_GPIO_2")
	)
	(segment
		(start 95.92437 -109.021118)
		(end 101.411532 -103.533956)
		(width 0.1143)
		(layer "B.Cu")
		(net "EXP_GPIO_2")
	)
	(segment
		(start 91.26982 -116.205508)
		(end 93.9546 -113.520728)
		(width 0.1143)
		(layer "B.Cu")
		(net "EXP_GPIO_2")
	)
	(segment
		(start 101.411532 -102.704392)
		(end 101.710236 -102.405688)
		(width 0.1143)
		(layer "B.Cu")
		(net "EXP_GPIO_2")
	)
	(segment
		(start 95.92437 -111.550958)
		(end 95.92437 -109.021118)
		(width 0.1143)
		(layer "B.Cu")
		(net "EXP_GPIO_2")
	)
	(segment
		(start 94.750128 -47.800006)
		(end 95.149924 -48.199802)
		(width 0.1143)
		(layer "F.Cu")
		(net "ICE_SEL")
	)
	(via
		(at 95.149924 -48.199802)
		(size 0.508)
		(drill 0.254)
		(layers "F.Cu" "B.Cu")
		(net "ICE_SEL")
	)
	(segment
		(start 96.463866 -47.4472)
		(end 95.53956 -47.4472)
		(width 0.1143)
		(layer "B.Cu")
		(net "ICE_SEL")
	)
	(segment
		(start 96.730566 -47.7139)
		(end 96.463866 -47.4472)
		(width 0.1143)
		(layer "B.Cu")
		(net "ICE_SEL")
	)
	(segment
		(start 95.53956 -47.4472)
		(end 95.149924 -47.836836)
		(width 0.1143)
		(layer "B.Cu")
		(net "ICE_SEL")
	)
	(segment
		(start 95.149924 -47.836836)
		(end 95.149924 -48.199802)
		(width 0.1143)
		(layer "B.Cu")
		(net "ICE_SEL")
	)
	(segment
		(start 108.349796 -85.349842)
		(end 107.84967 -84.849716)
		(width 0.1143)
		(layer "F.Cu")
		(net "SXP_ACTIVE_2")
	)
	(via
		(at 107.84967 -84.849716)
		(size 0.508)
		(drill 0.254)
		(layers "F.Cu" "B.Cu")
		(net "SXP_ACTIVE_2")
	)
	(via
		(at 106.94797 -81.534)
		(size 0.7112)
		(drill 0.3556)
		(layers "F.Cu" "B.Cu")
		(net "SXP_ACTIVE_2")
	)
	(segment
		(start 107.289092 -80.607408)
		(end 107.289092 -81.192878)
		(width 0.1143)
		(layer "B.Cu")
		(net "SXP_ACTIVE_2")
	)
	(segment
		(start 108.0135 -79.883)
		(end 107.289092 -80.607408)
		(width 0.1143)
		(layer "B.Cu")
		(net "SXP_ACTIVE_2")
	)
	(segment
		(start 107.289092 -81.192878)
		(end 106.94797 -81.534)
		(width 0.1143)
		(layer "B.Cu")
		(net "SXP_ACTIVE_2")
	)
	(segment
		(start 107.43692 -84.436966)
		(end 107.84967 -84.849716)
		(width 0.1143)
		(layer "B.Cu")
		(net "SXP_ACTIVE_2")
	)
	(segment
		(start 106.94797 -81.534)
		(end 106.864658 -81.617312)
		(width 0.1143)
		(layer "B.Cu")
		(net "SXP_ACTIVE_2")
	)
	(segment
		(start 107.43692 -83.80095)
		(end 107.43692 -84.436966)
		(width 0.1143)
		(layer "B.Cu")
		(net "SXP_ACTIVE_2")
	)
	(segment
		(start 106.864658 -83.228688)
		(end 107.43692 -83.80095)
		(width 0.1143)
		(layer "B.Cu")
		(net "SXP_ACTIVE_2")
	)
	(segment
		(start 106.864658 -81.617312)
		(end 106.864658 -83.228688)
		(width 0.1143)
		(layer "B.Cu")
		(net "SXP_ACTIVE_2")
	)
	(segment
		(start 105.950004 -37.399976)
		(end 106.3498 -37.799772)
		(width 0.1143)
		(layer "F.Cu")
		(net "SPARE3")
	)
	(via
		(at 106.3498 -37.799772)
		(size 0.508)
		(drill 0.254)
		(layers "F.Cu" "B.Cu")
		(net "SPARE3")
	)
	(segment
		(start 106.103166 -36.957)
		(end 106.103166 -37.553138)
		(width 0.1143)
		(layer "B.Cu")
		(net "SPARE3")
	)
	(segment
		(start 106.103166 -37.553138)
		(end 106.3498 -37.799772)
		(width 0.1143)
		(layer "B.Cu")
		(net "SPARE3")
	)
	(segment
		(start 113.792 -77.343)
		(end 114.26317 -77.81417)
		(width 0.1143)
		(layer "F.Cu")
		(net "EXP_TEST_MUX34")
	)
	(segment
		(start 114.26317 -78.842616)
		(end 116.350034 -80.92948)
		(width 0.1143)
		(layer "F.Cu")
		(net "EXP_TEST_MUX34")
	)
	(segment
		(start 114.26317 -77.81417)
		(end 114.26317 -78.842616)
		(width 0.1143)
		(layer "F.Cu")
		(net "EXP_TEST_MUX34")
	)
	(segment
		(start 116.350034 -80.92948)
		(end 116.350034 -82.349848)
		(width 0.1143)
		(layer "F.Cu")
		(net "EXP_TEST_MUX34")
	)
	(segment
		(start 95.993966 -56.156098)
		(end 96.350074 -55.79999)
		(width 0.1143)
		(layer "F.Cu")
		(net "ICE0_TDI")
	)
	(segment
		(start 94.215966 -62.6745)
		(end 94.215966 -61.468)
		(width 0.1143)
		(layer "F.Cu")
		(net "ICE0_TDI")
	)
	(segment
		(start 95.993966 -57.277)
		(end 95.993966 -56.156098)
		(width 0.1143)
		(layer "F.Cu")
		(net "ICE0_TDI")
	)
	(segment
		(start 94.215966 -59.055)
		(end 95.993966 -57.277)
		(width 0.1143)
		(layer "F.Cu")
		(net "ICE0_TDI")
	)
	(segment
		(start 94.215966 -61.468)
		(end 94.215966 -59.055)
		(width 0.1143)
		(layer "F.Cu")
		(net "ICE0_TDI")
	)
	(segment
		(start 165.7096 -117.475)
		(end 162.0774 -117.475)
		(width 0.254)
		(layer "F.Cu")
		(net "AGND_P0V9_E")
	)
	(segment
		(start 164.6555 -113.919)
		(end 163.477448 -113.919)
		(width 0.254)
		(layer "F.Cu")
		(net "AGND_P0V9_E")
	)
	(segment
		(start 165.7096 -122.339608)
		(end 165.7096 -117.475)
		(width 0.254)
		(layer "F.Cu")
		(net "AGND_P0V9_E")
	)
	(segment
		(start 161.7218 -113.6142)
		(end 160.61055 -114.72545)
		(width 0.254)
		(layer "F.Cu")
		(net "AGND_P0V9_E")
	)
	(segment
		(start 163.172648 -113.6142)
		(end 161.7218 -113.6142)
		(width 0.254)
		(layer "F.Cu")
		(net "AGND_P0V9_E")
	)
	(segment
		(start 165.481 -125.791722)
		(end 165.481 -123.942348)
		(width 0.254)
		(layer "F.Cu")
		(net "AGND_P0V9_E")
	)
	(segment
		(start 166.360348 -122.990356)
		(end 165.7096 -122.339608)
		(width 0.254)
		(layer "F.Cu")
		(net "AGND_P0V9_E")
	)
	(segment
		(start 160.61055 -116.79555)
		(end 161.29 -117.475)
		(width 0.254)
		(layer "F.Cu")
		(net "AGND_P0V9_E")
	)
	(segment
		(start 166.360348 -123.063)
		(end 166.360348 -122.990356)
		(width 0.254)
		(layer "F.Cu")
		(net "AGND_P0V9_E")
	)
	(segment
		(start 168.646348 -122.990356)
		(end 168.646348 -126.619)
		(width 0.254)
		(layer "F.Cu")
		(net "AGND_P0V9_E")
	)
	(segment
		(start 168.646348 -126.619)
		(end 168.255696 -127.009652)
		(width 0.254)
		(layer "F.Cu")
		(net "AGND_P0V9_E")
	)
	(segment
		(start 165.481 -123.942348)
		(end 166.360348 -123.063)
		(width 0.254)
		(layer "F.Cu")
		(net "AGND_P0V9_E")
	)
	(segment
		(start 168.255696 -127.009652)
		(end 166.69893 -127.009652)
		(width 0.254)
		(layer "F.Cu")
		(net "AGND_P0V9_E")
	)
	(segment
		(start 166.69893 -127.009652)
		(end 165.481 -125.791722)
		(width 0.254)
		(layer "F.Cu")
		(net "AGND_P0V9_E")
	)
	(segment
		(start 160.61055 -114.72545)
		(end 160.61055 -116.79555)
		(width 0.254)
		(layer "F.Cu")
		(net "AGND_P0V9_E")
	)
	(segment
		(start 163.477448 -113.919)
		(end 163.172648 -113.6142)
		(width 0.254)
		(layer "F.Cu")
		(net "AGND_P0V9_E")
	)
	(segment
		(start 161.29 -117.475)
		(end 162.0774 -117.475)
		(width 0.254)
		(layer "F.Cu")
		(net "AGND_P0V9_E")
	)
	(segment
		(start 169.789348 -122.990356)
		(end 168.646348 -122.990356)
		(width 0.254)
		(layer "F.Cu")
		(net "AGND_P0V9_E")
	)
	(via
		(at 162.0774 -117.475)
		(size 0.7112)
		(drill 0.3556)
		(layers "F.Cu" "B.Cu")
		(net "AGND_P0V9_E")
	)
	(segment
		(start 82.94243 -131.5466)
		(end 82.94243 -133.684772)
		(width 0.1143)
		(layer "F.Cu")
		(net "EXP_GPIO_3")
	)
	(segment
		(start 85.020658 -135.763)
		(end 86.62797 -135.763)
		(width 0.1143)
		(layer "F.Cu")
		(net "EXP_GPIO_3")
	)
	(segment
		(start 106.3498 -98.35007)
		(end 105.849674 -98.850196)
		(width 0.1143)
		(layer "F.Cu")
		(net "EXP_GPIO_3")
	)
	(segment
		(start 82.94243 -133.684772)
		(end 85.020658 -135.763)
		(width 0.1143)
		(layer "F.Cu")
		(net "EXP_GPIO_3")
	)
	(via
		(at 86.62797 -135.763)
		(size 0.5588)
		(drill 0.3048)
		(layers "F.Cu" "B.Cu")
		(net "EXP_GPIO_3")
	)
	(via
		(at 92.56522 -107.7722)
		(size 0.7112)
		(drill 0.3556)
		(layers "F.Cu" "B.Cu")
		(net "EXP_GPIO_3")
	)
	(via
		(at 105.849674 -98.850196)
		(size 0.508)
		(drill 0.254)
		(layers "F.Cu" "B.Cu")
		(net "EXP_GPIO_3")
	)
	(segment
		(start 92.92082 -107.3912)
		(end 94.248224 -107.3912)
		(width 0.1143)
		(layer "B.Cu")
		(net "EXP_GPIO_3")
	)
	(segment
		(start 88.522302 -133.889242)
		(end 88.522302 -122.73661)
		(width 0.1143)
		(layer "B.Cu")
		(net "EXP_GPIO_3")
	)
	(segment
		(start 87.9348 -122.149108)
		(end 87.9348 -120.495314)
		(width 0.1143)
		(layer "B.Cu")
		(net "EXP_GPIO_3")
	)
	(segment
		(start 100.05822 -101.581204)
		(end 100.05822 -101.420676)
		(width 0.1143)
		(layer "B.Cu")
		(net "EXP_GPIO_3")
	)
	(segment
		(start 100.755196 -100.7237)
		(end 100.755196 -100.67798)
		(width 0.1143)
		(layer "B.Cu")
		(net "EXP_GPIO_3")
	)
	(segment
		(start 105.55097 -98.850196)
		(end 105.849674 -98.850196)
		(width 0.1143)
		(layer "B.Cu")
		(net "EXP_GPIO_3")
	)
	(segment
		(start 92.56522 -107.7468)
		(end 92.92082 -107.3912)
		(width 0.1143)
		(layer "B.Cu")
		(net "EXP_GPIO_3")
	)
	(segment
		(start 92.56522 -107.7722)
		(end 92.56522 -107.7468)
		(width 0.1143)
		(layer "B.Cu")
		(net "EXP_GPIO_3")
	)
	(segment
		(start 86.648544 -135.763)
		(end 88.522302 -133.889242)
		(width 0.1143)
		(layer "B.Cu")
		(net "EXP_GPIO_3")
	)
	(segment
		(start 88.522302 -122.73661)
		(end 87.9348 -122.149108)
		(width 0.1143)
		(layer "B.Cu")
		(net "EXP_GPIO_3")
	)
	(segment
		(start 104.989122 -99.412044)
		(end 105.55097 -98.850196)
		(width 0.1143)
		(layer "B.Cu")
		(net "EXP_GPIO_3")
	)
	(segment
		(start 100.755196 -100.67798)
		(end 101.503734 -99.929442)
		(width 0.1143)
		(layer "B.Cu")
		(net "EXP_GPIO_3")
	)
	(segment
		(start 94.248224 -107.3912)
		(end 100.05822 -101.581204)
		(width 0.1143)
		(layer "B.Cu")
		(net "EXP_GPIO_3")
	)
	(segment
		(start 86.62797 -135.763)
		(end 86.648544 -135.763)
		(width 0.1143)
		(layer "B.Cu")
		(net "EXP_GPIO_3")
	)
	(segment
		(start 88.66251 -119.767604)
		(end 88.66251 -111.67491)
		(width 0.1143)
		(layer "B.Cu")
		(net "EXP_GPIO_3")
	)
	(segment
		(start 102.66807 -99.412044)
		(end 104.989122 -99.412044)
		(width 0.1143)
		(layer "B.Cu")
		(net "EXP_GPIO_3")
	)
	(segment
		(start 101.503734 -99.929442)
		(end 102.150672 -99.929442)
		(width 0.1143)
		(layer "B.Cu")
		(net "EXP_GPIO_3")
	)
	(segment
		(start 100.05822 -101.420676)
		(end 100.755196 -100.7237)
		(width 0.1143)
		(layer "B.Cu")
		(net "EXP_GPIO_3")
	)
	(segment
		(start 102.150672 -99.929442)
		(end 102.66807 -99.412044)
		(width 0.1143)
		(layer "B.Cu")
		(net "EXP_GPIO_3")
	)
	(segment
		(start 88.66251 -111.67491)
		(end 92.56522 -107.7722)
		(width 0.1143)
		(layer "B.Cu")
		(net "EXP_GPIO_3")
	)
	(segment
		(start 87.9348 -120.495314)
		(end 88.66251 -119.767604)
		(width 0.1143)
		(layer "B.Cu")
		(net "EXP_GPIO_3")
	)
	(segment
		(start 102.750112 -56.599836)
		(end 102.750112 -59.163712)
		(width 0.1143)
		(layer "F.Cu")
		(net "IOC_TRST_N")
	)
	(segment
		(start 105.083356 -61.496956)
		(end 105.083356 -61.674756)
		(width 0.1143)
		(layer "F.Cu")
		(net "IOC_TRST_N")
	)
	(segment
		(start 106.788966 -64.3001)
		(end 106.096816 -63.60795)
		(width 0.1143)
		(layer "F.Cu")
		(net "IOC_TRST_N")
	)
	(segment
		(start 106.788966 -65.4431)
		(end 106.788966 -64.3001)
		(width 0.1143)
		(layer "F.Cu")
		(net "IOC_TRST_N")
	)
	(segment
		(start 106.096816 -63.60795)
		(end 106.096816 -62.688216)
		(width 0.1143)
		(layer "F.Cu")
		(net "IOC_TRST_N")
	)
	(segment
		(start 105.083356 -61.674756)
		(end 105.7148 -62.3062)
		(width 0.1143)
		(layer "F.Cu")
		(net "IOC_TRST_N")
	)
	(segment
		(start 106.096816 -62.688216)
		(end 105.7148 -62.3062)
		(width 0.1143)
		(layer "F.Cu")
		(net "IOC_TRST_N")
	)
	(segment
		(start 102.750112 -59.163712)
		(end 105.083356 -61.496956)
		(width 0.1143)
		(layer "F.Cu")
		(net "IOC_TRST_N")
	)
	(segment
		(start 113.88217 -78.3082)
		(end 113.88217 -78.821026)
		(width 0.1143)
		(layer "F.Cu")
		(net "EXP_TEST_MUX35")
	)
	(segment
		(start 115.930934 -80.86979)
		(end 115.930934 -82.722974)
		(width 0.1143)
		(layer "F.Cu")
		(net "EXP_TEST_MUX35")
	)
	(segment
		(start 115.930934 -82.722974)
		(end 116.350034 -83.142074)
		(width 0.1143)
		(layer "F.Cu")
		(net "EXP_TEST_MUX35")
	)
	(segment
		(start 113.88217 -78.821026)
		(end 115.930934 -80.86979)
		(width 0.1143)
		(layer "F.Cu")
		(net "EXP_TEST_MUX35")
	)
	(segment
		(start 112.30737 -77.724)
		(end 113.29797 -77.724)
		(width 0.1143)
		(layer "F.Cu")
		(net "EXP_TEST_MUX35")
	)
	(segment
		(start 116.350034 -83.142074)
		(end 116.350034 -83.349846)
		(width 0.1143)
		(layer "F.Cu")
		(net "EXP_TEST_MUX35")
	)
	(segment
		(start 113.29797 -77.724)
		(end 113.88217 -78.3082)
		(width 0.1143)
		(layer "F.Cu")
		(net "EXP_TEST_MUX35")
	)
	(segment
		(start 128.531112 -106.673142)
		(end 128.565402 -106.673142)
		(width 0.1143)
		(layer "F.Cu")
		(net "EXP_RTRIM_A_N")
	)
	(segment
		(start 128.262888 -106.262932)
		(end 128.262888 -106.404918)
		(width 0.1143)
		(layer "F.Cu")
		(net "EXP_RTRIM_A_N")
	)
	(segment
		(start 128.62306 -106.7308)
		(end 128.565402 -106.673142)
		(width 0.1143)
		(layer "F.Cu")
		(net "EXP_RTRIM_A_N")
	)
	(segment
		(start 127.350012 -105.350056)
		(end 128.262888 -106.262932)
		(width 0.1143)
		(layer "F.Cu")
		(net "EXP_RTRIM_A_N")
	)
	(segment
		(start 128.262888 -106.404918)
		(end 128.531112 -106.673142)
		(width 0.1143)
		(layer "F.Cu")
		(net "EXP_RTRIM_A_N")
	)
	(segment
		(start 129.85877 -106.7308)
		(end 128.62306 -106.7308)
		(width 0.1143)
		(layer "F.Cu")
		(net "EXP_RTRIM_A_N")
	)
	(via
		(at 128.565402 -106.673142)
		(size 0.5588)
		(drill 0.3048)
		(layers "F.Cu" "B.Cu")
		(net "EXP_RTRIM_A_N")
	)
	(via
		(at 129.85877 -106.7308)
		(size 0.7112)
		(drill 0.3556)
		(layers "F.Cu" "B.Cu")
		(net "EXP_RTRIM_A_N")
	)
	(segment
		(start 128.63576 -106.7435)
		(end 128.565402 -106.673142)
		(width 0.1143)
		(layer "B.Cu")
		(net "EXP_RTRIM_A_N")
	)
	(segment
		(start 129.42697 -106.7435)
		(end 128.63576 -106.7435)
		(width 0.1143)
		(layer "B.Cu")
		(net "EXP_RTRIM_A_N")
	)
	(segment
		(start 221.34068 -87.60333)
		(end 222.45828 -87.60333)
		(width 0.1143)
		(layer "F.Cu")
		(net "SYS_RST_N_0")
	)
	(segment
		(start 222.45828 -87.60333)
		(end 222.58909 -87.47252)
		(width 0.1143)
		(layer "F.Cu")
		(net "SYS_RST_N_0")
	)
	(segment
		(start 105.950004 -34.99993)
		(end 105.550208 -34.600134)
		(width 0.1143)
		(layer "F.Cu")
		(net "SYS_RST_N_0")
	)
	(segment
		(start 224.36582 -87.47252)
		(end 229.48392 -82.35442)
		(width 0.1143)
		(layer "F.Cu")
		(net "SYS_RST_N_0")
	)
	(segment
		(start 222.58909 -87.47252)
		(end 224.36582 -87.47252)
		(width 0.1143)
		(layer "F.Cu")
		(net "SYS_RST_N_0")
	)
	(via
		(at 108.403644 -28.829)
		(size 0.7112)
		(drill 0.3556)
		(layers "F.Cu" "B.Cu")
		(net "SYS_RST_N_0")
	)
	(via
		(at 106.220768 -29.016198)
		(size 0.5588)
		(drill 0.3048)
		(layers "F.Cu" "B.Cu")
		(net "SYS_RST_N_0")
	)
	(via
		(at 105.550208 -34.600134)
		(size 0.508)
		(drill 0.254)
		(layers "F.Cu" "B.Cu")
		(net "SYS_RST_N_0")
	)
	(via
		(at 229.48392 -82.35442)
		(size 0.5588)
		(drill 0.3048)
		(layers "F.Cu" "B.Cu")
		(net "SYS_RST_N_0")
	)
	(via
		(at 157.448504 -49.53)
		(size 0.5588)
		(drill 0.3048)
		(layers "F.Cu" "B.Cu")
		(net "SYS_RST_N_0")
	)
	(segment
		(start 135.763 -71.501)
		(end 124.714 -71.501)
		(width 0.1143)
		(layer "B.Cu")
		(net "SYS_RST_N_0")
	)
	(segment
		(start 124.714 -71.501)
		(end 123.444 -72.771)
		(width 0.1143)
		(layer "B.Cu")
		(net "SYS_RST_N_0")
	)
	(segment
		(start 157.448504 -49.53)
		(end 157.226 -49.752504)
		(width 0.1143)
		(layer "B.Cu")
		(net "SYS_RST_N_0")
	)
	(segment
		(start 149.606 -63.373)
		(end 147.447 -65.532)
		(width 0.1143)
		(layer "B.Cu")
		(net "SYS_RST_N_0")
	)
	(segment
		(start 106.220768 -29.016198)
		(end 105.550208 -29.686758)
		(width 0.1143)
		(layer "B.Cu")
		(net "SYS_RST_N_0")
	)
	(segment
		(start 123.444 -72.771)
		(end 118.3005 -72.771)
		(width 0.1143)
		(layer "B.Cu")
		(net "SYS_RST_N_0")
	)
	(segment
		(start 106.407966 -28.829)
		(end 106.220768 -29.016198)
		(width 0.1143)
		(layer "B.Cu")
		(net "SYS_RST_N_0")
	)
	(segment
		(start 157.226 -49.752504)
		(end 157.226 -61.849)
		(width 0.1143)
		(layer "B.Cu")
		(net "SYS_RST_N_0")
	)
	(segment
		(start 105.550208 -29.686758)
		(end 105.550208 -34.600134)
		(width 0.1143)
		(layer "B.Cu")
		(net "SYS_RST_N_0")
	)
	(segment
		(start 111.170466 -28.829)
		(end 108.403644 -28.829)
		(width 0.1143)
		(layer "B.Cu")
		(net "SYS_RST_N_0")
	)
	(segment
		(start 155.702 -63.373)
		(end 149.606 -63.373)
		(width 0.1143)
		(layer "B.Cu")
		(net "SYS_RST_N_0")
	)
	(segment
		(start 108.403644 -28.829)
		(end 106.407966 -28.829)
		(width 0.1143)
		(layer "B.Cu")
		(net "SYS_RST_N_0")
	)
	(segment
		(start 141.732 -65.532)
		(end 135.763 -71.501)
		(width 0.1143)
		(layer "B.Cu")
		(net "SYS_RST_N_0")
	)
	(segment
		(start 157.226 -61.849)
		(end 155.702 -63.373)
		(width 0.1143)
		(layer "B.Cu")
		(net "SYS_RST_N_0")
	)
	(segment
		(start 147.447 -65.532)
		(end 141.732 -65.532)
		(width 0.1143)
		(layer "B.Cu")
		(net "SYS_RST_N_0")
	)
	(segment
		(start 125.392434 -35.814)
		(end 120.621298 -31.042864)
		(width 0.127)
		(layer "In2.Cu")
		(net "SYS_RST_N_0")
	)
	(segment
		(start 219.4814 -58.039)
		(end 229.235 -67.7926)
		(width 0.127)
		(layer "In2.Cu")
		(net "SYS_RST_N_0")
	)
	(segment
		(start 120.621298 -30.2768)
		(end 119.821198 -29.4767)
		(width 0.127)
		(layer "In2.Cu")
		(net "SYS_RST_N_0")
	)
	(segment
		(start 165.543992 -58.039)
		(end 219.4814 -58.039)
		(width 0.127)
		(layer "In2.Cu")
		(net "SYS_RST_N_0")
	)
	(segment
		(start 119.821198 -29.4767)
		(end 106.68127 -29.4767)
		(width 0.127)
		(layer "In2.Cu")
		(net "SYS_RST_N_0")
	)
	(segment
		(start 229.235 -82.1055)
		(end 229.48392 -82.35442)
		(width 0.127)
		(layer "In2.Cu")
		(net "SYS_RST_N_0")
	)
	(segment
		(start 120.621298 -31.042864)
		(end 120.621298 -30.2768)
		(width 0.127)
		(layer "In2.Cu")
		(net "SYS_RST_N_0")
	)
	(segment
		(start 158.369 -50.864008)
		(end 165.543992 -58.039)
		(width 0.127)
		(layer "In2.Cu")
		(net "SYS_RST_N_0")
	)
	(segment
		(start 156.686504 -48.768)
		(end 156.272992 -48.768)
		(width 0.127)
		(layer "In2.Cu")
		(net "SYS_RST_N_0")
	)
	(segment
		(start 158.369 -50.450496)
		(end 158.369 -50.864008)
		(width 0.127)
		(layer "In2.Cu")
		(net "SYS_RST_N_0")
	)
	(segment
		(start 134.239 -35.814)
		(end 125.392434 -35.814)
		(width 0.127)
		(layer "In2.Cu")
		(net "SYS_RST_N_0")
	)
	(segment
		(start 229.235 -67.7926)
		(end 229.235 -82.1055)
		(width 0.127)
		(layer "In2.Cu")
		(net "SYS_RST_N_0")
	)
	(segment
		(start 149.922992 -42.418)
		(end 140.843 -42.418)
		(width 0.127)
		(layer "In2.Cu")
		(net "SYS_RST_N_0")
	)
	(segment
		(start 106.68127 -29.4767)
		(end 106.220768 -29.016198)
		(width 0.127)
		(layer "In2.Cu")
		(net "SYS_RST_N_0")
	)
	(segment
		(start 140.843 -42.418)
		(end 134.239 -35.814)
		(width 0.127)
		(layer "In2.Cu")
		(net "SYS_RST_N_0")
	)
	(segment
		(start 157.448504 -49.53)
		(end 158.369 -50.450496)
		(width 0.127)
		(layer "In2.Cu")
		(net "SYS_RST_N_0")
	)
	(segment
		(start 157.448504 -49.53)
		(end 156.686504 -48.768)
		(width 0.127)
		(layer "In2.Cu")
		(net "SYS_RST_N_0")
	)
	(segment
		(start 156.272992 -48.768)
		(end 149.922992 -42.418)
		(width 0.127)
		(layer "In2.Cu")
		(net "SYS_RST_N_0")
	)
	(segment
		(start 18.923 -163.576)
		(end 19.685 -162.814)
		(width 0.1143)
		(layer "F.Cu")
		(net "SAS_HDD_LED6")
	)
	(segment
		(start 107.743498 -82.186526)
		(end 107.701842 -82.14487)
		(width 0.1143)
		(layer "F.Cu")
		(net "SAS_HDD_LED6")
	)
	(segment
		(start 16.786098 -165.712902)
		(end 18.923 -163.576)
		(width 0.1143)
		(layer "F.Cu")
		(net "SAS_HDD_LED6")
	)
	(segment
		(start 107.743498 -82.743548)
		(end 107.743498 -82.186526)
		(width 0.1143)
		(layer "F.Cu")
		(net "SAS_HDD_LED6")
	)
	(segment
		(start 31.75 -149.987254)
		(end 31.75 -149.606)
		(width 0.1143)
		(layer "F.Cu")
		(net "SAS_HDD_LED6")
	)
	(segment
		(start 19.685 -162.052254)
		(end 31.75 -149.987254)
		(width 0.1143)
		(layer "F.Cu")
		(net "SAS_HDD_LED6")
	)
	(segment
		(start 19.685 -162.814)
		(end 19.685 -162.052254)
		(width 0.1143)
		(layer "F.Cu")
		(net "SAS_HDD_LED6")
	)
	(segment
		(start 16.786098 -170.107356)
		(end 16.786098 -165.712902)
		(width 0.1143)
		(layer "F.Cu")
		(net "SAS_HDD_LED6")
	)
	(segment
		(start 108.349796 -83.349846)
		(end 107.743498 -82.743548)
		(width 0.1143)
		(layer "F.Cu")
		(net "SAS_HDD_LED6")
	)
	(segment
		(start 31.75 -149.606)
		(end 32.131 -149.225)
		(width 0.1143)
		(layer "F.Cu")
		(net "SAS_HDD_LED6")
	)
	(segment
		(start 107.701842 -82.14487)
		(end 107.701842 -81.478882)
		(width 0.1143)
		(layer "F.Cu")
		(net "SAS_HDD_LED6")
	)
	(via
		(at 32.131 -149.225)
		(size 0.5588)
		(drill 0.3048)
		(layers "F.Cu" "B.Cu")
		(net "SAS_HDD_LED6")
	)
	(via
		(at 107.701842 -81.478882)
		(size 0.508)
		(drill 0.254)
		(layers "F.Cu" "B.Cu")
		(net "SAS_HDD_LED6")
	)
	(via
		(at 18.923 -163.576)
		(size 0.7112)
		(drill 0.3556)
		(layers "F.Cu" "B.Cu")
		(net "SAS_HDD_LED6")
	)
	(segment
		(start 99.86391 -81.915)
		(end 98.485452 -81.915)
		(width 0.127)
		(layer "In5.Cu")
		(net "SAS_HDD_LED6")
	)
	(segment
		(start 107.41787 -80.945736)
		(end 107.41787 -80.748124)
		(width 0.127)
		(layer "In5.Cu")
		(net "SAS_HDD_LED6")
	)
	(segment
		(start 107.701842 -81.229708)
		(end 107.41787 -80.945736)
		(width 0.127)
		(layer "In5.Cu")
		(net "SAS_HDD_LED6")
	)
	(segment
		(start 105.5243 -79.9719)
		(end 101.80701 -79.9719)
		(width 0.127)
		(layer "In5.Cu")
		(net "SAS_HDD_LED6")
	)
	(segment
		(start 36.873688 -149.5933)
		(end 32.4993 -149.5933)
		(width 0.127)
		(layer "In5.Cu")
		(net "SAS_HDD_LED6")
	)
	(segment
		(start 32.4993 -149.5933)
		(end 32.131 -149.225)
		(width 0.127)
		(layer "In5.Cu")
		(net "SAS_HDD_LED6")
	)
	(segment
		(start 107.41787 -80.748124)
		(end 106.362246 -79.6925)
		(width 0.127)
		(layer "In5.Cu")
		(net "SAS_HDD_LED6")
	)
	(segment
		(start 44.907454 -142.719552)
		(end 43.747436 -142.719552)
		(width 0.127)
		(layer "In5.Cu")
		(net "SAS_HDD_LED6")
	)
	(segment
		(start 106.362246 -79.6925)
		(end 105.8037 -79.6925)
		(width 0.127)
		(layer "In5.Cu")
		(net "SAS_HDD_LED6")
	)
	(segment
		(start 98.485452 -81.915)
		(end 49.403 -130.997452)
		(width 0.127)
		(layer "In5.Cu")
		(net "SAS_HDD_LED6")
	)
	(segment
		(start 47.498 -139.954)
		(end 45.197522 -142.254478)
		(width 0.127)
		(layer "In5.Cu")
		(net "SAS_HDD_LED6")
	)
	(segment
		(start 43.747436 -142.719552)
		(end 36.873688 -149.5933)
		(width 0.127)
		(layer "In5.Cu")
		(net "SAS_HDD_LED6")
	)
	(segment
		(start 107.701842 -81.478882)
		(end 107.701842 -81.229708)
		(width 0.127)
		(layer "In5.Cu")
		(net "SAS_HDD_LED6")
	)
	(segment
		(start 49.403 -135.162036)
		(end 47.498 -137.067036)
		(width 0.127)
		(layer "In5.Cu")
		(net "SAS_HDD_LED6")
	)
	(segment
		(start 105.8037 -79.6925)
		(end 105.5243 -79.9719)
		(width 0.127)
		(layer "In5.Cu")
		(net "SAS_HDD_LED6")
	)
	(segment
		(start 47.498 -137.067036)
		(end 47.498 -139.954)
		(width 0.127)
		(layer "In5.Cu")
		(net "SAS_HDD_LED6")
	)
	(segment
		(start 101.80701 -79.9719)
		(end 99.86391 -81.915)
		(width 0.127)
		(layer "In5.Cu")
		(net "SAS_HDD_LED6")
	)
	(segment
		(start 45.197522 -142.254478)
		(end 45.197522 -142.429484)
		(width 0.127)
		(layer "In5.Cu")
		(net "SAS_HDD_LED6")
	)
	(segment
		(start 45.197522 -142.429484)
		(end 44.907454 -142.719552)
		(width 0.127)
		(layer "In5.Cu")
		(net "SAS_HDD_LED6")
	)
	(segment
		(start 49.403 -130.997452)
		(end 49.403 -135.162036)
		(width 0.127)
		(layer "In5.Cu")
		(net "SAS_HDD_LED6")
	)
	(segment
		(start 129.8448 -104.8004)
		(end 129.208022 -104.8004)
		(width 0.1143)
		(layer "F.Cu")
		(net "EXP_RTRIM_A")
	)
	(segment
		(start 127.350012 -104.350058)
		(end 128.504188 -105.504234)
		(width 0.1143)
		(layer "F.Cu")
		(net "EXP_RTRIM_A")
	)
	(segment
		(start 129.208022 -104.8004)
		(end 128.504188 -105.504234)
		(width 0.1143)
		(layer "F.Cu")
		(net "EXP_RTRIM_A")
	)
	(via
		(at 129.8448 -104.8004)
		(size 0.7112)
		(drill 0.3556)
		(layers "F.Cu" "B.Cu")
		(net "EXP_RTRIM_A")
	)
	(via
		(at 128.504188 -105.504234)
		(size 0.5588)
		(drill 0.3048)
		(layers "F.Cu" "B.Cu")
		(net "EXP_RTRIM_A")
	)
	(segment
		(start 129.42697 -105.8545)
		(end 128.854454 -105.8545)
		(width 0.1143)
		(layer "B.Cu")
		(net "EXP_RTRIM_A")
	)
	(segment
		(start 128.854454 -105.8545)
		(end 128.504188 -105.504234)
		(width 0.1143)
		(layer "B.Cu")
		(net "EXP_RTRIM_A")
	)
	(segment
		(start 117.26799 -38.198044)
		(end 117.26799 -38.56101)
		(width 0.1143)
		(layer "F.Cu")
		(net "SPARE4")
	)
	(segment
		(start 116.238274 -39.678102)
		(end 116.238274 -40.042592)
		(width 0.1143)
		(layer "F.Cu")
		(net "SPARE4")
	)
	(segment
		(start 117.26799 -38.56101)
		(end 116.844826 -38.984174)
		(width 0.1143)
		(layer "F.Cu")
		(net "SPARE4")
	)
	(segment
		(start 113.423192 -41.399968)
		(end 113.150142 -41.399968)
		(width 0.1143)
		(layer "F.Cu")
		(net "SPARE4")
	)
	(segment
		(start 113.80216 -41.021)
		(end 113.423192 -41.399968)
		(width 0.1143)
		(layer "F.Cu")
		(net "SPARE4")
	)
	(segment
		(start 116.844826 -39.07155)
		(end 116.238274 -39.678102)
		(width 0.1143)
		(layer "F.Cu")
		(net "SPARE4")
	)
	(segment
		(start 115.259866 -41.021)
		(end 113.80216 -41.021)
		(width 0.1143)
		(layer "F.Cu")
		(net "SPARE4")
	)
	(segment
		(start 116.238274 -40.042592)
		(end 115.259866 -41.021)
		(width 0.1143)
		(layer "F.Cu")
		(net "SPARE4")
	)
	(segment
		(start 116.844826 -38.984174)
		(end 116.844826 -39.07155)
		(width 0.1143)
		(layer "F.Cu")
		(net "SPARE4")
	)
	(via
		(at 117.26799 -38.198044)
		(size 0.508)
		(drill 0.254)
		(layers "F.Cu" "B.Cu")
		(net "SPARE4")
	)
	(segment
		(start 117.484906 -36.64458)
		(end 117.26799 -36.861496)
		(width 0.1143)
		(layer "B.Cu")
		(net "SPARE4")
	)
	(segment
		(start 117.26799 -36.861496)
		(end 117.26799 -38.198044)
		(width 0.1143)
		(layer "B.Cu")
		(net "SPARE4")
	)
	(segment
		(start 113.930684 -82.881724)
		(end 114.349784 -83.300824)
		(width 0.1143)
		(layer "F.Cu")
		(net "EXP_TEST_MUX27")
	)
	(segment
		(start 111.252 -76.327)
		(end 110.339124 -77.239876)
		(width 0.1143)
		(layer "F.Cu")
		(net "EXP_TEST_MUX27")
	)
	(segment
		(start 113.64468 -80.494378)
		(end 113.930684 -80.780382)
		(width 0.1143)
		(layer "F.Cu")
		(net "EXP_TEST_MUX27")
	)
	(segment
		(start 110.339124 -77.239876)
		(end 110.339124 -77.747876)
		(width 0.1143)
		(layer "F.Cu")
		(net "EXP_TEST_MUX27")
	)
	(segment
		(start 110.87862 -79.12862)
		(end 111.90859 -80.15859)
		(width 0.1143)
		(layer "F.Cu")
		(net "EXP_TEST_MUX27")
	)
	(segment
		(start 110.87862 -78.287372)
		(end 110.87862 -79.12862)
		(width 0.1143)
		(layer "F.Cu")
		(net "EXP_TEST_MUX27")
	)
	(segment
		(start 113.64468 -80.459834)
		(end 113.64468 -80.494378)
		(width 0.1143)
		(layer "F.Cu")
		(net "EXP_TEST_MUX27")
	)
	(segment
		(start 113.343436 -80.15859)
		(end 113.64468 -80.459834)
		(width 0.1143)
		(layer "F.Cu")
		(net "EXP_TEST_MUX27")
	)
	(segment
		(start 113.930684 -80.780382)
		(end 113.930684 -82.881724)
		(width 0.1143)
		(layer "F.Cu")
		(net "EXP_TEST_MUX27")
	)
	(segment
		(start 110.339124 -77.747876)
		(end 110.87862 -78.287372)
		(width 0.1143)
		(layer "F.Cu")
		(net "EXP_TEST_MUX27")
	)
	(segment
		(start 111.90859 -80.15859)
		(end 113.343436 -80.15859)
		(width 0.1143)
		(layer "F.Cu")
		(net "EXP_TEST_MUX27")
	)
	(segment
		(start 114.349784 -83.300824)
		(end 114.349784 -83.349846)
		(width 0.1143)
		(layer "F.Cu")
		(net "EXP_TEST_MUX27")
	)
	(segment
		(start 100.598732 -62.04585)
		(end 100.598478 -62.045596)
		(width 0.1143)
		(layer "F.Cu")
		(net "IOC_RESET#")
	)
	(segment
		(start 100.819966 -64.4525)
		(end 100.819966 -63.391034)
		(width 0.1143)
		(layer "F.Cu")
		(net "IOC_RESET#")
	)
	(segment
		(start 99.310952 -62.8777)
		(end 99.310952 -61.852048)
		(width 0.1143)
		(layer "F.Cu")
		(net "IOC_RESET#")
	)
	(segment
		(start 100.965 -63.246)
		(end 100.965 -63.147194)
		(width 0.1143)
		(layer "F.Cu")
		(net "IOC_RESET#")
	)
	(segment
		(start 101.00437 -62.451488)
		(end 101.004116 -62.451234)
		(width 0.1143)
		(layer "F.Cu")
		(net "IOC_RESET#")
	)
	(segment
		(start 100.076 -60.579)
		(end 100.457 -60.198)
		(width 0.1143)
		(layer "F.Cu")
		(net "IOC_RESET#")
	)
	(segment
		(start 100.598986 -62.04585)
		(end 100.598732 -62.04585)
		(width 0.1143)
		(layer "F.Cu")
		(net "IOC_RESET#")
	)
	(segment
		(start 99.310952 -61.852048)
		(end 100.076 -61.087)
		(width 0.1143)
		(layer "F.Cu")
		(net "IOC_RESET#")
	)
	(segment
		(start 106.41076 -33.218374)
		(end 106.41076 -31.75)
		(width 0.1143)
		(layer "F.Cu")
		(net "IOC_RESET#")
	)
	(segment
		(start 100.965 -63.147194)
		(end 101.004116 -63.108078)
		(width 0.1143)
		(layer "F.Cu")
		(net "IOC_RESET#")
	)
	(segment
		(start 112.75314 -44.203112)
		(end 112.75314 -44.206414)
		(width 0.1143)
		(layer "F.Cu")
		(net "IOC_RESET#")
	)
	(segment
		(start 100.025454 -62.045596)
		(end 100.0252 -62.04585)
		(width 0.1143)
		(layer "F.Cu")
		(net "IOC_RESET#")
	)
	(segment
		(start 101.004116 -63.024766)
		(end 101.00437 -63.024512)
		(width 0.1143)
		(layer "F.Cu")
		(net "IOC_RESET#")
	)
	(segment
		(start 101.00437 -63.024512)
		(end 101.00437 -62.451488)
		(width 0.1143)
		(layer "F.Cu")
		(net "IOC_RESET#")
	)
	(segment
		(start 100.076 -61.087)
		(end 100.076 -60.579)
		(width 0.1143)
		(layer "F.Cu")
		(net "IOC_RESET#")
	)
	(segment
		(start 99.619816 -62.534546)
		(end 99.51085 -62.643512)
		(width 0.1143)
		(layer "F.Cu")
		(net "IOC_RESET#")
	)
	(segment
		(start 99.51085 -62.677802)
		(end 99.310952 -62.8777)
		(width 0.1143)
		(layer "F.Cu")
		(net "IOC_RESET#")
	)
	(segment
		(start 101.004116 -62.451234)
		(end 101.004116 -62.45098)
		(width 0.1143)
		(layer "F.Cu")
		(net "IOC_RESET#")
	)
	(segment
		(start 100.0252 -62.04585)
		(end 100.024946 -62.04585)
		(width 0.1143)
		(layer "F.Cu")
		(net "IOC_RESET#")
	)
	(segment
		(start 101.004116 -62.45098)
		(end 100.598986 -62.04585)
		(width 0.1143)
		(layer "F.Cu")
		(net "IOC_RESET#")
	)
	(segment
		(start 100.598478 -62.045596)
		(end 100.025454 -62.045596)
		(width 0.1143)
		(layer "F.Cu")
		(net "IOC_RESET#")
	)
	(segment
		(start 112.350042 -43.800014)
		(end 112.75314 -44.203112)
		(width 0.1143)
		(layer "F.Cu")
		(net "IOC_RESET#")
	)
	(segment
		(start 106.750104 -33.920938)
		(end 106.381804 -33.552638)
		(width 0.1143)
		(layer "F.Cu")
		(net "IOC_RESET#")
	)
	(segment
		(start 99.619816 -62.45098)
		(end 99.619816 -62.534546)
		(width 0.1143)
		(layer "F.Cu")
		(net "IOC_RESET#")
	)
	(segment
		(start 99.51085 -62.643512)
		(end 99.51085 -62.677802)
		(width 0.1143)
		(layer "F.Cu")
		(net "IOC_RESET#")
	)
	(segment
		(start 100.024946 -62.04585)
		(end 99.619816 -62.45098)
		(width 0.1143)
		(layer "F.Cu")
		(net "IOC_RESET#")
	)
	(segment
		(start 106.750104 -34.19983)
		(end 106.750104 -33.920938)
		(width 0.1143)
		(layer "F.Cu")
		(net "IOC_RESET#")
	)
	(segment
		(start 106.381804 -33.552638)
		(end 106.381804 -33.24733)
		(width 0.1143)
		(layer "F.Cu")
		(net "IOC_RESET#")
	)
	(segment
		(start 101.004116 -63.108078)
		(end 101.004116 -63.024766)
		(width 0.1143)
		(layer "F.Cu")
		(net "IOC_RESET#")
	)
	(segment
		(start 106.381804 -33.24733)
		(end 106.41076 -33.218374)
		(width 0.1143)
		(layer "F.Cu")
		(net "IOC_RESET#")
	)
	(segment
		(start 100.819966 -63.391034)
		(end 100.965 -63.246)
		(width 0.1143)
		(layer "F.Cu")
		(net "IOC_RESET#")
	)
	(via
		(at 100.457 -60.198)
		(size 0.5588)
		(drill 0.254)
		(layers "F.Cu" "B.Cu")
		(net "IOC_RESET#")
	)
	(via
		(at 100.965 -63.246)
		(size 0.7112)
		(drill 0.3556)
		(layers "F.Cu" "B.Cu")
		(net "IOC_RESET#")
	)
	(via
		(at 106.41076 -31.75)
		(size 0.508)
		(drill 0.254)
		(layers "F.Cu" "B.Cu")
		(net "IOC_RESET#")
	)
	(via
		(at 112.75314 -44.206414)
		(size 0.508)
		(drill 0.254)
		(layers "F.Cu" "B.Cu")
		(net "IOC_RESET#")
	)
	(segment
		(start 108.158788 -42.592244)
		(end 106.737404 -41.17086)
		(width 0.127)
		(layer "In2.Cu")
		(net "IOC_RESET#")
	)
	(segment
		(start 111.192056 -36.751006)
		(end 111.569246 -36.373816)
		(width 0.127)
		(layer "In2.Cu")
		(net "IOC_RESET#")
	)
	(segment
		(start 113.174526 -46.777656)
		(end 111.438182 -48.514)
		(width 0.127)
		(layer "In2.Cu")
		(net "IOC_RESET#")
	)
	(segment
		(start 113.174526 -44.6278)
		(end 113.174526 -46.777656)
		(width 0.127)
		(layer "In2.Cu")
		(net "IOC_RESET#")
	)
	(segment
		(start 111.438182 -48.514)
		(end 99.84359 -48.514)
		(width 0.127)
		(layer "In2.Cu")
		(net "IOC_RESET#")
	)
	(segment
		(start 111.120174 -43.268392)
		(end 110.1598 -43.268392)
		(width 0.127)
		(layer "In2.Cu")
		(net "IOC_RESET#")
	)
	(segment
		(start 101.969062 -58.685938)
		(end 100.457 -60.198)
		(width 0.127)
		(layer "In2.Cu")
		(net "IOC_RESET#")
	)
	(segment
		(start 100.972112 -54.229)
		(end 101.969062 -55.22595)
		(width 0.127)
		(layer "In2.Cu")
		(net "IOC_RESET#")
	)
	(segment
		(start 106.737404 -40.823388)
		(end 110.809786 -36.751006)
		(width 0.127)
		(layer "In2.Cu")
		(net "IOC_RESET#")
	)
	(segment
		(start 111.569246 -34.426398)
		(end 110.670848 -33.528)
		(width 0.127)
		(layer "In2.Cu")
		(net "IOC_RESET#")
	)
	(segment
		(start 110.1598 -43.268392)
		(end 109.483652 -42.592244)
		(width 0.127)
		(layer "In2.Cu")
		(net "IOC_RESET#")
	)
	(segment
		(start 109.483652 -42.592244)
		(end 108.158788 -42.592244)
		(width 0.127)
		(layer "In2.Cu")
		(net "IOC_RESET#")
	)
	(segment
		(start 110.809786 -36.751006)
		(end 111.192056 -36.751006)
		(width 0.127)
		(layer "In2.Cu")
		(net "IOC_RESET#")
	)
	(segment
		(start 101.969062 -55.22595)
		(end 101.969062 -58.685938)
		(width 0.127)
		(layer "In2.Cu")
		(net "IOC_RESET#")
	)
	(segment
		(start 110.670848 -33.528)
		(end 107.380024 -33.528)
		(width 0.127)
		(layer "In2.Cu")
		(net "IOC_RESET#")
	)
	(segment
		(start 107.380024 -33.528)
		(end 106.41076 -32.558736)
		(width 0.127)
		(layer "In2.Cu")
		(net "IOC_RESET#")
	)
	(segment
		(start 111.569246 -36.373816)
		(end 111.569246 -34.426398)
		(width 0.127)
		(layer "In2.Cu")
		(net "IOC_RESET#")
	)
	(segment
		(start 112.75314 -44.206414)
		(end 113.174526 -44.6278)
		(width 0.127)
		(layer "In2.Cu")
		(net "IOC_RESET#")
	)
	(segment
		(start 106.737404 -41.17086)
		(end 106.737404 -40.823388)
		(width 0.127)
		(layer "In2.Cu")
		(net "IOC_RESET#")
	)
	(segment
		(start 99.530662 -53.973222)
		(end 99.78644 -54.229)
		(width 0.127)
		(layer "In2.Cu")
		(net "IOC_RESET#")
	)
	(segment
		(start 99.84359 -48.514)
		(end 99.530662 -48.826928)
		(width 0.127)
		(layer "In2.Cu")
		(net "IOC_RESET#")
	)
	(segment
		(start 112.75314 -44.206414)
		(end 112.058196 -44.206414)
		(width 0.127)
		(layer "In2.Cu")
		(net "IOC_RESET#")
	)
	(segment
		(start 112.058196 -44.206414)
		(end 111.120174 -43.268392)
		(width 0.127)
		(layer "In2.Cu")
		(net "IOC_RESET#")
	)
	(segment
		(start 99.530662 -48.826928)
		(end 99.530662 -53.973222)
		(width 0.127)
		(layer "In2.Cu")
		(net "IOC_RESET#")
	)
	(segment
		(start 99.78644 -54.229)
		(end 100.972112 -54.229)
		(width 0.127)
		(layer "In2.Cu")
		(net "IOC_RESET#")
	)
	(segment
		(start 106.41076 -32.558736)
		(end 106.41076 -31.75)
		(width 0.127)
		(layer "In2.Cu")
		(net "IOC_RESET#")
	)
	(segment
		(start 87.579962 -133.35)
		(end 87.306912 -133.07695)
		(width 0.1143)
		(layer "F.Cu")
		(net "EXP_GPIO_4")
	)
	(segment
		(start 109.349794 -96.350074)
		(end 108.849668 -96.8502)
		(width 0.1143)
		(layer "F.Cu")
		(net "EXP_GPIO_4")
	)
	(segment
		(start 88.534494 -133.35)
		(end 87.579962 -133.35)
		(width 0.1143)
		(layer "F.Cu")
		(net "EXP_GPIO_4")
	)
	(segment
		(start 86.903306 -133.096)
		(end 86.37397 -133.096)
		(width 0.1143)
		(layer "F.Cu")
		(net "EXP_GPIO_4")
	)
	(segment
		(start 90.325702 -131.570476)
		(end 90.325702 -132.29463)
		(width 0.1143)
		(layer "F.Cu")
		(net "EXP_GPIO_4")
	)
	(segment
		(start 88.93302 -132.951474)
		(end 88.534494 -133.35)
		(width 0.1143)
		(layer "F.Cu")
		(net "EXP_GPIO_4")
	)
	(segment
		(start 90.325702 -132.29463)
		(end 90.013282 -132.60705)
		(width 0.1143)
		(layer "F.Cu")
		(net "EXP_GPIO_4")
	)
	(segment
		(start 86.922356 -133.07695)
		(end 86.903306 -133.096)
		(width 0.1143)
		(layer "F.Cu")
		(net "EXP_GPIO_4")
	)
	(segment
		(start 87.306912 -133.07695)
		(end 86.922356 -133.07695)
		(width 0.1143)
		(layer "F.Cu")
		(net "EXP_GPIO_4")
	)
	(segment
		(start 89.239344 -132.60705)
		(end 88.93302 -132.913374)
		(width 0.1143)
		(layer "F.Cu")
		(net "EXP_GPIO_4")
	)
	(segment
		(start 88.93302 -132.913374)
		(end 88.93302 -132.951474)
		(width 0.1143)
		(layer "F.Cu")
		(net "EXP_GPIO_4")
	)
	(segment
		(start 90.013282 -132.60705)
		(end 89.239344 -132.60705)
		(width 0.1143)
		(layer "F.Cu")
		(net "EXP_GPIO_4")
	)
	(via
		(at 108.849668 -96.8502)
		(size 0.508)
		(drill 0.254)
		(layers "F.Cu" "B.Cu")
		(net "EXP_GPIO_4")
	)
	(via
		(at 86.37397 -133.096)
		(size 0.508)
		(drill 0.254)
		(layers "F.Cu" "B.Cu")
		(net "EXP_GPIO_4")
	)
	(via
		(at 98.467926 -98.38817)
		(size 0.7112)
		(drill 0.3556)
		(layers "F.Cu" "B.Cu")
		(net "EXP_GPIO_4")
	)
	(segment
		(start 103.161084 -97.954846)
		(end 103.678482 -97.437448)
		(width 0.1143)
		(layer "B.Cu")
		(net "EXP_GPIO_4")
	)
	(segment
		(start 107.020868 -98.262948)
		(end 107.262422 -98.021394)
		(width 0.1143)
		(layer "B.Cu")
		(net "EXP_GPIO_4")
	)
	(segment
		(start 103.678482 -97.437448)
		(end 104.020874 -97.437448)
		(width 0.1143)
		(layer "B.Cu")
		(net "EXP_GPIO_4")
	)
	(segment
		(start 100.442268 -97.30105)
		(end 101.096064 -97.954846)
		(width 0.1143)
		(layer "B.Cu")
		(net "EXP_GPIO_4")
	)
	(segment
		(start 104.020874 -97.437448)
		(end 104.262428 -97.679002)
		(width 0.1143)
		(layer "B.Cu")
		(net "EXP_GPIO_4")
	)
	(segment
		(start 98.51771 -98.38817)
		(end 98.90506 -98.000566)
		(width 0.1143)
		(layer "B.Cu")
		(net "EXP_GPIO_4")
	)
	(segment
		(start 107.678474 -97.437448)
		(end 107.846368 -97.437448)
		(width 0.1143)
		(layer "B.Cu")
		(net "EXP_GPIO_4")
	)
	(segment
		(start 98.467926 -98.38817)
		(end 98.51771 -98.38817)
		(width 0.1143)
		(layer "B.Cu")
		(net "EXP_GPIO_4")
	)
	(segment
		(start 98.181668 -98.674428)
		(end 97.266252 -98.674428)
		(width 0.1143)
		(layer "B.Cu")
		(net "EXP_GPIO_4")
	)
	(segment
		(start 101.096064 -97.954846)
		(end 103.161084 -97.954846)
		(width 0.1143)
		(layer "B.Cu")
		(net "EXP_GPIO_4")
	)
	(segment
		(start 86.63051 -109.31017)
		(end 86.63051 -132.83946)
		(width 0.1143)
		(layer "B.Cu")
		(net "EXP_GPIO_4")
	)
	(segment
		(start 104.262428 -97.846896)
		(end 104.67848 -98.262948)
		(width 0.1143)
		(layer "B.Cu")
		(net "EXP_GPIO_4")
	)
	(segment
		(start 98.90506 -97.572322)
		(end 99.176332 -97.30105)
		(width 0.1143)
		(layer "B.Cu")
		(net "EXP_GPIO_4")
	)
	(segment
		(start 99.176332 -97.30105)
		(end 100.442268 -97.30105)
		(width 0.1143)
		(layer "B.Cu")
		(net "EXP_GPIO_4")
	)
	(segment
		(start 98.467926 -98.38817)
		(end 98.181668 -98.674428)
		(width 0.1143)
		(layer "B.Cu")
		(net "EXP_GPIO_4")
	)
	(segment
		(start 86.63051 -132.83946)
		(end 86.37397 -133.096)
		(width 0.1143)
		(layer "B.Cu")
		(net "EXP_GPIO_4")
	)
	(segment
		(start 98.90506 -98.000566)
		(end 98.90506 -97.572322)
		(width 0.1143)
		(layer "B.Cu")
		(net "EXP_GPIO_4")
	)
	(segment
		(start 107.262422 -98.021394)
		(end 107.262422 -97.8535)
		(width 0.1143)
		(layer "B.Cu")
		(net "EXP_GPIO_4")
	)
	(segment
		(start 107.846368 -97.437448)
		(end 108.433616 -96.8502)
		(width 0.1143)
		(layer "B.Cu")
		(net "EXP_GPIO_4")
	)
	(segment
		(start 108.433616 -96.8502)
		(end 108.849668 -96.8502)
		(width 0.1143)
		(layer "B.Cu")
		(net "EXP_GPIO_4")
	)
	(segment
		(start 107.262422 -97.8535)
		(end 107.678474 -97.437448)
		(width 0.1143)
		(layer "B.Cu")
		(net "EXP_GPIO_4")
	)
	(segment
		(start 97.266252 -98.674428)
		(end 86.63051 -109.31017)
		(width 0.1143)
		(layer "B.Cu")
		(net "EXP_GPIO_4")
	)
	(segment
		(start 104.262428 -97.679002)
		(end 104.262428 -97.846896)
		(width 0.1143)
		(layer "B.Cu")
		(net "EXP_GPIO_4")
	)
	(segment
		(start 104.67848 -98.262948)
		(end 107.020868 -98.262948)
		(width 0.1143)
		(layer "B.Cu")
		(net "EXP_GPIO_4")
	)
	(segment
		(start 121.197116 -42.23385)
		(end 122.028966 -41.402)
		(width 0.1143)
		(layer "F.Cu")
		(net "SYS_HB_LED")
	)
	(segment
		(start 122.028966 -38.354)
		(end 122.282966 -38.1)
		(width 0.1143)
		(layer "F.Cu")
		(net "SYS_HB_LED")
	)
	(segment
		(start 119.552466 -42.926)
		(end 120.244616 -42.23385)
		(width 0.1143)
		(layer "F.Cu")
		(net "SYS_HB_LED")
	)
	(segment
		(start 122.028966 -41.402)
		(end 122.028966 -38.354)
		(width 0.1143)
		(layer "F.Cu")
		(net "SYS_HB_LED")
	)
	(segment
		(start 113.807748 -44.25696)
		(end 113.464848 -44.59986)
		(width 0.1143)
		(layer "F.Cu")
		(net "SYS_HB_LED")
	)
	(segment
		(start 117.475 -42.926)
		(end 117.475 -43.053)
		(width 0.1143)
		(layer "F.Cu")
		(net "SYS_HB_LED")
	)
	(segment
		(start 116.52885 -43.99915)
		(end 115.875816 -43.99915)
		(width 0.1143)
		(layer "F.Cu")
		(net "SYS_HB_LED")
	)
	(segment
		(start 117.475 -43.053)
		(end 116.52885 -43.99915)
		(width 0.1143)
		(layer "F.Cu")
		(net "SYS_HB_LED")
	)
	(segment
		(start 120.244616 -42.23385)
		(end 121.197116 -42.23385)
		(width 0.1143)
		(layer "F.Cu")
		(net "SYS_HB_LED")
	)
	(segment
		(start 117.475 -42.926)
		(end 119.552466 -42.926)
		(width 0.1143)
		(layer "F.Cu")
		(net "SYS_HB_LED")
	)
	(segment
		(start 115.875816 -43.99915)
		(end 115.618006 -44.25696)
		(width 0.1143)
		(layer "F.Cu")
		(net "SYS_HB_LED")
	)
	(segment
		(start 115.618006 -44.25696)
		(end 113.807748 -44.25696)
		(width 0.1143)
		(layer "F.Cu")
		(net "SYS_HB_LED")
	)
	(segment
		(start 113.464848 -44.59986)
		(end 113.150142 -44.59986)
		(width 0.1143)
		(layer "F.Cu")
		(net "SYS_HB_LED")
	)
	(via
		(at 122.028966 -36.6014)
		(size 0.7112)
		(drill 0.3556)
		(layers "F.Cu" "B.Cu")
		(net "SYS_HB_LED")
	)
	(via
		(at 122.282966 -38.1)
		(size 0.5588)
		(drill 0.3048)
		(layers "F.Cu" "B.Cu")
		(net "SYS_HB_LED")
	)
	(via
		(at 117.475 -42.926)
		(size 0.5588)
		(drill 0.3048)
		(layers "F.Cu" "B.Cu")
		(net "SYS_HB_LED")
	)
	(segment
		(start 123.324366 -36.957)
		(end 122.968766 -36.6014)
		(width 0.1143)
		(layer "B.Cu")
		(net "SYS_HB_LED")
	)
	(segment
		(start 122.968766 -36.6014)
		(end 122.028966 -36.6014)
		(width 0.1143)
		(layer "B.Cu")
		(net "SYS_HB_LED")
	)
	(segment
		(start 122.028966 -37.846)
		(end 122.282966 -38.1)
		(width 0.1143)
		(layer "B.Cu")
		(net "SYS_HB_LED")
	)
	(segment
		(start 122.028966 -36.6014)
		(end 122.028966 -37.846)
		(width 0.1143)
		(layer "B.Cu")
		(net "SYS_HB_LED")
	)
	(segment
		(start 118.4275 -42.926)
		(end 117.475 -42.926)
		(width 0.1143)
		(layer "B.Cu")
		(net "SYS_HB_LED")
	)
	(segment
		(start 93.550486 -45.009562)
		(end 93.550232 -45.009308)
		(width 0.1143)
		(layer "F.Cu")
		(net "IOC_SIO_BLINK")
	)
	(segment
		(start 93.950028 -45.39996)
		(end 93.580966 -45.030898)
		(width 0.1143)
		(layer "F.Cu")
		(net "IOC_SIO_BLINK")
	)
	(segment
		(start 93.572584 -45.030898)
		(end 93.551248 -45.009562)
		(width 0.1143)
		(layer "F.Cu")
		(net "IOC_SIO_BLINK")
	)
	(segment
		(start 93.580966 -45.030898)
		(end 93.572584 -45.030898)
		(width 0.1143)
		(layer "F.Cu")
		(net "IOC_SIO_BLINK")
	)
	(segment
		(start 93.551248 -45.009562)
		(end 93.550486 -45.009562)
		(width 0.1143)
		(layer "F.Cu")
		(net "IOC_SIO_BLINK")
	)
	(via
		(at 93.550232 -45.009308)
		(size 0.508)
		(drill 0.254)
		(layers "F.Cu" "B.Cu")
		(net "IOC_SIO_BLINK")
	)
	(segment
		(start 91.576652 -46.187868)
		(end 92.371672 -46.187868)
		(width 0.1143)
		(layer "B.Cu")
		(net "IOC_SIO_BLINK")
	)
	(segment
		(start 90.482166 -46.8122)
		(end 90.95232 -46.8122)
		(width 0.1143)
		(layer "B.Cu")
		(net "IOC_SIO_BLINK")
	)
	(segment
		(start 89.339166 -45.6692)
		(end 90.482166 -46.8122)
		(width 0.1143)
		(layer "B.Cu")
		(net "IOC_SIO_BLINK")
	)
	(segment
		(start 90.95232 -46.8122)
		(end 91.576652 -46.187868)
		(width 0.1143)
		(layer "B.Cu")
		(net "IOC_SIO_BLINK")
	)
	(segment
		(start 88.85682 -45.6692)
		(end 89.339166 -45.6692)
		(width 0.1143)
		(layer "B.Cu")
		(net "IOC_SIO_BLINK")
	)
	(segment
		(start 92.371672 -46.187868)
		(end 93.550232 -45.009308)
		(width 0.1143)
		(layer "B.Cu")
		(net "IOC_SIO_BLINK")
	)
	(segment
		(start 44.97197 -132.2705)
		(end 44.70273 -132.2705)
		(width 0.1143)
		(layer "F.Cu")
		(net "EXP_RST_R")
	)
	(segment
		(start 46.17847 -133.477)
		(end 44.97197 -132.2705)
		(width 0.1143)
		(layer "F.Cu")
		(net "EXP_RST_R")
	)
	(segment
		(start 45.09897 -134.62)
		(end 46.17847 -134.62)
		(width 0.1143)
		(layer "F.Cu")
		(net "EXP_RST_R")
	)
	(segment
		(start 46.17847 -134.62)
		(end 46.17847 -133.477)
		(width 0.1143)
		(layer "F.Cu")
		(net "EXP_RST_R")
	)
	(via
		(at 45.09897 -134.62)
		(size 0.7112)
		(drill 0.3556)
		(layers "F.Cu" "B.Cu")
		(net "EXP_RST_R")
	)
	(segment
		(start 109.50702 -78.12405)
		(end 110.194344 -78.12405)
		(width 0.1143)
		(layer "F.Cu")
		(net "EXP_TEST_MUX28")
	)
	(segment
		(start 109.13237 -77.7494)
		(end 109.50702 -78.12405)
		(width 0.1143)
		(layer "F.Cu")
		(net "EXP_TEST_MUX28")
	)
	(segment
		(start 109.05617 -77.7494)
		(end 109.13237 -77.7494)
		(width 0.1143)
		(layer "F.Cu")
		(net "EXP_TEST_MUX28")
	)
	(segment
		(start 110.51032 -79.14132)
		(end 112.08004 -80.71104)
		(width 0.1143)
		(layer "F.Cu")
		(net "EXP_TEST_MUX28")
	)
	(segment
		(start 112.382046 -80.71104)
		(end 113.349786 -81.67878)
		(width 0.1143)
		(layer "F.Cu")
		(net "EXP_TEST_MUX28")
	)
	(segment
		(start 110.194344 -78.12405)
		(end 110.51032 -78.440026)
		(width 0.1143)
		(layer "F.Cu")
		(net "EXP_TEST_MUX28")
	)
	(segment
		(start 112.08004 -80.71104)
		(end 112.382046 -80.71104)
		(width 0.1143)
		(layer "F.Cu")
		(net "EXP_TEST_MUX28")
	)
	(segment
		(start 110.51032 -78.440026)
		(end 110.51032 -79.14132)
		(width 0.1143)
		(layer "F.Cu")
		(net "EXP_TEST_MUX28")
	)
	(segment
		(start 113.349786 -81.67878)
		(end 113.349786 -82.349848)
		(width 0.1143)
		(layer "F.Cu")
		(net "EXP_TEST_MUX28")
	)
	(segment
		(start 46.36897 -139.319)
		(end 46.607222 -139.080748)
		(width 0.1143)
		(layer "F.Cu")
		(net "RESET_AND_N")
	)
	(segment
		(start 51.25847 -135.27024)
		(end 48.38573 -135.27024)
		(width 0.1143)
		(layer "F.Cu")
		(net "RESET_AND_N")
	)
	(segment
		(start 44.702222 -138.200384)
		(end 44.702222 -138.922252)
		(width 0.1143)
		(layer "F.Cu")
		(net "RESET_AND_N")
	)
	(segment
		(start 47.115222 -136.921748)
		(end 46.607222 -137.429748)
		(width 0.1143)
		(layer "F.Cu")
		(net "RESET_AND_N")
	)
	(segment
		(start 46.607222 -139.080748)
		(end 46.607222 -138.200384)
		(width 0.1143)
		(layer "F.Cu")
		(net "RESET_AND_N")
	)
	(segment
		(start 47.157386 -136.498584)
		(end 47.115222 -136.498584)
		(width 0.1143)
		(layer "F.Cu")
		(net "RESET_AND_N")
	)
	(segment
		(start 46.607222 -137.429748)
		(end 46.607222 -138.200384)
		(width 0.1143)
		(layer "F.Cu")
		(net "RESET_AND_N")
	)
	(segment
		(start 47.115222 -136.498584)
		(end 47.115222 -136.921748)
		(width 0.1143)
		(layer "F.Cu")
		(net "RESET_AND_N")
	)
	(segment
		(start 45.09897 -139.319)
		(end 46.36897 -139.319)
		(width 0.1143)
		(layer "F.Cu")
		(net "RESET_AND_N")
	)
	(segment
		(start 44.702222 -138.922252)
		(end 45.09897 -139.319)
		(width 0.1143)
		(layer "F.Cu")
		(net "RESET_AND_N")
	)
	(segment
		(start 48.38573 -135.27024)
		(end 47.99457 -135.6614)
		(width 0.1143)
		(layer "F.Cu")
		(net "RESET_AND_N")
	)
	(segment
		(start 47.99457 -135.6614)
		(end 47.157386 -136.498584)
		(width 0.1143)
		(layer "F.Cu")
		(net "RESET_AND_N")
	)
	(via
		(at 47.99457 -135.6614)
		(size 0.7112)
		(drill 0.3556)
		(layers "F.Cu" "B.Cu")
		(net "RESET_AND_N")
	)
	(segment
		(start 17.907 -165.481)
		(end 20.574 -162.814)
		(width 0.1143)
		(layer "F.Cu")
		(net "SAS_HDD_LED7")
	)
	(segment
		(start 17.186148 -170.107356)
		(end 17.186148 -166.201852)
		(width 0.1143)
		(layer "F.Cu")
		(net "SAS_HDD_LED7")
	)
	(segment
		(start 17.186148 -166.201852)
		(end 17.907 -165.481)
		(width 0.1143)
		(layer "F.Cu")
		(net "SAS_HDD_LED7")
	)
	(segment
		(start 32.81045 -147.47875)
		(end 34.671 -145.6182)
		(width 0.1143)
		(layer "F.Cu")
		(net "SAS_HDD_LED7")
	)
	(segment
		(start 109.349794 -86.34984)
		(end 108.849668 -85.849714)
		(width 0.1143)
		(layer "F.Cu")
		(net "SAS_HDD_LED7")
	)
	(segment
		(start 20.574 -162.814)
		(end 20.574 -161.684208)
		(width 0.1143)
		(layer "F.Cu")
		(net "SAS_HDD_LED7")
	)
	(segment
		(start 32.81045 -149.447758)
		(end 32.81045 -147.47875)
		(width 0.1143)
		(layer "F.Cu")
		(net "SAS_HDD_LED7")
	)
	(segment
		(start 20.574 -161.684208)
		(end 32.81045 -149.447758)
		(width 0.1143)
		(layer "F.Cu")
		(net "SAS_HDD_LED7")
	)
	(via
		(at 34.671 -145.6182)
		(size 0.5588)
		(drill 0.3048)
		(layers "F.Cu" "B.Cu")
		(net "SAS_HDD_LED7")
	)
	(via
		(at 17.907 -165.481)
		(size 0.7112)
		(drill 0.3556)
		(layers "F.Cu" "B.Cu")
		(net "SAS_HDD_LED7")
	)
	(via
		(at 108.849668 -85.849714)
		(size 0.508)
		(drill 0.254)
		(layers "F.Cu" "B.Cu")
		(net "SAS_HDD_LED7")
	)
	(segment
		(start 108.430568 -84.67598)
		(end 108.430568 -85.267038)
		(width 0.127)
		(layer "In5.Cu")
		(net "SAS_HDD_LED7")
	)
	(segment
		(start 34.671 -145.6182)
		(end 34.9631 -145.9103)
		(width 0.127)
		(layer "In5.Cu")
		(net "SAS_HDD_LED7")
	)
	(segment
		(start 107.696254 -78.201266)
		(end 107.696254 -78.380844)
		(width 0.127)
		(layer "In5.Cu")
		(net "SAS_HDD_LED7")
	)
	(segment
		(start 36.781232 -145.9103)
		(end 40.98417 -141.707362)
		(width 0.127)
		(layer "In5.Cu")
		(net "SAS_HDD_LED7")
	)
	(segment
		(start 44.577 -137.033)
		(end 44.577 -132.842)
		(width 0.127)
		(layer "In5.Cu")
		(net "SAS_HDD_LED7")
	)
	(segment
		(start 110.152942 -80.310736)
		(end 110.152942 -80.689196)
		(width 0.127)
		(layer "In5.Cu")
		(net "SAS_HDD_LED7")
	)
	(segment
		(start 109.294168 -83.998054)
		(end 108.998004 -84.294218)
		(width 0.127)
		(layer "In5.Cu")
		(net "SAS_HDD_LED7")
	)
	(segment
		(start 108.430568 -85.267038)
		(end 108.849668 -85.686138)
		(width 0.127)
		(layer "In5.Cu")
		(net "SAS_HDD_LED7")
	)
	(segment
		(start 110.768892 -81.305146)
		(end 110.768892 -82.390996)
		(width 0.127)
		(layer "In5.Cu")
		(net "SAS_HDD_LED7")
	)
	(segment
		(start 107.155488 -77.6605)
		(end 107.696254 -78.201266)
		(width 0.127)
		(layer "In5.Cu")
		(net "SAS_HDD_LED7")
	)
	(segment
		(start 47.117 -130.302)
		(end 47.117 -130.049524)
		(width 0.127)
		(layer "In5.Cu")
		(net "SAS_HDD_LED7")
	)
	(segment
		(start 108.998004 -84.294218)
		(end 108.81233 -84.294218)
		(width 0.127)
		(layer "In5.Cu")
		(net "SAS_HDD_LED7")
	)
	(segment
		(start 34.9631 -145.9103)
		(end 36.781232 -145.9103)
		(width 0.127)
		(layer "In5.Cu")
		(net "SAS_HDD_LED7")
	)
	(segment
		(start 108.81233 -84.294218)
		(end 108.430568 -84.67598)
		(width 0.127)
		(layer "In5.Cu")
		(net "SAS_HDD_LED7")
	)
	(segment
		(start 109.598206 -79.756)
		(end 110.152942 -80.310736)
		(width 0.127)
		(layer "In5.Cu")
		(net "SAS_HDD_LED7")
	)
	(segment
		(start 108.849668 -85.686138)
		(end 108.849668 -85.849714)
		(width 0.127)
		(layer "In5.Cu")
		(net "SAS_HDD_LED7")
	)
	(segment
		(start 99.506024 -77.6605)
		(end 107.155488 -77.6605)
		(width 0.127)
		(layer "In5.Cu")
		(net "SAS_HDD_LED7")
	)
	(segment
		(start 109.294168 -83.86572)
		(end 109.294168 -83.998054)
		(width 0.127)
		(layer "In5.Cu")
		(net "SAS_HDD_LED7")
	)
	(segment
		(start 47.117 -130.049524)
		(end 99.506024 -77.6605)
		(width 0.127)
		(layer "In5.Cu")
		(net "SAS_HDD_LED7")
	)
	(segment
		(start 110.768892 -82.390996)
		(end 109.294168 -83.86572)
		(width 0.127)
		(layer "In5.Cu")
		(net "SAS_HDD_LED7")
	)
	(segment
		(start 107.696254 -78.380844)
		(end 109.07141 -79.756)
		(width 0.127)
		(layer "In5.Cu")
		(net "SAS_HDD_LED7")
	)
	(segment
		(start 109.07141 -79.756)
		(end 109.598206 -79.756)
		(width 0.127)
		(layer "In5.Cu")
		(net "SAS_HDD_LED7")
	)
	(segment
		(start 110.152942 -80.689196)
		(end 110.768892 -81.305146)
		(width 0.127)
		(layer "In5.Cu")
		(net "SAS_HDD_LED7")
	)
	(segment
		(start 40.98417 -141.707362)
		(end 40.98417 -140.62583)
		(width 0.127)
		(layer "In5.Cu")
		(net "SAS_HDD_LED7")
	)
	(segment
		(start 44.577 -132.842)
		(end 47.117 -130.302)
		(width 0.127)
		(layer "In5.Cu")
		(net "SAS_HDD_LED7")
	)
	(segment
		(start 40.98417 -140.62583)
		(end 44.577 -137.033)
		(width 0.127)
		(layer "In5.Cu")
		(net "SAS_HDD_LED7")
	)
	(segment
		(start 94.972378 -54.737)
		(end 95.287084 -54.737)
		(width 0.1143)
		(layer "F.Cu")
		(net "ICE0_TMS")
	)
	(segment
		(start 94.14891 -55.45709)
		(end 94.413578 -55.192168)
		(width 0.1143)
		(layer "F.Cu")
		(net "ICE0_TMS")
	)
	(segment
		(start 94.898718 -54.66334)
		(end 94.972378 -54.737)
		(width 0.1143)
		(layer "F.Cu")
		(net "ICE0_TMS")
	)
	(segment
		(start 93.607128 -57.250838)
		(end 93.607128 -55.666894)
		(width 0.1143)
		(layer "F.Cu")
		(net "ICE0_TMS")
	)
	(segment
		(start 89.643966 -61.468)
		(end 89.643966 -59.835034)
		(width 0.1143)
		(layer "F.Cu")
		(net "ICE0_TMS")
	)
	(segment
		(start 94.413578 -54.860444)
		(end 94.610682 -54.66334)
		(width 0.1143)
		(layer "F.Cu")
		(net "ICE0_TMS")
	)
	(segment
		(start 94.610682 -54.66334)
		(end 94.898718 -54.66334)
		(width 0.1143)
		(layer "F.Cu")
		(net "ICE0_TMS")
	)
	(segment
		(start 93.816932 -55.45709)
		(end 94.14891 -55.45709)
		(width 0.1143)
		(layer "F.Cu")
		(net "ICE0_TMS")
	)
	(segment
		(start 91.186 -58.293)
		(end 92.564966 -58.293)
		(width 0.1143)
		(layer "F.Cu")
		(net "ICE0_TMS")
	)
	(segment
		(start 92.564966 -58.293)
		(end 93.607128 -57.250838)
		(width 0.1143)
		(layer "F.Cu")
		(net "ICE0_TMS")
	)
	(segment
		(start 89.643966 -59.835034)
		(end 91.186 -58.293)
		(width 0.1143)
		(layer "F.Cu")
		(net "ICE0_TMS")
	)
	(segment
		(start 94.413578 -55.192168)
		(end 94.413578 -54.860444)
		(width 0.1143)
		(layer "F.Cu")
		(net "ICE0_TMS")
	)
	(segment
		(start 95.287084 -54.737)
		(end 95.549974 -54.99989)
		(width 0.1143)
		(layer "F.Cu")
		(net "ICE0_TMS")
	)
	(segment
		(start 93.607128 -55.666894)
		(end 93.816932 -55.45709)
		(width 0.1143)
		(layer "F.Cu")
		(net "ICE0_TMS")
	)
	(segment
		(start 89.643966 -62.6745)
		(end 89.643966 -61.468)
		(width 0.1143)
		(layer "F.Cu")
		(net "ICE0_TMS")
	)
	(segment
		(start 99.568 -80.483202)
		(end 99.568 -80.55356)
		(width 0.1143)
		(layer "F.Cu")
		(net "SXP_ACTIVE_0")
	)
	(segment
		(start 99.32797 -76.8985)
		(end 98.56597 -77.6605)
		(width 0.1143)
		(layer "F.Cu")
		(net "SXP_ACTIVE_0")
	)
	(segment
		(start 98.56597 -77.6605)
		(end 98.56597 -78.105)
		(width 0.1143)
		(layer "F.Cu")
		(net "SXP_ACTIVE_0")
	)
	(segment
		(start 108.349796 -86.34984)
		(end 107.84967 -85.849714)
		(width 0.1143)
		(layer "F.Cu")
		(net "SXP_ACTIVE_0")
	)
	(segment
		(start 98.56597 -78.9686)
		(end 99.441 -79.84363)
		(width 0.1143)
		(layer "F.Cu")
		(net "SXP_ACTIVE_0")
	)
	(segment
		(start 99.568 -80.55356)
		(end 99.717606 -80.703166)
		(width 0.1143)
		(layer "F.Cu")
		(net "SXP_ACTIVE_0")
	)
	(segment
		(start 98.56597 -78.105)
		(end 98.56597 -78.9686)
		(width 0.1143)
		(layer "F.Cu")
		(net "SXP_ACTIVE_0")
	)
	(segment
		(start 99.441 -80.356202)
		(end 99.568 -80.483202)
		(width 0.1143)
		(layer "F.Cu")
		(net "SXP_ACTIVE_0")
	)
	(segment
		(start 99.441 -79.84363)
		(end 99.441 -80.356202)
		(width 0.1143)
		(layer "F.Cu")
		(net "SXP_ACTIVE_0")
	)
	(via
		(at 107.84967 -85.849714)
		(size 0.508)
		(drill 0.254)
		(layers "F.Cu" "B.Cu")
		(net "SXP_ACTIVE_0")
	)
	(via
		(at 99.717606 -80.703166)
		(size 0.508)
		(drill 0.254)
		(layers "F.Cu" "B.Cu")
		(net "SXP_ACTIVE_0")
	)
	(segment
		(start 99.856798 -80.772)
		(end 100.186998 -81.1022)
		(width 0.127)
		(layer "In2.Cu")
		(net "SXP_ACTIVE_0")
	)
	(segment
		(start 107.294172 -85.182202)
		(end 107.84967 -85.7377)
		(width 0.127)
		(layer "In2.Cu")
		(net "SXP_ACTIVE_0")
	)
	(segment
		(start 102.49662 -80.899)
		(end 104.111806 -80.899)
		(width 0.127)
		(layer "In2.Cu")
		(net "SXP_ACTIVE_0")
	)
	(segment
		(start 99.78644 -80.772)
		(end 99.856798 -80.772)
		(width 0.127)
		(layer "In2.Cu")
		(net "SXP_ACTIVE_0")
	)
	(segment
		(start 106.998008 -84.405216)
		(end 107.294172 -84.70138)
		(width 0.127)
		(layer "In2.Cu")
		(net "SXP_ACTIVE_0")
	)
	(segment
		(start 106.812334 -84.405216)
		(end 106.998008 -84.405216)
		(width 0.127)
		(layer "In2.Cu")
		(net "SXP_ACTIVE_0")
	)
	(segment
		(start 107.84967 -85.7377)
		(end 107.84967 -85.849714)
		(width 0.127)
		(layer "In2.Cu")
		(net "SXP_ACTIVE_0")
	)
	(segment
		(start 100.186998 -81.1022)
		(end 100.53066 -81.1022)
		(width 0.127)
		(layer "In2.Cu")
		(net "SXP_ACTIVE_0")
	)
	(segment
		(start 100.64496 -81.2165)
		(end 102.17912 -81.2165)
		(width 0.127)
		(layer "In2.Cu")
		(net "SXP_ACTIVE_0")
	)
	(segment
		(start 107.294172 -84.70138)
		(end 107.294172 -85.182202)
		(width 0.127)
		(layer "In2.Cu")
		(net "SXP_ACTIVE_0")
	)
	(segment
		(start 106.294174 -83.081368)
		(end 106.294174 -83.887056)
		(width 0.127)
		(layer "In2.Cu")
		(net "SXP_ACTIVE_0")
	)
	(segment
		(start 106.294174 -83.887056)
		(end 106.812334 -84.405216)
		(width 0.127)
		(layer "In2.Cu")
		(net "SXP_ACTIVE_0")
	)
	(segment
		(start 100.53066 -81.1022)
		(end 100.64496 -81.2165)
		(width 0.127)
		(layer "In2.Cu")
		(net "SXP_ACTIVE_0")
	)
	(segment
		(start 99.717606 -80.703166)
		(end 99.78644 -80.772)
		(width 0.127)
		(layer "In2.Cu")
		(net "SXP_ACTIVE_0")
	)
	(segment
		(start 102.17912 -81.2165)
		(end 102.49662 -80.899)
		(width 0.127)
		(layer "In2.Cu")
		(net "SXP_ACTIVE_0")
	)
	(segment
		(start 104.111806 -80.899)
		(end 106.294174 -83.081368)
		(width 0.127)
		(layer "In2.Cu")
		(net "SXP_ACTIVE_0")
	)
	(segment
		(start 199.517 -147.193)
		(end 199.198992 -146.874992)
		(width 0.1143)
		(layer "F.Cu")
		(net "EXP_I2C_VREF_2")
	)
	(segment
		(start 199.263 -148.209)
		(end 199.898 -148.209)
		(width 0.1143)
		(layer "F.Cu")
		(net "EXP_I2C_VREF_2")
	)
	(segment
		(start 201.247248 -148.209)
		(end 201.255376 -148.200872)
		(width 0.1143)
		(layer "F.Cu")
		(net "EXP_I2C_VREF_2")
	)
	(segment
		(start 201.247248 -147.193)
		(end 199.517 -147.193)
		(width 0.1143)
		(layer "F.Cu")
		(net "EXP_I2C_VREF_2")
	)
	(segment
		(start 199.198992 -146.874992)
		(end 197.737476 -146.874992)
		(width 0.1143)
		(layer "F.Cu")
		(net "EXP_I2C_VREF_2")
	)
	(segment
		(start 197.737476 -147.525232)
		(end 198.579232 -147.525232)
		(width 0.1143)
		(layer "F.Cu")
		(net "EXP_I2C_VREF_2")
	)
	(segment
		(start 201.255376 -147.184872)
		(end 201.247248 -147.193)
		(width 0.1143)
		(layer "F.Cu")
		(net "EXP_I2C_VREF_2")
	)
	(segment
		(start 198.579232 -147.525232)
		(end 199.263 -148.209)
		(width 0.1143)
		(layer "F.Cu")
		(net "EXP_I2C_VREF_2")
	)
	(segment
		(start 201.255376 -148.200872)
		(end 201.255376 -147.184872)
		(width 0.1143)
		(layer "F.Cu")
		(net "EXP_I2C_VREF_2")
	)
	(segment
		(start 199.898 -148.209)
		(end 201.247248 -148.209)
		(width 0.1143)
		(layer "F.Cu")
		(net "EXP_I2C_VREF_2")
	)
	(via
		(at 199.898 -148.209)
		(size 0.7112)
		(drill 0.3556)
		(layers "F.Cu" "B.Cu")
		(net "EXP_I2C_VREF_2")
	)
	(segment
		(start 95.358966 -62.6745)
		(end 95.358966 -60.325)
		(width 0.1143)
		(layer "F.Cu")
		(net "ICE0_TRST#")
	)
	(segment
		(start 96.350074 -57.531)
		(end 96.350074 -56.599836)
		(width 0.1143)
		(layer "F.Cu")
		(net "ICE0_TRST#")
	)
	(segment
		(start 95.358966 -58.522108)
		(end 96.350074 -57.531)
		(width 0.1143)
		(layer "F.Cu")
		(net "ICE0_TRST#")
	)
	(segment
		(start 95.358966 -60.325)
		(end 95.358966 -58.522108)
		(width 0.1143)
		(layer "F.Cu")
		(net "ICE0_TRST#")
	)
	(segment
		(start 40.52697 -135.1915)
		(end 40.52697 -136.2075)
		(width 0.127)
		(layer "F.Cu")
		(net "P3V3_STBY_R5")
	)
	(segment
		(start 39.95547 -134.62)
		(end 40.52697 -135.1915)
		(width 0.127)
		(layer "F.Cu")
		(net "P3V3_STBY_R5")
	)
	(segment
		(start 41.09847 -134.62)
		(end 39.95547 -134.62)
		(width 0.127)
		(layer "F.Cu")
		(net "P3V3_STBY_R5")
	)
	(segment
		(start 41.09847 -134.62)
		(end 41.09847 -133.5405)
		(width 0.127)
		(layer "F.Cu")
		(net "P3V3_STBY_R5")
	)
	(via
		(at 41.09847 -133.5405)
		(size 0.7112)
		(drill 0.3556)
		(layers "F.Cu" "B.Cu")
		(net "P3V3_STBY_R5")
	)
	(segment
		(start 89.66581 -133.10616)
		(end 89.43213 -133.10616)
		(width 0.1143)
		(layer "F.Cu")
		(net "EXP_GPIO_5")
	)
	(segment
		(start 90.31097 -133.096)
		(end 89.67597 -133.096)
		(width 0.1143)
		(layer "F.Cu")
		(net "EXP_GPIO_5")
	)
	(segment
		(start 90.724482 -131.570476)
		(end 90.724482 -132.682488)
		(width 0.1143)
		(layer "F.Cu")
		(net "EXP_GPIO_5")
	)
	(segment
		(start 89.67597 -133.096)
		(end 89.66581 -133.10616)
		(width 0.1143)
		(layer "F.Cu")
		(net "EXP_GPIO_5")
	)
	(segment
		(start 90.724482 -132.682488)
		(end 90.31097 -133.096)
		(width 0.1143)
		(layer "F.Cu")
		(net "EXP_GPIO_5")
	)
	(segment
		(start 103.349806 -100.350066)
		(end 102.84968 -100.850192)
		(width 0.1143)
		(layer "F.Cu")
		(net "EXP_GPIO_5")
	)
	(via
		(at 102.84968 -100.850192)
		(size 0.508)
		(drill 0.254)
		(layers "F.Cu" "B.Cu")
		(net "EXP_GPIO_5")
	)
	(via
		(at 91.40317 -111.8616)
		(size 0.7112)
		(drill 0.3556)
		(layers "F.Cu" "B.Cu")
		(net "EXP_GPIO_5")
	)
	(via
		(at 89.43213 -133.10616)
		(size 0.5588)
		(drill 0.3048)
		(layers "F.Cu" "B.Cu")
		(net "EXP_GPIO_5")
	)
	(segment
		(start 101.411532 -100.750116)
		(end 101.411532 -100.704396)
		(width 0.1143)
		(layer "B.Cu")
		(net "EXP_GPIO_5")
	)
	(segment
		(start 100.446332 -102.268274)
		(end 100.755196 -101.95941)
		(width 0.1143)
		(layer "B.Cu")
		(net "EXP_GPIO_5")
	)
	(segment
		(start 100.446332 -102.41534)
		(end 100.446332 -102.268274)
		(width 0.1143)
		(layer "B.Cu")
		(net "EXP_GPIO_5")
	)
	(segment
		(start 102.229412 -100.437442)
		(end 102.642162 -100.850192)
		(width 0.1143)
		(layer "B.Cu")
		(net "EXP_GPIO_5")
	)
	(segment
		(start 92.496894 -110.364778)
		(end 100.446332 -102.41534)
		(width 0.1143)
		(layer "B.Cu")
		(net "EXP_GPIO_5")
	)
	(segment
		(start 89.43213 -121.423176)
		(end 89.71026 -121.145046)
		(width 0.1143)
		(layer "B.Cu")
		(net "EXP_GPIO_5")
	)
	(segment
		(start 89.71026 -121.145046)
		(end 89.71026 -113.55451)
		(width 0.1143)
		(layer "B.Cu")
		(net "EXP_GPIO_5")
	)
	(segment
		(start 89.71026 -113.55451)
		(end 91.40317 -111.8616)
		(width 0.1143)
		(layer "B.Cu")
		(net "EXP_GPIO_5")
	)
	(segment
		(start 92.496894 -110.767876)
		(end 92.496894 -110.364778)
		(width 0.1143)
		(layer "B.Cu")
		(net "EXP_GPIO_5")
	)
	(segment
		(start 101.678486 -100.437442)
		(end 102.229412 -100.437442)
		(width 0.1143)
		(layer "B.Cu")
		(net "EXP_GPIO_5")
	)
	(segment
		(start 100.755196 -101.95941)
		(end 100.755196 -101.406452)
		(width 0.1143)
		(layer "B.Cu")
		(net "EXP_GPIO_5")
	)
	(segment
		(start 89.43213 -133.10616)
		(end 89.43213 -121.423176)
		(width 0.1143)
		(layer "B.Cu")
		(net "EXP_GPIO_5")
	)
	(segment
		(start 101.411532 -100.704396)
		(end 101.678486 -100.437442)
		(width 0.1143)
		(layer "B.Cu")
		(net "EXP_GPIO_5")
	)
	(segment
		(start 91.40317 -111.8616)
		(end 92.496894 -110.767876)
		(width 0.1143)
		(layer "B.Cu")
		(net "EXP_GPIO_5")
	)
	(segment
		(start 100.755196 -101.406452)
		(end 101.411532 -100.750116)
		(width 0.1143)
		(layer "B.Cu")
		(net "EXP_GPIO_5")
	)
	(segment
		(start 102.642162 -100.850192)
		(end 102.84968 -100.850192)
		(width 0.1143)
		(layer "B.Cu")
		(net "EXP_GPIO_5")
	)
	(segment
		(start 82.277712 -115.410742)
		(end 82.606896 -115.739926)
		(width 0.1143)
		(layer "F.Cu")
		(net "EXP_I2C_VREF_1")
	)
	(segment
		(start 83.072732 -116.205762)
		(end 82.606896 -115.739926)
		(width 0.1143)
		(layer "F.Cu")
		(net "EXP_I2C_VREF_1")
	)
	(segment
		(start 81.468722 -115.410742)
		(end 82.277712 -115.410742)
		(width 0.1143)
		(layer "F.Cu")
		(net "EXP_I2C_VREF_1")
	)
	(segment
		(start 81.468722 -115.410742)
		(end 81.468722 -114.394742)
		(width 0.1143)
		(layer "F.Cu")
		(net "EXP_I2C_VREF_1")
	)
	(segment
		(start 84.232242 -116.205762)
		(end 83.072732 -116.205762)
		(width 0.1143)
		(layer "F.Cu")
		(net "EXP_I2C_VREF_1")
	)
	(segment
		(start 83.071462 -114.394742)
		(end 84.232242 -115.555522)
		(width 0.1143)
		(layer "F.Cu")
		(net "EXP_I2C_VREF_1")
	)
	(segment
		(start 81.468722 -114.394742)
		(end 83.071462 -114.394742)
		(width 0.1143)
		(layer "F.Cu")
		(net "EXP_I2C_VREF_1")
	)
	(via
		(at 82.606896 -115.739926)
		(size 0.7112)
		(drill 0.3556)
		(layers "F.Cu" "B.Cu")
		(net "EXP_I2C_VREF_1")
	)
	(segment
		(start 98.167698 -99.28225)
		(end 98.904298 -100.01885)
		(width 0.1143)
		(layer "F.Cu")
		(net "EXP_PWM_OUT1")
	)
	(segment
		(start 98.904298 -100.01885)
		(end 99.3902 -100.01885)
		(width 0.1143)
		(layer "F.Cu")
		(net "EXP_PWM_OUT1")
	)
	(segment
		(start 95.91675 -99.28225)
		(end 98.167698 -99.28225)
		(width 0.1143)
		(layer "F.Cu")
		(net "EXP_PWM_OUT1")
	)
	(segment
		(start 95.504 -99.695)
		(end 95.91675 -99.28225)
		(width 0.1143)
		(layer "F.Cu")
		(net "EXP_PWM_OUT1")
	)
	(segment
		(start 99.58705 -99.822)
		(end 100.174044 -99.822)
		(width 0.1143)
		(layer "F.Cu")
		(net "EXP_PWM_OUT1")
	)
	(segment
		(start 101.170232 -98.529648)
		(end 102.349808 -97.350072)
		(width 0.1143)
		(layer "F.Cu")
		(net "EXP_PWM_OUT1")
	)
	(segment
		(start 101.170232 -98.825812)
		(end 101.170232 -98.529648)
		(width 0.1143)
		(layer "F.Cu")
		(net "EXP_PWM_OUT1")
	)
	(segment
		(start 99.3902 -100.01885)
		(end 99.58705 -99.822)
		(width 0.1143)
		(layer "F.Cu")
		(net "EXP_PWM_OUT1")
	)
	(segment
		(start 94.996 -99.695)
		(end 95.504 -99.695)
		(width 0.1143)
		(layer "F.Cu")
		(net "EXP_PWM_OUT1")
	)
	(segment
		(start 100.174044 -99.822)
		(end 101.170232 -98.825812)
		(width 0.1143)
		(layer "F.Cu")
		(net "EXP_PWM_OUT1")
	)
	(segment
		(start 90.239342 -123.642882)
		(end 89.690702 -123.094242)
		(width 0.1143)
		(layer "F.Cu")
		(net "EXP_I2C_VREF_0")
	)
	(segment
		(start 90.239342 -122.626882)
		(end 90.239342 -123.642882)
		(width 0.1143)
		(layer "F.Cu")
		(net "EXP_I2C_VREF_0")
	)
	(segment
		(start 90.239342 -122.626882)
		(end 90.056462 -122.444002)
		(width 0.1143)
		(layer "F.Cu")
		(net "EXP_I2C_VREF_0")
	)
	(segment
		(start 87.356442 -123.094242)
		(end 88.91397 -123.094242)
		(width 0.1143)
		(layer "F.Cu")
		(net "EXP_I2C_VREF_0")
	)
	(segment
		(start 90.056462 -122.444002)
		(end 87.356442 -122.444002)
		(width 0.1143)
		(layer "F.Cu")
		(net "EXP_I2C_VREF_0")
	)
	(segment
		(start 89.690702 -123.094242)
		(end 88.91397 -123.094242)
		(width 0.1143)
		(layer "F.Cu")
		(net "EXP_I2C_VREF_0")
	)
	(via
		(at 88.91397 -123.094242)
		(size 0.7112)
		(drill 0.3556)
		(layers "F.Cu" "B.Cu")
		(net "EXP_I2C_VREF_0")
	)
	(via
		(at 133.731 -36.83)
		(size 0.7112)
		(drill 0.3556)
		(layers "F.Cu" "B.Cu")
		(net "PMU_PLTRST_R_N")
	)
	(segment
		(start 134.239 -37.719)
		(end 133.731 -37.211)
		(width 0.1143)
		(layer "B.Cu")
		(net "PMU_PLTRST_R_N")
	)
	(segment
		(start 133.731 -36.703)
		(end 133.731 -36.83)
		(width 0.1143)
		(layer "B.Cu")
		(net "PMU_PLTRST_R_N")
	)
	(segment
		(start 133.731 -37.211)
		(end 133.731 -36.83)
		(width 0.1143)
		(layer "B.Cu")
		(net "PMU_PLTRST_R_N")
	)
	(segment
		(start 134.3025 -36.1315)
		(end 133.731 -36.703)
		(width 0.1143)
		(layer "B.Cu")
		(net "PMU_PLTRST_R_N")
	)
	(segment
		(start 134.9375 -37.719)
		(end 134.239 -37.719)
		(width 0.1143)
		(layer "B.Cu")
		(net "PMU_PLTRST_R_N")
	)
	(segment
		(start 134.90575 -36.1315)
		(end 134.3025 -36.1315)
		(width 0.1143)
		(layer "B.Cu")
		(net "PMU_PLTRST_R_N")
	)
	(segment
		(start 114.184684 -82.184748)
		(end 114.349784 -82.349848)
		(width 0.1143)
		(layer "F.Cu")
		(net "EXP_TEST_MUX29")
	)
	(segment
		(start 113.88598 -80.394302)
		(end 114.184684 -80.693006)
		(width 0.1143)
		(layer "F.Cu")
		(net "EXP_TEST_MUX29")
	)
	(segment
		(start 114.184684 -80.693006)
		(end 114.184684 -82.184748)
		(width 0.1143)
		(layer "F.Cu")
		(net "EXP_TEST_MUX29")
	)
	(segment
		(start 112.72266 -79.91729)
		(end 113.443512 -79.91729)
		(width 0.1143)
		(layer "F.Cu")
		(net "EXP_TEST_MUX29")
	)
	(segment
		(start 111.51997 -78.7146)
		(end 112.72266 -79.91729)
		(width 0.1143)
		(layer "F.Cu")
		(net "EXP_TEST_MUX29")
	)
	(segment
		(start 113.88598 -80.359758)
		(end 113.88598 -80.394302)
		(width 0.1143)
		(layer "F.Cu")
		(net "EXP_TEST_MUX29")
	)
	(segment
		(start 113.443512 -79.91729)
		(end 113.88598 -80.359758)
		(width 0.1143)
		(layer "F.Cu")
		(net "EXP_TEST_MUX29")
	)
	(segment
		(start 162.527996 -146.745452)
		(end 161.483548 -146.745452)
		(width 0.1143)
		(layer "F.Cu")
		(net "IOC_I2C_VREF")
	)
	(segment
		(start 161.29 -146.939)
		(end 161.29 -147.268692)
		(width 0.1143)
		(layer "F.Cu")
		(net "IOC_I2C_VREF")
	)
	(segment
		(start 160.4645 -145.0975)
		(end 160.528 -145.034)
		(width 0.1143)
		(layer "F.Cu")
		(net "IOC_I2C_VREF")
	)
	(segment
		(start 160.4645 -146.05)
		(end 160.4645 -145.0975)
		(width 0.1143)
		(layer "F.Cu")
		(net "IOC_I2C_VREF")
	)
	(segment
		(start 161.29 -147.268692)
		(end 161.417 -147.395692)
		(width 0.1143)
		(layer "F.Cu")
		(net "IOC_I2C_VREF")
	)
	(segment
		(start 160.4645 -147.066)
		(end 160.794192 -147.395692)
		(width 0.1143)
		(layer "F.Cu")
		(net "IOC_I2C_VREF")
	)
	(segment
		(start 161.483548 -146.745452)
		(end 161.29 -146.939)
		(width 0.1143)
		(layer "F.Cu")
		(net "IOC_I2C_VREF")
	)
	(segment
		(start 160.4645 -147.066)
		(end 160.4645 -146.05)
		(width 0.1143)
		(layer "F.Cu")
		(net "IOC_I2C_VREF")
	)
	(segment
		(start 160.794192 -147.395692)
		(end 161.417 -147.395692)
		(width 0.1143)
		(layer "F.Cu")
		(net "IOC_I2C_VREF")
	)
	(segment
		(start 162.527996 -147.395692)
		(end 161.417 -147.395692)
		(width 0.1143)
		(layer "F.Cu")
		(net "IOC_I2C_VREF")
	)
	(via
		(at 160.528 -145.034)
		(size 0.7112)
		(drill 0.3556)
		(layers "F.Cu" "B.Cu")
		(net "IOC_I2C_VREF")
	)
	(via
		(at 132.874766 -33.6804)
		(size 0.7112)
		(drill 0.3556)
		(layers "F.Cu" "B.Cu")
		(net "P3V3_STBY_B")
	)
	(segment
		(start 131.490466 -32.86125)
		(end 132.309616 -33.6804)
		(width 0.127)
		(layer "B.Cu")
		(net "P3V3_STBY_B")
	)
	(segment
		(start 133.141466 -32.766)
		(end 133.141466 -33.4137)
		(width 0.127)
		(layer "B.Cu")
		(net "P3V3_STBY_B")
	)
	(segment
		(start 133.141466 -33.4137)
		(end 132.874766 -33.6804)
		(width 0.127)
		(layer "B.Cu")
		(net "P3V3_STBY_B")
	)
	(segment
		(start 132.309616 -33.6804)
		(end 132.874766 -33.6804)
		(width 0.127)
		(layer "B.Cu")
		(net "P3V3_STBY_B")
	)
	(segment
		(start 105.938574 -61.76645)
		(end 105.70845 -61.76645)
		(width 0.1143)
		(layer "F.Cu")
		(net "LSI_SCAN_EN")
	)
	(segment
		(start 108.624116 -63.69812)
		(end 108.624116 -63.031116)
		(width 0.1143)
		(layer "F.Cu")
		(net "LSI_SCAN_EN")
	)
	(segment
		(start 108.624116 -63.031116)
		(end 107.95 -62.357)
		(width 0.1143)
		(layer "F.Cu")
		(net "LSI_SCAN_EN")
	)
	(segment
		(start 108.022136 -64.3001)
		(end 108.624116 -63.69812)
		(width 0.1143)
		(layer "F.Cu")
		(net "LSI_SCAN_EN")
	)
	(segment
		(start 103.213408 -56.280558)
		(end 103.549958 -55.944008)
		(width 0.1143)
		(layer "F.Cu")
		(net "LSI_SCAN_EN")
	)
	(segment
		(start 107.95 -62.357)
		(end 107.48645 -61.89345)
		(width 0.1143)
		(layer "F.Cu")
		(net "LSI_SCAN_EN")
	)
	(segment
		(start 103.549958 -55.944008)
		(end 103.549958 -55.79999)
		(width 0.1143)
		(layer "F.Cu")
		(net "LSI_SCAN_EN")
	)
	(segment
		(start 105.70845 -61.76645)
		(end 103.213408 -59.271408)
		(width 0.1143)
		(layer "F.Cu")
		(net "LSI_SCAN_EN")
	)
	(segment
		(start 106.065574 -61.89345)
		(end 105.938574 -61.76645)
		(width 0.1143)
		(layer "F.Cu")
		(net "LSI_SCAN_EN")
	)
	(segment
		(start 103.213408 -59.271408)
		(end 103.213408 -56.280558)
		(width 0.1143)
		(layer "F.Cu")
		(net "LSI_SCAN_EN")
	)
	(segment
		(start 107.48645 -61.89345)
		(end 106.065574 -61.89345)
		(width 0.1143)
		(layer "F.Cu")
		(net "LSI_SCAN_EN")
	)
	(segment
		(start 107.931966 -65.4431)
		(end 107.931966 -64.3001)
		(width 0.1143)
		(layer "F.Cu")
		(net "LSI_SCAN_EN")
	)
	(segment
		(start 107.931966 -64.3001)
		(end 108.022136 -64.3001)
		(width 0.1143)
		(layer "F.Cu")
		(net "LSI_SCAN_EN")
	)
	(via
		(at 107.95 -62.357)
		(size 0.7112)
		(drill 0.3556)
		(layers "F.Cu" "B.Cu")
		(net "LSI_SCAN_EN")
	)
	(segment
		(start 33.17875 -147.993608)
		(end 34.639758 -146.5326)
		(width 0.1143)
		(layer "F.Cu")
		(net "SAS_HDD_LED8")
	)
	(segment
		(start 34.639758 -146.5326)
		(end 34.671 -146.5326)
		(width 0.1143)
		(layer "F.Cu")
		(net "SAS_HDD_LED8")
	)
	(segment
		(start 17.584928 -170.107356)
		(end 17.584928 -166.65448)
		(width 0.1143)
		(layer "F.Cu")
		(net "SAS_HDD_LED8")
	)
	(segment
		(start 20.555204 -163.684204)
		(end 20.955 -163.284408)
		(width 0.1143)
		(layer "F.Cu")
		(net "SAS_HDD_LED8")
	)
	(segment
		(start 109.349794 -87.349838)
		(end 108.849668 -86.849712)
		(width 0.1143)
		(layer "F.Cu")
		(net "SAS_HDD_LED8")
	)
	(segment
		(start 20.955 -163.284408)
		(end 20.955 -161.824162)
		(width 0.1143)
		(layer "F.Cu")
		(net "SAS_HDD_LED8")
	)
	(segment
		(start 20.955 -161.824162)
		(end 33.17875 -149.600412)
		(width 0.1143)
		(layer "F.Cu")
		(net "SAS_HDD_LED8")
	)
	(segment
		(start 17.584928 -166.65448)
		(end 20.555204 -163.684204)
		(width 0.1143)
		(layer "F.Cu")
		(net "SAS_HDD_LED8")
	)
	(segment
		(start 33.17875 -149.600412)
		(end 33.17875 -147.993608)
		(width 0.1143)
		(layer "F.Cu")
		(net "SAS_HDD_LED8")
	)
	(via
		(at 108.849668 -86.849712)
		(size 0.508)
		(drill 0.254)
		(layers "F.Cu" "B.Cu")
		(net "SAS_HDD_LED8")
	)
	(via
		(at 34.671 -146.5326)
		(size 0.5588)
		(drill 0.3048)
		(layers "F.Cu" "B.Cu")
		(net "SAS_HDD_LED8")
	)
	(via
		(at 20.555204 -163.684204)
		(size 0.7112)
		(drill 0.3556)
		(layers "F.Cu" "B.Cu")
		(net "SAS_HDD_LED8")
	)
	(segment
		(start 108.29417 -83.81238)
		(end 109.898942 -82.207608)
		(width 0.127)
		(layer "In5.Cu")
		(net "SAS_HDD_LED8")
	)
	(segment
		(start 106.9975 -78.0415)
		(end 99.664012 -78.0415)
		(width 0.127)
		(layer "In5.Cu")
		(net "SAS_HDD_LED8")
	)
	(segment
		(start 107.812332 -86.405212)
		(end 107.43057 -86.02345)
		(width 0.127)
		(layer "In5.Cu")
		(net "SAS_HDD_LED8")
	)
	(segment
		(start 108.966 -80.01)
		(end 106.9975 -78.0415)
		(width 0.127)
		(layer "In5.Cu")
		(net "SAS_HDD_LED8")
	)
	(segment
		(start 47.498 -130.207512)
		(end 47.498 -130.556)
		(width 0.127)
		(layer "In5.Cu")
		(net "SAS_HDD_LED8")
	)
	(segment
		(start 36.69792 -146.5326)
		(end 34.671 -146.5326)
		(width 0.127)
		(layer "In5.Cu")
		(net "SAS_HDD_LED8")
	)
	(segment
		(start 107.43057 -84.67598)
		(end 107.812332 -84.294218)
		(width 0.127)
		(layer "In5.Cu")
		(net "SAS_HDD_LED8")
	)
	(segment
		(start 107.998006 -84.294218)
		(end 108.29417 -83.998054)
		(width 0.127)
		(layer "In5.Cu")
		(net "SAS_HDD_LED8")
	)
	(segment
		(start 107.812332 -84.294218)
		(end 107.998006 -84.294218)
		(width 0.127)
		(layer "In5.Cu")
		(net "SAS_HDD_LED8")
	)
	(segment
		(start 109.898942 -82.207608)
		(end 109.898942 -80.416146)
		(width 0.127)
		(layer "In5.Cu")
		(net "SAS_HDD_LED8")
	)
	(segment
		(start 108.405168 -86.405212)
		(end 107.812332 -86.405212)
		(width 0.127)
		(layer "In5.Cu")
		(net "SAS_HDD_LED8")
	)
	(segment
		(start 107.43057 -86.02345)
		(end 107.43057 -84.67598)
		(width 0.127)
		(layer "In5.Cu")
		(net "SAS_HDD_LED8")
	)
	(segment
		(start 109.492796 -80.01)
		(end 108.966 -80.01)
		(width 0.127)
		(layer "In5.Cu")
		(net "SAS_HDD_LED8")
	)
	(segment
		(start 109.898942 -80.416146)
		(end 109.492796 -80.01)
		(width 0.127)
		(layer "In5.Cu")
		(net "SAS_HDD_LED8")
	)
	(segment
		(start 99.664012 -78.0415)
		(end 47.498 -130.207512)
		(width 0.127)
		(layer "In5.Cu")
		(net "SAS_HDD_LED8")
	)
	(segment
		(start 47.498 -130.556)
		(end 45.593 -132.461)
		(width 0.127)
		(layer "In5.Cu")
		(net "SAS_HDD_LED8")
	)
	(segment
		(start 45.593 -132.461)
		(end 45.593 -137.63752)
		(width 0.127)
		(layer "In5.Cu")
		(net "SAS_HDD_LED8")
	)
	(segment
		(start 108.849668 -86.849712)
		(end 108.405168 -86.405212)
		(width 0.127)
		(layer "In5.Cu")
		(net "SAS_HDD_LED8")
	)
	(segment
		(start 108.29417 -83.998054)
		(end 108.29417 -83.81238)
		(width 0.127)
		(layer "In5.Cu")
		(net "SAS_HDD_LED8")
	)
	(segment
		(start 45.593 -137.63752)
		(end 36.69792 -146.5326)
		(width 0.127)
		(layer "In5.Cu")
		(net "SAS_HDD_LED8")
	)
	(via
		(at 118.193566 -28.4226)
		(size 0.7112)
		(drill 0.3556)
		(layers "F.Cu" "B.Cu")
		(net "SYS_RST")
	)
	(segment
		(start 121.610882 -30.988)
		(end 119.959882 -29.337)
		(width 0.1143)
		(layer "B.Cu")
		(net "SYS_RST")
	)
	(segment
		(start 113.329466 -28.829)
		(end 113.329466 -28.5115)
		(width 0.1143)
		(layer "B.Cu")
		(net "SYS_RST")
	)
	(segment
		(start 118.745 -29.337)
		(end 118.193566 -28.785566)
		(width 0.1143)
		(layer "B.Cu")
		(net "SYS_RST")
	)
	(segment
		(start 115.845336 -28.4226)
		(end 118.193566 -28.4226)
		(width 0.1143)
		(layer "B.Cu")
		(net "SYS_RST")
	)
	(segment
		(start 113.704116 -28.13685)
		(end 115.559586 -28.13685)
		(width 0.1143)
		(layer "B.Cu")
		(net "SYS_RST")
	)
	(segment
		(start 112.059466 -28.829)
		(end 113.329466 -28.829)
		(width 0.1143)
		(layer "B.Cu")
		(net "SYS_RST")
	)
	(segment
		(start 118.193566 -28.785566)
		(end 118.193566 -28.4226)
		(width 0.1143)
		(layer "B.Cu")
		(net "SYS_RST")
	)
	(segment
		(start 115.559586 -28.13685)
		(end 115.845336 -28.4226)
		(width 0.1143)
		(layer "B.Cu")
		(net "SYS_RST")
	)
	(segment
		(start 129.585466 -31.877)
		(end 128.696466 -30.988)
		(width 0.1143)
		(layer "B.Cu")
		(net "SYS_RST")
	)
	(segment
		(start 113.329466 -28.5115)
		(end 113.704116 -28.13685)
		(width 0.1143)
		(layer "B.Cu")
		(net "SYS_RST")
	)
	(segment
		(start 128.696466 -30.988)
		(end 121.610882 -30.988)
		(width 0.1143)
		(layer "B.Cu")
		(net "SYS_RST")
	)
	(segment
		(start 119.959882 -29.337)
		(end 118.745 -29.337)
		(width 0.1143)
		(layer "B.Cu")
		(net "SYS_RST")
	)
	(segment
		(start 112.350042 -36.599876)
		(end 112.359694 -36.599876)
		(width 0.1143)
		(layer "F.Cu")
		(net "IOC_GPIO_26")
	)
	(segment
		(start 112.359694 -36.599876)
		(end 112.74806 -36.21151)
		(width 0.1143)
		(layer "F.Cu")
		(net "IOC_GPIO_26")
	)
	(via
		(at 112.74806 -36.21151)
		(size 0.508)
		(drill 0.254)
		(layers "F.Cu" "B.Cu")
		(net "IOC_GPIO_26")
	)
	(segment
		(start 113.34496 -35.625532)
		(end 112.758982 -36.21151)
		(width 0.1143)
		(layer "B.Cu")
		(net "IOC_GPIO_26")
	)
	(segment
		(start 114.36477 -35.625532)
		(end 113.34496 -35.625532)
		(width 0.1143)
		(layer "B.Cu")
		(net "IOC_GPIO_26")
	)
	(segment
		(start 112.758982 -36.21151)
		(end 112.74806 -36.21151)
		(width 0.1143)
		(layer "B.Cu")
		(net "IOC_GPIO_26")
	)
	(segment
		(start 102.349808 -101.350064)
		(end 101.849682 -101.85019)
		(width 0.1143)
		(layer "F.Cu")
		(net "EXP_GPIO_6")
	)
	(segment
		(start 90.987626 -130.302)
		(end 90.56497 -130.302)
		(width 0.1143)
		(layer "F.Cu")
		(net "EXP_GPIO_6")
	)
	(segment
		(start 91.124532 -131.570476)
		(end 91.124532 -130.438906)
		(width 0.1143)
		(layer "F.Cu")
		(net "EXP_GPIO_6")
	)
	(segment
		(start 91.124532 -130.438906)
		(end 90.987626 -130.302)
		(width 0.1143)
		(layer "F.Cu")
		(net "EXP_GPIO_6")
	)
	(via
		(at 101.849682 -101.85019)
		(size 0.508)
		(drill 0.254)
		(layers "F.Cu" "B.Cu")
		(net "EXP_GPIO_6")
	)
	(via
		(at 95.2754 -110.98657)
		(size 0.7112)
		(drill 0.3556)
		(layers "F.Cu" "B.Cu")
		(net "EXP_GPIO_6")
	)
	(via
		(at 90.56497 -130.302)
		(size 0.508)
		(drill 0.254)
		(layers "F.Cu" "B.Cu")
		(net "EXP_GPIO_6")
	)
	(segment
		(start 95.2754 -110.98657)
		(end 95.55607 -110.7059)
		(width 0.1143)
		(layer "B.Cu")
		(net "EXP_GPIO_6")
	)
	(segment
		(start 90.87612 -126.582932)
		(end 90.87612 -115.38585)
		(width 0.1143)
		(layer "B.Cu")
		(net "EXP_GPIO_6")
	)
	(segment
		(start 90.87612 -115.38585)
		(end 95.2754 -110.98657)
		(width 0.1143)
		(layer "B.Cu")
		(net "EXP_GPIO_6")
	)
	(segment
		(start 90.22842 -129.96545)
		(end 90.22842 -128.373378)
		(width 0.1143)
		(layer "B.Cu")
		(net "EXP_GPIO_6")
	)
	(segment
		(start 101.170232 -103.254302)
		(end 101.170232 -102.568502)
		(width 0.1143)
		(layer "B.Cu")
		(net "EXP_GPIO_6")
	)
	(segment
		(start 90.22842 -128.373378)
		(end 90.90152 -127.700278)
		(width 0.1143)
		(layer "B.Cu")
		(net "EXP_GPIO_6")
	)
	(segment
		(start 90.90152 -126.608332)
		(end 90.87612 -126.582932)
		(width 0.1143)
		(layer "B.Cu")
		(net "EXP_GPIO_6")
	)
	(segment
		(start 90.56497 -130.302)
		(end 90.22842 -129.96545)
		(width 0.1143)
		(layer "B.Cu")
		(net "EXP_GPIO_6")
	)
	(segment
		(start 95.55607 -108.868464)
		(end 101.170232 -103.254302)
		(width 0.1143)
		(layer "B.Cu")
		(net "EXP_GPIO_6")
	)
	(segment
		(start 95.55607 -110.7059)
		(end 95.55607 -108.868464)
		(width 0.1143)
		(layer "B.Cu")
		(net "EXP_GPIO_6")
	)
	(segment
		(start 101.849682 -101.889052)
		(end 101.849682 -101.85019)
		(width 0.1143)
		(layer "B.Cu")
		(net "EXP_GPIO_6")
	)
	(segment
		(start 101.170232 -102.568502)
		(end 101.849682 -101.889052)
		(width 0.1143)
		(layer "B.Cu")
		(net "EXP_GPIO_6")
	)
	(segment
		(start 90.90152 -127.700278)
		(end 90.90152 -126.608332)
		(width 0.1143)
		(layer "B.Cu")
		(net "EXP_GPIO_6")
	)
	(via
		(at 135.001 -31.623)
		(size 0.7112)
		(drill 0.3556)
		(layers "F.Cu" "B.Cu")
		(net "P3V3_STBY_R")
	)
	(segment
		(start 134.030466 -31.623)
		(end 135.001 -31.623)
		(width 0.127)
		(layer "B.Cu")
		(net "P3V3_STBY_R")
	)
	(segment
		(start 135.186166 -31.623)
		(end 135.001 -31.623)
		(width 0.127)
		(layer "B.Cu")
		(net "P3V3_STBY_R")
	)
	(segment
		(start 134.030466 -32.766)
		(end 134.030466 -31.623)
		(width 0.127)
		(layer "B.Cu")
		(net "P3V3_STBY_R")
	)
	(segment
		(start 135.89 -32.326834)
		(end 135.186166 -31.623)
		(width 0.127)
		(layer "B.Cu")
		(net "P3V3_STBY_R")
	)
	(segment
		(start 135.89 -34.2265)
		(end 135.89 -32.326834)
		(width 0.127)
		(layer "B.Cu")
		(net "P3V3_STBY_R")
	)
	(segment
		(start 113.150142 -38.199822)
		(end 113.194338 -38.199822)
		(width 0.1143)
		(layer "F.Cu")
		(net "IOC_GPIO_27")
	)
	(segment
		(start 113.194338 -38.199822)
		(end 113.537238 -37.856922)
		(width 0.1143)
		(layer "F.Cu")
		(net "IOC_GPIO_27")
	)
	(segment
		(start 113.537238 -37.856922)
		(end 114.525044 -37.856922)
		(width 0.1143)
		(layer "F.Cu")
		(net "IOC_GPIO_27")
	)
	(segment
		(start 114.525044 -37.856922)
		(end 114.726466 -37.6555)
		(width 0.1143)
		(layer "F.Cu")
		(net "IOC_GPIO_27")
	)
	(via
		(at 114.726466 -37.6555)
		(size 0.508)
		(drill 0.254)
		(layers "F.Cu" "B.Cu")
		(net "IOC_GPIO_27")
	)
	(segment
		(start 114.154966 -37.084)
		(end 114.726466 -37.6555)
		(width 0.1143)
		(layer "B.Cu")
		(net "IOC_GPIO_27")
	)
	(segment
		(start 114.154966 -36.957)
		(end 114.154966 -37.084)
		(width 0.1143)
		(layer "B.Cu")
		(net "IOC_GPIO_27")
	)
	(segment
		(start 99.83597 -85.344)
		(end 99.20097 -85.344)
		(width 0.1143)
		(layer "F.Cu")
		(net "SXP_ACTIVE_1")
	)
	(segment
		(start 97.54997 -86.233)
		(end 96.34347 -86.233)
		(width 0.1143)
		(layer "F.Cu")
		(net "SXP_ACTIVE_1")
	)
	(segment
		(start 109.349794 -89.349834)
		(end 108.849668 -88.849708)
		(width 0.1143)
		(layer "F.Cu")
		(net "SXP_ACTIVE_1")
	)
	(segment
		(start 100.08997 -85.09)
		(end 99.83597 -85.344)
		(width 0.1143)
		(layer "F.Cu")
		(net "SXP_ACTIVE_1")
	)
	(segment
		(start 98.31197 -86.233)
		(end 97.54997 -86.233)
		(width 0.1143)
		(layer "F.Cu")
		(net "SXP_ACTIVE_1")
	)
	(segment
		(start 99.20097 -85.344)
		(end 98.31197 -86.233)
		(width 0.1143)
		(layer "F.Cu")
		(net "SXP_ACTIVE_1")
	)
	(via
		(at 100.08997 -85.09)
		(size 0.508)
		(drill 0.254)
		(layers "F.Cu" "B.Cu")
		(net "SXP_ACTIVE_1")
	)
	(via
		(at 108.849668 -88.849708)
		(size 0.508)
		(drill 0.254)
		(layers "F.Cu" "B.Cu")
		(net "SXP_ACTIVE_1")
	)
	(segment
		(start 100.08997 -85.09)
		(end 100.249736 -85.249766)
		(width 0.127)
		(layer "In2.Cu")
		(net "SXP_ACTIVE_1")
	)
	(segment
		(start 100.532438 -85.344)
		(end 101.93528 -85.344)
		(width 0.127)
		(layer "In2.Cu")
		(net "SXP_ACTIVE_1")
	)
	(segment
		(start 106.763312 -88.392)
		(end 108.21797 -88.392)
		(width 0.127)
		(layer "In2.Cu")
		(net "SXP_ACTIVE_1")
	)
	(segment
		(start 100.438204 -85.249766)
		(end 100.532438 -85.344)
		(width 0.127)
		(layer "In2.Cu")
		(net "SXP_ACTIVE_1")
	)
	(segment
		(start 101.93528 -85.344)
		(end 103.30561 -86.71433)
		(width 0.127)
		(layer "In2.Cu")
		(net "SXP_ACTIVE_1")
	)
	(segment
		(start 103.776526 -87.40521)
		(end 104.033828 -87.40521)
		(width 0.127)
		(layer "In2.Cu")
		(net "SXP_ACTIVE_1")
	)
	(segment
		(start 104.17683 -87.548212)
		(end 105.919524 -87.548212)
		(width 0.127)
		(layer "In2.Cu")
		(net "SXP_ACTIVE_1")
	)
	(segment
		(start 100.249736 -85.249766)
		(end 100.438204 -85.249766)
		(width 0.127)
		(layer "In2.Cu")
		(net "SXP_ACTIVE_1")
	)
	(segment
		(start 108.675678 -88.849708)
		(end 108.849668 -88.849708)
		(width 0.127)
		(layer "In2.Cu")
		(net "SXP_ACTIVE_1")
	)
	(segment
		(start 104.033828 -87.40521)
		(end 104.17683 -87.548212)
		(width 0.127)
		(layer "In2.Cu")
		(net "SXP_ACTIVE_1")
	)
	(segment
		(start 108.21797 -88.392)
		(end 108.675678 -88.849708)
		(width 0.127)
		(layer "In2.Cu")
		(net "SXP_ACTIVE_1")
	)
	(segment
		(start 103.30561 -86.934294)
		(end 103.776526 -87.40521)
		(width 0.127)
		(layer "In2.Cu")
		(net "SXP_ACTIVE_1")
	)
	(segment
		(start 105.919524 -87.548212)
		(end 106.763312 -88.392)
		(width 0.127)
		(layer "In2.Cu")
		(net "SXP_ACTIVE_1")
	)
	(segment
		(start 103.30561 -86.71433)
		(end 103.30561 -86.934294)
		(width 0.127)
		(layer "In2.Cu")
		(net "SXP_ACTIVE_1")
	)
	(segment
		(start 112.349788 -85.349842)
		(end 111.849662 -84.849716)
		(width 0.1143)
		(layer "F.Cu")
		(net "EXP_LED18")
	)
	(via
		(at 111.849662 -84.849716)
		(size 0.508)
		(drill 0.254)
		(layers "F.Cu" "B.Cu")
		(net "EXP_LED18")
	)
	(segment
		(start 111.101378 -85.598)
		(end 111.849662 -84.849716)
		(width 0.1143)
		(layer "B.Cu")
		(net "EXP_LED18")
	)
	(segment
		(start 110.88497 -85.598)
		(end 111.101378 -85.598)
		(width 0.1143)
		(layer "B.Cu")
		(net "EXP_LED18")
	)
	(segment
		(start 112.350042 -38.999922)
		(end 112.355884 -38.999922)
		(width 0.1143)
		(layer "F.Cu")
		(net "IOC_GPIO_28")
	)
	(segment
		(start 112.74806 -38.607746)
		(end 112.748314 -38.607746)
		(width 0.1143)
		(layer "F.Cu")
		(net "IOC_GPIO_28")
	)
	(segment
		(start 112.355884 -38.999922)
		(end 112.74806 -38.607746)
		(width 0.1143)
		(layer "F.Cu")
		(net "IOC_GPIO_28")
	)
	(via
		(at 112.748314 -38.607746)
		(size 0.508)
		(drill 0.254)
		(layers "F.Cu" "B.Cu")
		(net "IOC_GPIO_28")
	)
	(segment
		(start 114.660426 -38.1381)
		(end 114.114326 -38.6842)
		(width 0.1143)
		(layer "B.Cu")
		(net "IOC_GPIO_28")
	)
	(segment
		(start 115.437666 -38.1381)
		(end 114.660426 -38.1381)
		(width 0.1143)
		(layer "B.Cu")
		(net "IOC_GPIO_28")
	)
	(segment
		(start 112.824768 -38.6842)
		(end 112.748314 -38.607746)
		(width 0.1143)
		(layer "B.Cu")
		(net "IOC_GPIO_28")
	)
	(segment
		(start 114.114326 -38.6842)
		(end 112.824768 -38.6842)
		(width 0.1143)
		(layer "B.Cu")
		(net "IOC_GPIO_28")
	)
	(segment
		(start 33.54705 -149.753066)
		(end 33.54705 -148.895308)
		(width 0.1143)
		(layer "F.Cu")
		(net "SAS_HDD_LED9")
	)
	(segment
		(start 33.909 -148.533358)
		(end 33.909 -147.955)
		(width 0.1143)
		(layer "F.Cu")
		(net "SAS_HDD_LED9")
	)
	(segment
		(start 108.768896 -80.912208)
		(end 108.70311 -80.846422)
		(width 0.1143)
		(layer "F.Cu")
		(net "SAS_HDD_LED9")
	)
	(segment
		(start 33.54705 -148.895308)
		(end 33.909 -148.533358)
		(width 0.1143)
		(layer "F.Cu")
		(net "SAS_HDD_LED9")
	)
	(segment
		(start 19.304 -165.735)
		(end 21.463 -163.576)
		(width 0.1143)
		(layer "F.Cu")
		(net "SAS_HDD_LED9")
	)
	(segment
		(start 17.984978 -167.054022)
		(end 19.304 -165.735)
		(width 0.1143)
		(layer "F.Cu")
		(net "SAS_HDD_LED9")
	)
	(segment
		(start 108.768896 -82.768948)
		(end 108.768896 -80.912208)
		(width 0.1143)
		(layer "F.Cu")
		(net "SAS_HDD_LED9")
	)
	(segment
		(start 17.984978 -170.107356)
		(end 17.984978 -167.054022)
		(width 0.1143)
		(layer "F.Cu")
		(net "SAS_HDD_LED9")
	)
	(segment
		(start 21.463 -161.837116)
		(end 33.54705 -149.753066)
		(width 0.1143)
		(layer "F.Cu")
		(net "SAS_HDD_LED9")
	)
	(segment
		(start 109.349794 -83.349846)
		(end 108.768896 -82.768948)
		(width 0.1143)
		(layer "F.Cu")
		(net "SAS_HDD_LED9")
	)
	(segment
		(start 21.463 -163.576)
		(end 21.463 -161.837116)
		(width 0.1143)
		(layer "F.Cu")
		(net "SAS_HDD_LED9")
	)
	(via
		(at 108.70311 -80.846422)
		(size 0.508)
		(drill 0.254)
		(layers "F.Cu" "B.Cu")
		(net "SAS_HDD_LED9")
	)
	(via
		(at 19.304 -165.735)
		(size 0.7112)
		(drill 0.3556)
		(layers "F.Cu" "B.Cu")
		(net "SAS_HDD_LED9")
	)
	(via
		(at 33.909 -147.955)
		(size 0.5588)
		(drill 0.3048)
		(layers "F.Cu" "B.Cu")
		(net "SAS_HDD_LED9")
	)
	(segment
		(start 48.26 -132.715)
		(end 48.26 -130.523488)
		(width 0.127)
		(layer "In5.Cu")
		(net "SAS_HDD_LED9")
	)
	(segment
		(start 48.26 -130.523488)
		(end 99.979988 -78.8035)
		(width 0.127)
		(layer "In5.Cu")
		(net "SAS_HDD_LED9")
	)
	(segment
		(start 106.820716 -78.8035)
		(end 108.70311 -80.685894)
		(width 0.127)
		(layer "In5.Cu")
		(net "SAS_HDD_LED9")
	)
	(segment
		(start 33.909 -147.955)
		(end 36.353496 -147.955)
		(width 0.127)
		(layer "In5.Cu")
		(net "SAS_HDD_LED9")
	)
	(segment
		(start 46.355 -134.62)
		(end 48.26 -132.715)
		(width 0.127)
		(layer "In5.Cu")
		(net "SAS_HDD_LED9")
	)
	(segment
		(start 36.353496 -147.955)
		(end 46.355 -137.953496)
		(width 0.127)
		(layer "In5.Cu")
		(net "SAS_HDD_LED9")
	)
	(segment
		(start 46.355 -137.953496)
		(end 46.355 -134.62)
		(width 0.127)
		(layer "In5.Cu")
		(net "SAS_HDD_LED9")
	)
	(segment
		(start 108.70311 -80.685894)
		(end 108.70311 -80.846422)
		(width 0.127)
		(layer "In5.Cu")
		(net "SAS_HDD_LED9")
	)
	(segment
		(start 99.979988 -78.8035)
		(end 106.820716 -78.8035)
		(width 0.127)
		(layer "In5.Cu")
		(net "SAS_HDD_LED9")
	)
	(segment
		(start 115.350036 -85.317076)
		(end 114.864642 -84.831682)
		(width 0.1143)
		(layer "F.Cu")
		(net "EXP_TEST_MUX30")
	)
	(segment
		(start 115.350036 -85.349842)
		(end 115.350036 -85.317076)
		(width 0.1143)
		(layer "F.Cu")
		(net "EXP_TEST_MUX30")
	)
	(via
		(at 114.864642 -84.831682)
		(size 0.508)
		(drill 0.254)
		(layers "F.Cu" "B.Cu")
		(net "EXP_TEST_MUX30")
	)
	(segment
		(start 113.80597 -79.121)
		(end 114.18697 -79.502)
		(width 0.1143)
		(layer "B.Cu")
		(net "EXP_TEST_MUX30")
	)
	(segment
		(start 114.18697 -80.518)
		(end 114.864642 -81.195672)
		(width 0.1143)
		(layer "B.Cu")
		(net "EXP_TEST_MUX30")
	)
	(segment
		(start 114.18697 -79.502)
		(end 114.18697 -80.518)
		(width 0.1143)
		(layer "B.Cu")
		(net "EXP_TEST_MUX30")
	)
	(segment
		(start 114.864642 -81.195672)
		(end 114.864642 -84.831682)
		(width 0.1143)
		(layer "B.Cu")
		(net "EXP_TEST_MUX30")
	)
	(segment
		(start 112.350042 -38.199822)
		(end 112.75187 -37.797994)
		(width 0.1143)
		(layer "F.Cu")
		(net "IOC_GPIO_29")
	)
	(segment
		(start 112.75187 -37.797994)
		(end 112.757712 -37.797994)
		(width 0.1143)
		(layer "F.Cu")
		(net "IOC_GPIO_29")
	)
	(via
		(at 112.757712 -37.797994)
		(size 0.508)
		(drill 0.254)
		(layers "F.Cu" "B.Cu")
		(net "IOC_GPIO_29")
	)
	(segment
		(start 113.039398 -38.07968)
		(end 112.757712 -37.797994)
		(width 0.1143)
		(layer "B.Cu")
		(net "IOC_GPIO_29")
	)
	(segment
		(start 113.626646 -38.07968)
		(end 113.039398 -38.07968)
		(width 0.1143)
		(layer "B.Cu")
		(net "IOC_GPIO_29")
	)
	(segment
		(start 109.862112 -86.83752)
		(end 109.82071 -86.83752)
		(width 0.1143)
		(layer "F.Cu")
		(net "EXP_ADC_IN1")
	)
	(segment
		(start 110.349792 -86.34984)
		(end 109.862112 -86.83752)
		(width 0.1143)
		(layer "F.Cu")
		(net "EXP_ADC_IN1")
	)
	(via
		(at 107.429808 -82.677)
		(size 0.7112)
		(drill 0.3556)
		(layers "F.Cu" "B.Cu")
		(net "EXP_ADC_IN1")
	)
	(via
		(at 109.82071 -86.83752)
		(size 0.508)
		(drill 0.254)
		(layers "F.Cu" "B.Cu")
		(net "EXP_ADC_IN1")
	)
	(segment
		(start 107.94746 -82.677)
		(end 108.336842 -83.066382)
		(width 0.1143)
		(layer "B.Cu")
		(net "EXP_ADC_IN1")
	)
	(segment
		(start 108.336842 -83.066382)
		(end 108.336842 -85.032088)
		(width 0.1143)
		(layer "B.Cu")
		(net "EXP_ADC_IN1")
	)
	(segment
		(start 108.59897 -85.294216)
		(end 108.878116 -85.294216)
		(width 0.1143)
		(layer "B.Cu")
		(net "EXP_ADC_IN1")
	)
	(segment
		(start 108.336842 -85.032088)
		(end 108.59897 -85.294216)
		(width 0.1143)
		(layer "B.Cu")
		(net "EXP_ADC_IN1")
	)
	(segment
		(start 109.36097 -86.37778)
		(end 109.82071 -86.83752)
		(width 0.1143)
		(layer "B.Cu")
		(net "EXP_ADC_IN1")
	)
	(segment
		(start 109.36097 -85.77707)
		(end 109.36097 -86.37778)
		(width 0.1143)
		(layer "B.Cu")
		(net "EXP_ADC_IN1")
	)
	(segment
		(start 108.878116 -85.294216)
		(end 109.36097 -85.77707)
		(width 0.1143)
		(layer "B.Cu")
		(net "EXP_ADC_IN1")
	)
	(segment
		(start 107.429808 -82.677)
		(end 107.94746 -82.677)
		(width 0.1143)
		(layer "B.Cu")
		(net "EXP_ADC_IN1")
	)
	(segment
		(start 111.95431 -36.194746)
		(end 111.992156 -36.1569)
		(width 0.1143)
		(layer "F.Cu")
		(net "IOC_GPIO_25")
	)
	(segment
		(start 111.95431 -37.00018)
		(end 111.95431 -36.194746)
		(width 0.1143)
		(layer "F.Cu")
		(net "IOC_GPIO_25")
	)
	(segment
		(start 111.992156 -36.148518)
		(end 112.340644 -35.80003)
		(width 0.1143)
		(layer "F.Cu")
		(net "IOC_GPIO_25")
	)
	(segment
		(start 111.992156 -36.1569)
		(end 111.992156 -36.148518)
		(width 0.1143)
		(layer "F.Cu")
		(net "IOC_GPIO_25")
	)
	(segment
		(start 112.340644 -35.80003)
		(end 112.350042 -35.80003)
		(width 0.1143)
		(layer "F.Cu")
		(net "IOC_GPIO_25")
	)
	(via
		(at 111.95431 -37.00018)
		(size 0.508)
		(drill 0.254)
		(layers "F.Cu" "B.Cu")
		(net "IOC_GPIO_25")
	)
	(segment
		(start 111.95431 -36.576)
		(end 111.95431 -37.00018)
		(width 0.1143)
		(layer "B.Cu")
		(net "IOC_GPIO_25")
	)
	(segment
		(start 112.532668 -35.32251)
		(end 111.972344 -36.263834)
		(width 0.1143)
		(layer "B.Cu")
		(net "IOC_GPIO_25")
	)
	(segment
		(start 111.972344 -36.263834)
		(end 111.95431 -36.576)
		(width 0.1143)
		(layer "B.Cu")
		(net "IOC_GPIO_25")
	)
	(segment
		(start 87.64397 -134.112)
		(end 87.38997 -134.366)
		(width 0.1143)
		(layer "F.Cu")
		(net "EXP_GPIO_13")
	)
	(segment
		(start 104.349804 -98.35007)
		(end 103.849678 -98.850196)
		(width 0.1143)
		(layer "F.Cu")
		(net "EXP_GPIO_13")
	)
	(segment
		(start 91.924632 -132.752338)
		(end 90.56497 -134.112)
		(width 0.1143)
		(layer "F.Cu")
		(net "EXP_GPIO_13")
	)
	(segment
		(start 90.56497 -134.112)
		(end 87.64397 -134.112)
		(width 0.1143)
		(layer "F.Cu")
		(net "EXP_GPIO_13")
	)
	(segment
		(start 91.924632 -131.570476)
		(end 91.924632 -132.752338)
		(width 0.1143)
		(layer "F.Cu")
		(net "EXP_GPIO_13")
	)
	(via
		(at 97.282 -101.854)
		(size 0.7112)
		(drill 0.3556)
		(layers "F.Cu" "B.Cu")
		(net "EXP_GPIO_13")
	)
	(via
		(at 87.38997 -134.366)
		(size 0.508)
		(drill 0.254)
		(layers "F.Cu" "B.Cu")
		(net "EXP_GPIO_13")
	)
	(via
		(at 103.849678 -98.850196)
		(size 0.508)
		(drill 0.254)
		(layers "F.Cu" "B.Cu")
		(net "EXP_GPIO_13")
	)
	(segment
		(start 87.38997 -134.366)
		(end 88.154002 -133.601968)
		(width 0.1143)
		(layer "B.Cu")
		(net "EXP_GPIO_13")
	)
	(segment
		(start 87.5665 -122.301762)
		(end 87.5665 -120.34266)
		(width 0.1143)
		(layer "B.Cu")
		(net "EXP_GPIO_13")
	)
	(segment
		(start 88.00338 -108.979208)
		(end 95.128588 -101.854)
		(width 0.1143)
		(layer "B.Cu")
		(net "EXP_GPIO_13")
	)
	(segment
		(start 95.128588 -101.854)
		(end 97.282 -101.854)
		(width 0.1143)
		(layer "B.Cu")
		(net "EXP_GPIO_13")
	)
	(segment
		(start 88.00338 -119.90578)
		(end 88.00338 -108.979208)
		(width 0.1143)
		(layer "B.Cu")
		(net "EXP_GPIO_13")
	)
	(segment
		(start 97.421446 -101.854)
		(end 98.920046 -100.3554)
		(width 0.1143)
		(layer "B.Cu")
		(net "EXP_GPIO_13")
	)
	(segment
		(start 103.46944 -98.850196)
		(end 103.849678 -98.850196)
		(width 0.1143)
		(layer "B.Cu")
		(net "EXP_GPIO_13")
	)
	(segment
		(start 98.920046 -100.3554)
		(end 100.255832 -100.3554)
		(width 0.1143)
		(layer "B.Cu")
		(net "EXP_GPIO_13")
	)
	(segment
		(start 88.154002 -122.889264)
		(end 87.5665 -122.301762)
		(width 0.1143)
		(layer "B.Cu")
		(net "EXP_GPIO_13")
	)
	(segment
		(start 103.05669 -98.437446)
		(end 103.46944 -98.850196)
		(width 0.1143)
		(layer "B.Cu")
		(net "EXP_GPIO_13")
	)
	(segment
		(start 88.154002 -133.601968)
		(end 88.154002 -122.889264)
		(width 0.1143)
		(layer "B.Cu")
		(net "EXP_GPIO_13")
	)
	(segment
		(start 100.255832 -100.3554)
		(end 102.173786 -98.437446)
		(width 0.1143)
		(layer "B.Cu")
		(net "EXP_GPIO_13")
	)
	(segment
		(start 102.173786 -98.437446)
		(end 103.05669 -98.437446)
		(width 0.1143)
		(layer "B.Cu")
		(net "EXP_GPIO_13")
	)
	(segment
		(start 97.282 -101.854)
		(end 97.421446 -101.854)
		(width 0.1143)
		(layer "B.Cu")
		(net "EXP_GPIO_13")
	)
	(segment
		(start 87.5665 -120.34266)
		(end 88.00338 -119.90578)
		(width 0.1143)
		(layer "B.Cu")
		(net "EXP_GPIO_13")
	)
	(segment
		(start 290.034472 -170.240452)
		(end 290.034472 -170.249342)
		(width 0.127)
		(layer "F.Cu")
		(net "TP_BMC_GPIOE0")
	)
	(segment
		(start 290.434776 -169.840148)
		(end 290.034472 -170.240452)
		(width 0.127)
		(layer "F.Cu")
		(net "TP_BMC_GPIOE0")
	)
	(via
		(at 290.034472 -170.249342)
		(size 0.508)
		(drill 0.254)
		(layers "F.Cu" "B.Cu")
		(net "TP_BMC_GPIOE0")
	)
	(segment
		(start 289.24504 -170.57624)
		(end 289.571938 -170.249342)
		(width 0.127)
		(layer "B.Cu")
		(net "TP_BMC_GPIOE0")
	)
	(segment
		(start 289.571938 -170.249342)
		(end 290.034472 -170.249342)
		(width 0.127)
		(layer "B.Cu")
		(net "TP_BMC_GPIOE0")
	)
	(segment
		(start 286.891984 -167.135556)
		(end 286.891984 -167.582342)
		(width 0.127)
		(layer "F.Cu")
		(net "TP_BMC_GPIOF1")
	)
	(segment
		(start 284.0609 -162.0901)
		(end 284.0609 -163.976812)
		(width 0.127)
		(layer "F.Cu")
		(net "TP_BMC_GPIOF1")
	)
	(segment
		(start 284.48 -161.671)
		(end 284.0609 -162.0901)
		(width 0.127)
		(layer "F.Cu")
		(net "TP_BMC_GPIOF1")
	)
	(segment
		(start 284.79496 -164.710872)
		(end 284.79496 -165.038532)
		(width 0.127)
		(layer "F.Cu")
		(net "TP_BMC_GPIOF1")
	)
	(segment
		(start 284.0609 -163.976812)
		(end 284.79496 -164.710872)
		(width 0.127)
		(layer "F.Cu")
		(net "TP_BMC_GPIOF1")
	)
	(segment
		(start 284.48 -161.163)
		(end 284.48 -161.671)
		(width 0.127)
		(layer "F.Cu")
		(net "TP_BMC_GPIOF1")
	)
	(segment
		(start 287.234884 -167.925242)
		(end 287.234884 -168.240202)
		(width 0.127)
		(layer "F.Cu")
		(net "TP_BMC_GPIOF1")
	)
	(segment
		(start 284.79496 -165.038532)
		(end 286.891984 -167.135556)
		(width 0.127)
		(layer "F.Cu")
		(net "TP_BMC_GPIOF1")
	)
	(segment
		(start 286.891984 -167.582342)
		(end 287.234884 -167.925242)
		(width 0.127)
		(layer "F.Cu")
		(net "TP_BMC_GPIOF1")
	)
	(segment
		(start 300.42866 -181.446424)
		(end 300.431708 -181.446424)
		(width 0.127)
		(layer "F.Cu")
		(net "TP_BMC_GPIOM4")
	)
	(segment
		(start 300.03496 -181.840124)
		(end 300.42866 -181.446424)
		(width 0.127)
		(layer "F.Cu")
		(net "TP_BMC_GPIOM4")
	)
	(via
		(at 300.431708 -181.446424)
		(size 0.508)
		(drill 0.254)
		(layers "F.Cu" "B.Cu")
		(net "TP_BMC_GPIOM4")
	)
	(segment
		(start 300.54804 -181.562756)
		(end 300.431708 -181.446424)
		(width 0.127)
		(layer "B.Cu")
		(net "TP_BMC_GPIOM4")
	)
	(segment
		(start 300.9519 -182.91048)
		(end 300.54804 -182.50662)
		(width 0.127)
		(layer "B.Cu")
		(net "TP_BMC_GPIOM4")
	)
	(segment
		(start 300.54804 -182.50662)
		(end 300.54804 -181.562756)
		(width 0.127)
		(layer "B.Cu")
		(net "TP_BMC_GPIOM4")
	)
	(segment
		(start 285.496 -163.703)
		(end 285.5468 -163.7538)
		(width 0.127)
		(layer "F.Cu")
		(net "TP_BMC_GPIOF4")
	)
	(segment
		(start 285.5468 -164.961062)
		(end 287.692084 -167.106346)
		(width 0.127)
		(layer "F.Cu")
		(net "TP_BMC_GPIOF4")
	)
	(segment
		(start 287.692084 -167.582342)
		(end 288.034984 -167.925242)
		(width 0.127)
		(layer "F.Cu")
		(net "TP_BMC_GPIOF4")
	)
	(segment
		(start 285.5468 -163.7538)
		(end 285.5468 -164.961062)
		(width 0.127)
		(layer "F.Cu")
		(net "TP_BMC_GPIOF4")
	)
	(segment
		(start 287.692084 -167.106346)
		(end 287.692084 -167.582342)
		(width 0.127)
		(layer "F.Cu")
		(net "TP_BMC_GPIOF4")
	)
	(segment
		(start 288.034984 -167.925242)
		(end 288.034984 -168.240202)
		(width 0.127)
		(layer "F.Cu")
		(net "TP_BMC_GPIOF4")
	)
	(segment
		(start 288.034984 -169.840148)
		(end 288.044128 -169.840148)
		(width 0.127)
		(layer "F.Cu")
		(net "TP_BMC_GPIOF0")
	)
	(segment
		(start 288.044128 -169.840148)
		(end 288.44113 -170.23715)
		(width 0.127)
		(layer "F.Cu")
		(net "TP_BMC_GPIOF0")
	)
	(via
		(at 288.44113 -170.23715)
		(size 0.508)
		(drill 0.254)
		(layers "F.Cu" "B.Cu")
		(net "TP_BMC_GPIOF0")
	)
	(segment
		(start 287.788096 -169.037)
		(end 288.029142 -169.278046)
		(width 0.0889)
		(layer "B.Cu")
		(net "TP_BMC_GPIOF0")
	)
	(segment
		(start 288.029142 -169.591482)
		(end 288.44113 -170.00347)
		(width 0.0889)
		(layer "B.Cu")
		(net "TP_BMC_GPIOF0")
	)
	(segment
		(start 288.029142 -169.278046)
		(end 288.029142 -169.591482)
		(width 0.0889)
		(layer "B.Cu")
		(net "TP_BMC_GPIOF0")
	)
	(segment
		(start 288.44113 -170.00347)
		(end 288.44113 -170.23715)
		(width 0.0889)
		(layer "B.Cu")
		(net "TP_BMC_GPIOF0")
	)
	(segment
		(start 286.41294 -168.56964)
		(end 286.8803 -169.037)
		(width 0.0889)
		(layer "B.Cu")
		(net "TP_BMC_GPIOF0")
	)
	(segment
		(start 286.8803 -169.037)
		(end 287.788096 -169.037)
		(width 0.0889)
		(layer "B.Cu")
		(net "TP_BMC_GPIOF0")
	)
	(segment
		(start 305.435 -184.785)
		(end 305.308 -184.658)
		(width 0.127)
		(layer "F.Cu")
		(net "TP_BMC_GPIOM6")
	)
	(segment
		(start 302.18507 -183.44007)
		(end 301.634906 -183.44007)
		(width 0.127)
		(layer "F.Cu")
		(net "TP_BMC_GPIOM6")
	)
	(segment
		(start 305.308 -184.658)
		(end 303.403 -184.658)
		(width 0.127)
		(layer "F.Cu")
		(net "TP_BMC_GPIOM6")
	)
	(segment
		(start 303.403 -184.658)
		(end 302.18507 -183.44007)
		(width 0.127)
		(layer "F.Cu")
		(net "TP_BMC_GPIOM6")
	)
	(segment
		(start 288.83483 -169.840148)
		(end 288.441892 -169.44721)
		(width 0.127)
		(layer "F.Cu")
		(net "TP_BMC_GPIOF3")
	)
	(segment
		(start 288.441892 -169.44721)
		(end 288.441892 -169.43832)
		(width 0.127)
		(layer "F.Cu")
		(net "TP_BMC_GPIOF3")
	)
	(via
		(at 288.441892 -169.43832)
		(size 0.508)
		(drill 0.254)
		(layers "F.Cu" "B.Cu")
		(net "TP_BMC_GPIOF3")
	)
	(segment
		(start 288.32302 -167.96512)
		(end 288.325306 -167.96512)
		(width 0.1016)
		(layer "B.Cu")
		(net "TP_BMC_GPIOF3")
	)
	(segment
		(start 288.01695 -167.11295)
		(end 288.01695 -167.65905)
		(width 0.127)
		(layer "B.Cu")
		(net "TP_BMC_GPIOF3")
	)
	(segment
		(start 288.01695 -167.65905)
		(end 288.32302 -167.96512)
		(width 0.127)
		(layer "B.Cu")
		(net "TP_BMC_GPIOF3")
	)
	(segment
		(start 288.836862 -168.476676)
		(end 288.836862 -169.04335)
		(width 0.1016)
		(layer "B.Cu")
		(net "TP_BMC_GPIOF3")
	)
	(segment
		(start 288.325306 -167.96512)
		(end 288.836862 -168.476676)
		(width 0.1016)
		(layer "B.Cu")
		(net "TP_BMC_GPIOF3")
	)
	(segment
		(start 288.836862 -169.04335)
		(end 288.441892 -169.43832)
		(width 0.1016)
		(layer "B.Cu")
		(net "TP_BMC_GPIOF3")
	)
	(segment
		(start 287.782 -166.878)
		(end 288.01695 -167.11295)
		(width 0.127)
		(layer "B.Cu")
		(net "TP_BMC_GPIOF3")
	)
	(segment
		(start 285.106618 -164.591238)
		(end 285.106618 -164.964618)
		(width 0.127)
		(layer "F.Cu")
		(net "TP_BMC_GPIOF5")
	)
	(segment
		(start 284.607 -164.09162)
		(end 285.106618 -164.591238)
		(width 0.127)
		(layer "F.Cu")
		(net "TP_BMC_GPIOF5")
	)
	(segment
		(start 287.234884 -167.092884)
		(end 287.234884 -167.440102)
		(width 0.127)
		(layer "F.Cu")
		(net "TP_BMC_GPIOF5")
	)
	(segment
		(start 285.106618 -164.964618)
		(end 287.234884 -167.092884)
		(width 0.127)
		(layer "F.Cu")
		(net "TP_BMC_GPIOF5")
	)
	(segment
		(start 284.607 -162.433)
		(end 284.607 -164.09162)
		(width 0.127)
		(layer "F.Cu")
		(net "TP_BMC_GPIOF5")
	)
	(segment
		(start 286.244538 -167.249856)
		(end 286.434784 -167.440102)
		(width 0.127)
		(layer "F.Cu")
		(net "TP_BMC_GPIOF2")
	)
	(segment
		(start 284.49016 -165.196774)
		(end 286.244538 -166.951152)
		(width 0.127)
		(layer "F.Cu")
		(net "TP_BMC_GPIOF2")
	)
	(segment
		(start 283.7561 -161.963608)
		(end 283.7561 -164.103304)
		(width 0.127)
		(layer "F.Cu")
		(net "TP_BMC_GPIOF2")
	)
	(segment
		(start 283.9085 -160.4645)
		(end 283.9085 -161.811208)
		(width 0.127)
		(layer "F.Cu")
		(net "TP_BMC_GPIOF2")
	)
	(segment
		(start 284.48 -159.893)
		(end 283.9085 -160.4645)
		(width 0.127)
		(layer "F.Cu")
		(net "TP_BMC_GPIOF2")
	)
	(segment
		(start 283.9085 -161.811208)
		(end 283.7561 -161.963608)
		(width 0.127)
		(layer "F.Cu")
		(net "TP_BMC_GPIOF2")
	)
	(segment
		(start 283.7561 -164.103304)
		(end 284.49016 -164.837364)
		(width 0.127)
		(layer "F.Cu")
		(net "TP_BMC_GPIOF2")
	)
	(segment
		(start 284.49016 -164.837364)
		(end 284.49016 -165.196774)
		(width 0.127)
		(layer "F.Cu")
		(net "TP_BMC_GPIOF2")
	)
	(segment
		(start 286.244538 -166.951152)
		(end 286.244538 -167.249856)
		(width 0.127)
		(layer "F.Cu")
		(net "TP_BMC_GPIOF2")
	)
	(segment
		(start 302.540924 -182.271924)
		(end 301.344076 -182.271924)
		(width 0.127)
		(layer "F.Cu")
		(net "TP_BMC_GPIOM5")
	)
	(segment
		(start 301.344076 -182.271924)
		(end 300.975776 -182.640224)
		(width 0.127)
		(layer "F.Cu")
		(net "TP_BMC_GPIOM5")
	)
	(segment
		(start 305.159918 -182.731918)
		(end 303.000918 -182.731918)
		(width 0.127)
		(layer "F.Cu")
		(net "TP_BMC_GPIOM5")
	)
	(segment
		(start 300.975776 -182.640224)
		(end 300.834806 -182.640224)
		(width 0.127)
		(layer "F.Cu")
		(net "TP_BMC_GPIOM5")
	)
	(segment
		(start 305.308 -182.88)
		(end 305.159918 -182.731918)
		(width 0.127)
		(layer "F.Cu")
		(net "TP_BMC_GPIOM5")
	)
	(segment
		(start 303.000918 -182.731918)
		(end 302.540924 -182.271924)
		(width 0.127)
		(layer "F.Cu")
		(net "TP_BMC_GPIOM5")
	)
	(segment
		(start 298.008548 -180.688488)
		(end 298.008548 -180.624226)
		(width 0.127)
		(layer "F.Cu")
		(net "TP_BMC_GPIOM7")
	)
	(segment
		(start 298.43476 -181.040024)
		(end 298.360084 -181.040024)
		(width 0.127)
		(layer "F.Cu")
		(net "TP_BMC_GPIOM7")
	)
	(segment
		(start 298.360084 -181.040024)
		(end 298.008548 -180.688488)
		(width 0.127)
		(layer "F.Cu")
		(net "TP_BMC_GPIOM7")
	)
	(via
		(at 298.008548 -180.624226)
		(size 0.508)
		(drill 0.254)
		(layers "F.Cu" "B.Cu")
		(net "TP_BMC_GPIOM7")
	)
	(segment
		(start 297.18 -180.54066)
		(end 297.263566 -180.624226)
		(width 0.127)
		(layer "B.Cu")
		(net "TP_BMC_GPIOM7")
	)
	(segment
		(start 297.263566 -180.624226)
		(end 298.008548 -180.624226)
		(width 0.127)
		(layer "B.Cu")
		(net "TP_BMC_GPIOM7")
	)
	(segment
		(start 299.23486 -181.040024)
		(end 299.23486 -181.030626)
		(width 0.127)
		(layer "F.Cu")
		(net "TP_BMC_GPIOM3")
	)
	(segment
		(start 299.23486 -181.030626)
		(end 298.83481 -180.630576)
		(width 0.127)
		(layer "F.Cu")
		(net "TP_BMC_GPIOM3")
	)
	(via
		(at 298.83481 -180.630576)
		(size 0.508)
		(drill 0.254)
		(layers "F.Cu" "B.Cu")
		(net "TP_BMC_GPIOM3")
	)
	(segment
		(start 298.83481 -180.68163)
		(end 298.83481 -180.630576)
		(width 0.1016)
		(layer "B.Cu")
		(net "TP_BMC_GPIOM3")
	)
	(segment
		(start 299.238162 -181.084982)
		(end 298.83481 -180.68163)
		(width 0.1016)
		(layer "B.Cu")
		(net "TP_BMC_GPIOM3")
	)
	(segment
		(start 299.238162 -181.874922)
		(end 299.238162 -181.084982)
		(width 0.1016)
		(layer "B.Cu")
		(net "TP_BMC_GPIOM3")
	)
	(segment
		(start 299.77334 -182.4101)
		(end 299.238162 -181.874922)
		(width 0.1016)
		(layer "B.Cu")
		(net "TP_BMC_GPIOM3")
	)
	(segment
		(start 316.992 -151.892)
		(end 315.9125 -151.892)
		(width 0.1143)
		(layer "F.Cu")
		(net "RTC_I2C_SDA")
	)
	(segment
		(start 318.77 -151.892)
		(end 316.992 -151.892)
		(width 0.1143)
		(layer "F.Cu")
		(net "RTC_I2C_SDA")
	)
	(via
		(at 316.992 -151.892)
		(size 0.7112)
		(drill 0.3556)
		(layers "F.Cu" "B.Cu")
		(net "RTC_I2C_SDA")
	)
	(segment
		(start 316.992 -150.622)
		(end 315.9125 -150.622)
		(width 0.1143)
		(layer "F.Cu")
		(net "RTC_I2C_SCL")
	)
	(segment
		(start 318.77 -150.622)
		(end 316.992 -150.622)
		(width 0.1143)
		(layer "F.Cu")
		(net "RTC_I2C_SCL")
	)
	(via
		(at 316.992 -150.622)
		(size 0.7112)
		(drill 0.3556)
		(layers "F.Cu" "B.Cu")
		(net "RTC_I2C_SCL")
	)
	(segment
		(start 307.648864 -205.541372)
		(end 307.648864 -206.937864)
		(width 0.1143)
		(layer "F.Cu")
		(net "BMC_I2C_A_SDA")
	)
	(segment
		(start 55.8165 -210.6295)
		(end 54.6735 -211.7725)
		(width 0.1143)
		(layer "F.Cu")
		(net "BMC_I2C_A_SDA")
	)
	(segment
		(start 290.1315 -68.707)
		(end 291.846 -68.707)
		(width 0.1143)
		(layer "F.Cu")
		(net "BMC_I2C_A_SDA")
	)
	(segment
		(start 307.648864 -206.937864)
		(end 310.642 -209.931)
		(width 0.1143)
		(layer "F.Cu")
		(net "BMC_I2C_A_SDA")
	)
	(segment
		(start 315.0235 -152.4)
		(end 315.9125 -153.289)
		(width 0.1143)
		(layer "F.Cu")
		(net "BMC_I2C_A_SDA")
	)
	(segment
		(start 315.9125 -153.289)
		(end 324.739 -153.289)
		(width 0.1143)
		(layer "F.Cu")
		(net "BMC_I2C_A_SDA")
	)
	(segment
		(start 55.88 -210.6295)
		(end 55.8165 -210.6295)
		(width 0.1143)
		(layer "F.Cu")
		(net "BMC_I2C_A_SDA")
	)
	(segment
		(start 315.0235 -151.892)
		(end 315.0235 -152.4)
		(width 0.1143)
		(layer "F.Cu")
		(net "BMC_I2C_A_SDA")
	)
	(segment
		(start 334.391 -211.8995)
		(end 334.391 -213.106)
		(width 0.1143)
		(layer "F.Cu")
		(net "BMC_I2C_A_SDA")
	)
	(segment
		(start 333.375 -216.916)
		(end 333.375 -216.154)
		(width 0.1143)
		(layer "F.Cu")
		(net "BMC_I2C_A_SDA")
	)
	(segment
		(start 292.5572 -67.9958)
		(end 293.0398 -67.9958)
		(width 0.1143)
		(layer "F.Cu")
		(net "BMC_I2C_A_SDA")
	)
	(segment
		(start 39.243 -205.105)
		(end 39.243 -206.375)
		(width 0.1143)
		(layer "F.Cu")
		(net "BMC_I2C_A_SDA")
	)
	(segment
		(start 333.375 -216.154)
		(end 333.248 -216.027)
		(width 0.1143)
		(layer "F.Cu")
		(net "BMC_I2C_A_SDA")
	)
	(segment
		(start 37.26688 -203.12888)
		(end 39.243 -205.105)
		(width 0.1143)
		(layer "F.Cu")
		(net "BMC_I2C_A_SDA")
	)
	(segment
		(start 35.827716 -203.12888)
		(end 37.26688 -203.12888)
		(width 0.1143)
		(layer "F.Cu")
		(net "BMC_I2C_A_SDA")
	)
	(segment
		(start 291.846 -68.707)
		(end 292.5572 -67.9958)
		(width 0.1143)
		(layer "F.Cu")
		(net "BMC_I2C_A_SDA")
	)
	(via
		(at 310.642 -209.931)
		(size 0.5588)
		(drill 0.3048)
		(layers "F.Cu" "B.Cu")
		(net "BMC_I2C_A_SDA")
	)
	(via
		(at 333.248 -216.027)
		(size 0.5588)
		(drill 0.3048)
		(layers "F.Cu" "B.Cu")
		(net "BMC_I2C_A_SDA")
	)
	(via
		(at 39.243 -206.375)
		(size 0.5588)
		(drill 0.3048)
		(layers "F.Cu" "B.Cu")
		(net "BMC_I2C_A_SDA")
	)
	(via
		(at 293.0398 -67.9958)
		(size 0.5588)
		(drill 0.3048)
		(layers "F.Cu" "B.Cu")
		(net "BMC_I2C_A_SDA")
	)
	(via
		(at 54.6735 -211.7725)
		(size 0.5588)
		(drill 0.3048)
		(layers "F.Cu" "B.Cu")
		(net "BMC_I2C_A_SDA")
	)
	(via
		(at 324.739 -153.289)
		(size 0.5588)
		(drill 0.3048)
		(layers "F.Cu" "B.Cu")
		(net "BMC_I2C_A_SDA")
	)
	(via
		(at 324.07479 -170.31335)
		(size 0.5588)
		(drill 0.3048)
		(layers "F.Cu" "B.Cu")
		(net "BMC_I2C_A_SDA")
	)
	(via
		(at 334.391 -213.106)
		(size 0.5588)
		(drill 0.3048)
		(layers "F.Cu" "B.Cu")
		(net "BMC_I2C_A_SDA")
	)
	(via
		(at 324.612 -166.878)
		(size 0.7112)
		(drill 0.3556)
		(layers "F.Cu" "B.Cu")
		(net "BMC_I2C_A_SDA")
	)
	(segment
		(start 318.4525 -169.418)
		(end 319.4685 -169.545)
		(width 0.1143)
		(layer "B.Cu")
		(net "BMC_I2C_A_SDA")
	)
	(segment
		(start 324.46341 -153.56459)
		(end 324.739 -153.289)
		(width 0.1143)
		(layer "B.Cu")
		(net "BMC_I2C_A_SDA")
	)
	(segment
		(start 322.463668 -169.8752)
		(end 322.901818 -170.31335)
		(width 0.1143)
		(layer "B.Cu")
		(net "BMC_I2C_A_SDA")
	)
	(segment
		(start 324.612 -166.878)
		(end 324.993 -166.497)
		(width 0.1143)
		(layer "B.Cu")
		(net "BMC_I2C_A_SDA")
	)
	(segment
		(start 324.46341 -158.09341)
		(end 324.46341 -153.56459)
		(width 0.1143)
		(layer "B.Cu")
		(net "BMC_I2C_A_SDA")
	)
	(segment
		(start 324.07479 -170.31335)
		(end 324.07479 -167.41521)
		(width 0.1143)
		(layer "B.Cu")
		(net "BMC_I2C_A_SDA")
	)
	(segment
		(start 322.901818 -170.31335)
		(end 324.07479 -170.31335)
		(width 0.1143)
		(layer "B.Cu")
		(net "BMC_I2C_A_SDA")
	)
	(segment
		(start 319.4685 -169.545)
		(end 319.4685 -169.455084)
		(width 0.1143)
		(layer "B.Cu")
		(net "BMC_I2C_A_SDA")
	)
	(segment
		(start 320.070734 -168.85285)
		(end 320.644266 -168.85285)
		(width 0.1143)
		(layer "B.Cu")
		(net "BMC_I2C_A_SDA")
	)
	(segment
		(start 324.993 -166.497)
		(end 324.993 -158.623)
		(width 0.1143)
		(layer "B.Cu")
		(net "BMC_I2C_A_SDA")
	)
	(segment
		(start 324.993 -158.623)
		(end 324.46341 -158.09341)
		(width 0.1143)
		(layer "B.Cu")
		(net "BMC_I2C_A_SDA")
	)
	(segment
		(start 324.07479 -167.41521)
		(end 324.612 -166.878)
		(width 0.1143)
		(layer "B.Cu")
		(net "BMC_I2C_A_SDA")
	)
	(segment
		(start 321.666616 -169.8752)
		(end 322.463668 -169.8752)
		(width 0.1143)
		(layer "B.Cu")
		(net "BMC_I2C_A_SDA")
	)
	(segment
		(start 319.4685 -169.455084)
		(end 320.070734 -168.85285)
		(width 0.1143)
		(layer "B.Cu")
		(net "BMC_I2C_A_SDA")
	)
	(segment
		(start 320.644266 -168.85285)
		(end 321.666616 -169.8752)
		(width 0.1143)
		(layer "B.Cu")
		(net "BMC_I2C_A_SDA")
	)
	(segment
		(start 64.5287 -211.7217)
		(end 68.4784 -215.6714)
		(width 0.127)
		(layer "In2.Cu")
		(net "BMC_I2C_A_SDA")
	)
	(segment
		(start 328.549 -143.259302)
		(end 328.549 -140.482828)
		(width 0.127)
		(layer "In2.Cu")
		(net "BMC_I2C_A_SDA")
	)
	(segment
		(start 323.806566 -215.519)
		(end 332.74 -215.519)
		(width 0.127)
		(layer "In2.Cu")
		(net "BMC_I2C_A_SDA")
	)
	(segment
		(start 322.66636 -200.262236)
		(end 313.948064 -208.980532)
		(width 0.127)
		(layer "In2.Cu")
		(net "BMC_I2C_A_SDA")
	)
	(segment
		(start 301.244 -88.773)
		(end 300.355 -87.884)
		(width 0.127)
		(layer "In2.Cu")
		(net "BMC_I2C_A_SDA")
	)
	(segment
		(start 54.6735 -211.7725)
		(end 54.356 -212.09)
		(width 0.127)
		(layer "In2.Cu")
		(net "BMC_I2C_A_SDA")
	)
	(segment
		(start 175.3743 -220.8403)
		(end 181.561232 -220.8403)
		(width 0.127)
		(layer "In2.Cu")
		(net "BMC_I2C_A_SDA")
	)
	(segment
		(start 63.4238 -211.7852)
		(end 63.4873 -211.7217)
		(width 0.127)
		(layer "In2.Cu")
		(net "BMC_I2C_A_SDA")
	)
	(segment
		(start 205.243176 -220.8403)
		(end 234.262676 -191.8208)
		(width 0.127)
		(layer "In2.Cu")
		(net "BMC_I2C_A_SDA")
	)
	(segment
		(start 41.783 -206.375)
		(end 39.243 -206.375)
		(width 0.127)
		(layer "In2.Cu")
		(net "BMC_I2C_A_SDA")
	)
	(segment
		(start 293.116 -68.072)
		(end 293.0398 -67.9958)
		(width 0.127)
		(layer "In2.Cu")
		(net "BMC_I2C_A_SDA")
	)
	(segment
		(start 311.592468 -208.980532)
		(end 310.642 -209.931)
		(width 0.127)
		(layer "In2.Cu")
		(net "BMC_I2C_A_SDA")
	)
	(segment
		(start 63.4873 -211.7217)
		(end 64.5287 -211.7217)
		(width 0.127)
		(layer "In2.Cu")
		(net "BMC_I2C_A_SDA")
	)
	(segment
		(start 106.045 -220.98)
		(end 127.114046 -220.98)
		(width 0.127)
		(layer "In2.Cu")
		(net "BMC_I2C_A_SDA")
	)
	(segment
		(start 275.88845 -242.195604)
		(end 275.888704 -242.19535)
		(width 0.127)
		(layer "In2.Cu")
		(net "BMC_I2C_A_SDA")
	)
	(segment
		(start 324.739 -153.289)
		(end 326.727566 -153.289)
		(width 0.127)
		(layer "In2.Cu")
		(net "BMC_I2C_A_SDA")
	)
	(segment
		(start 297.130216 -242.19535)
		(end 323.806566 -215.519)
		(width 0.127)
		(layer "In2.Cu")
		(net "BMC_I2C_A_SDA")
	)
	(segment
		(start 309.372 -123.019566)
		(end 299.8597 -113.507266)
		(width 0.127)
		(layer "In2.Cu")
		(net "BMC_I2C_A_SDA")
	)
	(segment
		(start 188.914532 -220.8403)
		(end 205.243176 -220.8403)
		(width 0.127)
		(layer "In2.Cu")
		(net "BMC_I2C_A_SDA")
	)
	(segment
		(start 322.66636 -175.80864)
		(end 322.66636 -200.262236)
		(width 0.127)
		(layer "In2.Cu")
		(net "BMC_I2C_A_SDA")
	)
	(segment
		(start 309.372 -123.503436)
		(end 309.372 -123.019566)
		(width 0.127)
		(layer "In2.Cu")
		(net "BMC_I2C_A_SDA")
	)
	(segment
		(start 329.692 -144.402302)
		(end 328.549 -143.259302)
		(width 0.127)
		(layer "In2.Cu")
		(net "BMC_I2C_A_SDA")
	)
	(segment
		(start 319.17259 -131.106418)
		(end 317.233046 -131.106418)
		(width 0.127)
		(layer "In2.Cu")
		(net "BMC_I2C_A_SDA")
	)
	(segment
		(start 234.262676 -191.8208)
		(end 251.411232 -191.8208)
		(width 0.127)
		(layer "In2.Cu")
		(net "BMC_I2C_A_SDA")
	)
	(segment
		(start 293.116 -72.517)
		(end 293.116 -68.072)
		(width 0.127)
		(layer "In2.Cu")
		(net "BMC_I2C_A_SDA")
	)
	(segment
		(start 54.356 -212.09)
		(end 47.498 -212.09)
		(width 0.127)
		(layer "In2.Cu")
		(net "BMC_I2C_A_SDA")
	)
	(segment
		(start 300.609 -95.885)
		(end 301.244 -95.25)
		(width 0.127)
		(layer "In2.Cu")
		(net "BMC_I2C_A_SDA")
	)
	(segment
		(start 54.6735 -211.7725)
		(end 54.6862 -211.7852)
		(width 0.127)
		(layer "In2.Cu")
		(net "BMC_I2C_A_SDA")
	)
	(segment
		(start 182.043832 -220.3577)
		(end 188.431932 -220.3577)
		(width 0.127)
		(layer "In2.Cu")
		(net "BMC_I2C_A_SDA")
	)
	(segment
		(start 333.248 -214.249)
		(end 334.391 -213.106)
		(width 0.127)
		(layer "In2.Cu")
		(net "BMC_I2C_A_SDA")
	)
	(segment
		(start 262.445754 -242.195604)
		(end 275.88845 -242.195604)
		(width 0.127)
		(layer "In2.Cu")
		(net "BMC_I2C_A_SDA")
	)
	(segment
		(start 172.7327 -218.1987)
		(end 175.3743 -220.8403)
		(width 0.127)
		(layer "In2.Cu")
		(net "BMC_I2C_A_SDA")
	)
	(segment
		(start 169.7863 -218.1987)
		(end 172.7327 -218.1987)
		(width 0.127)
		(layer "In2.Cu")
		(net "BMC_I2C_A_SDA")
	)
	(segment
		(start 127.114046 -220.98)
		(end 128.625346 -219.4687)
		(width 0.127)
		(layer "In2.Cu")
		(net "BMC_I2C_A_SDA")
	)
	(segment
		(start 275.888704 -242.19535)
		(end 297.130216 -242.19535)
		(width 0.127)
		(layer "In2.Cu")
		(net "BMC_I2C_A_SDA")
	)
	(segment
		(start 333.248 -216.027)
		(end 333.248 -214.249)
		(width 0.127)
		(layer "In2.Cu")
		(net "BMC_I2C_A_SDA")
	)
	(segment
		(start 47.498 -212.09)
		(end 41.783 -206.375)
		(width 0.127)
		(layer "In2.Cu")
		(net "BMC_I2C_A_SDA")
	)
	(segment
		(start 300.609 -102.362)
		(end 300.609 -95.885)
		(width 0.127)
		(layer "In2.Cu")
		(net "BMC_I2C_A_SDA")
	)
	(segment
		(start 251.411232 -191.8208)
		(end 254.7493 -195.158868)
		(width 0.127)
		(layer "In2.Cu")
		(net "BMC_I2C_A_SDA")
	)
	(segment
		(start 313.948064 -208.980532)
		(end 311.592468 -208.980532)
		(width 0.127)
		(layer "In2.Cu")
		(net "BMC_I2C_A_SDA")
	)
	(segment
		(start 312.931048 -127.062484)
		(end 309.372 -123.503436)
		(width 0.127)
		(layer "In2.Cu")
		(net "BMC_I2C_A_SDA")
	)
	(segment
		(start 188.431932 -220.3577)
		(end 188.914532 -220.8403)
		(width 0.127)
		(layer "In2.Cu")
		(net "BMC_I2C_A_SDA")
	)
	(segment
		(start 328.549 -140.482828)
		(end 319.17259 -131.106418)
		(width 0.127)
		(layer "In2.Cu")
		(net "BMC_I2C_A_SDA")
	)
	(segment
		(start 181.561232 -220.8403)
		(end 182.043832 -220.3577)
		(width 0.127)
		(layer "In2.Cu")
		(net "BMC_I2C_A_SDA")
	)
	(segment
		(start 254.7493 -195.158868)
		(end 254.7493 -219.8497)
		(width 0.127)
		(layer "In2.Cu")
		(net "BMC_I2C_A_SDA")
	)
	(segment
		(start 329.692 -150.324566)
		(end 329.692 -144.402302)
		(width 0.127)
		(layer "In2.Cu")
		(net "BMC_I2C_A_SDA")
	)
	(segment
		(start 324.07479 -170.31335)
		(end 324.07479 -174.40021)
		(width 0.127)
		(layer "In2.Cu")
		(net "BMC_I2C_A_SDA")
	)
	(segment
		(start 100.7364 -215.6714)
		(end 106.045 -220.98)
		(width 0.127)
		(layer "In2.Cu")
		(net "BMC_I2C_A_SDA")
	)
	(segment
		(start 326.727566 -153.289)
		(end 329.692 -150.324566)
		(width 0.127)
		(layer "In2.Cu")
		(net "BMC_I2C_A_SDA")
	)
	(segment
		(start 324.07479 -174.40021)
		(end 322.66636 -175.80864)
		(width 0.127)
		(layer "In2.Cu")
		(net "BMC_I2C_A_SDA")
	)
	(segment
		(start 254.020828 -220.578172)
		(end 254.020828 -233.770678)
		(width 0.127)
		(layer "In2.Cu")
		(net "BMC_I2C_A_SDA")
	)
	(segment
		(start 300.355 -87.884)
		(end 300.355 -79.756)
		(width 0.127)
		(layer "In2.Cu")
		(net "BMC_I2C_A_SDA")
	)
	(segment
		(start 128.625346 -219.4687)
		(end 168.5163 -219.4687)
		(width 0.127)
		(layer "In2.Cu")
		(net "BMC_I2C_A_SDA")
	)
	(segment
		(start 68.4784 -215.6714)
		(end 100.7364 -215.6714)
		(width 0.127)
		(layer "In2.Cu")
		(net "BMC_I2C_A_SDA")
	)
	(segment
		(start 317.233046 -131.106418)
		(end 313.189112 -127.062484)
		(width 0.127)
		(layer "In2.Cu")
		(net "BMC_I2C_A_SDA")
	)
	(segment
		(start 254.020828 -233.770678)
		(end 262.445754 -242.195604)
		(width 0.127)
		(layer "In2.Cu")
		(net "BMC_I2C_A_SDA")
	)
	(segment
		(start 301.244 -95.25)
		(end 301.244 -88.773)
		(width 0.127)
		(layer "In2.Cu")
		(net "BMC_I2C_A_SDA")
	)
	(segment
		(start 300.355 -79.756)
		(end 293.116 -72.517)
		(width 0.127)
		(layer "In2.Cu")
		(net "BMC_I2C_A_SDA")
	)
	(segment
		(start 54.6862 -211.7852)
		(end 63.4238 -211.7852)
		(width 0.127)
		(layer "In2.Cu")
		(net "BMC_I2C_A_SDA")
	)
	(segment
		(start 299.8597 -113.507266)
		(end 299.8597 -103.1113)
		(width 0.127)
		(layer "In2.Cu")
		(net "BMC_I2C_A_SDA")
	)
	(segment
		(start 254.7493 -219.8497)
		(end 254.020828 -220.578172)
		(width 0.127)
		(layer "In2.Cu")
		(net "BMC_I2C_A_SDA")
	)
	(segment
		(start 168.5163 -219.4687)
		(end 169.7863 -218.1987)
		(width 0.127)
		(layer "In2.Cu")
		(net "BMC_I2C_A_SDA")
	)
	(segment
		(start 332.74 -215.519)
		(end 333.248 -216.027)
		(width 0.127)
		(layer "In2.Cu")
		(net "BMC_I2C_A_SDA")
	)
	(segment
		(start 313.189112 -127.062484)
		(end 312.931048 -127.062484)
		(width 0.127)
		(layer "In2.Cu")
		(net "BMC_I2C_A_SDA")
	)
	(segment
		(start 299.8597 -103.1113)
		(end 300.609 -102.362)
		(width 0.127)
		(layer "In2.Cu")
		(net "BMC_I2C_A_SDA")
	)
	(segment
		(start 311.15 -209.931)
		(end 310.642 -209.931)
		(width 0.127)
		(layer "In5.Cu")
		(net "BMC_I2C_A_SDA")
	)
	(segment
		(start 333.459836 -214.037164)
		(end 315.256164 -214.037164)
		(width 0.127)
		(layer "In5.Cu")
		(net "BMC_I2C_A_SDA")
	)
	(segment
		(start 334.391 -213.106)
		(end 333.459836 -214.037164)
		(width 0.127)
		(layer "In5.Cu")
		(net "BMC_I2C_A_SDA")
	)
	(segment
		(start 315.256164 -214.037164)
		(end 311.15 -209.931)
		(width 0.127)
		(layer "In5.Cu")
		(net "BMC_I2C_A_SDA")
	)
	(segment
		(start 290.1315 -66.675)
		(end 292.1 -66.675)
		(width 0.1143)
		(layer "F.Cu")
		(net "BMC_I2C_A_SCL")
	)
	(segment
		(start 336.804 -216.916)
		(end 336.804 -216.281)
		(width 0.1143)
		(layer "F.Cu")
		(net "BMC_I2C_A_SCL")
	)
	(segment
		(start 314.5282 -153.049732)
		(end 315.402468 -153.924)
		(width 0.1143)
		(layer "F.Cu")
		(net "BMC_I2C_A_SCL")
	)
	(segment
		(start 336.804 -216.281)
		(end 333.375 -212.852)
		(width 0.1143)
		(layer "F.Cu")
		(net "BMC_I2C_A_SCL")
	)
	(segment
		(start 315.0235 -150.622)
		(end 314.706 -150.622)
		(width 0.1143)
		(layer "F.Cu")
		(net "BMC_I2C_A_SCL")
	)
	(segment
		(start 314.5282 -150.7998)
		(end 314.5282 -153.049732)
		(width 0.1143)
		(layer "F.Cu")
		(net "BMC_I2C_A_SCL")
	)
	(segment
		(start 292.354 -66.929)
		(end 292.354 -67.183)
		(width 0.1143)
		(layer "F.Cu")
		(net "BMC_I2C_A_SCL")
	)
	(segment
		(start 315.402468 -153.924)
		(end 323.723 -153.924)
		(width 0.1143)
		(layer "F.Cu")
		(net "BMC_I2C_A_SCL")
	)
	(segment
		(start 292.1 -66.675)
		(end 292.354 -66.929)
		(width 0.1143)
		(layer "F.Cu")
		(net "BMC_I2C_A_SCL")
	)
	(segment
		(start 309.752492 -206.502)
		(end 311.785 -206.502)
		(width 0.1143)
		(layer "F.Cu")
		(net "BMC_I2C_A_SCL")
	)
	(segment
		(start 333.375 -212.852)
		(end 333.375 -211.8995)
		(width 0.1143)
		(layer "F.Cu")
		(net "BMC_I2C_A_SCL")
	)
	(segment
		(start 35.827716 -206.43088)
		(end 38.27272 -206.43088)
		(width 0.1143)
		(layer "F.Cu")
		(net "BMC_I2C_A_SCL")
	)
	(segment
		(start 58.928 -210.6295)
		(end 58.928 -209.55)
		(width 0.1143)
		(layer "F.Cu")
		(net "BMC_I2C_A_SCL")
	)
	(segment
		(start 308.791864 -205.541372)
		(end 309.752492 -206.502)
		(width 0.1143)
		(layer "F.Cu")
		(net "BMC_I2C_A_SCL")
	)
	(segment
		(start 38.27272 -206.43088)
		(end 38.3286 -206.375)
		(width 0.1143)
		(layer "F.Cu")
		(net "BMC_I2C_A_SCL")
	)
	(segment
		(start 311.785 -206.502)
		(end 313.755532 -208.472532)
		(width 0.1143)
		(layer "F.Cu")
		(net "BMC_I2C_A_SCL")
	)
	(segment
		(start 314.706 -150.622)
		(end 314.5282 -150.7998)
		(width 0.1143)
		(layer "F.Cu")
		(net "BMC_I2C_A_SCL")
	)
	(via
		(at 323.520308 -169.586148)
		(size 0.5588)
		(drill 0.3048)
		(layers "F.Cu" "B.Cu")
		(net "BMC_I2C_A_SCL")
	)
	(via
		(at 333.375 -212.852)
		(size 0.5588)
		(drill 0.3048)
		(layers "F.Cu" "B.Cu")
		(net "BMC_I2C_A_SCL")
	)
	(via
		(at 313.755532 -208.472532)
		(size 0.5588)
		(drill 0.3048)
		(layers "F.Cu" "B.Cu")
		(net "BMC_I2C_A_SCL")
	)
	(via
		(at 38.3286 -206.375)
		(size 0.5588)
		(drill 0.3048)
		(layers "F.Cu" "B.Cu")
		(net "BMC_I2C_A_SCL")
	)
	(via
		(at 58.928 -209.55)
		(size 0.5588)
		(drill 0.3048)
		(layers "F.Cu" "B.Cu")
		(net "BMC_I2C_A_SCL")
	)
	(via
		(at 292.354 -67.183)
		(size 0.5588)
		(drill 0.3048)
		(layers "F.Cu" "B.Cu")
		(net "BMC_I2C_A_SCL")
	)
	(via
		(at 323.977 -164.338)
		(size 0.7112)
		(drill 0.3556)
		(layers "F.Cu" "B.Cu")
		(net "BMC_I2C_A_SCL")
	)
	(via
		(at 323.723 -153.924)
		(size 0.5588)
		(drill 0.3048)
		(layers "F.Cu" "B.Cu")
		(net "BMC_I2C_A_SCL")
	)
	(segment
		(start 319.4685 -167.894)
		(end 319.703958 -168.129458)
		(width 0.1143)
		(layer "B.Cu")
		(net "BMC_I2C_A_SCL")
	)
	(segment
		(start 319.703958 -168.139618)
		(end 319.92189 -168.35755)
		(width 0.1143)
		(layer "B.Cu")
		(net "BMC_I2C_A_SCL")
	)
	(segment
		(start 323.520308 -164.794692)
		(end 323.977 -164.338)
		(width 0.1143)
		(layer "B.Cu")
		(net "BMC_I2C_A_SCL")
	)
	(segment
		(start 321.021202 -168.528746)
		(end 322.462906 -168.528746)
		(width 0.1143)
		(layer "B.Cu")
		(net "BMC_I2C_A_SCL")
	)
	(segment
		(start 319.92189 -168.35755)
		(end 320.850006 -168.35755)
		(width 0.1143)
		(layer "B.Cu")
		(net "BMC_I2C_A_SCL")
	)
	(segment
		(start 320.850006 -168.35755)
		(end 321.021202 -168.528746)
		(width 0.1143)
		(layer "B.Cu")
		(net "BMC_I2C_A_SCL")
	)
	(segment
		(start 322.462906 -168.528746)
		(end 323.520308 -169.586148)
		(width 0.1143)
		(layer "B.Cu")
		(net "BMC_I2C_A_SCL")
	)
	(segment
		(start 318.4525 -167.894)
		(end 319.4685 -167.894)
		(width 0.1143)
		(layer "B.Cu")
		(net "BMC_I2C_A_SCL")
	)
	(segment
		(start 324.485 -158.833566)
		(end 323.723 -158.071566)
		(width 0.1143)
		(layer "B.Cu")
		(net "BMC_I2C_A_SCL")
	)
	(segment
		(start 323.520308 -169.586148)
		(end 323.520308 -164.794692)
		(width 0.1143)
		(layer "B.Cu")
		(net "BMC_I2C_A_SCL")
	)
	(segment
		(start 319.703958 -168.129458)
		(end 319.703958 -168.139618)
		(width 0.1143)
		(layer "B.Cu")
		(net "BMC_I2C_A_SCL")
	)
	(segment
		(start 323.977 -164.338)
		(end 324.485 -163.83)
		(width 0.1143)
		(layer "B.Cu")
		(net "BMC_I2C_A_SCL")
	)
	(segment
		(start 323.723 -158.071566)
		(end 323.723 -153.924)
		(width 0.1143)
		(layer "B.Cu")
		(net "BMC_I2C_A_SCL")
	)
	(segment
		(start 324.485 -163.83)
		(end 324.485 -158.833566)
		(width 0.1143)
		(layer "B.Cu")
		(net "BMC_I2C_A_SCL")
	)
	(segment
		(start 300.863 -79.387954)
		(end 300.863 -87.63)
		(width 0.127)
		(layer "In2.Cu")
		(net "BMC_I2C_A_SCL")
	)
	(segment
		(start 331.47 -214.757)
		(end 333.375 -212.852)
		(width 0.127)
		(layer "In2.Cu")
		(net "BMC_I2C_A_SCL")
	)
	(segment
		(start 323.520308 -169.586148)
		(end 323.520308 -173.430692)
		(width 0.127)
		(layer "In2.Cu")
		(net "BMC_I2C_A_SCL")
	)
	(segment
		(start 313.746388 -208.463388)
		(end 313.755532 -208.472532)
		(width 0.127)
		(layer "In2.Cu")
		(net "BMC_I2C_A_SCL")
	)
	(segment
		(start 54.450234 -211.2772)
		(end 54.412134 -211.3153)
		(width 0.127)
		(layer "In2.Cu")
		(net "BMC_I2C_A_SCL")
	)
	(segment
		(start 313.625484 -126.78029)
		(end 317.443612 -130.598418)
		(width 0.127)
		(layer "In2.Cu")
		(net "BMC_I2C_A_SCL")
	)
	(segment
		(start 301.752 -88.519)
		(end 301.752 -95.631)
		(width 0.127)
		(layer "In2.Cu")
		(net "BMC_I2C_A_SCL")
	)
	(segment
		(start 321.4497 -197.660768)
		(end 321.4497 -200.759822)
		(width 0.127)
		(layer "In2.Cu")
		(net "BMC_I2C_A_SCL")
	)
	(segment
		(start 168.305734 -218.9607)
		(end 169.575734 -217.6907)
		(width 0.127)
		(layer "In2.Cu")
		(net "BMC_I2C_A_SCL")
	)
	(segment
		(start 204.328268 -219.4052)
		(end 205.95971 -219.4052)
		(width 0.127)
		(layer "In2.Cu")
		(net "BMC_I2C_A_SCL")
	)
	(segment
		(start 262.65632 -241.687604)
		(end 274.948396 -241.687604)
		(width 0.127)
		(layer "In2.Cu")
		(net "BMC_I2C_A_SCL")
	)
	(segment
		(start 274.948396 -241.687604)
		(end 275.082 -241.554)
		(width 0.127)
		(layer "In2.Cu")
		(net "BMC_I2C_A_SCL")
	)
	(segment
		(start 317.443612 -130.598418)
		(end 319.383156 -130.598418)
		(width 0.127)
		(layer "In2.Cu")
		(net "BMC_I2C_A_SCL")
	)
	(segment
		(start 313.625484 -126.554484)
		(end 313.625484 -126.78029)
		(width 0.127)
		(layer "In2.Cu")
		(net "BMC_I2C_A_SCL")
	)
	(segment
		(start 100.965 -215.011)
		(end 104.9147 -218.9607)
		(width 0.127)
		(layer "In2.Cu")
		(net "BMC_I2C_A_SCL")
	)
	(segment
		(start 293.9034 -72.428354)
		(end 300.863 -79.387954)
		(width 0.127)
		(layer "In2.Cu")
		(net "BMC_I2C_A_SCL")
	)
	(segment
		(start 330.2 -144.191736)
		(end 330.2 -150.535132)
		(width 0.127)
		(layer "In2.Cu")
		(net "BMC_I2C_A_SCL")
	)
	(segment
		(start 254.528828 -220.832172)
		(end 254.528828 -233.560112)
		(width 0.127)
		(layer "In2.Cu")
		(net "BMC_I2C_A_SCL")
	)
	(segment
		(start 47.4853 -211.3153)
		(end 42.037 -205.867)
		(width 0.127)
		(layer "In2.Cu")
		(net "BMC_I2C_A_SCL")
	)
	(segment
		(start 54.412134 -211.3153)
		(end 47.4853 -211.3153)
		(width 0.127)
		(layer "In2.Cu")
		(net "BMC_I2C_A_SCL")
	)
	(segment
		(start 329.057 -140.272262)
		(end 329.057 -143.048736)
		(width 0.127)
		(layer "In2.Cu")
		(net "BMC_I2C_A_SCL")
	)
	(segment
		(start 322.072 -174.879)
		(end 322.072 -197.038468)
		(width 0.127)
		(layer "In2.Cu")
		(net "BMC_I2C_A_SCL")
	)
	(segment
		(start 68.58 -215.011)
		(end 100.965 -215.011)
		(width 0.127)
		(layer "In2.Cu")
		(net "BMC_I2C_A_SCL")
	)
	(segment
		(start 330.2 -150.535132)
		(end 326.811132 -153.924)
		(width 0.127)
		(layer "In2.Cu")
		(net "BMC_I2C_A_SCL")
	)
	(segment
		(start 319.383156 -130.598418)
		(end 329.057 -140.272262)
		(width 0.127)
		(layer "In2.Cu")
		(net "BMC_I2C_A_SCL")
	)
	(segment
		(start 251.621798 -191.3128)
		(end 255.2573 -194.948302)
		(width 0.127)
		(layer "In2.Cu")
		(net "BMC_I2C_A_SCL")
	)
	(segment
		(start 109.191298 -218.9099)
		(end 109.643926 -218.9099)
		(width 0.127)
		(layer "In2.Cu")
		(net "BMC_I2C_A_SCL")
	)
	(segment
		(start 58.928 -209.55)
		(end 57.2008 -211.2772)
		(width 0.127)
		(layer "In2.Cu")
		(net "BMC_I2C_A_SCL")
	)
	(segment
		(start 321.4497 -200.759822)
		(end 313.746388 -208.463388)
		(width 0.127)
		(layer "In2.Cu")
		(net "BMC_I2C_A_SCL")
	)
	(segment
		(start 323.520308 -173.430692)
		(end 322.072 -174.879)
		(width 0.127)
		(layer "In2.Cu")
		(net "BMC_I2C_A_SCL")
	)
	(segment
		(start 169.575734 -217.6907)
		(end 178.255168 -217.6907)
		(width 0.127)
		(layer "In2.Cu")
		(net "BMC_I2C_A_SCL")
	)
	(segment
		(start 255.2573 -194.948302)
		(end 255.2573 -220.1037)
		(width 0.127)
		(layer "In2.Cu")
		(net "BMC_I2C_A_SCL")
	)
	(segment
		(start 301.752 -95.631)
		(end 301.1297 -96.2533)
		(width 0.127)
		(layer "In2.Cu")
		(net "BMC_I2C_A_SCL")
	)
	(segment
		(start 104.9147 -218.9607)
		(end 109.140498 -218.9607)
		(width 0.127)
		(layer "In2.Cu")
		(net "BMC_I2C_A_SCL")
	)
	(segment
		(start 109.643926 -218.9099)
		(end 109.694726 -218.9607)
		(width 0.127)
		(layer "In2.Cu")
		(net "BMC_I2C_A_SCL")
	)
	(segment
		(start 301.1297 -96.2533)
		(end 301.1297 -114.0587)
		(width 0.127)
		(layer "In2.Cu")
		(net "BMC_I2C_A_SCL")
	)
	(segment
		(start 301.1297 -114.0587)
		(end 313.625484 -126.554484)
		(width 0.127)
		(layer "In2.Cu")
		(net "BMC_I2C_A_SCL")
	)
	(segment
		(start 255.2573 -220.1037)
		(end 254.528828 -220.832172)
		(width 0.127)
		(layer "In2.Cu")
		(net "BMC_I2C_A_SCL")
	)
	(segment
		(start 62.4713 -211.1883)
		(end 64.7573 -211.1883)
		(width 0.127)
		(layer "In2.Cu")
		(net "BMC_I2C_A_SCL")
	)
	(segment
		(start 60.833 -209.55)
		(end 62.4713 -211.1883)
		(width 0.127)
		(layer "In2.Cu")
		(net "BMC_I2C_A_SCL")
	)
	(segment
		(start 109.140498 -218.9607)
		(end 109.191298 -218.9099)
		(width 0.127)
		(layer "In2.Cu")
		(net "BMC_I2C_A_SCL")
	)
	(segment
		(start 254.528828 -233.560112)
		(end 262.65632 -241.687604)
		(width 0.127)
		(layer "In2.Cu")
		(net "BMC_I2C_A_SCL")
	)
	(segment
		(start 180.325268 -219.7608)
		(end 203.972668 -219.7608)
		(width 0.127)
		(layer "In2.Cu")
		(net "BMC_I2C_A_SCL")
	)
	(segment
		(start 292.354 -67.183)
		(end 293.1414 -67.183)
		(width 0.127)
		(layer "In2.Cu")
		(net "BMC_I2C_A_SCL")
	)
	(segment
		(start 323.85 -214.757)
		(end 331.47 -214.757)
		(width 0.127)
		(layer "In2.Cu")
		(net "BMC_I2C_A_SCL")
	)
	(segment
		(start 329.057 -143.048736)
		(end 330.2 -144.191736)
		(width 0.127)
		(layer "In2.Cu")
		(net "BMC_I2C_A_SCL")
	)
	(segment
		(start 203.972668 -219.7608)
		(end 204.328268 -219.4052)
		(width 0.127)
		(layer "In2.Cu")
		(net "BMC_I2C_A_SCL")
	)
	(segment
		(start 38.8366 -205.867)
		(end 38.3286 -206.375)
		(width 0.127)
		(layer "In2.Cu")
		(net "BMC_I2C_A_SCL")
	)
	(segment
		(start 234.05211 -191.3128)
		(end 251.621798 -191.3128)
		(width 0.127)
		(layer "In2.Cu")
		(net "BMC_I2C_A_SCL")
	)
	(segment
		(start 109.694726 -218.9607)
		(end 168.305734 -218.9607)
		(width 0.127)
		(layer "In2.Cu")
		(net "BMC_I2C_A_SCL")
	)
	(segment
		(start 275.082 -241.554)
		(end 297.053 -241.554)
		(width 0.127)
		(layer "In2.Cu")
		(net "BMC_I2C_A_SCL")
	)
	(segment
		(start 64.7573 -211.1883)
		(end 68.58 -215.011)
		(width 0.127)
		(layer "In2.Cu")
		(net "BMC_I2C_A_SCL")
	)
	(segment
		(start 293.9034 -67.945)
		(end 293.9034 -72.428354)
		(width 0.127)
		(layer "In2.Cu")
		(net "BMC_I2C_A_SCL")
	)
	(segment
		(start 297.053 -241.554)
		(end 323.85 -214.757)
		(width 0.127)
		(layer "In2.Cu")
		(net "BMC_I2C_A_SCL")
	)
	(segment
		(start 42.037 -205.867)
		(end 38.8366 -205.867)
		(width 0.127)
		(layer "In2.Cu")
		(net "BMC_I2C_A_SCL")
	)
	(segment
		(start 57.2008 -211.2772)
		(end 54.450234 -211.2772)
		(width 0.127)
		(layer "In2.Cu")
		(net "BMC_I2C_A_SCL")
	)
	(segment
		(start 300.863 -87.63)
		(end 301.752 -88.519)
		(width 0.127)
		(layer "In2.Cu")
		(net "BMC_I2C_A_SCL")
	)
	(segment
		(start 178.255168 -217.6907)
		(end 180.325268 -219.7608)
		(width 0.127)
		(layer "In2.Cu")
		(net "BMC_I2C_A_SCL")
	)
	(segment
		(start 326.811132 -153.924)
		(end 323.723 -153.924)
		(width 0.127)
		(layer "In2.Cu")
		(net "BMC_I2C_A_SCL")
	)
	(segment
		(start 205.95971 -219.4052)
		(end 234.05211 -191.3128)
		(width 0.127)
		(layer "In2.Cu")
		(net "BMC_I2C_A_SCL")
	)
	(segment
		(start 322.072 -197.038468)
		(end 321.4497 -197.660768)
		(width 0.127)
		(layer "In2.Cu")
		(net "BMC_I2C_A_SCL")
	)
	(segment
		(start 293.1414 -67.183)
		(end 293.9034 -67.945)
		(width 0.127)
		(layer "In2.Cu")
		(net "BMC_I2C_A_SCL")
	)
	(segment
		(start 58.928 -209.55)
		(end 60.833 -209.55)
		(width 0.127)
		(layer "In2.Cu")
		(net "BMC_I2C_A_SCL")
	)
	(segment
		(start 333.375 -212.852)
		(end 332.697836 -213.529164)
		(width 0.127)
		(layer "In5.Cu")
		(net "BMC_I2C_A_SCL")
	)
	(segment
		(start 313.755532 -209.894424)
		(end 313.755532 -208.472532)
		(width 0.127)
		(layer "In5.Cu")
		(net "BMC_I2C_A_SCL")
	)
	(segment
		(start 332.697836 -213.529164)
		(end 317.390272 -213.529164)
		(width 0.127)
		(layer "In5.Cu")
		(net "BMC_I2C_A_SCL")
	)
	(segment
		(start 317.390272 -213.529164)
		(end 313.755532 -209.894424)
		(width 0.127)
		(layer "In5.Cu")
		(net "BMC_I2C_A_SCL")
	)
	(segment
		(start 184.031128 -14.596364)
		(end 185.792364 -14.596364)
		(width 0.1143)
		(layer "F.Cu")
		(net "TEMP_1_A0")
	)
	(segment
		(start 186.14009 -14.26591)
		(end 185.801 -14.605)
		(width 0.1143)
		(layer "F.Cu")
		(net "TEMP_1_A0")
	)
	(segment
		(start 185.792364 -14.596364)
		(end 185.801 -14.605)
		(width 0.1143)
		(layer "F.Cu")
		(net "TEMP_1_A0")
	)
	(segment
		(start 182.888128 -14.596364)
		(end 184.031128 -14.596364)
		(width 0.1143)
		(layer "F.Cu")
		(net "TEMP_1_A0")
	)
	(segment
		(start 187.2488 -14.26591)
		(end 186.14009 -14.26591)
		(width 0.1143)
		(layer "F.Cu")
		(net "TEMP_1_A0")
	)
	(via
		(at 185.801 -14.605)
		(size 0.7112)
		(drill 0.3556)
		(layers "F.Cu" "B.Cu")
		(net "TEMP_1_A0")
	)
	(segment
		(start 185.928 -15.621)
		(end 185.039 -15.621)
		(width 0.127)
		(layer "F.Cu")
		(net "TEMP_1_A1")
	)
	(segment
		(start 185.039 -15.621)
		(end 184.920636 -15.739364)
		(width 0.127)
		(layer "F.Cu")
		(net "TEMP_1_A1")
	)
	(segment
		(start 184.031128 -15.739364)
		(end 182.888128 -15.739364)
		(width 0.127)
		(layer "F.Cu")
		(net "TEMP_1_A1")
	)
	(segment
		(start 184.920636 -15.739364)
		(end 184.031128 -15.739364)
		(width 0.127)
		(layer "F.Cu")
		(net "TEMP_1_A1")
	)
	(segment
		(start 186.63412 -14.91488)
		(end 185.928 -15.621)
		(width 0.127)
		(layer "F.Cu")
		(net "TEMP_1_A1")
	)
	(segment
		(start 187.2488 -14.91488)
		(end 186.63412 -14.91488)
		(width 0.127)
		(layer "F.Cu")
		(net "TEMP_1_A1")
	)
	(via
		(at 185.039 -15.621)
		(size 0.7112)
		(drill 0.3556)
		(layers "F.Cu" "B.Cu")
		(net "TEMP_1_A1")
	)
	(segment
		(start 191.20612 -14.91488)
		(end 191.77 -14.351)
		(width 0.1143)
		(layer "F.Cu")
		(net "TEMP_1_SDA")
	)
	(segment
		(start 189.9412 -14.91488)
		(end 191.20612 -14.91488)
		(width 0.1143)
		(layer "F.Cu")
		(net "TEMP_1_SDA")
	)
	(segment
		(start 191.77 -14.351)
		(end 192.024 -14.097)
		(width 0.1143)
		(layer "F.Cu")
		(net "TEMP_1_SDA")
	)
	(segment
		(start 192.7225 -14.097)
		(end 192.7225 -13.081)
		(width 0.1143)
		(layer "F.Cu")
		(net "TEMP_1_SDA")
	)
	(segment
		(start 192.024 -14.097)
		(end 192.7225 -14.097)
		(width 0.1143)
		(layer "F.Cu")
		(net "TEMP_1_SDA")
	)
	(via
		(at 191.77 -14.351)
		(size 0.7112)
		(drill 0.3556)
		(layers "F.Cu" "B.Cu")
		(net "TEMP_1_SDA")
	)
	(segment
		(start 191.46012 -15.56512)
		(end 191.643 -15.748)
		(width 0.1143)
		(layer "F.Cu")
		(net "TEMP_1_SCL")
	)
	(segment
		(start 192.024 -16.129)
		(end 191.643 -15.748)
		(width 0.1143)
		(layer "F.Cu")
		(net "TEMP_1_SCL")
	)
	(segment
		(start 192.7225 -15.113)
		(end 192.7225 -16.129)
		(width 0.1143)
		(layer "F.Cu")
		(net "TEMP_1_SCL")
	)
	(segment
		(start 192.7225 -16.129)
		(end 192.024 -16.129)
		(width 0.1143)
		(layer "F.Cu")
		(net "TEMP_1_SCL")
	)
	(segment
		(start 189.9412 -15.56512)
		(end 191.46012 -15.56512)
		(width 0.1143)
		(layer "F.Cu")
		(net "TEMP_1_SCL")
	)
	(via
		(at 191.643 -15.748)
		(size 0.7112)
		(drill 0.3556)
		(layers "F.Cu" "B.Cu")
		(net "TEMP_1_SCL")
	)
	(segment
		(start 261.874 -87.503)
		(end 261.874 -88.519)
		(width 0.1143)
		(layer "F.Cu")
		(net "BMC_I2C_D_SDA")
	)
	(segment
		(start 144.66697 -93.147388)
		(end 144.66697 -92.456)
		(width 0.1143)
		(layer "F.Cu")
		(net "BMC_I2C_D_SDA")
	)
	(segment
		(start 337.710526 -151.226774)
		(end 336.7913 -152.146)
		(width 0.1143)
		(layer "F.Cu")
		(net "BMC_I2C_D_SDA")
	)
	(segment
		(start 326.5678 -134.5438)
		(end 326.1106 -135.001)
		(width 0.1143)
		(layer "F.Cu")
		(net "BMC_I2C_D_SDA")
	)
	(segment
		(start 338.662518 -151.226774)
		(end 337.710526 -151.226774)
		(width 0.1143)
		(layer "F.Cu")
		(net "BMC_I2C_D_SDA")
	)
	(segment
		(start 143.415258 -94.3991)
		(end 144.66697 -93.147388)
		(width 0.1143)
		(layer "F.Cu")
		(net "BMC_I2C_D_SDA")
	)
	(segment
		(start 326.1106 -135.001)
		(end 317.881 -135.001)
		(width 0.1143)
		(layer "F.Cu")
		(net "BMC_I2C_D_SDA")
	)
	(segment
		(start 299.212 -91.5035)
		(end 299.212 -90.551)
		(width 0.1143)
		(layer "F.Cu")
		(net "BMC_I2C_D_SDA")
	)
	(segment
		(start 198.6915 -24.3205)
		(end 261.874 -87.503)
		(width 0.1143)
		(layer "F.Cu")
		(net "BMC_I2C_D_SDA")
	)
	(segment
		(start 193.6115 -13.081)
		(end 198.6915 -18.161)
		(width 0.1143)
		(layer "F.Cu")
		(net "BMC_I2C_D_SDA")
	)
	(segment
		(start 117.1575 -69.342)
		(end 117.1575 -67.48653)
		(width 0.1143)
		(layer "F.Cu")
		(net "BMC_I2C_D_SDA")
	)
	(segment
		(start 141.97457 -94.3991)
		(end 143.415258 -94.3991)
		(width 0.1143)
		(layer "F.Cu")
		(net "BMC_I2C_D_SDA")
	)
	(segment
		(start 198.6915 -18.161)
		(end 198.6915 -24.3205)
		(width 0.1143)
		(layer "F.Cu")
		(net "BMC_I2C_D_SDA")
	)
	(segment
		(start 117.1575 -67.48653)
		(end 116.59997 -66.929)
		(width 0.1143)
		(layer "F.Cu")
		(net "BMC_I2C_D_SDA")
	)
	(via
		(at 299.212 -90.551)
		(size 0.5588)
		(drill 0.3048)
		(layers "F.Cu" "B.Cu")
		(net "BMC_I2C_D_SDA")
	)
	(via
		(at 116.59997 -66.929)
		(size 0.5588)
		(drill 0.3048)
		(layers "F.Cu" "B.Cu")
		(net "BMC_I2C_D_SDA")
	)
	(via
		(at 261.874 -88.519)
		(size 0.5588)
		(drill 0.3048)
		(layers "F.Cu" "B.Cu")
		(net "BMC_I2C_D_SDA")
	)
	(via
		(at 144.66697 -92.456)
		(size 0.5588)
		(drill 0.3048)
		(layers "F.Cu" "B.Cu")
		(net "BMC_I2C_D_SDA")
	)
	(via
		(at 326.5678 -134.5438)
		(size 0.5588)
		(drill 0.3048)
		(layers "F.Cu" "B.Cu")
		(net "BMC_I2C_D_SDA")
	)
	(via
		(at 135.763 -75.057)
		(size 0.5588)
		(drill 0.3048)
		(layers "F.Cu" "B.Cu")
		(net "BMC_I2C_D_SDA")
	)
	(via
		(at 317.881 -135.001)
		(size 0.5588)
		(drill 0.3048)
		(layers "F.Cu" "B.Cu")
		(net "BMC_I2C_D_SDA")
	)
	(via
		(at 317.881 -136.144)
		(size 0.7112)
		(drill 0.3556)
		(layers "F.Cu" "B.Cu")
		(net "BMC_I2C_D_SDA")
	)
	(via
		(at 336.7913 -152.146)
		(size 0.5588)
		(drill 0.3048)
		(layers "F.Cu" "B.Cu")
		(net "BMC_I2C_D_SDA")
	)
	(segment
		(start 137.7442 -80.577182)
		(end 137.719816 -80.552798)
		(width 0.1143)
		(layer "B.Cu")
		(net "BMC_I2C_D_SDA")
	)
	(segment
		(start 318.21755 -138.00455)
		(end 317.881 -137.668)
		(width 0.1143)
		(layer "B.Cu")
		(net "BMC_I2C_D_SDA")
	)
	(segment
		(start 317.881 -137.668)
		(end 317.881 -136.144)
		(width 0.1143)
		(layer "B.Cu")
		(net "BMC_I2C_D_SDA")
	)
	(segment
		(start 319.4685 -165.354)
		(end 319.532 -165.354)
		(width 0.1143)
		(layer "B.Cu")
		(net "BMC_I2C_D_SDA")
	)
	(segment
		(start 321.988942 -164.827204)
		(end 321.988942 -161.583878)
		(width 0.1143)
		(layer "B.Cu")
		(net "BMC_I2C_D_SDA")
	)
	(segment
		(start 135.5344 -75.933808)
		(end 135.5344 -75.2856)
		(width 0.1143)
		(layer "B.Cu")
		(net "BMC_I2C_D_SDA")
	)
	(segment
		(start 321.690746 -165.1254)
		(end 321.988942 -164.827204)
		(width 0.1143)
		(layer "B.Cu")
		(net "BMC_I2C_D_SDA")
	)
	(segment
		(start 317.881 -135.001)
		(end 317.881 -136.144)
		(width 0.1143)
		(layer "B.Cu")
		(net "BMC_I2C_D_SDA")
	)
	(segment
		(start 321.988942 -161.583878)
		(end 318.21755 -157.812486)
		(width 0.1143)
		(layer "B.Cu")
		(net "BMC_I2C_D_SDA")
	)
	(segment
		(start 321.344544 -165.1254)
		(end 321.690746 -165.1254)
		(width 0.1143)
		(layer "B.Cu")
		(net "BMC_I2C_D_SDA")
	)
	(segment
		(start 320.650362 -165.81755)
		(end 321.344544 -165.1254)
		(width 0.1143)
		(layer "B.Cu")
		(net "BMC_I2C_D_SDA")
	)
	(segment
		(start 136.901682 -78.54315)
		(end 136.011158 -78.54315)
		(width 0.1143)
		(layer "B.Cu")
		(net "BMC_I2C_D_SDA")
	)
	(segment
		(start 318.4525 -165.354)
		(end 319.4685 -165.354)
		(width 0.1143)
		(layer "B.Cu")
		(net "BMC_I2C_D_SDA")
	)
	(segment
		(start 138.428984 -81.278984)
		(end 137.7442 -80.5942)
		(width 0.1143)
		(layer "B.Cu")
		(net "BMC_I2C_D_SDA")
	)
	(segment
		(start 138.428984 -87.726774)
		(end 138.428984 -81.278984)
		(width 0.1143)
		(layer "B.Cu")
		(net "BMC_I2C_D_SDA")
	)
	(segment
		(start 135.5344 -75.2856)
		(end 135.763 -75.057)
		(width 0.1143)
		(layer "B.Cu")
		(net "BMC_I2C_D_SDA")
	)
	(segment
		(start 137.719816 -79.361284)
		(end 136.901682 -78.54315)
		(width 0.1143)
		(layer "B.Cu")
		(net "BMC_I2C_D_SDA")
	)
	(segment
		(start 319.99555 -165.81755)
		(end 320.650362 -165.81755)
		(width 0.1143)
		(layer "B.Cu")
		(net "BMC_I2C_D_SDA")
	)
	(segment
		(start 136.011158 -78.54315)
		(end 135.107426 -77.639418)
		(width 0.1143)
		(layer "B.Cu")
		(net "BMC_I2C_D_SDA")
	)
	(segment
		(start 135.107426 -76.360782)
		(end 135.5344 -75.933808)
		(width 0.1143)
		(layer "B.Cu")
		(net "BMC_I2C_D_SDA")
	)
	(segment
		(start 141.12621 -90.424)
		(end 138.428984 -87.726774)
		(width 0.1143)
		(layer "B.Cu")
		(net "BMC_I2C_D_SDA")
	)
	(segment
		(start 137.719816 -80.552798)
		(end 137.719816 -79.361284)
		(width 0.1143)
		(layer "B.Cu")
		(net "BMC_I2C_D_SDA")
	)
	(segment
		(start 142.822676 -90.424)
		(end 141.12621 -90.424)
		(width 0.1143)
		(layer "B.Cu")
		(net "BMC_I2C_D_SDA")
	)
	(segment
		(start 144.66697 -92.456)
		(end 144.66697 -92.268294)
		(width 0.1143)
		(layer "B.Cu")
		(net "BMC_I2C_D_SDA")
	)
	(segment
		(start 319.532 -165.354)
		(end 319.99555 -165.81755)
		(width 0.1143)
		(layer "B.Cu")
		(net "BMC_I2C_D_SDA")
	)
	(segment
		(start 297.18 -88.519)
		(end 299.212 -90.551)
		(width 0.1143)
		(layer "B.Cu")
		(net "BMC_I2C_D_SDA")
	)
	(segment
		(start 137.7442 -80.5942)
		(end 137.7442 -80.577182)
		(width 0.1143)
		(layer "B.Cu")
		(net "BMC_I2C_D_SDA")
	)
	(segment
		(start 135.107426 -77.639418)
		(end 135.107426 -76.360782)
		(width 0.1143)
		(layer "B.Cu")
		(net "BMC_I2C_D_SDA")
	)
	(segment
		(start 261.874 -88.519)
		(end 297.18 -88.519)
		(width 0.1143)
		(layer "B.Cu")
		(net "BMC_I2C_D_SDA")
	)
	(segment
		(start 144.66697 -92.268294)
		(end 142.822676 -90.424)
		(width 0.1143)
		(layer "B.Cu")
		(net "BMC_I2C_D_SDA")
	)
	(segment
		(start 318.21755 -157.812486)
		(end 318.21755 -138.00455)
		(width 0.1143)
		(layer "B.Cu")
		(net "BMC_I2C_D_SDA")
	)
	(segment
		(start 182.712868 -90.424)
		(end 146.69897 -90.424)
		(width 0.127)
		(layer "In2.Cu")
		(net "BMC_I2C_D_SDA")
	)
	(segment
		(start 259.763768 -87.5157)
		(end 256.360168 -90.9193)
		(width 0.127)
		(layer "In2.Cu")
		(net "BMC_I2C_D_SDA")
	)
	(segment
		(start 116.59997 -65.702434)
		(end 116.59997 -66.929)
		(width 0.127)
		(layer "In2.Cu")
		(net "BMC_I2C_D_SDA")
	)
	(segment
		(start 135.763 -75.057)
		(end 135.763 -74.803)
		(width 0.127)
		(layer "In2.Cu")
		(net "BMC_I2C_D_SDA")
	)
	(segment
		(start 233.2863 -90.9193)
		(end 227.965 -85.598)
		(width 0.127)
		(layer "In2.Cu")
		(net "BMC_I2C_D_SDA")
	)
	(segment
		(start 261.874 -88.519)
		(end 261.874 -88.218264)
		(width 0.127)
		(layer "In2.Cu")
		(net "BMC_I2C_D_SDA")
	)
	(segment
		(start 297.5737 -102.2223)
		(end 297.5737 -114.062002)
		(width 0.127)
		(layer "In2.Cu")
		(net "BMC_I2C_D_SDA")
	)
	(segment
		(start 316.601348 -132.630418)
		(end 316.653418 -132.630418)
		(width 0.127)
		(layer "In2.Cu")
		(net "BMC_I2C_D_SDA")
	)
	(segment
		(start 134.24662 -73.28662)
		(end 133.87959 -73.28662)
		(width 0.127)
		(layer "In2.Cu")
		(net "BMC_I2C_D_SDA")
	)
	(segment
		(start 135.763 -74.803)
		(end 134.24662 -73.28662)
		(width 0.127)
		(layer "In2.Cu")
		(net "BMC_I2C_D_SDA")
	)
	(segment
		(start 298.77004 -101.02596)
		(end 297.5737 -102.2223)
		(width 0.127)
		(layer "In2.Cu")
		(net "BMC_I2C_D_SDA")
	)
	(segment
		(start 119.5832 -64.5922)
		(end 117.710204 -64.5922)
		(width 0.127)
		(layer "In2.Cu")
		(net "BMC_I2C_D_SDA")
	)
	(segment
		(start 128.086358 -67.493388)
		(end 122.484388 -67.493388)
		(width 0.127)
		(layer "In2.Cu")
		(net "BMC_I2C_D_SDA")
	)
	(segment
		(start 332.867 -140.843)
		(end 332.867 -148.2217)
		(width 0.127)
		(layer "In2.Cu")
		(net "BMC_I2C_D_SDA")
	)
	(segment
		(start 306.07 -123.230132)
		(end 311.426352 -128.586484)
		(width 0.127)
		(layer "In2.Cu")
		(net "BMC_I2C_D_SDA")
	)
	(segment
		(start 299.085 -95.003366)
		(end 299.085 -96.454468)
		(width 0.127)
		(layer "In2.Cu")
		(net "BMC_I2C_D_SDA")
	)
	(segment
		(start 332.867 -148.2217)
		(end 336.7913 -152.146)
		(width 0.127)
		(layer "In2.Cu")
		(net "BMC_I2C_D_SDA")
	)
	(segment
		(start 261.874 -88.218264)
		(end 261.171436 -87.5157)
		(width 0.127)
		(layer "In2.Cu")
		(net "BMC_I2C_D_SDA")
	)
	(segment
		(start 326.5678 -134.5438)
		(end 332.867 -140.843)
		(width 0.127)
		(layer "In2.Cu")
		(net "BMC_I2C_D_SDA")
	)
	(segment
		(start 133.87959 -73.28662)
		(end 128.086358 -67.493388)
		(width 0.127)
		(layer "In2.Cu")
		(net "BMC_I2C_D_SDA")
	)
	(segment
		(start 306.07 -122.558302)
		(end 306.07 -123.230132)
		(width 0.127)
		(layer "In2.Cu")
		(net "BMC_I2C_D_SDA")
	)
	(segment
		(start 122.484388 -67.493388)
		(end 119.5832 -64.5922)
		(width 0.127)
		(layer "In2.Cu")
		(net "BMC_I2C_D_SDA")
	)
	(segment
		(start 299.48505 -90.82405)
		(end 299.48505 -94.603316)
		(width 0.127)
		(layer "In2.Cu")
		(net "BMC_I2C_D_SDA")
	)
	(segment
		(start 188.008768 -85.1281)
		(end 182.712868 -90.424)
		(width 0.127)
		(layer "In2.Cu")
		(net "BMC_I2C_D_SDA")
	)
	(segment
		(start 298.3357 -97.203768)
		(end 298.3357 -97.614232)
		(width 0.127)
		(layer "In2.Cu")
		(net "BMC_I2C_D_SDA")
	)
	(segment
		(start 312.557414 -128.586484)
		(end 316.601348 -132.630418)
		(width 0.127)
		(layer "In2.Cu")
		(net "BMC_I2C_D_SDA")
	)
	(segment
		(start 317.881 -133.858)
		(end 317.881 -135.001)
		(width 0.127)
		(layer "In2.Cu")
		(net "BMC_I2C_D_SDA")
	)
	(segment
		(start 256.360168 -90.9193)
		(end 233.2863 -90.9193)
		(width 0.127)
		(layer "In2.Cu")
		(net "BMC_I2C_D_SDA")
	)
	(segment
		(start 299.212 -90.551)
		(end 299.48505 -90.82405)
		(width 0.127)
		(layer "In2.Cu")
		(net "BMC_I2C_D_SDA")
	)
	(segment
		(start 218.848686 -85.1281)
		(end 188.008768 -85.1281)
		(width 0.127)
		(layer "In2.Cu")
		(net "BMC_I2C_D_SDA")
	)
	(segment
		(start 299.48505 -94.603316)
		(end 299.085 -95.003366)
		(width 0.127)
		(layer "In2.Cu")
		(net "BMC_I2C_D_SDA")
	)
	(segment
		(start 227.965 -85.598)
		(end 219.318586 -85.598)
		(width 0.127)
		(layer "In2.Cu")
		(net "BMC_I2C_D_SDA")
	)
	(segment
		(start 146.69897 -90.424)
		(end 144.66697 -92.456)
		(width 0.127)
		(layer "In2.Cu")
		(net "BMC_I2C_D_SDA")
	)
	(segment
		(start 117.710204 -64.5922)
		(end 116.59997 -65.702434)
		(width 0.127)
		(layer "In2.Cu")
		(net "BMC_I2C_D_SDA")
	)
	(segment
		(start 298.3357 -97.614232)
		(end 298.77004 -98.048572)
		(width 0.127)
		(layer "In2.Cu")
		(net "BMC_I2C_D_SDA")
	)
	(segment
		(start 261.171436 -87.5157)
		(end 259.763768 -87.5157)
		(width 0.127)
		(layer "In2.Cu")
		(net "BMC_I2C_D_SDA")
	)
	(segment
		(start 298.77004 -98.048572)
		(end 298.77004 -101.02596)
		(width 0.127)
		(layer "In2.Cu")
		(net "BMC_I2C_D_SDA")
	)
	(segment
		(start 219.318586 -85.598)
		(end 218.848686 -85.1281)
		(width 0.127)
		(layer "In2.Cu")
		(net "BMC_I2C_D_SDA")
	)
	(segment
		(start 311.426352 -128.586484)
		(end 312.557414 -128.586484)
		(width 0.127)
		(layer "In2.Cu")
		(net "BMC_I2C_D_SDA")
	)
	(segment
		(start 316.653418 -132.630418)
		(end 317.881 -133.858)
		(width 0.127)
		(layer "In2.Cu")
		(net "BMC_I2C_D_SDA")
	)
	(segment
		(start 299.085 -96.454468)
		(end 298.3357 -97.203768)
		(width 0.127)
		(layer "In2.Cu")
		(net "BMC_I2C_D_SDA")
	)
	(segment
		(start 297.5737 -114.062002)
		(end 306.07 -122.558302)
		(width 0.127)
		(layer "In2.Cu")
		(net "BMC_I2C_D_SDA")
	)
	(segment
		(start 260.470904 -88.075262)
		(end 260.470904 -88.216486)
		(width 0.1143)
		(layer "F.Cu")
		(net "BMC_I2C_D_SCL")
	)
	(segment
		(start 301.0535 -90.043)
		(end 298.831 -90.043)
		(width 0.1143)
		(layer "F.Cu")
		(net "BMC_I2C_D_SCL")
	)
	(segment
		(start 298.831 -90.043)
		(end 298.323 -90.551)
		(width 0.1143)
		(layer "F.Cu")
		(net "BMC_I2C_D_SCL")
	)
	(segment
		(start 261.874 -89.619582)
		(end 261.874 -90.4113)
		(width 0.1143)
		(layer "F.Cu")
		(net "BMC_I2C_D_SCL")
	)
	(segment
		(start 139.391644 -94.04096)
		(end 139.326366 -93.975682)
		(width 0.1143)
		(layer "F.Cu")
		(net "BMC_I2C_D_SCL")
	)
	(segment
		(start 139.7381 -94.3991)
		(end 139.414758 -94.075758)
		(width 0.1143)
		(layer "F.Cu")
		(net "BMC_I2C_D_SCL")
	)
	(segment
		(start 318.8462 -154.8384)
		(end 318.77 -154.7622)
		(width 0.1143)
		(layer "F.Cu")
		(net "BMC_I2C_D_SCL")
	)
	(segment
		(start 333.468218 -152.377648)
		(end 328.901552 -152.377648)
		(width 0.1143)
		(layer "F.Cu")
		(net "BMC_I2C_D_SCL")
	)
	(segment
		(start 118.364 -70.9295)
		(end 118.364 -66.94043)
		(width 0.1143)
		(layer "F.Cu")
		(net "BMC_I2C_D_SCL")
	)
	(segment
		(start 328.901552 -152.377648)
		(end 326.4408 -154.8384)
		(width 0.1143)
		(layer "F.Cu")
		(net "BMC_I2C_D_SCL")
	)
	(segment
		(start 197.6247 -25.229058)
		(end 260.470904 -88.075262)
		(width 0.1143)
		(layer "F.Cu")
		(net "BMC_I2C_D_SCL")
	)
	(segment
		(start 140.95857 -94.3991)
		(end 139.7381 -94.3991)
		(width 0.1143)
		(layer "F.Cu")
		(net "BMC_I2C_D_SCL")
	)
	(segment
		(start 139.29106 -93.95206)
		(end 139.192 -93.853)
		(width 0.1143)
		(layer "F.Cu")
		(net "BMC_I2C_D_SCL")
	)
	(segment
		(start 260.470904 -88.216486)
		(end 261.874 -89.619582)
		(width 0.1143)
		(layer "F.Cu")
		(net "BMC_I2C_D_SCL")
	)
	(segment
		(start 302.1965 -91.186)
		(end 301.0535 -90.043)
		(width 0.1143)
		(layer "F.Cu")
		(net "BMC_I2C_D_SCL")
	)
	(segment
		(start 117.86997 -66.4464)
		(end 117.86997 -65.151)
		(width 0.1143)
		(layer "F.Cu")
		(net "BMC_I2C_D_SCL")
	)
	(segment
		(start 139.414758 -94.075758)
		(end 139.391644 -94.04096)
		(width 0.1143)
		(layer "F.Cu")
		(net "BMC_I2C_D_SCL")
	)
	(segment
		(start 117.6655 -71.628)
		(end 118.364 -70.9295)
		(width 0.1143)
		(layer "F.Cu")
		(net "BMC_I2C_D_SCL")
	)
	(segment
		(start 118.364 -66.94043)
		(end 117.86997 -66.4464)
		(width 0.1143)
		(layer "F.Cu")
		(net "BMC_I2C_D_SCL")
	)
	(segment
		(start 197.6247 -19.1262)
		(end 197.6247 -25.229058)
		(width 0.1143)
		(layer "F.Cu")
		(net "BMC_I2C_D_SCL")
	)
	(segment
		(start 193.6115 -15.113)
		(end 197.6247 -19.1262)
		(width 0.1143)
		(layer "F.Cu")
		(net "BMC_I2C_D_SCL")
	)
	(segment
		(start 326.4408 -154.8384)
		(end 318.8462 -154.8384)
		(width 0.1143)
		(layer "F.Cu")
		(net "BMC_I2C_D_SCL")
	)
	(segment
		(start 139.326366 -93.975682)
		(end 139.29106 -93.95206)
		(width 0.1143)
		(layer "F.Cu")
		(net "BMC_I2C_D_SCL")
	)
	(segment
		(start 298.323 -90.551)
		(end 298.2976 -90.551)
		(width 0.1143)
		(layer "F.Cu")
		(net "BMC_I2C_D_SCL")
	)
	(via
		(at 319.405 -157.607)
		(size 0.7112)
		(drill 0.3556)
		(layers "F.Cu" "B.Cu")
		(net "BMC_I2C_D_SCL")
	)
	(via
		(at 139.192 -93.853)
		(size 0.5588)
		(drill 0.3048)
		(layers "F.Cu" "B.Cu")
		(net "BMC_I2C_D_SCL")
	)
	(via
		(at 318.77 -154.7622)
		(size 0.5588)
		(drill 0.3048)
		(layers "F.Cu" "B.Cu")
		(net "BMC_I2C_D_SCL")
	)
	(via
		(at 317.309754 -134.286752)
		(size 0.5588)
		(drill 0.3048)
		(layers "F.Cu" "B.Cu")
		(net "BMC_I2C_D_SCL")
	)
	(via
		(at 117.86997 -65.151)
		(size 0.5588)
		(drill 0.3048)
		(layers "F.Cu" "B.Cu")
		(net "BMC_I2C_D_SCL")
	)
	(via
		(at 135.02386 -75.59548)
		(size 0.5588)
		(drill 0.3048)
		(layers "F.Cu" "B.Cu")
		(net "BMC_I2C_D_SCL")
	)
	(via
		(at 298.2976 -90.551)
		(size 0.5588)
		(drill 0.3048)
		(layers "F.Cu" "B.Cu")
		(net "BMC_I2C_D_SCL")
	)
	(via
		(at 261.874 -90.4113)
		(size 0.5588)
		(drill 0.3048)
		(layers "F.Cu" "B.Cu")
		(net "BMC_I2C_D_SCL")
	)
	(segment
		(start 317.858394 -134.286752)
		(end 318.77 -135.198358)
		(width 0.1143)
		(layer "B.Cu")
		(net "BMC_I2C_D_SCL")
	)
	(segment
		(start 318.77 -156.972)
		(end 319.405 -157.607)
		(width 0.1143)
		(layer "B.Cu")
		(net "BMC_I2C_D_SCL")
	)
	(segment
		(start 318.4525 -166.878)
		(end 319.4685 -166.878)
		(width 0.1143)
		(layer "B.Cu")
		(net "BMC_I2C_D_SCL")
	)
	(segment
		(start 133.75005 -79.342996)
		(end 133.75005 -76.86929)
		(width 0.1143)
		(layer "B.Cu")
		(net "BMC_I2C_D_SCL")
	)
	(segment
		(start 134.9502 -80.543146)
		(end 133.75005 -79.342996)
		(width 0.1143)
		(layer "B.Cu")
		(net "BMC_I2C_D_SCL")
	)
	(segment
		(start 319.97015 -166.31285)
		(end 321.550792 -166.31285)
		(width 0.1143)
		(layer "B.Cu")
		(net "BMC_I2C_D_SCL")
	)
	(segment
		(start 137.5156 -92.1766)
		(end 137.5156 -88.524334)
		(width 0.1143)
		(layer "B.Cu")
		(net "BMC_I2C_D_SCL")
	)
	(segment
		(start 318.77 -154.7622)
		(end 318.77 -156.972)
		(width 0.1143)
		(layer "B.Cu")
		(net "BMC_I2C_D_SCL")
	)
	(segment
		(start 137.5156 -88.524334)
		(end 137.451084 -88.459818)
		(width 0.1143)
		(layer "B.Cu")
		(net "BMC_I2C_D_SCL")
	)
	(segment
		(start 317.309754 -134.286752)
		(end 317.858394 -134.286752)
		(width 0.1143)
		(layer "B.Cu")
		(net "BMC_I2C_D_SCL")
	)
	(segment
		(start 261.9883 -90.4113)
		(end 261.874 -90.4113)
		(width 0.1143)
		(layer "B.Cu")
		(net "BMC_I2C_D_SCL")
	)
	(segment
		(start 298.2976 -90.551)
		(end 262.128 -90.551)
		(width 0.1143)
		(layer "B.Cu")
		(net "BMC_I2C_D_SCL")
	)
	(segment
		(start 137.451084 -88.459818)
		(end 137.451084 -83.857084)
		(width 0.1143)
		(layer "B.Cu")
		(net "BMC_I2C_D_SCL")
	)
	(segment
		(start 137.451084 -83.857084)
		(end 134.9502 -81.3562)
		(width 0.1143)
		(layer "B.Cu")
		(net "BMC_I2C_D_SCL")
	)
	(segment
		(start 134.9502 -81.3562)
		(end 134.9502 -80.543146)
		(width 0.1143)
		(layer "B.Cu")
		(net "BMC_I2C_D_SCL")
	)
	(segment
		(start 318.77 -135.198358)
		(end 318.77 -154.7622)
		(width 0.1143)
		(layer "B.Cu")
		(net "BMC_I2C_D_SCL")
	)
	(segment
		(start 139.192 -93.853)
		(end 137.5156 -92.1766)
		(width 0.1143)
		(layer "B.Cu")
		(net "BMC_I2C_D_SCL")
	)
	(segment
		(start 319.4685 -166.878)
		(end 319.4685 -166.8145)
		(width 0.1143)
		(layer "B.Cu")
		(net "BMC_I2C_D_SCL")
	)
	(segment
		(start 262.128 -90.551)
		(end 261.9883 -90.4113)
		(width 0.1143)
		(layer "B.Cu")
		(net "BMC_I2C_D_SCL")
	)
	(segment
		(start 322.48983 -165.373812)
		(end 322.48983 -160.69183)
		(width 0.1143)
		(layer "B.Cu")
		(net "BMC_I2C_D_SCL")
	)
	(segment
		(start 319.4685 -166.8145)
		(end 319.97015 -166.31285)
		(width 0.1143)
		(layer "B.Cu")
		(net "BMC_I2C_D_SCL")
	)
	(segment
		(start 321.550792 -166.31285)
		(end 322.48983 -165.373812)
		(width 0.1143)
		(layer "B.Cu")
		(net "BMC_I2C_D_SCL")
	)
	(segment
		(start 133.75005 -76.86929)
		(end 135.02386 -75.59548)
		(width 0.1143)
		(layer "B.Cu")
		(net "BMC_I2C_D_SCL")
	)
	(segment
		(start 322.48983 -160.69183)
		(end 319.405 -157.607)
		(width 0.1143)
		(layer "B.Cu")
		(net "BMC_I2C_D_SCL")
	)
	(segment
		(start 119.223536 -65.151)
		(end 117.86997 -65.151)
		(width 0.127)
		(layer "In2.Cu")
		(net "BMC_I2C_D_SCL")
	)
	(segment
		(start 297.0657 -101.9683)
		(end 298.26204 -100.77196)
		(width 0.127)
		(layer "In2.Cu")
		(net "BMC_I2C_D_SCL")
	)
	(segment
		(start 142.802356 -94.022926)
		(end 143.087598 -94.307406)
		(width 0.127)
		(layer "In2.Cu")
		(net "BMC_I2C_D_SCL")
	)
	(segment
		(start 127.88138 -68.453)
		(end 122.525536 -68.453)
		(width 0.127)
		(layer "In2.Cu")
		(net "BMC_I2C_D_SCL")
	)
	(segment
		(start 312.753248 -130.631946)
		(end 305.562 -123.440698)
		(width 0.127)
		(layer "In2.Cu")
		(net "BMC_I2C_D_SCL")
	)
	(segment
		(start 233.618278 -93.5863)
		(end 258.699 -93.5863)
		(width 0.127)
		(layer "In2.Cu")
		(net "BMC_I2C_D_SCL")
	)
	(segment
		(start 297.8277 -96.993202)
		(end 298.577 -96.243902)
		(width 0.127)
		(layer "In2.Cu")
		(net "BMC_I2C_D_SCL")
	)
	(segment
		(start 298.26204 -100.77196)
		(end 298.26204 -98.259138)
		(width 0.127)
		(layer "In2.Cu")
		(net "BMC_I2C_D_SCL")
	)
	(segment
		(start 142.63243 -93.853)
		(end 142.802356 -94.022926)
		(width 0.127)
		(layer "In2.Cu")
		(net "BMC_I2C_D_SCL")
	)
	(segment
		(start 217.51544 -87.40648)
		(end 218.70797 -88.59901)
		(width 0.127)
		(layer "In2.Cu")
		(net "BMC_I2C_D_SCL")
	)
	(segment
		(start 122.525536 -68.453)
		(end 119.223536 -65.151)
		(width 0.127)
		(layer "In2.Cu")
		(net "BMC_I2C_D_SCL")
	)
	(segment
		(start 317.309754 -134.286752)
		(end 317.317628 -134.286752)
		(width 0.127)
		(layer "In2.Cu")
		(net "BMC_I2C_D_SCL")
	)
	(segment
		(start 228.630988 -88.59901)
		(end 233.618278 -93.5863)
		(width 0.127)
		(layer "In2.Cu")
		(net "BMC_I2C_D_SCL")
	)
	(segment
		(start 183.1975 -92.1385)
		(end 187.92952 -87.40648)
		(width 0.127)
		(layer "In2.Cu")
		(net "BMC_I2C_D_SCL")
	)
	(segment
		(start 144.97177 -94.307406)
		(end 147.140676 -92.1385)
		(width 0.127)
		(layer "In2.Cu")
		(net "BMC_I2C_D_SCL")
	)
	(segment
		(start 297.8277 -97.824798)
		(end 297.8277 -96.993202)
		(width 0.127)
		(layer "In2.Cu")
		(net "BMC_I2C_D_SCL")
	)
	(segment
		(start 147.140676 -92.1385)
		(end 183.1975 -92.1385)
		(width 0.127)
		(layer "In2.Cu")
		(net "BMC_I2C_D_SCL")
	)
	(segment
		(start 143.087598 -94.307406)
		(end 144.97177 -94.307406)
		(width 0.127)
		(layer "In2.Cu")
		(net "BMC_I2C_D_SCL")
	)
	(segment
		(start 298.97705 -94.39275)
		(end 298.97705 -91.23045)
		(width 0.127)
		(layer "In2.Cu")
		(net "BMC_I2C_D_SCL")
	)
	(segment
		(start 218.70797 -88.59901)
		(end 228.630988 -88.59901)
		(width 0.127)
		(layer "In2.Cu")
		(net "BMC_I2C_D_SCL")
	)
	(segment
		(start 313.88431 -130.631946)
		(end 312.753248 -130.631946)
		(width 0.127)
		(layer "In2.Cu")
		(net "BMC_I2C_D_SCL")
	)
	(segment
		(start 135.02386 -75.59548)
		(end 127.88138 -68.453)
		(width 0.127)
		(layer "In2.Cu")
		(net "BMC_I2C_D_SCL")
	)
	(segment
		(start 298.577 -96.243902)
		(end 298.577 -94.7928)
		(width 0.127)
		(layer "In2.Cu")
		(net "BMC_I2C_D_SCL")
	)
	(segment
		(start 298.26204 -98.259138)
		(end 297.8277 -97.824798)
		(width 0.127)
		(layer "In2.Cu")
		(net "BMC_I2C_D_SCL")
	)
	(segment
		(start 317.317628 -134.065264)
		(end 313.88431 -130.631946)
		(width 0.127)
		(layer "In2.Cu")
		(net "BMC_I2C_D_SCL")
	)
	(segment
		(start 187.92952 -87.40648)
		(end 217.51544 -87.40648)
		(width 0.127)
		(layer "In2.Cu")
		(net "BMC_I2C_D_SCL")
	)
	(segment
		(start 297.0657 -114.272568)
		(end 297.0657 -101.9683)
		(width 0.127)
		(layer "In2.Cu")
		(net "BMC_I2C_D_SCL")
	)
	(segment
		(start 317.317628 -134.286752)
		(end 317.317628 -134.065264)
		(width 0.127)
		(layer "In2.Cu")
		(net "BMC_I2C_D_SCL")
	)
	(segment
		(start 305.562 -122.768868)
		(end 297.0657 -114.272568)
		(width 0.127)
		(layer "In2.Cu")
		(net "BMC_I2C_D_SCL")
	)
	(segment
		(start 298.577 -94.7928)
		(end 298.97705 -94.39275)
		(width 0.127)
		(layer "In2.Cu")
		(net "BMC_I2C_D_SCL")
	)
	(segment
		(start 298.97705 -91.23045)
		(end 298.2976 -90.551)
		(width 0.127)
		(layer "In2.Cu")
		(net "BMC_I2C_D_SCL")
	)
	(segment
		(start 139.192 -93.853)
		(end 142.63243 -93.853)
		(width 0.127)
		(layer "In2.Cu")
		(net "BMC_I2C_D_SCL")
	)
	(segment
		(start 258.699 -93.5863)
		(end 261.874 -90.4113)
		(width 0.127)
		(layer "In2.Cu")
		(net "BMC_I2C_D_SCL")
	)
	(segment
		(start 305.562 -123.440698)
		(end 305.562 -122.768868)
		(width 0.127)
		(layer "In2.Cu")
		(net "BMC_I2C_D_SCL")
	)
	(segment
		(start 298.43476 -180.240178)
		(end 298.400978 -180.240178)
		(width 0.127)
		(layer "F.Cu")
		(net "TP_BMC_GPIOL7")
	)
	(segment
		(start 298.400978 -180.240178)
		(end 298.076366 -179.915566)
		(width 0.127)
		(layer "F.Cu")
		(net "TP_BMC_GPIOL7")
	)
	(segment
		(start 298.076366 -179.915566)
		(end 297.94581 -179.915566)
		(width 0.127)
		(layer "F.Cu")
		(net "TP_BMC_GPIOL7")
	)
	(via
		(at 297.94581 -179.915566)
		(size 0.508)
		(drill 0.254)
		(layers "F.Cu" "B.Cu")
		(net "TP_BMC_GPIOL7")
	)
	(segment
		(start 297.263566 -179.915566)
		(end 297.94581 -179.915566)
		(width 0.127)
		(layer "B.Cu")
		(net "TP_BMC_GPIOL7")
	)
	(segment
		(start 296.672 -179.324)
		(end 297.263566 -179.915566)
		(width 0.127)
		(layer "B.Cu")
		(net "TP_BMC_GPIOL7")
	)
	(segment
		(start 306.578 -181.737)
		(end 306.07 -182.245)
		(width 0.127)
		(layer "F.Cu")
		(net "TP_BMC_GPIOL6")
	)
	(segment
		(start 302.87341 -182.245)
		(end 302.646334 -182.017924)
		(width 0.127)
		(layer "F.Cu")
		(net "TP_BMC_GPIOL6")
	)
	(segment
		(start 301.812706 -182.017924)
		(end 301.634906 -181.840124)
		(width 0.127)
		(layer "F.Cu")
		(net "TP_BMC_GPIOL6")
	)
	(segment
		(start 306.07 -182.245)
		(end 302.87341 -182.245)
		(width 0.127)
		(layer "F.Cu")
		(net "TP_BMC_GPIOL6")
	)
	(segment
		(start 302.646334 -182.017924)
		(end 301.812706 -182.017924)
		(width 0.127)
		(layer "F.Cu")
		(net "TP_BMC_GPIOL6")
	)
	(segment
		(start 301.059596 -181.040024)
		(end 300.834806 -181.040024)
		(width 0.127)
		(layer "F.Cu")
		(net "TP_BMC_GPIOL5")
	)
	(segment
		(start 304.3809 -180.6321)
		(end 304.0761 -180.9369)
		(width 0.127)
		(layer "F.Cu")
		(net "TP_BMC_GPIOL5")
	)
	(segment
		(start 304.0761 -180.9369)
		(end 302.016922 -180.9369)
		(width 0.127)
		(layer "F.Cu")
		(net "TP_BMC_GPIOL5")
	)
	(segment
		(start 306.7939 -180.6321)
		(end 304.3809 -180.6321)
		(width 0.127)
		(layer "F.Cu")
		(net "TP_BMC_GPIOL5")
	)
	(segment
		(start 306.959 -180.467)
		(end 306.7939 -180.6321)
		(width 0.127)
		(layer "F.Cu")
		(net "TP_BMC_GPIOL5")
	)
	(segment
		(start 301.402496 -180.697124)
		(end 301.059596 -181.040024)
		(width 0.127)
		(layer "F.Cu")
		(net "TP_BMC_GPIOL5")
	)
	(segment
		(start 301.777146 -180.697124)
		(end 301.402496 -180.697124)
		(width 0.127)
		(layer "F.Cu")
		(net "TP_BMC_GPIOL5")
	)
	(segment
		(start 302.016922 -180.9369)
		(end 301.777146 -180.697124)
		(width 0.127)
		(layer "F.Cu")
		(net "TP_BMC_GPIOL5")
	)
	(segment
		(start 299.231558 -180.240178)
		(end 298.83481 -179.84343)
		(width 0.127)
		(layer "F.Cu")
		(net "TP_BMC_GPIOL4")
	)
	(segment
		(start 299.23486 -180.240178)
		(end 299.231558 -180.240178)
		(width 0.127)
		(layer "F.Cu")
		(net "TP_BMC_GPIOL4")
	)
	(via
		(at 298.83481 -179.84343)
		(size 0.508)
		(drill 0.254)
		(layers "F.Cu" "B.Cu")
		(net "TP_BMC_GPIOL4")
	)
	(segment
		(start 303.8094 -182.6514)
		(end 300.849284 -179.691284)
		(width 0.127)
		(layer "B.Cu")
		(net "TP_BMC_GPIOL4")
	)
	(segment
		(start 299.00499 -179.84343)
		(end 298.83481 -179.84343)
		(width 0.1016)
		(layer "B.Cu")
		(net "TP_BMC_GPIOL4")
	)
	(segment
		(start 300.598586 -179.428902)
		(end 299.81144 -179.428902)
		(width 0.1016)
		(layer "B.Cu")
		(net "TP_BMC_GPIOL4")
	)
	(segment
		(start 299.81144 -179.428902)
		(end 299.802042 -179.4383)
		(width 0.1016)
		(layer "B.Cu")
		(net "TP_BMC_GPIOL4")
	)
	(segment
		(start 300.849284 -179.6796)
		(end 300.598586 -179.428902)
		(width 0.1016)
		(layer "B.Cu")
		(net "TP_BMC_GPIOL4")
	)
	(segment
		(start 299.802042 -179.4383)
		(end 299.409866 -179.4383)
		(width 0.1016)
		(layer "B.Cu")
		(net "TP_BMC_GPIOL4")
	)
	(segment
		(start 300.849284 -179.691284)
		(end 300.849284 -179.6796)
		(width 0.127)
		(layer "B.Cu")
		(net "TP_BMC_GPIOL4")
	)
	(segment
		(start 299.409866 -179.4383)
		(end 299.00499 -179.84343)
		(width 0.1016)
		(layer "B.Cu")
		(net "TP_BMC_GPIOL4")
	)
	(segment
		(start 308.102 -180.975)
		(end 308.0639 -181.0131)
		(width 0.127)
		(layer "F.Cu")
		(net "TP_BMC_GPIOL3")
	)
	(segment
		(start 301.836582 -181.2417)
		(end 301.634906 -181.040024)
		(width 0.127)
		(layer "F.Cu")
		(net "TP_BMC_GPIOL3")
	)
	(segment
		(start 308.0639 -181.0131)
		(end 304.6603 -181.0131)
		(width 0.127)
		(layer "F.Cu")
		(net "TP_BMC_GPIOL3")
	)
	(segment
		(start 304.4317 -181.2417)
		(end 301.836582 -181.2417)
		(width 0.127)
		(layer "F.Cu")
		(net "TP_BMC_GPIOL3")
	)
	(segment
		(start 304.6603 -181.0131)
		(end 304.4317 -181.2417)
		(width 0.127)
		(layer "F.Cu")
		(net "TP_BMC_GPIOL3")
	)
	(segment
		(start 300.029118 -180.240178)
		(end 299.63364 -179.8447)
		(width 0.127)
		(layer "F.Cu")
		(net "TP_BMC_GPIOL2")
	)
	(segment
		(start 300.03496 -180.240178)
		(end 300.029118 -180.240178)
		(width 0.127)
		(layer "F.Cu")
		(net "TP_BMC_GPIOL2")
	)
	(via
		(at 299.63364 -179.8447)
		(size 0.508)
		(drill 0.254)
		(layers "F.Cu" "B.Cu")
		(net "TP_BMC_GPIOL2")
	)
	(segment
		(start 302.39208 -182.67934)
		(end 302.39208 -181.76748)
		(width 0.127)
		(layer "B.Cu")
		(net "TP_BMC_GPIOL2")
	)
	(segment
		(start 300.94428 -180.31968)
		(end 300.10862 -180.31968)
		(width 0.127)
		(layer "B.Cu")
		(net "TP_BMC_GPIOL2")
	)
	(segment
		(start 302.39208 -181.76748)
		(end 300.94428 -180.31968)
		(width 0.127)
		(layer "B.Cu")
		(net "TP_BMC_GPIOL2")
	)
	(segment
		(start 300.10862 -180.31968)
		(end 299.63364 -179.8447)
		(width 0.127)
		(layer "B.Cu")
		(net "TP_BMC_GPIOL2")
	)
	(segment
		(start 302.45304 -182.7403)
		(end 302.39208 -182.67934)
		(width 0.127)
		(layer "B.Cu")
		(net "TP_BMC_GPIOL2")
	)
	(segment
		(start 160.4645 -149.479)
		(end 161.247328 -148.696172)
		(width 0.1143)
		(layer "F.Cu")
		(net "IOC_P3V3_SDA_14")
	)
	(segment
		(start 167.0685 -152.0825)
		(end 166.10457 -151.11857)
		(width 0.1143)
		(layer "F.Cu")
		(net "IOC_P3V3_SDA_14")
	)
	(segment
		(start 167.0685 -154.1526)
		(end 167.0685 -152.0825)
		(width 0.1143)
		(layer "F.Cu")
		(net "IOC_P3V3_SDA_14")
	)
	(segment
		(start 163.682172 -148.696172)
		(end 166.10457 -151.11857)
		(width 0.1143)
		(layer "F.Cu")
		(net "IOC_P3V3_SDA_14")
	)
	(segment
		(start 162.527996 -148.696172)
		(end 163.682172 -148.696172)
		(width 0.1143)
		(layer "F.Cu")
		(net "IOC_P3V3_SDA_14")
	)
	(segment
		(start 161.247328 -148.696172)
		(end 162.527996 -148.696172)
		(width 0.1143)
		(layer "F.Cu")
		(net "IOC_P3V3_SDA_14")
	)
	(via
		(at 166.10457 -151.11857)
		(size 0.7112)
		(drill 0.3556)
		(layers "F.Cu" "B.Cu")
		(net "IOC_P3V3_SDA_14")
	)
	(segment
		(start 160.754568 -148.045932)
		(end 160.4645 -148.336)
		(width 0.1143)
		(layer "F.Cu")
		(net "IOC_P3V3_SCL_14")
	)
	(segment
		(start 159.88665 -147.75815)
		(end 158.43885 -147.75815)
		(width 0.1143)
		(layer "F.Cu")
		(net "IOC_P3V3_SCL_14")
	)
	(segment
		(start 158.43885 -147.75815)
		(end 157.2133 -148.9837)
		(width 0.1143)
		(layer "F.Cu")
		(net "IOC_P3V3_SCL_14")
	)
	(segment
		(start 157.2133 -155.1813)
		(end 157.2133 -151.638)
		(width 0.1143)
		(layer "F.Cu")
		(net "IOC_P3V3_SCL_14")
	)
	(segment
		(start 157.2133 -148.9837)
		(end 157.2133 -151.638)
		(width 0.1143)
		(layer "F.Cu")
		(net "IOC_P3V3_SCL_14")
	)
	(segment
		(start 160.4645 -148.336)
		(end 159.88665 -147.75815)
		(width 0.1143)
		(layer "F.Cu")
		(net "IOC_P3V3_SCL_14")
	)
	(segment
		(start 159.4485 -155.6766)
		(end 157.7086 -155.6766)
		(width 0.1143)
		(layer "F.Cu")
		(net "IOC_P3V3_SCL_14")
	)
	(segment
		(start 157.7086 -155.6766)
		(end 157.2133 -155.1813)
		(width 0.1143)
		(layer "F.Cu")
		(net "IOC_P3V3_SCL_14")
	)
	(segment
		(start 162.527996 -148.045932)
		(end 160.754568 -148.045932)
		(width 0.1143)
		(layer "F.Cu")
		(net "IOC_P3V3_SCL_14")
	)
	(via
		(at 157.2133 -151.638)
		(size 0.7112)
		(drill 0.3556)
		(layers "F.Cu" "B.Cu")
		(net "IOC_P3V3_SCL_14")
	)
	(segment
		(start 162.27044 -155.6766)
		(end 162.3822 -155.56484)
		(width 0.1143)
		(layer "F.Cu")
		(net "IOC_P3V3_R_SCL_14")
	)
	(segment
		(start 160.3375 -155.6766)
		(end 162.27044 -155.6766)
		(width 0.1143)
		(layer "F.Cu")
		(net "IOC_P3V3_R_SCL_14")
	)
	(segment
		(start 160.3375 -156.6545)
		(end 160.3375 -155.6766)
		(width 0.1143)
		(layer "F.Cu")
		(net "IOC_P3V3_R_SCL_14")
	)
	(segment
		(start 160.401 -156.718)
		(end 160.3375 -156.6545)
		(width 0.1143)
		(layer "F.Cu")
		(net "IOC_P3V3_R_SCL_14")
	)
	(via
		(at 160.401 -156.718)
		(size 0.7112)
		(drill 0.3556)
		(layers "F.Cu" "B.Cu")
		(net "IOC_P3V3_R_SCL_14")
	)
	(segment
		(start 162.27044 -154.1526)
		(end 162.3822 -154.26436)
		(width 0.1143)
		(layer "F.Cu")
		(net "EXP_IOC_BMC_R_SDA_14")
	)
	(segment
		(start 160.3375 -153.2255)
		(end 160.3375 -154.1526)
		(width 0.1143)
		(layer "F.Cu")
		(net "EXP_IOC_BMC_R_SDA_14")
	)
	(segment
		(start 160.3375 -154.1526)
		(end 162.27044 -154.1526)
		(width 0.1143)
		(layer "F.Cu")
		(net "EXP_IOC_BMC_R_SDA_14")
	)
	(segment
		(start 160.274 -153.162)
		(end 160.3375 -153.2255)
		(width 0.1143)
		(layer "F.Cu")
		(net "EXP_IOC_BMC_R_SDA_14")
	)
	(via
		(at 160.274 -153.162)
		(size 0.7112)
		(drill 0.3556)
		(layers "F.Cu" "B.Cu")
		(net "EXP_IOC_BMC_R_SDA_14")
	)
	(segment
		(start 166.1795 -156.6545)
		(end 166.1795 -155.8036)
		(width 0.1143)
		(layer "F.Cu")
		(net "EXP_IOC_BMC_R_SCL_14")
	)
	(segment
		(start 165.608 -155.702)
		(end 165.47084 -155.56484)
		(width 0.1143)
		(layer "F.Cu")
		(net "EXP_IOC_BMC_R_SCL_14")
	)
	(segment
		(start 166.243 -156.718)
		(end 166.1795 -156.6545)
		(width 0.1143)
		(layer "F.Cu")
		(net "EXP_IOC_BMC_R_SCL_14")
	)
	(segment
		(start 166.1795 -155.8036)
		(end 166.0779 -155.702)
		(width 0.1143)
		(layer "F.Cu")
		(net "EXP_IOC_BMC_R_SCL_14")
	)
	(segment
		(start 166.0779 -155.702)
		(end 165.608 -155.702)
		(width 0.1143)
		(layer "F.Cu")
		(net "EXP_IOC_BMC_R_SCL_14")
	)
	(segment
		(start 165.47084 -155.56484)
		(end 164.2618 -155.56484)
		(width 0.1143)
		(layer "F.Cu")
		(net "EXP_IOC_BMC_R_SCL_14")
	)
	(via
		(at 166.243 -156.718)
		(size 0.7112)
		(drill 0.3556)
		(layers "F.Cu" "B.Cu")
		(net "EXP_IOC_BMC_R_SCL_14")
	)
	(segment
		(start 166.06774 -154.26436)
		(end 164.2618 -154.26436)
		(width 0.1143)
		(layer "F.Cu")
		(net "IOC_P3V3_R_SDA_14")
	)
	(segment
		(start 166.1795 -153.0985)
		(end 166.1795 -154.1526)
		(width 0.1143)
		(layer "F.Cu")
		(net "IOC_P3V3_R_SDA_14")
	)
	(segment
		(start 166.243 -153.035)
		(end 166.1795 -153.0985)
		(width 0.1143)
		(layer "F.Cu")
		(net "IOC_P3V3_R_SDA_14")
	)
	(segment
		(start 166.1795 -154.1526)
		(end 166.06774 -154.26436)
		(width 0.1143)
		(layer "F.Cu")
		(net "IOC_P3V3_R_SDA_14")
	)
	(via
		(at 166.243 -153.035)
		(size 0.7112)
		(drill 0.3556)
		(layers "F.Cu" "B.Cu")
		(net "IOC_P3V3_R_SDA_14")
	)
	(segment
		(start 302.895508 -179.95265)
		(end 302.82388 -180.024278)
		(width 0.127)
		(layer "F.Cu")
		(net "TP_BMC_GPIOL0")
	)
	(segment
		(start 302.82388 -180.024278)
		(end 301.850806 -180.024278)
		(width 0.127)
		(layer "F.Cu")
		(net "TP_BMC_GPIOL0")
	)
	(segment
		(start 301.850806 -180.024278)
		(end 301.634906 -180.240178)
		(width 0.127)
		(layer "F.Cu")
		(net "TP_BMC_GPIOL0")
	)
	(segment
		(start 305.17465 -179.95265)
		(end 302.895508 -179.95265)
		(width 0.127)
		(layer "F.Cu")
		(net "TP_BMC_GPIOL0")
	)
	(segment
		(start 305.308 -180.086)
		(end 305.17465 -179.95265)
		(width 0.127)
		(layer "F.Cu")
		(net "TP_BMC_GPIOL0")
	)
	(segment
		(start 297.557698 -179.440078)
		(end 297.4848 -179.36718)
		(width 0.127)
		(layer "F.Cu")
		(net "TP_BMC_GPIOL1")
	)
	(segment
		(start 298.43476 -179.440078)
		(end 297.557698 -179.440078)
		(width 0.127)
		(layer "F.Cu")
		(net "TP_BMC_GPIOL1")
	)
	(via
		(at 297.4848 -179.36718)
		(size 0.508)
		(drill 0.254)
		(layers "F.Cu" "B.Cu")
		(net "TP_BMC_GPIOL1")
	)
	(segment
		(start 297.67022 -179.36718)
		(end 297.4848 -179.36718)
		(width 0.127)
		(layer "B.Cu")
		(net "TP_BMC_GPIOL1")
	)
	(segment
		(start 298.0944 -178.943)
		(end 297.67022 -179.36718)
		(width 0.127)
		(layer "B.Cu")
		(net "TP_BMC_GPIOL1")
	)
	(segment
		(start 88.453468 -121.143522)
		(end 88.80729 -120.7897)
		(width 0.1143)
		(layer "F.Cu")
		(net "BMC_I2C_F_SDA")
	)
	(segment
		(start 89.256108 -120.340882)
		(end 88.85301 -120.74398)
		(width 0.1143)
		(layer "F.Cu")
		(net "BMC_I2C_F_SDA")
	)
	(segment
		(start 87.356442 -121.143522)
		(end 88.453468 -121.143522)
		(width 0.1143)
		(layer "F.Cu")
		(net "BMC_I2C_F_SDA")
	)
	(segment
		(start 88.85301 -120.74398)
		(end 88.85301 -120.7897)
		(width 0.1143)
		(layer "F.Cu")
		(net "BMC_I2C_F_SDA")
	)
	(segment
		(start 88.80729 -120.7897)
		(end 88.85301 -120.7897)
		(width 0.1143)
		(layer "F.Cu")
		(net "BMC_I2C_F_SDA")
	)
	(segment
		(start 90.239342 -120.340882)
		(end 89.256108 -120.340882)
		(width 0.1143)
		(layer "F.Cu")
		(net "BMC_I2C_F_SDA")
	)
	(via
		(at 327.152 -171.370498)
		(size 0.7112)
		(drill 0.3556)
		(layers "F.Cu" "B.Cu")
		(net "BMC_I2C_F_SDA")
	)
	(via
		(at 88.85301 -120.7897)
		(size 0.5588)
		(drill 0.3048)
		(layers "F.Cu" "B.Cu")
		(net "BMC_I2C_F_SDA")
	)
	(via
		(at 327.55078 -151.74722)
		(size 0.5588)
		(drill 0.3048)
		(layers "F.Cu" "B.Cu")
		(net "BMC_I2C_F_SDA")
	)
	(segment
		(start 318.4525 -172.593)
		(end 319.2272 -171.8183)
		(width 0.1143)
		(layer "B.Cu")
		(net "BMC_I2C_F_SDA")
	)
	(segment
		(start 321.700652 -170.96105)
		(end 322.148454 -170.96105)
		(width 0.1143)
		(layer "B.Cu")
		(net "BMC_I2C_F_SDA")
	)
	(segment
		(start 322.148454 -170.96105)
		(end 322.491354 -171.30395)
		(width 0.1143)
		(layer "B.Cu")
		(net "BMC_I2C_F_SDA")
	)
	(segment
		(start 334.299814 -163.103814)
		(end 327.55078 -156.35478)
		(width 0.1143)
		(layer "B.Cu")
		(net "BMC_I2C_F_SDA")
	)
	(segment
		(start 319.2272 -171.8183)
		(end 320.148204 -171.8183)
		(width 0.1143)
		(layer "B.Cu")
		(net "BMC_I2C_F_SDA")
	)
	(segment
		(start 327.463404 -171.059094)
		(end 330.836778 -171.059094)
		(width 0.1143)
		(layer "B.Cu")
		(net "BMC_I2C_F_SDA")
	)
	(segment
		(start 324.637908 -171.15155)
		(end 326.933052 -171.15155)
		(width 0.1143)
		(layer "B.Cu")
		(net "BMC_I2C_F_SDA")
	)
	(segment
		(start 320.528696 -171.4373)
		(end 321.224402 -171.4373)
		(width 0.1143)
		(layer "B.Cu")
		(net "BMC_I2C_F_SDA")
	)
	(segment
		(start 334.299814 -167.596058)
		(end 334.299814 -163.103814)
		(width 0.1143)
		(layer "B.Cu")
		(net "BMC_I2C_F_SDA")
	)
	(segment
		(start 324.485508 -171.30395)
		(end 324.637908 -171.15155)
		(width 0.1143)
		(layer "B.Cu")
		(net "BMC_I2C_F_SDA")
	)
	(segment
		(start 320.148204 -171.8183)
		(end 320.528696 -171.4373)
		(width 0.1143)
		(layer "B.Cu")
		(net "BMC_I2C_F_SDA")
	)
	(segment
		(start 322.491354 -171.30395)
		(end 324.485508 -171.30395)
		(width 0.1143)
		(layer "B.Cu")
		(net "BMC_I2C_F_SDA")
	)
	(segment
		(start 321.224402 -171.4373)
		(end 321.700652 -170.96105)
		(width 0.1143)
		(layer "B.Cu")
		(net "BMC_I2C_F_SDA")
	)
	(segment
		(start 326.933052 -171.15155)
		(end 327.152 -171.370498)
		(width 0.1143)
		(layer "B.Cu")
		(net "BMC_I2C_F_SDA")
	)
	(segment
		(start 330.836778 -171.059094)
		(end 334.299814 -167.596058)
		(width 0.1143)
		(layer "B.Cu")
		(net "BMC_I2C_F_SDA")
	)
	(segment
		(start 327.152 -171.370498)
		(end 327.463404 -171.059094)
		(width 0.1143)
		(layer "B.Cu")
		(net "BMC_I2C_F_SDA")
	)
	(segment
		(start 327.55078 -156.35478)
		(end 327.55078 -151.74722)
		(width 0.1143)
		(layer "B.Cu")
		(net "BMC_I2C_F_SDA")
	)
	(segment
		(start 292.056566 -135.509)
		(end 296.933366 -130.6322)
		(width 0.127)
		(layer "In2.Cu")
		(net "BMC_I2C_F_SDA")
	)
	(segment
		(start 179.676298 -143.5354)
		(end 180.34508 -144.204182)
		(width 0.127)
		(layer "In2.Cu")
		(net "BMC_I2C_F_SDA")
	)
	(segment
		(start 328.023728 -148.108162)
		(end 328.023728 -151.274272)
		(width 0.127)
		(layer "In2.Cu")
		(net "BMC_I2C_F_SDA")
	)
	(segment
		(start 328.023728 -151.274272)
		(end 327.55078 -151.74722)
		(width 0.127)
		(layer "In2.Cu")
		(net "BMC_I2C_F_SDA")
	)
	(segment
		(start 88.85301 -120.7897)
		(end 88.871044 -120.807734)
		(width 0.127)
		(layer "In2.Cu")
		(net "BMC_I2C_F_SDA")
	)
	(segment
		(start 304.5079 -130.6322)
		(end 305.015646 -131.139946)
		(width 0.127)
		(layer "In2.Cu")
		(net "BMC_I2C_F_SDA")
	)
	(segment
		(start 285.242 -135.509)
		(end 292.056566 -135.509)
		(width 0.127)
		(layer "In2.Cu")
		(net "BMC_I2C_F_SDA")
	)
	(segment
		(start 316.809628 -134.27583)
		(end 316.809628 -134.63016)
		(width 0.127)
		(layer "In2.Cu")
		(net "BMC_I2C_F_SDA")
	)
	(segment
		(start 192.0367 -143.383)
		(end 195.373752 -146.720052)
		(width 0.127)
		(layer "In2.Cu")
		(net "BMC_I2C_F_SDA")
	)
	(segment
		(start 184.973468 -143.383)
		(end 192.0367 -143.383)
		(width 0.127)
		(layer "In2.Cu")
		(net "BMC_I2C_F_SDA")
	)
	(segment
		(start 296.933366 -130.6322)
		(end 304.5079 -130.6322)
		(width 0.127)
		(layer "In2.Cu")
		(net "BMC_I2C_F_SDA")
	)
	(segment
		(start 88.871044 -120.807734)
		(end 89.266776 -120.807734)
		(width 0.127)
		(layer "In2.Cu")
		(net "BMC_I2C_F_SDA")
	)
	(segment
		(start 111.461042 -143.002)
		(end 157.781498 -143.002)
		(width 0.127)
		(layer "In2.Cu")
		(net "BMC_I2C_F_SDA")
	)
	(segment
		(start 184.152286 -144.204182)
		(end 184.973468 -143.383)
		(width 0.127)
		(layer "In2.Cu")
		(net "BMC_I2C_F_SDA")
	)
	(segment
		(start 305.015646 -131.139946)
		(end 313.673744 -131.139946)
		(width 0.127)
		(layer "In2.Cu")
		(net "BMC_I2C_F_SDA")
	)
	(segment
		(start 321.945 -142.029434)
		(end 328.023728 -148.108162)
		(width 0.127)
		(layer "In2.Cu")
		(net "BMC_I2C_F_SDA")
	)
	(segment
		(start 204.008482 -145.923)
		(end 274.828 -145.923)
		(width 0.127)
		(layer "In2.Cu")
		(net "BMC_I2C_F_SDA")
	)
	(segment
		(start 195.373752 -146.720052)
		(end 199.994266 -146.720052)
		(width 0.127)
		(layer "In2.Cu")
		(net "BMC_I2C_F_SDA")
	)
	(segment
		(start 200.600818 -146.1135)
		(end 203.817982 -146.1135)
		(width 0.127)
		(layer "In2.Cu")
		(net "BMC_I2C_F_SDA")
	)
	(segment
		(start 313.673744 -131.139946)
		(end 316.809628 -134.27583)
		(width 0.127)
		(layer "In2.Cu")
		(net "BMC_I2C_F_SDA")
	)
	(segment
		(start 316.809628 -134.63016)
		(end 319.949068 -137.7696)
		(width 0.127)
		(layer "In2.Cu")
		(net "BMC_I2C_F_SDA")
	)
	(segment
		(start 321.945 -139.144502)
		(end 321.945 -142.029434)
		(width 0.127)
		(layer "In2.Cu")
		(net "BMC_I2C_F_SDA")
	)
	(segment
		(start 89.266776 -120.807734)
		(end 111.461042 -143.002)
		(width 0.127)
		(layer "In2.Cu")
		(net "BMC_I2C_F_SDA")
	)
	(segment
		(start 320.570098 -137.7696)
		(end 321.945 -139.144502)
		(width 0.127)
		(layer "In2.Cu")
		(net "BMC_I2C_F_SDA")
	)
	(segment
		(start 199.994266 -146.720052)
		(end 200.600818 -146.1135)
		(width 0.127)
		(layer "In2.Cu")
		(net "BMC_I2C_F_SDA")
	)
	(segment
		(start 274.828 -145.923)
		(end 285.242 -135.509)
		(width 0.127)
		(layer "In2.Cu")
		(net "BMC_I2C_F_SDA")
	)
	(segment
		(start 180.34508 -144.204182)
		(end 184.152286 -144.204182)
		(width 0.127)
		(layer "In2.Cu")
		(net "BMC_I2C_F_SDA")
	)
	(segment
		(start 157.781498 -143.002)
		(end 158.314898 -143.5354)
		(width 0.127)
		(layer "In2.Cu")
		(net "BMC_I2C_F_SDA")
	)
	(segment
		(start 203.817982 -146.1135)
		(end 204.008482 -145.923)
		(width 0.127)
		(layer "In2.Cu")
		(net "BMC_I2C_F_SDA")
	)
	(segment
		(start 319.949068 -137.7696)
		(end 320.570098 -137.7696)
		(width 0.127)
		(layer "In2.Cu")
		(net "BMC_I2C_F_SDA")
	)
	(segment
		(start 158.314898 -143.5354)
		(end 179.676298 -143.5354)
		(width 0.127)
		(layer "In2.Cu")
		(net "BMC_I2C_F_SDA")
	)
	(segment
		(start 87.356442 -121.793762)
		(end 88.79205 -121.793762)
		(width 0.1143)
		(layer "F.Cu")
		(net "BMC_I2C_F_SCL")
	)
	(segment
		(start 89.929462 -121.793762)
		(end 88.79205 -121.793762)
		(width 0.1143)
		(layer "F.Cu")
		(net "BMC_I2C_F_SCL")
	)
	(segment
		(start 90.239342 -121.483882)
		(end 89.929462 -121.793762)
		(width 0.1143)
		(layer "F.Cu")
		(net "BMC_I2C_F_SCL")
	)
	(via
		(at 326.531478 -148.59)
		(size 0.5588)
		(drill 0.3048)
		(layers "F.Cu" "B.Cu")
		(net "BMC_I2C_F_SCL")
	)
	(via
		(at 330.2 -169.926)
		(size 0.7112)
		(drill 0.3556)
		(layers "F.Cu" "B.Cu")
		(net "BMC_I2C_F_SCL")
	)
	(via
		(at 88.79205 -121.793762)
		(size 0.5588)
		(drill 0.3048)
		(layers "F.Cu" "B.Cu")
		(net "BMC_I2C_F_SCL")
	)
	(segment
		(start 329.562206 -170.563794)
		(end 330.2 -169.926)
		(width 0.1143)
		(layer "B.Cu")
		(net "BMC_I2C_F_SCL")
	)
	(segment
		(start 321.49542 -170.46575)
		(end 322.353686 -170.46575)
		(width 0.1143)
		(layer "B.Cu")
		(net "BMC_I2C_F_SCL")
	)
	(segment
		(start 322.696586 -170.80865)
		(end 324.280276 -170.80865)
		(width 0.1143)
		(layer "B.Cu")
		(net "BMC_I2C_F_SCL")
	)
	(segment
		(start 333.804514 -167.390826)
		(end 331.26934 -169.926)
		(width 0.1143)
		(layer "B.Cu")
		(net "BMC_I2C_F_SCL")
	)
	(segment
		(start 320.187828 -170.942)
		(end 321.01917 -170.942)
		(width 0.1143)
		(layer "B.Cu")
		(net "BMC_I2C_F_SCL")
	)
	(segment
		(start 333.804514 -163.497514)
		(end 333.804514 -167.390826)
		(width 0.1143)
		(layer "B.Cu")
		(net "BMC_I2C_F_SCL")
	)
	(segment
		(start 324.525132 -170.563794)
		(end 329.562206 -170.563794)
		(width 0.1143)
		(layer "B.Cu")
		(net "BMC_I2C_F_SCL")
	)
	(segment
		(start 324.280276 -170.80865)
		(end 324.525132 -170.563794)
		(width 0.1143)
		(layer "B.Cu")
		(net "BMC_I2C_F_SCL")
	)
	(segment
		(start 326.531478 -156.224478)
		(end 333.804514 -163.497514)
		(width 0.1143)
		(layer "B.Cu")
		(net "BMC_I2C_F_SCL")
	)
	(segment
		(start 331.26934 -169.926)
		(end 330.2 -169.926)
		(width 0.1143)
		(layer "B.Cu")
		(net "BMC_I2C_F_SCL")
	)
	(segment
		(start 318.7065 -171.323)
		(end 319.806828 -171.323)
		(width 0.1143)
		(layer "B.Cu")
		(net "BMC_I2C_F_SCL")
	)
	(segment
		(start 319.806828 -171.323)
		(end 320.187828 -170.942)
		(width 0.1143)
		(layer "B.Cu")
		(net "BMC_I2C_F_SCL")
	)
	(segment
		(start 321.01917 -170.942)
		(end 321.49542 -170.46575)
		(width 0.1143)
		(layer "B.Cu")
		(net "BMC_I2C_F_SCL")
	)
	(segment
		(start 318.4525 -171.577)
		(end 318.7065 -171.323)
		(width 0.1143)
		(layer "B.Cu")
		(net "BMC_I2C_F_SCL")
	)
	(segment
		(start 326.531478 -148.59)
		(end 326.531478 -156.224478)
		(width 0.1143)
		(layer "B.Cu")
		(net "BMC_I2C_F_SCL")
	)
	(segment
		(start 322.353686 -170.46575)
		(end 322.696586 -170.80865)
		(width 0.1143)
		(layer "B.Cu")
		(net "BMC_I2C_F_SCL")
	)
	(segment
		(start 192.378584 -147.228052)
		(end 189.041532 -143.891)
		(width 0.127)
		(layer "In2.Cu")
		(net "BMC_I2C_F_SCL")
	)
	(segment
		(start 320.359532 -138.2776)
		(end 319.738502 -138.2776)
		(width 0.127)
		(layer "In2.Cu")
		(net "BMC_I2C_F_SCL")
	)
	(segment
		(start 157.570932 -143.51)
		(end 111.250476 -143.51)
		(width 0.127)
		(layer "In2.Cu")
		(net "BMC_I2C_F_SCL")
	)
	(segment
		(start 205.170532 -146.431)
		(end 204.980032 -146.6215)
		(width 0.127)
		(layer "In2.Cu")
		(net "BMC_I2C_F_SCL")
	)
	(segment
		(start 204.980032 -146.6215)
		(end 200.811384 -146.6215)
		(width 0.127)
		(layer "In2.Cu")
		(net "BMC_I2C_F_SCL")
	)
	(segment
		(start 313.463178 -131.647946)
		(end 304.80508 -131.647946)
		(width 0.127)
		(layer "In2.Cu")
		(net "BMC_I2C_F_SCL")
	)
	(segment
		(start 297.531536 -131.1402)
		(end 292.527736 -136.144)
		(width 0.127)
		(layer "In2.Cu")
		(net "BMC_I2C_F_SCL")
	)
	(segment
		(start 189.041532 -143.891)
		(end 185.184034 -143.891)
		(width 0.127)
		(layer "In2.Cu")
		(net "BMC_I2C_F_SCL")
	)
	(segment
		(start 286.388302 -136.144)
		(end 276.101302 -146.431)
		(width 0.127)
		(layer "In2.Cu")
		(net "BMC_I2C_F_SCL")
	)
	(segment
		(start 200.204832 -147.228052)
		(end 192.378584 -147.228052)
		(width 0.127)
		(layer "In2.Cu")
		(net "BMC_I2C_F_SCL")
	)
	(segment
		(start 304.80508 -131.647946)
		(end 304.297334 -131.1402)
		(width 0.127)
		(layer "In2.Cu")
		(net "BMC_I2C_F_SCL")
	)
	(segment
		(start 326.531478 -148.59)
		(end 326.531478 -147.334478)
		(width 0.127)
		(layer "In2.Cu")
		(net "BMC_I2C_F_SCL")
	)
	(segment
		(start 92.708476 -124.968)
		(end 91.966288 -124.968)
		(width 0.127)
		(layer "In2.Cu")
		(net "BMC_I2C_F_SCL")
	)
	(segment
		(start 276.101302 -146.431)
		(end 205.170532 -146.431)
		(width 0.127)
		(layer "In2.Cu")
		(net "BMC_I2C_F_SCL")
	)
	(segment
		(start 180.134514 -144.712182)
		(end 179.465732 -144.0434)
		(width 0.127)
		(layer "In2.Cu")
		(net "BMC_I2C_F_SCL")
	)
	(segment
		(start 316.301628 -134.840726)
		(end 316.301628 -134.486396)
		(width 0.127)
		(layer "In2.Cu")
		(net "BMC_I2C_F_SCL")
	)
	(segment
		(start 200.811384 -146.6215)
		(end 200.204832 -147.228052)
		(width 0.127)
		(layer "In2.Cu")
		(net "BMC_I2C_F_SCL")
	)
	(segment
		(start 319.738502 -138.2776)
		(end 316.301628 -134.840726)
		(width 0.127)
		(layer "In2.Cu")
		(net "BMC_I2C_F_SCL")
	)
	(segment
		(start 91.966288 -124.968)
		(end 88.79205 -121.793762)
		(width 0.127)
		(layer "In2.Cu")
		(net "BMC_I2C_F_SCL")
	)
	(segment
		(start 111.250476 -143.51)
		(end 92.708476 -124.968)
		(width 0.127)
		(layer "In2.Cu")
		(net "BMC_I2C_F_SCL")
	)
	(segment
		(start 185.184034 -143.891)
		(end 184.362852 -144.712182)
		(width 0.127)
		(layer "In2.Cu")
		(net "BMC_I2C_F_SCL")
	)
	(segment
		(start 184.362852 -144.712182)
		(end 180.134514 -144.712182)
		(width 0.127)
		(layer "In2.Cu")
		(net "BMC_I2C_F_SCL")
	)
	(segment
		(start 158.104332 -144.0434)
		(end 157.570932 -143.51)
		(width 0.127)
		(layer "In2.Cu")
		(net "BMC_I2C_F_SCL")
	)
	(segment
		(start 321.437 -139.355068)
		(end 320.359532 -138.2776)
		(width 0.127)
		(layer "In2.Cu")
		(net "BMC_I2C_F_SCL")
	)
	(segment
		(start 316.301628 -134.486396)
		(end 313.463178 -131.647946)
		(width 0.127)
		(layer "In2.Cu")
		(net "BMC_I2C_F_SCL")
	)
	(segment
		(start 292.527736 -136.144)
		(end 286.388302 -136.144)
		(width 0.127)
		(layer "In2.Cu")
		(net "BMC_I2C_F_SCL")
	)
	(segment
		(start 326.531478 -147.334478)
		(end 321.437 -142.24)
		(width 0.127)
		(layer "In2.Cu")
		(net "BMC_I2C_F_SCL")
	)
	(segment
		(start 304.297334 -131.1402)
		(end 297.531536 -131.1402)
		(width 0.127)
		(layer "In2.Cu")
		(net "BMC_I2C_F_SCL")
	)
	(segment
		(start 179.465732 -144.0434)
		(end 158.104332 -144.0434)
		(width 0.127)
		(layer "In2.Cu")
		(net "BMC_I2C_F_SCL")
	)
	(segment
		(start 321.437 -142.24)
		(end 321.437 -139.355068)
		(width 0.127)
		(layer "In2.Cu")
		(net "BMC_I2C_F_SCL")
	)
	(segment
		(start 106.3498 -104.350058)
		(end 106.3498 -104.48417)
		(width 0.1143)
		(layer "F.Cu")
		(net "EXP_SCL_0")
	)
	(segment
		(start 13.181584 -223.171512)
		(end 13.181584 -223.181672)
		(width 0.1143)
		(layer "F.Cu")
		(net "EXP_SCL_0")
	)
	(segment
		(start 14.237716 -222.94088)
		(end 13.412216 -222.94088)
		(width 0.1143)
		(layer "F.Cu")
		(net "EXP_SCL_0")
	)
	(segment
		(start 186.998356 -141.868652)
		(end 187.061348 -141.868652)
		(width 0.1143)
		(layer "F.Cu")
		(net "EXP_SCL_0")
	)
	(segment
		(start 81.730342 -121.864882)
		(end 82.508852 -121.864882)
		(width 0.1143)
		(layer "F.Cu")
		(net "EXP_SCL_0")
	)
	(segment
		(start 32.9184 -213.79688)
		(end 30.28188 -213.79688)
		(width 0.1143)
		(layer "F.Cu")
		(net "EXP_SCL_0")
	)
	(segment
		(start 105.983786 -104.850184)
		(end 105.849674 -104.850184)
		(width 0.1143)
		(layer "F.Cu")
		(net "EXP_SCL_0")
	)
	(segment
		(start 187.061348 -141.868652)
		(end 185.42 -143.51)
		(width 0.1143)
		(layer "F.Cu")
		(net "EXP_SCL_0")
	)
	(segment
		(start 185.42 -143.51)
		(end 185.42 -144.3736)
		(width 0.1143)
		(layer "F.Cu")
		(net "EXP_SCL_0")
	)
	(segment
		(start 13.412216 -222.94088)
		(end 13.181584 -223.171512)
		(width 0.1143)
		(layer "F.Cu")
		(net "EXP_SCL_0")
	)
	(segment
		(start 185.42 -144.3736)
		(end 185.3946 -144.399)
		(width 0.1143)
		(layer "F.Cu")
		(net "EXP_SCL_0")
	)
	(segment
		(start 82.765392 -122.0724)
		(end 82.766916 -122.073924)
		(width 0.1143)
		(layer "F.Cu")
		(net "EXP_SCL_0")
	)
	(segment
		(start 30.28188 -213.79688)
		(end 28.575 -212.09)
		(width 0.1143)
		(layer "F.Cu")
		(net "EXP_SCL_0")
	)
	(segment
		(start 106.3498 -104.48417)
		(end 105.983786 -104.850184)
		(width 0.1143)
		(layer "F.Cu")
		(net "EXP_SCL_0")
	)
	(segment
		(start 82.71637 -122.0724)
		(end 82.765392 -122.0724)
		(width 0.1143)
		(layer "F.Cu")
		(net "EXP_SCL_0")
	)
	(segment
		(start 82.508852 -121.864882)
		(end 82.71637 -122.0724)
		(width 0.1143)
		(layer "F.Cu")
		(net "EXP_SCL_0")
	)
	(via
		(at 82.766916 -122.073924)
		(size 0.5588)
		(drill 0.3048)
		(layers "F.Cu" "B.Cu")
		(net "EXP_SCL_0")
	)
	(via
		(at 105.849674 -104.850184)
		(size 0.508)
		(drill 0.254)
		(layers "F.Cu" "B.Cu")
		(net "EXP_SCL_0")
	)
	(via
		(at 185.3946 -144.399)
		(size 0.5588)
		(drill 0.3048)
		(layers "F.Cu" "B.Cu")
		(net "EXP_SCL_0")
	)
	(via
		(at 13.181584 -223.181672)
		(size 0.5588)
		(drill 0.3048)
		(layers "F.Cu" "B.Cu")
		(net "EXP_SCL_0")
	)
	(via
		(at 14.351 -221.996)
		(size 0.7112)
		(drill 0.3556)
		(layers "F.Cu" "B.Cu")
		(net "EXP_SCL_0")
	)
	(via
		(at 28.575 -212.09)
		(size 0.5588)
		(drill 0.3048)
		(layers "F.Cu" "B.Cu")
		(net "EXP_SCL_0")
	)
	(segment
		(start 13.181584 -223.165416)
		(end 14.351 -221.996)
		(width 0.1143)
		(layer "B.Cu")
		(net "EXP_SCL_0")
	)
	(segment
		(start 40.679116 -199.985884)
		(end 28.575 -212.09)
		(width 0.1143)
		(layer "B.Cu")
		(net "EXP_SCL_0")
	)
	(segment
		(start 82.773266 -149.601428)
		(end 66.0908 -166.283894)
		(width 0.1143)
		(layer "B.Cu")
		(net "EXP_SCL_0")
	)
	(segment
		(start 51.501294 -177.455068)
		(end 40.679116 -188.277246)
		(width 0.1143)
		(layer "B.Cu")
		(net "EXP_SCL_0")
	)
	(segment
		(start 66.0908 -170.760136)
		(end 59.685936 -177.165)
		(width 0.1143)
		(layer "B.Cu")
		(net "EXP_SCL_0")
	)
	(segment
		(start 12.82954 -223.181672)
		(end 13.181584 -223.181672)
		(width 0.1143)
		(layer "B.Cu")
		(net "EXP_SCL_0")
	)
	(segment
		(start 59.685936 -177.165)
		(end 51.791108 -177.165)
		(width 0.1143)
		(layer "B.Cu")
		(net "EXP_SCL_0")
	)
	(segment
		(start 40.679116 -188.277246)
		(end 40.679116 -199.985884)
		(width 0.1143)
		(layer "B.Cu")
		(net "EXP_SCL_0")
	)
	(segment
		(start 13.181584 -223.181672)
		(end 13.181584 -223.165416)
		(width 0.1143)
		(layer "B.Cu")
		(net "EXP_SCL_0")
	)
	(segment
		(start 82.766916 -122.073924)
		(end 82.773266 -122.080274)
		(width 0.1143)
		(layer "B.Cu")
		(net "EXP_SCL_0")
	)
	(segment
		(start 11.4935 -221.615)
		(end 11.4935 -221.845632)
		(width 0.1143)
		(layer "B.Cu")
		(net "EXP_SCL_0")
	)
	(segment
		(start 82.773266 -122.080274)
		(end 82.773266 -149.601428)
		(width 0.1143)
		(layer "B.Cu")
		(net "EXP_SCL_0")
	)
	(segment
		(start 11.4935 -221.845632)
		(end 12.82954 -223.181672)
		(width 0.1143)
		(layer "B.Cu")
		(net "EXP_SCL_0")
	)
	(segment
		(start 28.575 -212.09)
		(end 20.25142 -220.41358)
		(width 0.1143)
		(layer "B.Cu")
		(net "EXP_SCL_0")
	)
	(segment
		(start 51.791108 -177.165)
		(end 51.501294 -177.454814)
		(width 0.1143)
		(layer "B.Cu")
		(net "EXP_SCL_0")
	)
	(segment
		(start 20.25142 -220.41358)
		(end 15.93342 -220.41358)
		(width 0.1143)
		(layer "B.Cu")
		(net "EXP_SCL_0")
	)
	(segment
		(start 51.501294 -177.454814)
		(end 51.501294 -177.455068)
		(width 0.1143)
		(layer "B.Cu")
		(net "EXP_SCL_0")
	)
	(segment
		(start 15.93342 -220.41358)
		(end 14.351 -221.996)
		(width 0.1143)
		(layer "B.Cu")
		(net "EXP_SCL_0")
	)
	(segment
		(start 66.0908 -166.283894)
		(end 66.0908 -170.760136)
		(width 0.1143)
		(layer "B.Cu")
		(net "EXP_SCL_0")
	)
	(segment
		(start 102.94112 -107.7468)
		(end 101.149404 -107.7468)
		(width 0.127)
		(layer "In2.Cu")
		(net "EXP_SCL_0")
	)
	(segment
		(start 179.902866 -145.1991)
		(end 177.6349 -145.1991)
		(width 0.127)
		(layer "In2.Cu")
		(net "EXP_SCL_0")
	)
	(segment
		(start 82.76717 -122.07367)
		(end 82.766916 -122.073924)
		(width 0.127)
		(layer "In2.Cu")
		(net "EXP_SCL_0")
	)
	(segment
		(start 100.894896 -108.001308)
		(end 100.894896 -108.001562)
		(width 0.127)
		(layer "In2.Cu")
		(net "EXP_SCL_0")
	)
	(segment
		(start 103.39324 -107.29468)
		(end 102.94112 -107.7468)
		(width 0.127)
		(layer "In2.Cu")
		(net "EXP_SCL_0")
	)
	(segment
		(start 88.659716 -120.309894)
		(end 88.632284 -120.309894)
		(width 0.127)
		(layer "In2.Cu")
		(net "EXP_SCL_0")
	)
	(segment
		(start 88.957404 -123.19)
		(end 88.941656 -123.19)
		(width 0.127)
		(layer "In2.Cu")
		(net "EXP_SCL_0")
	)
	(segment
		(start 104.998012 -107.29468)
		(end 103.39324 -107.29468)
		(width 0.127)
		(layer "In2.Cu")
		(net "EXP_SCL_0")
	)
	(segment
		(start 98.918776 -109.977682)
		(end 96.688402 -112.20831)
		(width 0.127)
		(layer "In2.Cu")
		(net "EXP_SCL_0")
	)
	(segment
		(start 101.149404 -107.7468)
		(end 100.894896 -108.001308)
		(width 0.127)
		(layer "In2.Cu")
		(net "EXP_SCL_0")
	)
	(segment
		(start 105.849674 -104.850184)
		(end 105.849674 -105.221532)
		(width 0.127)
		(layer "In2.Cu")
		(net "EXP_SCL_0")
	)
	(segment
		(start 157.953202 -145.4277)
		(end 157.076902 -146.304)
		(width 0.127)
		(layer "In2.Cu")
		(net "EXP_SCL_0")
	)
	(segment
		(start 185.3946 -144.399)
		(end 184.573418 -145.220182)
		(width 0.127)
		(layer "In2.Cu")
		(net "EXP_SCL_0")
	)
	(segment
		(start 163.10991 -146.304)
		(end 159.661098 -146.304)
		(width 0.127)
		(layer "In2.Cu")
		(net "EXP_SCL_0")
	)
	(segment
		(start 157.076902 -146.304)
		(end 112.666526 -146.304)
		(width 0.127)
		(layer "In2.Cu")
		(net "EXP_SCL_0")
	)
	(segment
		(start 88.29675 -120.645428)
		(end 88.29675 -120.672606)
		(width 0.127)
		(layer "In2.Cu")
		(net "EXP_SCL_0")
	)
	(segment
		(start 88.824816 -123.07316)
		(end 83.766152 -123.07316)
		(width 0.127)
		(layer "In2.Cu")
		(net "EXP_SCL_0")
	)
	(segment
		(start 177.292 -145.542)
		(end 170.012868 -145.542)
		(width 0.127)
		(layer "In2.Cu")
		(net "EXP_SCL_0")
	)
	(segment
		(start 91.243404 -125.476)
		(end 88.957404 -123.19)
		(width 0.127)
		(layer "In2.Cu")
		(net "EXP_SCL_0")
	)
	(segment
		(start 87.810594 -121.158)
		(end 87.77224 -121.1961)
		(width 0.127)
		(layer "In2.Cu")
		(net "EXP_SCL_0")
	)
	(segment
		(start 88.941656 -123.19)
		(end 88.824816 -123.07316)
		(width 0.127)
		(layer "In2.Cu")
		(net "EXP_SCL_0")
	)
	(segment
		(start 95.679768 -113.9063)
		(end 95.06331 -113.9063)
		(width 0.127)
		(layer "In2.Cu")
		(net "EXP_SCL_0")
	)
	(segment
		(start 163.98621 -145.4277)
		(end 163.10991 -146.304)
		(width 0.127)
		(layer "In2.Cu")
		(net "EXP_SCL_0")
	)
	(segment
		(start 88.29675 -120.672606)
		(end 88.154002 -120.8151)
		(width 0.127)
		(layer "In2.Cu")
		(net "EXP_SCL_0")
	)
	(segment
		(start 87.77224 -121.1961)
		(end 87.70747 -121.26087)
		(width 0.127)
		(layer "In2.Cu")
		(net "EXP_SCL_0")
	)
	(segment
		(start 105.849674 -105.221532)
		(end 105.405174 -105.666032)
		(width 0.127)
		(layer "In2.Cu")
		(net "EXP_SCL_0")
	)
	(segment
		(start 88.632284 -120.309894)
		(end 88.29675 -120.645428)
		(width 0.127)
		(layer "In2.Cu")
		(net "EXP_SCL_0")
	)
	(segment
		(start 83.766152 -123.07316)
		(end 82.766916 -122.073924)
		(width 0.127)
		(layer "In2.Cu")
		(net "EXP_SCL_0")
	)
	(segment
		(start 105.405174 -105.666032)
		(end 105.405174 -106.887518)
		(width 0.127)
		(layer "In2.Cu")
		(net "EXP_SCL_0")
	)
	(segment
		(start 165.694106 -146.304)
		(end 164.817806 -145.4277)
		(width 0.127)
		(layer "In2.Cu")
		(net "EXP_SCL_0")
	)
	(segment
		(start 177.6349 -145.1991)
		(end 177.292 -145.542)
		(width 0.127)
		(layer "In2.Cu")
		(net "EXP_SCL_0")
	)
	(segment
		(start 82.76717 -122.0216)
		(end 82.76717 -122.07367)
		(width 0.127)
		(layer "In2.Cu")
		(net "EXP_SCL_0")
	)
	(segment
		(start 159.661098 -146.304)
		(end 158.784798 -145.4277)
		(width 0.127)
		(layer "In2.Cu")
		(net "EXP_SCL_0")
	)
	(segment
		(start 164.817806 -145.4277)
		(end 163.98621 -145.4277)
		(width 0.127)
		(layer "In2.Cu")
		(net "EXP_SCL_0")
	)
	(segment
		(start 169.250868 -146.304)
		(end 165.694106 -146.304)
		(width 0.127)
		(layer "In2.Cu")
		(net "EXP_SCL_0")
	)
	(segment
		(start 100.894896 -108.001562)
		(end 98.918776 -109.977682)
		(width 0.127)
		(layer "In2.Cu")
		(net "EXP_SCL_0")
	)
	(segment
		(start 88.108536 -120.860566)
		(end 87.810594 -121.158)
		(width 0.127)
		(layer "In2.Cu")
		(net "EXP_SCL_0")
	)
	(segment
		(start 87.70747 -121.26087)
		(end 83.5279 -121.26087)
		(width 0.127)
		(layer "In2.Cu")
		(net "EXP_SCL_0")
	)
	(segment
		(start 96.26727 -112.629442)
		(end 96.26727 -113.318798)
		(width 0.127)
		(layer "In2.Cu")
		(net "EXP_SCL_0")
	)
	(segment
		(start 96.26727 -113.318798)
		(end 95.679768 -113.9063)
		(width 0.127)
		(layer "In2.Cu")
		(net "EXP_SCL_0")
	)
	(segment
		(start 170.012868 -145.542)
		(end 169.250868 -146.304)
		(width 0.127)
		(layer "In2.Cu")
		(net "EXP_SCL_0")
	)
	(segment
		(start 88.154002 -120.8151)
		(end 88.108536 -120.860566)
		(width 0.127)
		(layer "In2.Cu")
		(net "EXP_SCL_0")
	)
	(segment
		(start 83.5279 -121.26087)
		(end 82.76717 -122.0216)
		(width 0.127)
		(layer "In2.Cu")
		(net "EXP_SCL_0")
	)
	(segment
		(start 95.06331 -113.9063)
		(end 88.659716 -120.309894)
		(width 0.127)
		(layer "In2.Cu")
		(net "EXP_SCL_0")
	)
	(segment
		(start 105.405174 -106.887518)
		(end 104.998012 -107.29468)
		(width 0.127)
		(layer "In2.Cu")
		(net "EXP_SCL_0")
	)
	(segment
		(start 158.784798 -145.4277)
		(end 157.953202 -145.4277)
		(width 0.127)
		(layer "In2.Cu")
		(net "EXP_SCL_0")
	)
	(segment
		(start 112.666526 -146.304)
		(end 91.838526 -125.476)
		(width 0.127)
		(layer "In2.Cu")
		(net "EXP_SCL_0")
	)
	(segment
		(start 96.688402 -112.20831)
		(end 96.26727 -112.629442)
		(width 0.127)
		(layer "In2.Cu")
		(net "EXP_SCL_0")
	)
	(segment
		(start 179.923948 -145.220182)
		(end 179.902866 -145.1991)
		(width 0.127)
		(layer "In2.Cu")
		(net "EXP_SCL_0")
	)
	(segment
		(start 91.838526 -125.476)
		(end 91.243404 -125.476)
		(width 0.127)
		(layer "In2.Cu")
		(net "EXP_SCL_0")
	)
	(segment
		(start 184.573418 -145.220182)
		(end 179.923948 -145.220182)
		(width 0.127)
		(layer "In2.Cu")
		(net "EXP_SCL_0")
	)
	(segment
		(start 186.944 -143.138652)
		(end 186.309 -143.773652)
		(width 0.1143)
		(layer "F.Cu")
		(net "EXP_SDA_0")
	)
	(segment
		(start 186.998356 -143.138652)
		(end 186.944 -143.138652)
		(width 0.1143)
		(layer "F.Cu")
		(net "EXP_SDA_0")
	)
	(segment
		(start 14.237716 -224.08388)
		(end 13.031216 -224.08388)
		(width 0.1143)
		(layer "F.Cu")
		(net "EXP_SDA_0")
	)
	(segment
		(start 186.309 -143.773652)
		(end 186.309 -144.399)
		(width 0.1143)
		(layer "F.Cu")
		(net "EXP_SDA_0")
	)
	(segment
		(start 81.730342 -120.721882)
		(end 82.54238 -120.721882)
		(width 0.1143)
		(layer "F.Cu")
		(net "EXP_SDA_0")
	)
	(segment
		(start 30.77464 -213.14664)
		(end 28.758388 -211.130388)
		(width 0.1143)
		(layer "F.Cu")
		(net "EXP_SDA_0")
	)
	(segment
		(start 104.349804 -106.350054)
		(end 103.849678 -106.85018)
		(width 0.1143)
		(layer "F.Cu")
		(net "EXP_SDA_0")
	)
	(segment
		(start 82.54238 -120.721882)
		(end 82.76717 -120.946672)
		(width 0.1143)
		(layer "F.Cu")
		(net "EXP_SDA_0")
	)
	(segment
		(start 82.76717 -121.154952)
		(end 82.771742 -121.159524)
		(width 0.1143)
		(layer "F.Cu")
		(net "EXP_SDA_0")
	)
	(segment
		(start 82.76717 -120.946672)
		(end 82.76717 -121.154952)
		(width 0.1143)
		(layer "F.Cu")
		(net "EXP_SDA_0")
	)
	(segment
		(start 32.9184 -213.14664)
		(end 30.77464 -213.14664)
		(width 0.1143)
		(layer "F.Cu")
		(net "EXP_SDA_0")
	)
	(via
		(at 13.031216 -224.08388)
		(size 0.5588)
		(drill 0.3048)
		(layers "F.Cu" "B.Cu")
		(net "EXP_SDA_0")
	)
	(via
		(at 11.811 -223.393)
		(size 0.7112)
		(drill 0.3556)
		(layers "F.Cu" "B.Cu")
		(net "EXP_SDA_0")
	)
	(via
		(at 82.771742 -121.159524)
		(size 0.5588)
		(drill 0.3048)
		(layers "F.Cu" "B.Cu")
		(net "EXP_SDA_0")
	)
	(via
		(at 28.758388 -211.130388)
		(size 0.5588)
		(drill 0.3048)
		(layers "F.Cu" "B.Cu")
		(net "EXP_SDA_0")
	)
	(via
		(at 186.309 -144.399)
		(size 0.5588)
		(drill 0.3048)
		(layers "F.Cu" "B.Cu")
		(net "EXP_SDA_0")
	)
	(via
		(at 103.849678 -106.85018)
		(size 0.508)
		(drill 0.254)
		(layers "F.Cu" "B.Cu")
		(net "EXP_SDA_0")
	)
	(segment
		(start 82.277966 -122.285506)
		(end 82.271362 -122.278902)
		(width 0.1143)
		(layer "B.Cu")
		(net "EXP_SDA_0")
	)
	(segment
		(start 40.183562 -188.072268)
		(end 51.005994 -177.249836)
		(width 0.1143)
		(layer "B.Cu")
		(net "EXP_SDA_0")
	)
	(segment
		(start 51.58613 -176.6697)
		(end 51.59883 -176.657)
		(width 0.1143)
		(layer "B.Cu")
		(net "EXP_SDA_0")
	)
	(segment
		(start 19.97075 -219.918026)
		(end 12.174474 -219.918026)
		(width 0.1143)
		(layer "B.Cu")
		(net "EXP_SDA_0")
	)
	(segment
		(start 28.758388 -211.130388)
		(end 19.97075 -219.918026)
		(width 0.1143)
		(layer "B.Cu")
		(net "EXP_SDA_0")
	)
	(segment
		(start 51.005994 -177.249836)
		(end 51.005994 -177.249582)
		(width 0.1143)
		(layer "B.Cu")
		(net "EXP_SDA_0")
	)
	(segment
		(start 12.647168 -223.699832)
		(end 13.031216 -224.08388)
		(width 0.1143)
		(layer "B.Cu")
		(net "EXP_SDA_0")
	)
	(segment
		(start 65.5955 -170.554904)
		(end 65.5955 -166.078662)
		(width 0.1143)
		(layer "B.Cu")
		(net "EXP_SDA_0")
	)
	(segment
		(start 59.493404 -176.657)
		(end 65.5955 -170.554904)
		(width 0.1143)
		(layer "B.Cu")
		(net "EXP_SDA_0")
	)
	(segment
		(start 28.758388 -211.130388)
		(end 40.183816 -199.70496)
		(width 0.1143)
		(layer "B.Cu")
		(net "EXP_SDA_0")
	)
	(segment
		(start 11.811 -223.393)
		(end 12.117832 -223.699832)
		(width 0.1143)
		(layer "B.Cu")
		(net "EXP_SDA_0")
	)
	(segment
		(start 51.005994 -177.249582)
		(end 51.585876 -176.6697)
		(width 0.1143)
		(layer "B.Cu")
		(net "EXP_SDA_0")
	)
	(segment
		(start 82.271362 -122.278902)
		(end 82.271362 -121.868946)
		(width 0.1143)
		(layer "B.Cu")
		(net "EXP_SDA_0")
	)
	(segment
		(start 82.271362 -121.868946)
		(end 82.277966 -121.862342)
		(width 0.1143)
		(layer "B.Cu")
		(net "EXP_SDA_0")
	)
	(segment
		(start 40.183816 -199.70496)
		(end 40.183816 -188.482478)
		(width 0.1143)
		(layer "B.Cu")
		(net "EXP_SDA_0")
	)
	(segment
		(start 11.4935 -220.599)
		(end 10.9728 -221.1197)
		(width 0.1143)
		(layer "B.Cu")
		(net "EXP_SDA_0")
	)
	(segment
		(start 82.277966 -121.862342)
		(end 82.277966 -121.6533)
		(width 0.1143)
		(layer "B.Cu")
		(net "EXP_SDA_0")
	)
	(segment
		(start 12.117832 -223.699832)
		(end 12.647168 -223.699832)
		(width 0.1143)
		(layer "B.Cu")
		(net "EXP_SDA_0")
	)
	(segment
		(start 40.183816 -188.482478)
		(end 40.183562 -188.482224)
		(width 0.1143)
		(layer "B.Cu")
		(net "EXP_SDA_0")
	)
	(segment
		(start 40.183562 -188.482224)
		(end 40.183562 -188.072268)
		(width 0.1143)
		(layer "B.Cu")
		(net "EXP_SDA_0")
	)
	(segment
		(start 10.9728 -222.0468)
		(end 11.811 -222.885)
		(width 0.1143)
		(layer "B.Cu")
		(net "EXP_SDA_0")
	)
	(segment
		(start 11.811 -222.885)
		(end 11.811 -223.393)
		(width 0.1143)
		(layer "B.Cu")
		(net "EXP_SDA_0")
	)
	(segment
		(start 82.277966 -121.6533)
		(end 82.771742 -121.159524)
		(width 0.1143)
		(layer "B.Cu")
		(net "EXP_SDA_0")
	)
	(segment
		(start 12.174474 -219.918026)
		(end 11.4935 -220.599)
		(width 0.1143)
		(layer "B.Cu")
		(net "EXP_SDA_0")
	)
	(segment
		(start 65.5955 -166.078662)
		(end 82.277966 -149.396196)
		(width 0.1143)
		(layer "B.Cu")
		(net "EXP_SDA_0")
	)
	(segment
		(start 10.9728 -221.1197)
		(end 10.9728 -222.0468)
		(width 0.1143)
		(layer "B.Cu")
		(net "EXP_SDA_0")
	)
	(segment
		(start 51.585876 -176.6697)
		(end 51.58613 -176.6697)
		(width 0.1143)
		(layer "B.Cu")
		(net "EXP_SDA_0")
	)
	(segment
		(start 82.277966 -149.396196)
		(end 82.277966 -122.285506)
		(width 0.1143)
		(layer "B.Cu")
		(net "EXP_SDA_0")
	)
	(segment
		(start 51.59883 -176.657)
		(end 59.493404 -176.657)
		(width 0.1143)
		(layer "B.Cu")
		(net "EXP_SDA_0")
	)
	(segment
		(start 164.196776 -145.9357)
		(end 164.60724 -145.9357)
		(width 0.127)
		(layer "In2.Cu")
		(net "EXP_SDA_0")
	)
	(segment
		(start 159.450532 -146.812)
		(end 163.320476 -146.812)
		(width 0.127)
		(layer "In2.Cu")
		(net "EXP_SDA_0")
	)
	(segment
		(start 88.421972 -119.80164)
		(end 88.449404 -119.80164)
		(width 0.127)
		(layer "In2.Cu")
		(net "EXP_SDA_0")
	)
	(segment
		(start 157.287468 -146.812)
		(end 158.163768 -145.9357)
		(width 0.127)
		(layer "In2.Cu")
		(net "EXP_SDA_0")
	)
	(segment
		(start 165.48354 -146.812)
		(end 169.461434 -146.812)
		(width 0.127)
		(layer "In2.Cu")
		(net "EXP_SDA_0")
	)
	(segment
		(start 169.461434 -146.812)
		(end 170.223434 -146.05)
		(width 0.127)
		(layer "In2.Cu")
		(net "EXP_SDA_0")
	)
	(segment
		(start 103.47833 -106.85018)
		(end 103.849678 -106.85018)
		(width 0.127)
		(layer "In2.Cu")
		(net "EXP_SDA_0")
	)
	(segment
		(start 82.771742 -121.159524)
		(end 82.258916 -121.67235)
		(width 0.127)
		(layer "In2.Cu")
		(net "EXP_SDA_0")
	)
	(segment
		(start 100.812092 -107.3658)
		(end 102.96271 -107.3658)
		(width 0.127)
		(layer "In2.Cu")
		(net "EXP_SDA_0")
	)
	(segment
		(start 179.532534 -145.7071)
		(end 179.553616 -145.728182)
		(width 0.127)
		(layer "In2.Cu")
		(net "EXP_SDA_0")
	)
	(segment
		(start 178.9049 -145.7071)
		(end 179.532534 -145.7071)
		(width 0.127)
		(layer "In2.Cu")
		(net "EXP_SDA_0")
	)
	(segment
		(start 88.449404 -119.80164)
		(end 94.852744 -113.3983)
		(width 0.127)
		(layer "In2.Cu")
		(net "EXP_SDA_0")
	)
	(segment
		(start 82.771742 -121.159524)
		(end 83.178396 -120.75287)
		(width 0.127)
		(layer "In2.Cu")
		(net "EXP_SDA_0")
	)
	(segment
		(start 164.60724 -145.9357)
		(end 165.48354 -146.812)
		(width 0.127)
		(layer "In2.Cu")
		(net "EXP_SDA_0")
	)
	(segment
		(start 83.178396 -120.75287)
		(end 87.491316 -120.75287)
		(width 0.127)
		(layer "In2.Cu")
		(net "EXP_SDA_0")
	)
	(segment
		(start 158.163768 -145.9357)
		(end 158.574232 -145.9357)
		(width 0.127)
		(layer "In2.Cu")
		(net "EXP_SDA_0")
	)
	(segment
		(start 94.852744 -113.3983)
		(end 95.469202 -113.3983)
		(width 0.127)
		(layer "In2.Cu")
		(net "EXP_SDA_0")
	)
	(segment
		(start 179.553616 -145.728182)
		(end 184.783984 -145.728182)
		(width 0.127)
		(layer "In2.Cu")
		(net "EXP_SDA_0")
	)
	(segment
		(start 83.555586 -123.58116)
		(end 88.61425 -123.58116)
		(width 0.127)
		(layer "In2.Cu")
		(net "EXP_SDA_0")
	)
	(segment
		(start 184.783984 -145.728182)
		(end 186.113166 -144.399)
		(width 0.127)
		(layer "In2.Cu")
		(net "EXP_SDA_0")
	)
	(segment
		(start 178.562 -146.05)
		(end 178.9049 -145.7071)
		(width 0.127)
		(layer "In2.Cu")
		(net "EXP_SDA_0")
	)
	(segment
		(start 87.78875 -120.434862)
		(end 88.421972 -119.80164)
		(width 0.127)
		(layer "In2.Cu")
		(net "EXP_SDA_0")
	)
	(segment
		(start 170.223434 -146.05)
		(end 178.562 -146.05)
		(width 0.127)
		(layer "In2.Cu")
		(net "EXP_SDA_0")
	)
	(segment
		(start 92.64396 -127)
		(end 112.45596 -146.812)
		(width 0.127)
		(layer "In2.Cu")
		(net "EXP_SDA_0")
	)
	(segment
		(start 186.113166 -144.399)
		(end 186.309 -144.399)
		(width 0.127)
		(layer "In2.Cu")
		(net "EXP_SDA_0")
	)
	(segment
		(start 82.258916 -121.67235)
		(end 82.258916 -122.28449)
		(width 0.127)
		(layer "In2.Cu")
		(net "EXP_SDA_0")
	)
	(segment
		(start 88.61425 -123.58116)
		(end 92.03309 -127)
		(width 0.127)
		(layer "In2.Cu")
		(net "EXP_SDA_0")
	)
	(segment
		(start 112.45596 -146.812)
		(end 157.287468 -146.812)
		(width 0.127)
		(layer "In2.Cu")
		(net "EXP_SDA_0")
	)
	(segment
		(start 95.469202 -113.3983)
		(end 95.75927 -113.108232)
		(width 0.127)
		(layer "In2.Cu")
		(net "EXP_SDA_0")
	)
	(segment
		(start 102.96271 -107.3658)
		(end 103.47833 -106.85018)
		(width 0.127)
		(layer "In2.Cu")
		(net "EXP_SDA_0")
	)
	(segment
		(start 163.320476 -146.812)
		(end 164.196776 -145.9357)
		(width 0.127)
		(layer "In2.Cu")
		(net "EXP_SDA_0")
	)
	(segment
		(start 82.258916 -122.28449)
		(end 83.555586 -123.58116)
		(width 0.127)
		(layer "In2.Cu")
		(net "EXP_SDA_0")
	)
	(segment
		(start 98.285554 -109.892338)
		(end 100.812092 -107.3658)
		(width 0.127)
		(layer "In2.Cu")
		(net "EXP_SDA_0")
	)
	(segment
		(start 87.491316 -120.75287)
		(end 87.78875 -120.455436)
		(width 0.127)
		(layer "In2.Cu")
		(net "EXP_SDA_0")
	)
	(segment
		(start 95.75927 -112.418876)
		(end 98.285554 -109.892338)
		(width 0.127)
		(layer "In2.Cu")
		(net "EXP_SDA_0")
	)
	(segment
		(start 92.03309 -127)
		(end 92.64396 -127)
		(width 0.127)
		(layer "In2.Cu")
		(net "EXP_SDA_0")
	)
	(segment
		(start 87.78875 -120.455436)
		(end 87.78875 -120.434862)
		(width 0.127)
		(layer "In2.Cu")
		(net "EXP_SDA_0")
	)
	(segment
		(start 95.75927 -113.108232)
		(end 95.75927 -112.418876)
		(width 0.127)
		(layer "In2.Cu")
		(net "EXP_SDA_0")
	)
	(segment
		(start 158.574232 -145.9357)
		(end 159.450532 -146.812)
		(width 0.127)
		(layer "In2.Cu")
		(net "EXP_SDA_0")
	)
	(segment
		(start 266.5095 -176.022)
		(end 267.335 -176.022)
		(width 0.1143)
		(layer "F.Cu")
		(net "BMC_SALT3")
	)
	(segment
		(start 288.034984 -173.04004)
		(end 288.045652 -173.04004)
		(width 0.1143)
		(layer "F.Cu")
		(net "BMC_SALT3")
	)
	(segment
		(start 267.1064 -174.9298)
		(end 267.3604 -175.1838)
		(width 0.1143)
		(layer "F.Cu")
		(net "BMC_SALT3")
	)
	(segment
		(start 288.045652 -173.04004)
		(end 288.46399 -172.621702)
		(width 0.1143)
		(layer "F.Cu")
		(net "BMC_SALT3")
	)
	(segment
		(start 267.3604 -175.9966)
		(end 267.335 -176.022)
		(width 0.1143)
		(layer "F.Cu")
		(net "BMC_SALT3")
	)
	(segment
		(start 267.3604 -175.1838)
		(end 267.3604 -175.9966)
		(width 0.1143)
		(layer "F.Cu")
		(net "BMC_SALT3")
	)
	(via
		(at 288.46399 -172.621702)
		(size 0.508)
		(drill 0.254)
		(layers "F.Cu" "B.Cu")
		(net "BMC_SALT3")
	)
	(via
		(at 267.335 -176.022)
		(size 0.5588)
		(drill 0.3048)
		(layers "F.Cu" "B.Cu")
		(net "BMC_SALT3")
	)
	(via
		(at 267.1064 -174.9298)
		(size 0.7112)
		(drill 0.3556)
		(layers "F.Cu" "B.Cu")
		(net "BMC_SALT3")
	)
	(segment
		(start 271.2847 -174.9933)
		(end 271.604232 -174.9933)
		(width 0.127)
		(layer "In2.Cu")
		(net "BMC_SALT3")
	)
	(segment
		(start 267.335 -176.022)
		(end 267.97 -175.387)
		(width 0.127)
		(layer "In2.Cu")
		(net "BMC_SALT3")
	)
	(segment
		(start 288.440876 -172.644816)
		(end 288.46399 -172.621702)
		(width 0.127)
		(layer "In2.Cu")
		(net "BMC_SALT3")
	)
	(segment
		(start 282.56738 -174.016416)
		(end 283.29636 -173.287436)
		(width 0.127)
		(layer "In2.Cu")
		(net "BMC_SALT3")
	)
	(segment
		(start 288.05505 -173.030642)
		(end 288.440876 -172.644816)
		(width 0.0889)
		(layer "In2.Cu")
		(net "BMC_SALT3")
	)
	(segment
		(start 286.623252 -173.013116)
		(end 287.100772 -173.013116)
		(width 0.127)
		(layer "In2.Cu")
		(net "BMC_SALT3")
	)
	(segment
		(start 283.513022 -173.282356)
		(end 285.715456 -173.282356)
		(width 0.127)
		(layer "In2.Cu")
		(net "BMC_SALT3")
	)
	(segment
		(start 285.755588 -173.322488)
		(end 286.31388 -173.322488)
		(width 0.127)
		(layer "In2.Cu")
		(net "BMC_SALT3")
	)
	(segment
		(start 287.118298 -173.030642)
		(end 288.05505 -173.030642)
		(width 0.0889)
		(layer "In2.Cu")
		(net "BMC_SALT3")
	)
	(segment
		(start 270.891 -175.387)
		(end 271.2847 -174.9933)
		(width 0.127)
		(layer "In2.Cu")
		(net "BMC_SALT3")
	)
	(segment
		(start 287.110932 -173.023276)
		(end 287.118298 -173.030642)
		(width 0.0889)
		(layer "In2.Cu")
		(net "BMC_SALT3")
	)
	(segment
		(start 283.29636 -173.287436)
		(end 283.507942 -173.287436)
		(width 0.127)
		(layer "In2.Cu")
		(net "BMC_SALT3")
	)
	(segment
		(start 285.715456 -173.282356)
		(end 285.755588 -173.322488)
		(width 0.127)
		(layer "In2.Cu")
		(net "BMC_SALT3")
	)
	(segment
		(start 272.581116 -174.016416)
		(end 282.56738 -174.016416)
		(width 0.127)
		(layer "In2.Cu")
		(net "BMC_SALT3")
	)
	(segment
		(start 283.507942 -173.287436)
		(end 283.513022 -173.282356)
		(width 0.127)
		(layer "In2.Cu")
		(net "BMC_SALT3")
	)
	(segment
		(start 271.604232 -174.9933)
		(end 272.581116 -174.016416)
		(width 0.127)
		(layer "In2.Cu")
		(net "BMC_SALT3")
	)
	(segment
		(start 267.97 -175.387)
		(end 270.891 -175.387)
		(width 0.127)
		(layer "In2.Cu")
		(net "BMC_SALT3")
	)
	(segment
		(start 286.31388 -173.322488)
		(end 286.623252 -173.013116)
		(width 0.127)
		(layer "In2.Cu")
		(net "BMC_SALT3")
	)
	(segment
		(start 287.100772 -173.013116)
		(end 287.110932 -173.023276)
		(width 0.127)
		(layer "In2.Cu")
		(net "BMC_SALT3")
	)
	(segment
		(start 267.64234 -172.974)
		(end 267.73632 -172.88002)
		(width 0.1143)
		(layer "F.Cu")
		(net "BMC_SALT4")
	)
	(segment
		(start 266.5095 -172.974)
		(end 267.64234 -172.974)
		(width 0.1143)
		(layer "F.Cu")
		(net "BMC_SALT4")
	)
	(segment
		(start 288.034984 -171.440094)
		(end 288.25444 -171.65955)
		(width 0.1143)
		(layer "F.Cu")
		(net "BMC_SALT4")
	)
	(segment
		(start 288.25444 -171.65955)
		(end 288.41065 -171.65955)
		(width 0.1143)
		(layer "F.Cu")
		(net "BMC_SALT4")
	)
	(segment
		(start 288.41065 -171.65955)
		(end 288.5821 -171.831)
		(width 0.1143)
		(layer "F.Cu")
		(net "BMC_SALT4")
	)
	(via
		(at 266.827 -172.847)
		(size 0.7112)
		(drill 0.3556)
		(layers "F.Cu" "B.Cu")
		(net "BMC_SALT4")
	)
	(via
		(at 288.5821 -171.831)
		(size 0.508)
		(drill 0.254)
		(layers "F.Cu" "B.Cu")
		(net "BMC_SALT4")
	)
	(via
		(at 267.73632 -172.88002)
		(size 0.508)
		(drill 0.254)
		(layers "F.Cu" "B.Cu")
		(net "BMC_SALT4")
	)
	(segment
		(start 267.7033 -172.847)
		(end 267.73632 -172.88002)
		(width 0.1143)
		(layer "B.Cu")
		(net "BMC_SALT4")
	)
	(segment
		(start 266.827 -172.847)
		(end 267.7033 -172.847)
		(width 0.1143)
		(layer "B.Cu")
		(net "BMC_SALT4")
	)
	(segment
		(start 286.369252 -171.435776)
		(end 286.378396 -171.44492)
		(width 0.0889)
		(layer "In2.Cu")
		(net "BMC_SALT4")
	)
	(segment
		(start 269.199868 -171.416472)
		(end 286.349948 -171.416472)
		(width 0.127)
		(layer "In2.Cu")
		(net "BMC_SALT4")
	)
	(segment
		(start 286.378396 -171.44492)
		(end 288.19602 -171.44492)
		(width 0.0889)
		(layer "In2.Cu")
		(net "BMC_SALT4")
	)
	(segment
		(start 288.19602 -171.44492)
		(end 288.5821 -171.831)
		(width 0.0889)
		(layer "In2.Cu")
		(net "BMC_SALT4")
	)
	(segment
		(start 286.349948 -171.416472)
		(end 286.369252 -171.435776)
		(width 0.127)
		(layer "In2.Cu")
		(net "BMC_SALT4")
	)
	(segment
		(start 267.73632 -172.88002)
		(end 269.199868 -171.416472)
		(width 0.127)
		(layer "In2.Cu")
		(net "BMC_SALT4")
	)
	(segment
		(start 259.207 -167.7035)
		(end 264.4775 -172.974)
		(width 0.1143)
		(layer "F.Cu")
		(net "NIC_SMBUS_ALERT_N")
	)
	(segment
		(start 247.65 -134.747)
		(end 250.46305 -137.56005)
		(width 0.1143)
		(layer "F.Cu")
		(net "NIC_SMBUS_ALERT_N")
	)
	(segment
		(start 251.1806 -110.4392)
		(end 251.1806 -112.0394)
		(width 0.1143)
		(layer "F.Cu")
		(net "NIC_SMBUS_ALERT_N")
	)
	(segment
		(start 264.4775 -172.974)
		(end 265.6205 -172.974)
		(width 0.1143)
		(layer "F.Cu")
		(net "NIC_SMBUS_ALERT_N")
	)
	(segment
		(start 249.000264 -114.219736)
		(end 249.000264 -115.93576)
		(width 0.1143)
		(layer "F.Cu")
		(net "NIC_SMBUS_ALERT_N")
	)
	(segment
		(start 259.207 -154.94)
		(end 259.207 -167.7035)
		(width 0.1143)
		(layer "F.Cu")
		(net "NIC_SMBUS_ALERT_N")
	)
	(segment
		(start 250.46305 -137.56005)
		(end 250.46305 -146.19605)
		(width 0.1143)
		(layer "F.Cu")
		(net "NIC_SMBUS_ALERT_N")
	)
	(segment
		(start 266.5095 -173.863)
		(end 265.6205 -172.974)
		(width 0.1143)
		(layer "F.Cu")
		(net "NIC_SMBUS_ALERT_N")
	)
	(segment
		(start 251.1806 -112.0394)
		(end 249.000264 -114.219736)
		(width 0.1143)
		(layer "F.Cu")
		(net "NIC_SMBUS_ALERT_N")
	)
	(segment
		(start 247.65 -117.286024)
		(end 247.65 -134.747)
		(width 0.1143)
		(layer "F.Cu")
		(net "NIC_SMBUS_ALERT_N")
	)
	(segment
		(start 250.46305 -146.19605)
		(end 259.207 -154.94)
		(width 0.1143)
		(layer "F.Cu")
		(net "NIC_SMBUS_ALERT_N")
	)
	(segment
		(start 266.5095 -173.99)
		(end 266.5095 -173.863)
		(width 0.1143)
		(layer "F.Cu")
		(net "NIC_SMBUS_ALERT_N")
	)
	(segment
		(start 249.000264 -115.93576)
		(end 247.65 -117.286024)
		(width 0.1143)
		(layer "F.Cu")
		(net "NIC_SMBUS_ALERT_N")
	)
	(via
		(at 251.1806 -110.4392)
		(size 0.5588)
		(drill 0.3048)
		(layers "F.Cu" "B.Cu")
		(net "NIC_SMBUS_ALERT_N")
	)
	(segment
		(start 179.578 -79.756)
		(end 179.578 -80.419702)
		(width 0.127)
		(layer "In2.Cu")
		(net "NIC_SMBUS_ALERT_N")
	)
	(segment
		(start 219.529152 -85.09)
		(end 228.346 -85.09)
		(width 0.127)
		(layer "In2.Cu")
		(net "NIC_SMBUS_ALERT_N")
	)
	(segment
		(start 256.0447 -90.4113)
		(end 259.4483 -87.0077)
		(width 0.127)
		(layer "In2.Cu")
		(net "NIC_SMBUS_ALERT_N")
	)
	(segment
		(start 228.346 -85.09)
		(end 233.6673 -90.4113)
		(width 0.127)
		(layer "In2.Cu")
		(net "NIC_SMBUS_ALERT_N")
	)
	(segment
		(start 259.4483 -87.0077)
		(end 261.382002 -87.0077)
		(width 0.127)
		(layer "In2.Cu")
		(net "NIC_SMBUS_ALERT_N")
	)
	(segment
		(start 262.382 -100.203)
		(end 260.604 -101.981)
		(width 0.127)
		(layer "In2.Cu")
		(net "NIC_SMBUS_ALERT_N")
	)
	(segment
		(start 178.562 -78.74)
		(end 179.578 -79.756)
		(width 0.127)
		(layer "In2.Cu")
		(net "NIC_SMBUS_ALERT_N")
	)
	(segment
		(start 260.604 -101.981)
		(end 260.604 -103.580184)
		(width 0.127)
		(layer "In2.Cu")
		(net "NIC_SMBUS_ALERT_N")
	)
	(segment
		(start 178.449986 -73.75017)
		(end 178.562 -73.862184)
		(width 0.127)
		(layer "In2.Cu")
		(net "NIC_SMBUS_ALERT_N")
	)
	(segment
		(start 216.608152 -82.169)
		(end 219.529152 -85.09)
		(width 0.127)
		(layer "In2.Cu")
		(net "NIC_SMBUS_ALERT_N")
	)
	(segment
		(start 178.562 -73.862184)
		(end 178.562 -78.74)
		(width 0.127)
		(layer "In2.Cu")
		(net "NIC_SMBUS_ALERT_N")
	)
	(segment
		(start 233.6673 -90.4113)
		(end 256.0447 -90.4113)
		(width 0.127)
		(layer "In2.Cu")
		(net "NIC_SMBUS_ALERT_N")
	)
	(segment
		(start 253.744984 -110.4392)
		(end 251.1806 -110.4392)
		(width 0.127)
		(layer "In2.Cu")
		(net "NIC_SMBUS_ALERT_N")
	)
	(segment
		(start 181.327298 -82.169)
		(end 216.608152 -82.169)
		(width 0.127)
		(layer "In2.Cu")
		(net "NIC_SMBUS_ALERT_N")
	)
	(segment
		(start 260.604 -103.580184)
		(end 253.744984 -110.4392)
		(width 0.127)
		(layer "In2.Cu")
		(net "NIC_SMBUS_ALERT_N")
	)
	(segment
		(start 262.382 -88.007698)
		(end 262.382 -100.203)
		(width 0.127)
		(layer "In2.Cu")
		(net "NIC_SMBUS_ALERT_N")
	)
	(segment
		(start 261.382002 -87.0077)
		(end 262.382 -88.007698)
		(width 0.127)
		(layer "In2.Cu")
		(net "NIC_SMBUS_ALERT_N")
	)
	(segment
		(start 179.578 -80.419702)
		(end 181.327298 -82.169)
		(width 0.127)
		(layer "In2.Cu")
		(net "NIC_SMBUS_ALERT_N")
	)
	(segment
		(start 215.14308 -89.52992)
		(end 215.265 -89.408)
		(width 0.1143)
		(layer "F.Cu")
		(net "NIC_SMBUS_SDA")
	)
	(segment
		(start 208.5594 -89.52992)
		(end 215.14308 -89.52992)
		(width 0.1143)
		(layer "F.Cu")
		(net "NIC_SMBUS_SDA")
	)
	(via
		(at 310.007 -130.302)
		(size 0.5588)
		(drill 0.3048)
		(layers "F.Cu" "B.Cu")
		(net "NIC_SMBUS_SDA")
	)
	(via
		(at 293.4716 -94.361)
		(size 0.5588)
		(drill 0.3048)
		(layers "F.Cu" "B.Cu")
		(net "NIC_SMBUS_SDA")
	)
	(via
		(at 215.265 -89.408)
		(size 0.5588)
		(drill 0.3048)
		(layers "F.Cu" "B.Cu")
		(net "NIC_SMBUS_SDA")
	)
	(via
		(at 208.5594 -89.52992)
		(size 0.5588)
		(drill 0.3048)
		(layers "F.Cu" "B.Cu")
		(net "NIC_SMBUS_SDA")
	)
	(segment
		(start 320.613532 -163.449)
		(end 320.04 -163.449)
		(width 0.1143)
		(layer "B.Cu")
		(net "NIC_SMBUS_SDA")
	)
	(segment
		(start 176.64303 -80.25003)
		(end 178.562 -82.169)
		(width 0.1143)
		(layer "B.Cu")
		(net "NIC_SMBUS_SDA")
	)
	(segment
		(start 207.645 -88.61552)
		(end 208.5594 -89.52992)
		(width 0.1143)
		(layer "B.Cu")
		(net "NIC_SMBUS_SDA")
	)
	(segment
		(start 215.265 -89.42324)
		(end 215.265 -89.408)
		(width 0.1143)
		(layer "B.Cu")
		(net "NIC_SMBUS_SDA")
	)
	(segment
		(start 310.134 -130.302)
		(end 310.515 -130.683)
		(width 0.1143)
		(layer "B.Cu")
		(net "NIC_SMBUS_SDA")
	)
	(segment
		(start 293.4716 -94.361)
		(end 293.4716 -94.0816)
		(width 0.1143)
		(layer "B.Cu")
		(net "NIC_SMBUS_SDA")
	)
	(segment
		(start 178.562 -82.169)
		(end 206.756 -82.169)
		(width 0.1143)
		(layer "B.Cu")
		(net "NIC_SMBUS_SDA")
	)
	(segment
		(start 321.35445 -161.649918)
		(end 321.35445 -162.708082)
		(width 0.1143)
		(layer "B.Cu")
		(net "NIC_SMBUS_SDA")
	)
	(segment
		(start 321.35445 -162.708082)
		(end 320.613532 -163.449)
		(width 0.1143)
		(layer "B.Cu")
		(net "NIC_SMBUS_SDA")
	)
	(segment
		(start 316.978792 -157.27426)
		(end 321.35445 -161.649918)
		(width 0.1143)
		(layer "B.Cu")
		(net "NIC_SMBUS_SDA")
	)
	(segment
		(start 310.515 -130.683)
		(end 310.838596 -130.683)
		(width 0.1143)
		(layer "B.Cu")
		(net "NIC_SMBUS_SDA")
	)
	(segment
		(start 219.44076 -93.599)
		(end 215.265 -89.42324)
		(width 0.1143)
		(layer "B.Cu")
		(net "NIC_SMBUS_SDA")
	)
	(segment
		(start 176.449736 -80.25003)
		(end 176.64303 -80.25003)
		(width 0.1143)
		(layer "B.Cu")
		(net "NIC_SMBUS_SDA")
	)
	(segment
		(start 319.4685 -164.0205)
		(end 319.4685 -164.338)
		(width 0.1143)
		(layer "B.Cu")
		(net "NIC_SMBUS_SDA")
	)
	(segment
		(start 310.838596 -130.683)
		(end 316.978792 -136.823196)
		(width 0.1143)
		(layer "B.Cu")
		(net "NIC_SMBUS_SDA")
	)
	(segment
		(start 292.989 -93.599)
		(end 219.44076 -93.599)
		(width 0.1143)
		(layer "B.Cu")
		(net "NIC_SMBUS_SDA")
	)
	(segment
		(start 207.645 -83.058)
		(end 207.645 -88.61552)
		(width 0.1143)
		(layer "B.Cu")
		(net "NIC_SMBUS_SDA")
	)
	(segment
		(start 310.007 -130.302)
		(end 310.134 -130.302)
		(width 0.1143)
		(layer "B.Cu")
		(net "NIC_SMBUS_SDA")
	)
	(segment
		(start 293.4716 -94.0816)
		(end 292.989 -93.599)
		(width 0.1143)
		(layer "B.Cu")
		(net "NIC_SMBUS_SDA")
	)
	(segment
		(start 206.756 -82.169)
		(end 207.645 -83.058)
		(width 0.1143)
		(layer "B.Cu")
		(net "NIC_SMBUS_SDA")
	)
	(segment
		(start 318.4525 -164.338)
		(end 319.4685 -164.338)
		(width 0.1143)
		(layer "B.Cu")
		(net "NIC_SMBUS_SDA")
	)
	(segment
		(start 320.04 -163.449)
		(end 319.4685 -164.0205)
		(width 0.1143)
		(layer "B.Cu")
		(net "NIC_SMBUS_SDA")
	)
	(segment
		(start 316.978792 -136.823196)
		(end 316.978792 -157.27426)
		(width 0.1143)
		(layer "B.Cu")
		(net "NIC_SMBUS_SDA")
	)
	(segment
		(start 304.546 -123.995434)
		(end 307.975 -127.424434)
		(width 0.127)
		(layer "In2.Cu")
		(net "NIC_SMBUS_SDA")
	)
	(segment
		(start 293.4716 -94.361)
		(end 293.624 -94.5134)
		(width 0.127)
		(layer "In2.Cu")
		(net "NIC_SMBUS_SDA")
	)
	(segment
		(start 308.780434 -130.302)
		(end 310.007 -130.302)
		(width 0.127)
		(layer "In2.Cu")
		(net "NIC_SMBUS_SDA")
	)
	(segment
		(start 293.624 -105.4862)
		(end 296.0497 -107.9119)
		(width 0.127)
		(layer "In2.Cu")
		(net "NIC_SMBUS_SDA")
	)
	(segment
		(start 307.975 -127.424434)
		(end 307.975 -129.496566)
		(width 0.127)
		(layer "In2.Cu")
		(net "NIC_SMBUS_SDA")
	)
	(segment
		(start 307.975 -129.496566)
		(end 308.780434 -130.302)
		(width 0.127)
		(layer "In2.Cu")
		(net "NIC_SMBUS_SDA")
	)
	(segment
		(start 296.0497 -107.9119)
		(end 296.0497 -114.6937)
		(width 0.127)
		(layer "In2.Cu")
		(net "NIC_SMBUS_SDA")
	)
	(segment
		(start 296.0497 -114.6937)
		(end 304.546 -123.19)
		(width 0.127)
		(layer "In2.Cu")
		(net "NIC_SMBUS_SDA")
	)
	(segment
		(start 293.624 -94.5134)
		(end 293.624 -105.4862)
		(width 0.127)
		(layer "In2.Cu")
		(net "NIC_SMBUS_SDA")
	)
	(segment
		(start 304.546 -123.19)
		(end 304.546 -123.995434)
		(width 0.127)
		(layer "In2.Cu")
		(net "NIC_SMBUS_SDA")
	)
	(segment
		(start 208.5594 -88.51392)
		(end 213.94166 -88.51392)
		(width 0.1143)
		(layer "F.Cu")
		(net "NIC_SMBUS_SCL")
	)
	(segment
		(start 213.94166 -88.51392)
		(end 214.48014 -87.97544)
		(width 0.1143)
		(layer "F.Cu")
		(net "NIC_SMBUS_SCL")
	)
	(via
		(at 308.4703 -129.286)
		(size 0.5588)
		(drill 0.3048)
		(layers "F.Cu" "B.Cu")
		(net "NIC_SMBUS_SCL")
	)
	(via
		(at 294.0558 -93.599)
		(size 0.5588)
		(drill 0.3048)
		(layers "F.Cu" "B.Cu")
		(net "NIC_SMBUS_SCL")
	)
	(via
		(at 214.48014 -87.97544)
		(size 0.5588)
		(drill 0.3048)
		(layers "F.Cu" "B.Cu")
		(net "NIC_SMBUS_SCL")
	)
	(via
		(at 208.5594 -88.51392)
		(size 0.5588)
		(drill 0.3048)
		(layers "F.Cu" "B.Cu")
		(net "NIC_SMBUS_SCL")
	)
	(segment
		(start 316.483492 -157.479492)
		(end 316.483492 -137.028428)
		(width 0.1143)
		(layer "B.Cu")
		(net "NIC_SMBUS_SCL")
	)
	(segment
		(start 219.89923 -92.222828)
		(end 219.612972 -91.93657)
		(width 0.1143)
		(layer "B.Cu")
		(net "NIC_SMBUS_SCL")
	)
	(segment
		(start 310.785764 -131.3307)
		(end 310.344058 -131.3307)
		(width 0.1143)
		(layer "B.Cu")
		(net "NIC_SMBUS_SCL")
	)
	(segment
		(start 214.84844 -87.97544)
		(end 214.48014 -87.97544)
		(width 0.1143)
		(layer "B.Cu")
		(net "NIC_SMBUS_SCL")
	)
	(segment
		(start 318.516 -162.8775)
		(end 320.167 -162.8775)
		(width 0.1143)
		(layer "B.Cu")
		(net "NIC_SMBUS_SCL")
	)
	(segment
		(start 208.28 -88.23452)
		(end 208.5594 -88.51392)
		(width 0.1143)
		(layer "B.Cu")
		(net "NIC_SMBUS_SCL")
	)
	(segment
		(start 320.85915 -162.50285)
		(end 320.85915 -161.85515)
		(width 0.1143)
		(layer "B.Cu")
		(net "NIC_SMBUS_SCL")
	)
	(segment
		(start 316.483492 -137.028428)
		(end 310.785764 -131.3307)
		(width 0.1143)
		(layer "B.Cu")
		(net "NIC_SMBUS_SCL")
	)
	(segment
		(start 177.450496 -78.24978)
		(end 177.450496 -80.283304)
		(width 0.1143)
		(layer "B.Cu")
		(net "NIC_SMBUS_SCL")
	)
	(segment
		(start 294.0558 -93.5228)
		(end 293.624 -93.091)
		(width 0.1143)
		(layer "B.Cu")
		(net "NIC_SMBUS_SCL")
	)
	(segment
		(start 177.450496 -80.283304)
		(end 178.828192 -81.661)
		(width 0.1143)
		(layer "B.Cu")
		(net "NIC_SMBUS_SCL")
	)
	(segment
		(start 219.89923 -92.336112)
		(end 219.89923 -92.222828)
		(width 0.1143)
		(layer "B.Cu")
		(net "NIC_SMBUS_SCL")
	)
	(segment
		(start 178.828192 -81.661)
		(end 207.645 -81.661)
		(width 0.1143)
		(layer "B.Cu")
		(net "NIC_SMBUS_SCL")
	)
	(segment
		(start 219.612972 -91.93657)
		(end 218.80957 -91.93657)
		(width 0.1143)
		(layer "B.Cu")
		(net "NIC_SMBUS_SCL")
	)
	(segment
		(start 310.344058 -131.3307)
		(end 308.4703 -129.456942)
		(width 0.1143)
		(layer "B.Cu")
		(net "NIC_SMBUS_SCL")
	)
	(segment
		(start 320.85915 -161.85515)
		(end 316.483492 -157.479492)
		(width 0.1143)
		(layer "B.Cu")
		(net "NIC_SMBUS_SCL")
	)
	(segment
		(start 320.167 -162.8775)
		(end 320.4845 -162.8775)
		(width 0.1143)
		(layer "B.Cu")
		(net "NIC_SMBUS_SCL")
	)
	(segment
		(start 318.4525 -162.814)
		(end 318.516 -162.8775)
		(width 0.1143)
		(layer "B.Cu")
		(net "NIC_SMBUS_SCL")
	)
	(segment
		(start 207.645 -81.661)
		(end 208.28 -82.296)
		(width 0.1143)
		(layer "B.Cu")
		(net "NIC_SMBUS_SCL")
	)
	(segment
		(start 293.624 -93.091)
		(end 220.654118 -93.091)
		(width 0.1143)
		(layer "B.Cu")
		(net "NIC_SMBUS_SCL")
	)
	(segment
		(start 208.28 -82.296)
		(end 208.28 -88.23452)
		(width 0.1143)
		(layer "B.Cu")
		(net "NIC_SMBUS_SCL")
	)
	(segment
		(start 294.0558 -93.599)
		(end 294.0558 -93.5228)
		(width 0.1143)
		(layer "B.Cu")
		(net "NIC_SMBUS_SCL")
	)
	(segment
		(start 308.4703 -129.456942)
		(end 308.4703 -129.286)
		(width 0.1143)
		(layer "B.Cu")
		(net "NIC_SMBUS_SCL")
	)
	(segment
		(start 320.4845 -162.8775)
		(end 320.85915 -162.50285)
		(width 0.1143)
		(layer "B.Cu")
		(net "NIC_SMBUS_SCL")
	)
	(segment
		(start 220.654118 -93.091)
		(end 219.89923 -92.336112)
		(width 0.1143)
		(layer "B.Cu")
		(net "NIC_SMBUS_SCL")
	)
	(segment
		(start 218.80957 -91.93657)
		(end 214.84844 -87.97544)
		(width 0.1143)
		(layer "B.Cu")
		(net "NIC_SMBUS_SCL")
	)
	(segment
		(start 294.0558 -93.599)
		(end 294.056054 -93.599254)
		(width 0.127)
		(layer "In2.Cu")
		(net "NIC_SMBUS_SCL")
	)
	(segment
		(start 294.056054 -93.599254)
		(end 294.056054 -93.947488)
		(width 0.127)
		(layer "In2.Cu")
		(net "NIC_SMBUS_SCL")
	)
	(segment
		(start 294.132 -94.023434)
		(end 294.132 -104.902)
		(width 0.127)
		(layer "In2.Cu")
		(net "NIC_SMBUS_SCL")
	)
	(segment
		(start 296.5577 -107.3277)
		(end 296.5577 -114.483134)
		(width 0.127)
		(layer "In2.Cu")
		(net "NIC_SMBUS_SCL")
	)
	(segment
		(start 308.483 -129.286)
		(end 308.4703 -129.286)
		(width 0.127)
		(layer "In2.Cu")
		(net "NIC_SMBUS_SCL")
	)
	(segment
		(start 294.132 -104.902)
		(end 296.5577 -107.3277)
		(width 0.127)
		(layer "In2.Cu")
		(net "NIC_SMBUS_SCL")
	)
	(segment
		(start 308.483 -127.127)
		(end 308.483 -129.286)
		(width 0.127)
		(layer "In2.Cu")
		(net "NIC_SMBUS_SCL")
	)
	(segment
		(start 305.054 -122.979434)
		(end 305.054 -123.698)
		(width 0.127)
		(layer "In2.Cu")
		(net "NIC_SMBUS_SCL")
	)
	(segment
		(start 296.5577 -114.483134)
		(end 305.054 -122.979434)
		(width 0.127)
		(layer "In2.Cu")
		(net "NIC_SMBUS_SCL")
	)
	(segment
		(start 305.054 -123.698)
		(end 308.483 -127.127)
		(width 0.127)
		(layer "In2.Cu")
		(net "NIC_SMBUS_SCL")
	)
	(segment
		(start 294.056054 -93.947488)
		(end 294.132 -94.023434)
		(width 0.127)
		(layer "In2.Cu")
		(net "NIC_SMBUS_SCL")
	)
	(segment
		(start 292.481 -157.2895)
		(end 292.481 -156.718)
		(width 0.1143)
		(layer "F.Cu")
		(net "EXP_HDD_PRE_INT_N")
	)
	(segment
		(start 91.567 -144.859502)
		(end 91.567 -149.479)
		(width 0.1143)
		(layer "F.Cu")
		(net "EXP_HDD_PRE_INT_N")
	)
	(segment
		(start 292.481 -156.718)
		(end 288.4424 -152.6794)
		(width 0.1143)
		(layer "F.Cu")
		(net "EXP_HDD_PRE_INT_N")
	)
	(segment
		(start 92.324682 -137.209276)
		(end 92.324682 -138.298682)
		(width 0.1143)
		(layer "F.Cu")
		(net "EXP_HDD_PRE_INT_N")
	)
	(segment
		(start 268.4399 -153.2001)
		(end 268.224 -153.416)
		(width 0.1143)
		(layer "F.Cu")
		(net "EXP_HDD_PRE_INT_N")
	)
	(segment
		(start 93.091 -139.065)
		(end 93.091 -139.573)
		(width 0.1143)
		(layer "F.Cu")
		(net "EXP_HDD_PRE_INT_N")
	)
	(segment
		(start 93.091 -143.335502)
		(end 91.567 -144.859502)
		(width 0.1143)
		(layer "F.Cu")
		(net "EXP_HDD_PRE_INT_N")
	)
	(segment
		(start 272.1356 -152.6794)
		(end 271.6149 -153.2001)
		(width 0.1143)
		(layer "F.Cu")
		(net "EXP_HDD_PRE_INT_N")
	)
	(segment
		(start 288.4424 -152.6794)
		(end 272.1356 -152.6794)
		(width 0.1143)
		(layer "F.Cu")
		(net "EXP_HDD_PRE_INT_N")
	)
	(segment
		(start 271.6149 -153.2001)
		(end 268.4399 -153.2001)
		(width 0.1143)
		(layer "F.Cu")
		(net "EXP_HDD_PRE_INT_N")
	)
	(segment
		(start 93.091 -139.573)
		(end 93.091 -143.335502)
		(width 0.1143)
		(layer "F.Cu")
		(net "EXP_HDD_PRE_INT_N")
	)
	(segment
		(start 92.324682 -138.298682)
		(end 93.091 -139.065)
		(width 0.1143)
		(layer "F.Cu")
		(net "EXP_HDD_PRE_INT_N")
	)
	(via
		(at 268.224 -153.416)
		(size 0.5588)
		(drill 0.3048)
		(layers "F.Cu" "B.Cu")
		(net "EXP_HDD_PRE_INT_N")
	)
	(via
		(at 91.567 -149.479)
		(size 0.5588)
		(drill 0.3048)
		(layers "F.Cu" "B.Cu")
		(net "EXP_HDD_PRE_INT_N")
	)
	(via
		(at 93.091 -139.573)
		(size 0.7112)
		(drill 0.3556)
		(layers "F.Cu" "B.Cu")
		(net "EXP_HDD_PRE_INT_N")
	)
	(via
		(at 265.557 -162.433)
		(size 0.5588)
		(drill 0.3048)
		(layers "F.Cu" "B.Cu")
		(net "EXP_HDD_PRE_INT_N")
	)
	(segment
		(start 193.68262 -161.962846)
		(end 193.466466 -162.179)
		(width 0.127)
		(layer "In2.Cu")
		(net "EXP_HDD_PRE_INT_N")
	)
	(segment
		(start 171.536614 -163.322254)
		(end 171.11599 -163.322254)
		(width 0.127)
		(layer "In2.Cu")
		(net "EXP_HDD_PRE_INT_N")
	)
	(segment
		(start 171.11599 -163.322254)
		(end 171.115736 -163.322)
		(width 0.127)
		(layer "In2.Cu")
		(net "EXP_HDD_PRE_INT_N")
	)
	(segment
		(start 219.421964 -163.4363)
		(end 219.383864 -163.3982)
		(width 0.127)
		(layer "In2.Cu")
		(net "EXP_HDD_PRE_INT_N")
	)
	(segment
		(start 229.089966 -161.1503)
		(end 226.803966 -163.4363)
		(width 0.127)
		(layer "In2.Cu")
		(net "EXP_HDD_PRE_INT_N")
	)
	(segment
		(start 105.803954 -162.306)
		(end 92.976954 -149.479)
		(width 0.127)
		(layer "In2.Cu")
		(net "EXP_HDD_PRE_INT_N")
	)
	(segment
		(start 262.255 -162.433)
		(end 260.9723 -161.1503)
		(width 0.127)
		(layer "In2.Cu")
		(net "EXP_HDD_PRE_INT_N")
	)
	(segment
		(start 265.557 -162.433)
		(end 262.255 -162.433)
		(width 0.127)
		(layer "In2.Cu")
		(net "EXP_HDD_PRE_INT_N")
	)
	(segment
		(start 215.152732 -162.6362)
		(end 203.800202 -162.6362)
		(width 0.127)
		(layer "In2.Cu")
		(net "EXP_HDD_PRE_INT_N")
	)
	(segment
		(start 192.710308 -162.179)
		(end 191.668908 -163.2204)
		(width 0.127)
		(layer "In2.Cu")
		(net "EXP_HDD_PRE_INT_N")
	)
	(segment
		(start 191.668908 -163.2204)
		(end 172.554138 -163.2204)
		(width 0.127)
		(layer "In2.Cu")
		(net "EXP_HDD_PRE_INT_N")
	)
	(segment
		(start 219.383864 -163.3982)
		(end 215.914732 -163.3982)
		(width 0.127)
		(layer "In2.Cu")
		(net "EXP_HDD_PRE_INT_N")
	)
	(segment
		(start 153.923746 -162.4203)
		(end 105.919016 -162.4203)
		(width 0.127)
		(layer "In2.Cu")
		(net "EXP_HDD_PRE_INT_N")
	)
	(segment
		(start 215.914732 -163.3982)
		(end 215.152732 -162.6362)
		(width 0.127)
		(layer "In2.Cu")
		(net "EXP_HDD_PRE_INT_N")
	)
	(segment
		(start 203.126848 -161.962846)
		(end 193.68262 -161.962846)
		(width 0.127)
		(layer "In2.Cu")
		(net "EXP_HDD_PRE_INT_N")
	)
	(segment
		(start 260.9723 -161.1503)
		(end 229.089966 -161.1503)
		(width 0.127)
		(layer "In2.Cu")
		(net "EXP_HDD_PRE_INT_N")
	)
	(segment
		(start 172.554138 -163.2204)
		(end 172.528484 -163.194746)
		(width 0.127)
		(layer "In2.Cu")
		(net "EXP_HDD_PRE_INT_N")
	)
	(segment
		(start 105.919016 -162.4203)
		(end 105.804462 -162.306)
		(width 0.127)
		(layer "In2.Cu")
		(net "EXP_HDD_PRE_INT_N")
	)
	(segment
		(start 154.825446 -163.322)
		(end 153.923746 -162.4203)
		(width 0.127)
		(layer "In2.Cu")
		(net "EXP_HDD_PRE_INT_N")
	)
	(segment
		(start 105.804462 -162.306)
		(end 105.803954 -162.306)
		(width 0.127)
		(layer "In2.Cu")
		(net "EXP_HDD_PRE_INT_N")
	)
	(segment
		(start 193.466466 -162.179)
		(end 192.710308 -162.179)
		(width 0.127)
		(layer "In2.Cu")
		(net "EXP_HDD_PRE_INT_N")
	)
	(segment
		(start 171.115736 -163.322)
		(end 154.825446 -163.322)
		(width 0.127)
		(layer "In2.Cu")
		(net "EXP_HDD_PRE_INT_N")
	)
	(segment
		(start 171.664122 -163.194746)
		(end 171.536614 -163.322254)
		(width 0.127)
		(layer "In2.Cu")
		(net "EXP_HDD_PRE_INT_N")
	)
	(segment
		(start 226.803966 -163.4363)
		(end 219.421964 -163.4363)
		(width 0.127)
		(layer "In2.Cu")
		(net "EXP_HDD_PRE_INT_N")
	)
	(segment
		(start 172.528484 -163.194746)
		(end 171.664122 -163.194746)
		(width 0.127)
		(layer "In2.Cu")
		(net "EXP_HDD_PRE_INT_N")
	)
	(segment
		(start 92.976954 -149.479)
		(end 91.567 -149.479)
		(width 0.127)
		(layer "In2.Cu")
		(net "EXP_HDD_PRE_INT_N")
	)
	(segment
		(start 203.800202 -162.6362)
		(end 203.126848 -161.962846)
		(width 0.127)
		(layer "In2.Cu")
		(net "EXP_HDD_PRE_INT_N")
	)
	(segment
		(start 265.557 -162.433)
		(end 265.557 -156.083)
		(width 0.127)
		(layer "In5.Cu")
		(net "EXP_HDD_PRE_INT_N")
	)
	(segment
		(start 265.557 -156.083)
		(end 268.224 -153.416)
		(width 0.127)
		(layer "In5.Cu")
		(net "EXP_HDD_PRE_INT_N")
	)
	(segment
		(start 90.18397 -139.5095)
		(end 90.325702 -139.367768)
		(width 0.1143)
		(layer "F.Cu")
		(net "EXP_SELF_TRAY")
	)
	(segment
		(start 89.16797 -139.827)
		(end 89.48547 -139.5095)
		(width 0.1143)
		(layer "F.Cu")
		(net "EXP_SELF_TRAY")
	)
	(segment
		(start 89.48547 -139.5095)
		(end 90.18397 -139.5095)
		(width 0.1143)
		(layer "F.Cu")
		(net "EXP_SELF_TRAY")
	)
	(segment
		(start 90.325702 -139.367768)
		(end 90.325702 -137.209276)
		(width 0.1143)
		(layer "F.Cu")
		(net "EXP_SELF_TRAY")
	)
	(via
		(at 89.16797 -139.827)
		(size 0.7112)
		(drill 0.3556)
		(layers "F.Cu" "B.Cu")
		(net "EXP_SELF_TRAY")
	)
	(segment
		(start 299.68698 -179.08524)
		(end 299.63364 -179.0319)
		(width 0.127)
		(layer "F.Cu")
		(net "TP_BMC_GPIOJ6")
	)
	(segment
		(start 300.627796 -179.440078)
		(end 300.272958 -179.08524)
		(width 0.127)
		(layer "F.Cu")
		(net "TP_BMC_GPIOJ6")
	)
	(segment
		(start 300.834806 -179.440078)
		(end 300.627796 -179.440078)
		(width 0.127)
		(layer "F.Cu")
		(net "TP_BMC_GPIOJ6")
	)
	(segment
		(start 300.272958 -179.08524)
		(end 299.68698 -179.08524)
		(width 0.127)
		(layer "F.Cu")
		(net "TP_BMC_GPIOJ6")
	)
	(via
		(at 299.63364 -179.0319)
		(size 0.508)
		(drill 0.254)
		(layers "F.Cu" "B.Cu")
		(net "TP_BMC_GPIOJ6")
	)
	(segment
		(start 301.13224 -179.0319)
		(end 299.63364 -179.0319)
		(width 0.127)
		(layer "B.Cu")
		(net "TP_BMC_GPIOJ6")
	)
	(segment
		(start 303.26584 -181.1655)
		(end 301.13224 -179.0319)
		(width 0.127)
		(layer "B.Cu")
		(net "TP_BMC_GPIOJ6")
	)
	(segment
		(start 300.834806 -180.240178)
		(end 300.618398 -180.240178)
		(width 0.127)
		(layer "F.Cu")
		(net "TP_BMC_GPIOJ5")
	)
	(segment
		(start 300.618398 -180.240178)
		(end 300.211998 -180.646578)
		(width 0.127)
		(layer "F.Cu")
		(net "TP_BMC_GPIOJ5")
	)
	(segment
		(start 300.211998 -180.646578)
		(end 299.637704 -180.646578)
		(width 0.127)
		(layer "F.Cu")
		(net "TP_BMC_GPIOJ5")
	)
	(via
		(at 299.637704 -180.646578)
		(size 0.508)
		(drill 0.254)
		(layers "F.Cu" "B.Cu")
		(net "TP_BMC_GPIOJ5")
	)
	(segment
		(start 300.435518 -180.646578)
		(end 299.637704 -180.646578)
		(width 0.127)
		(layer "B.Cu")
		(net "TP_BMC_GPIOJ5")
	)
	(segment
		(start 301.58182 -181.79288)
		(end 300.435518 -180.646578)
		(width 0.127)
		(layer "B.Cu")
		(net "TP_BMC_GPIOJ5")
	)
	(segment
		(start 301.889922 -179.440078)
		(end 302.133 -179.197)
		(width 0.127)
		(layer "F.Cu")
		(net "TP_BMC_GPIOJ7")
	)
	(segment
		(start 301.634906 -179.440078)
		(end 301.889922 -179.440078)
		(width 0.127)
		(layer "F.Cu")
		(net "TP_BMC_GPIOJ7")
	)
	(segment
		(start 302.133 -179.197)
		(end 302.26 -179.197)
		(width 0.127)
		(layer "F.Cu")
		(net "TP_BMC_GPIOJ7")
	)
	(via
		(at 302.26 -179.197)
		(size 0.508)
		(drill 0.254)
		(layers "F.Cu" "B.Cu")
		(net "TP_BMC_GPIOJ7")
	)
	(segment
		(start 302.641 -179.197)
		(end 302.26 -179.197)
		(width 0.127)
		(layer "B.Cu")
		(net "TP_BMC_GPIOJ7")
	)
	(segment
		(start 303.276 -178.562)
		(end 302.641 -179.197)
		(width 0.127)
		(layer "B.Cu")
		(net "TP_BMC_GPIOJ7")
	)
	(segment
		(start 299.23486 -179.43068)
		(end 298.83481 -179.03063)
		(width 0.127)
		(layer "F.Cu")
		(net "TP_BMC_GPIOJ4")
	)
	(segment
		(start 299.23486 -179.440078)
		(end 299.23486 -179.43068)
		(width 0.127)
		(layer "F.Cu")
		(net "TP_BMC_GPIOJ4")
	)
	(via
		(at 298.83481 -179.03063)
		(size 0.508)
		(drill 0.254)
		(layers "F.Cu" "B.Cu")
		(net "TP_BMC_GPIOJ4")
	)
	(segment
		(start 299.92066 -178.726084)
		(end 299.807376 -178.6128)
		(width 0.127)
		(layer "B.Cu")
		(net "TP_BMC_GPIOJ4")
	)
	(segment
		(start 301.201836 -178.726084)
		(end 299.92066 -178.726084)
		(width 0.127)
		(layer "B.Cu")
		(net "TP_BMC_GPIOJ4")
	)
	(segment
		(start 299.459904 -178.6128)
		(end 299.042074 -179.03063)
		(width 0.127)
		(layer "B.Cu")
		(net "TP_BMC_GPIOJ4")
	)
	(segment
		(start 299.042074 -179.03063)
		(end 298.83481 -179.03063)
		(width 0.127)
		(layer "B.Cu")
		(net "TP_BMC_GPIOJ4")
	)
	(segment
		(start 301.55642 -178.3715)
		(end 301.201836 -178.726084)
		(width 0.127)
		(layer "B.Cu")
		(net "TP_BMC_GPIOJ4")
	)
	(segment
		(start 299.807376 -178.6128)
		(end 299.459904 -178.6128)
		(width 0.127)
		(layer "B.Cu")
		(net "TP_BMC_GPIOJ4")
	)
	(segment
		(start 8.713216 -226.17938)
		(end 8.903716 -226.17938)
		(width 0.1143)
		(layer "F.Cu")
		(net "BMC_SELF_TRAY")
	)
	(segment
		(start 10.668 -224.536)
		(end 10.668 -224.923096)
		(width 0.1143)
		(layer "F.Cu")
		(net "BMC_SELF_TRAY")
	)
	(segment
		(start 298.43476 -181.83987)
		(end 298.831762 -181.442868)
		(width 0.1143)
		(layer "F.Cu")
		(net "BMC_SELF_TRAY")
	)
	(segment
		(start 298.43476 -181.840124)
		(end 298.43476 -181.83987)
		(width 0.1143)
		(layer "F.Cu")
		(net "BMC_SELF_TRAY")
	)
	(segment
		(start 10.668 -224.923096)
		(end 10.237216 -225.35388)
		(width 0.1143)
		(layer "F.Cu")
		(net "BMC_SELF_TRAY")
	)
	(segment
		(start 8.903716 -226.17938)
		(end 9.729216 -225.35388)
		(width 0.1143)
		(layer "F.Cu")
		(net "BMC_SELF_TRAY")
	)
	(segment
		(start 9.729216 -225.35388)
		(end 10.237216 -225.35388)
		(width 0.1143)
		(layer "F.Cu")
		(net "BMC_SELF_TRAY")
	)
	(via
		(at 270.002 -198.12)
		(size 0.5588)
		(drill 0.3048)
		(layers "F.Cu" "B.Cu")
		(net "BMC_SELF_TRAY")
	)
	(via
		(at 10.668 -224.536)
		(size 0.7112)
		(drill 0.3556)
		(layers "F.Cu" "B.Cu")
		(net "BMC_SELF_TRAY")
	)
	(via
		(at 10.237216 -225.35388)
		(size 0.5588)
		(drill 0.3048)
		(layers "F.Cu" "B.Cu")
		(net "BMC_SELF_TRAY")
	)
	(via
		(at 275.1328 -242.951)
		(size 0.5588)
		(drill 0.3048)
		(layers "F.Cu" "B.Cu")
		(net "BMC_SELF_TRAY")
	)
	(via
		(at 298.831762 -181.442868)
		(size 0.508)
		(drill 0.254)
		(layers "F.Cu" "B.Cu")
		(net "BMC_SELF_TRAY")
	)
	(segment
		(start 63.373 -216.2937)
		(end 63.881 -216.8017)
		(width 0.127)
		(layer "In2.Cu")
		(net "BMC_SELF_TRAY")
	)
	(segment
		(start 253.3269 -233.795316)
		(end 262.482584 -242.951)
		(width 0.127)
		(layer "In2.Cu")
		(net "BMC_SELF_TRAY")
	)
	(segment
		(start 211.2772 -216.4588)
		(end 233.856784 -193.879216)
		(width 0.127)
		(layer "In2.Cu")
		(net "BMC_SELF_TRAY")
	)
	(segment
		(start 280.873962 -196.0753)
		(end 285.052262 -191.897)
		(width 0.127)
		(layer "In2.Cu")
		(net "BMC_SELF_TRAY")
	)
	(segment
		(start 63.881 -216.8017)
		(end 67.0687 -216.8017)
		(width 0.127)
		(layer "In2.Cu")
		(net "BMC_SELF_TRAY")
	)
	(segment
		(start 107.442 -225.202242)
		(end 110.573058 -228.3333)
		(width 0.127)
		(layer "In2.Cu")
		(net "BMC_SELF_TRAY")
	)
	(segment
		(start 67.0687 -216.8017)
		(end 67.691 -217.424)
		(width 0.127)
		(layer "In2.Cu")
		(net "BMC_SELF_TRAY")
	)
	(segment
		(start 10.237216 -225.35388)
		(end 16.185896 -219.4052)
		(width 0.127)
		(layer "In2.Cu")
		(net "BMC_SELF_TRAY")
	)
	(segment
		(start 45.709332 -219.4052)
		(end 48.820832 -216.2937)
		(width 0.127)
		(layer "In2.Cu")
		(net "BMC_SELF_TRAY")
	)
	(segment
		(start 110.573058 -228.3333)
		(end 203.371704 -228.3333)
		(width 0.127)
		(layer "In2.Cu")
		(net "BMC_SELF_TRAY")
	)
	(segment
		(start 251.443236 -193.879216)
		(end 253.3269 -195.76288)
		(width 0.127)
		(layer "In2.Cu")
		(net "BMC_SELF_TRAY")
	)
	(segment
		(start 299.249846 -183.68645)
		(end 299.249846 -181.860952)
		(width 0.127)
		(layer "In2.Cu")
		(net "BMC_SELF_TRAY")
	)
	(segment
		(start 253.3269 -195.76288)
		(end 253.3269 -233.795316)
		(width 0.127)
		(layer "In2.Cu")
		(net "BMC_SELF_TRAY")
	)
	(segment
		(start 203.371704 -228.3333)
		(end 211.2772 -220.427804)
		(width 0.127)
		(layer "In2.Cu")
		(net "BMC_SELF_TRAY")
	)
	(segment
		(start 262.482584 -242.951)
		(end 275.1328 -242.951)
		(width 0.127)
		(layer "In2.Cu")
		(net "BMC_SELF_TRAY")
	)
	(segment
		(start 107.442 -224.960434)
		(end 107.442 -225.202242)
		(width 0.127)
		(layer "In2.Cu")
		(net "BMC_SELF_TRAY")
	)
	(segment
		(start 299.249846 -181.860952)
		(end 298.831762 -181.442868)
		(width 0.127)
		(layer "In2.Cu")
		(net "BMC_SELF_TRAY")
	)
	(segment
		(start 270.002 -198.12)
		(end 278.638 -198.12)
		(width 0.127)
		(layer "In2.Cu")
		(net "BMC_SELF_TRAY")
	)
	(segment
		(start 99.905566 -217.424)
		(end 107.442 -224.960434)
		(width 0.127)
		(layer "In2.Cu")
		(net "BMC_SELF_TRAY")
	)
	(segment
		(start 285.052262 -191.897)
		(end 291.039296 -191.897)
		(width 0.127)
		(layer "In2.Cu")
		(net "BMC_SELF_TRAY")
	)
	(segment
		(start 48.820832 -216.2937)
		(end 63.373 -216.2937)
		(width 0.127)
		(layer "In2.Cu")
		(net "BMC_SELF_TRAY")
	)
	(segment
		(start 278.638 -198.12)
		(end 280.6827 -196.0753)
		(width 0.127)
		(layer "In2.Cu")
		(net "BMC_SELF_TRAY")
	)
	(segment
		(start 280.6827 -196.0753)
		(end 280.873962 -196.0753)
		(width 0.127)
		(layer "In2.Cu")
		(net "BMC_SELF_TRAY")
	)
	(segment
		(start 211.2772 -220.427804)
		(end 211.2772 -216.4588)
		(width 0.127)
		(layer "In2.Cu")
		(net "BMC_SELF_TRAY")
	)
	(segment
		(start 67.691 -217.424)
		(end 99.905566 -217.424)
		(width 0.127)
		(layer "In2.Cu")
		(net "BMC_SELF_TRAY")
	)
	(segment
		(start 291.039296 -191.897)
		(end 299.249846 -183.68645)
		(width 0.127)
		(layer "In2.Cu")
		(net "BMC_SELF_TRAY")
	)
	(segment
		(start 233.856784 -193.879216)
		(end 251.443236 -193.879216)
		(width 0.127)
		(layer "In2.Cu")
		(net "BMC_SELF_TRAY")
	)
	(segment
		(start 16.185896 -219.4052)
		(end 45.709332 -219.4052)
		(width 0.127)
		(layer "In2.Cu")
		(net "BMC_SELF_TRAY")
	)
	(segment
		(start 275.1328 -213.101682)
		(end 275.7551 -212.479382)
		(width 0.127)
		(layer "In5.Cu")
		(net "BMC_SELF_TRAY")
	)
	(segment
		(start 275.7551 -212.479382)
		(end 275.7551 -212.068918)
		(width 0.127)
		(layer "In5.Cu")
		(net "BMC_SELF_TRAY")
	)
	(segment
		(start 275.7551 -212.068918)
		(end 274.574 -210.887818)
		(width 0.127)
		(layer "In5.Cu")
		(net "BMC_SELF_TRAY")
	)
	(segment
		(start 274.574 -210.887818)
		(end 274.574 -202.692)
		(width 0.127)
		(layer "In5.Cu")
		(net "BMC_SELF_TRAY")
	)
	(segment
		(start 275.1328 -242.951)
		(end 275.1328 -213.101682)
		(width 0.127)
		(layer "In5.Cu")
		(net "BMC_SELF_TRAY")
	)
	(segment
		(start 274.574 -202.692)
		(end 270.002 -198.12)
		(width 0.127)
		(layer "In5.Cu")
		(net "BMC_SELF_TRAY")
	)
	(segment
		(start 295.234868 -168.155112)
		(end 295.234868 -168.240202)
		(width 0.127)
		(layer "F.Cu")
		(net "TP_BMC_GPIOV3")
	)
	(segment
		(start 296.453814 -163.925504)
		(end 296.453814 -164.8333)
		(width 0.127)
		(layer "F.Cu")
		(net "TP_BMC_GPIOV3")
	)
	(segment
		(start 302.133 -159.131)
		(end 301.208948 -160.055052)
		(width 0.127)
		(layer "F.Cu")
		(net "TP_BMC_GPIOV3")
	)
	(segment
		(start 296.07764 -166.83736)
		(end 295.656 -167.259)
		(width 0.127)
		(layer "F.Cu")
		(net "TP_BMC_GPIOV3")
	)
	(segment
		(start 296.453814 -164.8333)
		(end 296.07764 -165.209474)
		(width 0.127)
		(layer "F.Cu")
		(net "TP_BMC_GPIOV3")
	)
	(segment
		(start 295.656 -167.73398)
		(end 295.234868 -168.155112)
		(width 0.127)
		(layer "F.Cu")
		(net "TP_BMC_GPIOV3")
	)
	(segment
		(start 295.656 -167.259)
		(end 295.656 -167.73398)
		(width 0.127)
		(layer "F.Cu")
		(net "TP_BMC_GPIOV3")
	)
	(segment
		(start 300.324266 -160.055052)
		(end 296.453814 -163.925504)
		(width 0.127)
		(layer "F.Cu")
		(net "TP_BMC_GPIOV3")
	)
	(segment
		(start 296.07764 -165.209474)
		(end 296.07764 -166.83736)
		(width 0.127)
		(layer "F.Cu")
		(net "TP_BMC_GPIOV3")
	)
	(segment
		(start 303.149 -159.131)
		(end 302.133 -159.131)
		(width 0.127)
		(layer "F.Cu")
		(net "TP_BMC_GPIOV3")
	)
	(segment
		(start 301.208948 -160.055052)
		(end 300.324266 -160.055052)
		(width 0.127)
		(layer "F.Cu")
		(net "TP_BMC_GPIOV3")
	)
	(segment
		(start 294.8432 -171.031916)
		(end 294.8432 -171.041314)
		(width 0.127)
		(layer "F.Cu")
		(net "TP_BMC_GPIOT7")
	)
	(segment
		(start 295.234868 -170.640248)
		(end 294.8432 -171.031916)
		(width 0.127)
		(layer "F.Cu")
		(net "TP_BMC_GPIOT7")
	)
	(segment
		(start 294.8432 -171.041314)
		(end 294.83558 -171.048934)
		(width 0.127)
		(layer "F.Cu")
		(net "TP_BMC_GPIOT7")
	)
	(via
		(at 294.83558 -171.048934)
		(size 0.508)
		(drill 0.254)
		(layers "F.Cu" "B.Cu")
		(net "TP_BMC_GPIOT7")
	)
	(segment
		(start 295.235376 -169.728134)
		(end 294.93718 -170.02633)
		(width 0.1016)
		(layer "B.Cu")
		(net "TP_BMC_GPIOT7")
	)
	(segment
		(start 295.656 -167.64)
		(end 295.235376 -168.060624)
		(width 0.1016)
		(layer "B.Cu")
		(net "TP_BMC_GPIOT7")
	)
	(segment
		(start 294.93718 -170.02633)
		(end 294.93718 -170.947334)
		(width 0.1016)
		(layer "B.Cu")
		(net "TP_BMC_GPIOT7")
	)
	(segment
		(start 294.93718 -170.947334)
		(end 294.83558 -171.048934)
		(width 0.1016)
		(layer "B.Cu")
		(net "TP_BMC_GPIOT7")
	)
	(segment
		(start 295.235376 -168.060624)
		(end 295.235376 -169.728134)
		(width 0.1016)
		(layer "B.Cu")
		(net "TP_BMC_GPIOT7")
	)
	(segment
		(start 298.43476 -169.836084)
		(end 298.041822 -169.443146)
		(width 0.127)
		(layer "F.Cu")
		(net "TP_BMC_GPIOA7")
	)
	(segment
		(start 298.43476 -169.840148)
		(end 298.43476 -169.836084)
		(width 0.127)
		(layer "F.Cu")
		(net "TP_BMC_GPIOA7")
	)
	(segment
		(start 298.041822 -169.443146)
		(end 298.030646 -169.443146)
		(width 0.127)
		(layer "F.Cu")
		(net "TP_BMC_GPIOA7")
	)
	(via
		(at 298.030646 -169.443146)
		(size 0.508)
		(drill 0.254)
		(layers "F.Cu" "B.Cu")
		(net "TP_BMC_GPIOA7")
	)
	(segment
		(start 298.030646 -169.261282)
		(end 298.030646 -169.443146)
		(width 0.0889)
		(layer "B.Cu")
		(net "TP_BMC_GPIOA7")
	)
	(segment
		(start 298.42968 -167.78732)
		(end 298.42968 -168.862248)
		(width 0.0889)
		(layer "B.Cu")
		(net "TP_BMC_GPIOA7")
	)
	(segment
		(start 298.577 -167.64)
		(end 298.42968 -167.78732)
		(width 0.0889)
		(layer "B.Cu")
		(net "TP_BMC_GPIOA7")
	)
	(segment
		(start 298.42968 -168.862248)
		(end 298.030646 -169.261282)
		(width 0.0889)
		(layer "B.Cu")
		(net "TP_BMC_GPIOA7")
	)
	(segment
		(start 294.434768 -169.840148)
		(end 294.434768 -169.830496)
		(width 0.127)
		(layer "F.Cu")
		(net "TP_BMC_GPIOU3")
	)
	(segment
		(start 294.434768 -169.830496)
		(end 294.04437 -169.440098)
		(width 0.127)
		(layer "F.Cu")
		(net "TP_BMC_GPIOU3")
	)
	(via
		(at 294.04437 -169.440098)
		(size 0.508)
		(drill 0.254)
		(layers "F.Cu" "B.Cu")
		(net "TP_BMC_GPIOU3")
	)
	(segment
		(start 294.33012 -170.28922)
		(end 294.33012 -169.725848)
		(width 0.127)
		(layer "B.Cu")
		(net "TP_BMC_GPIOU3")
	)
	(segment
		(start 294.33012 -169.725848)
		(end 294.04437 -169.440098)
		(width 0.127)
		(layer "B.Cu")
		(net "TP_BMC_GPIOU3")
	)
	(segment
		(start 294.434768 -169.040048)
		(end 294.82034 -168.654476)
		(width 0.127)
		(layer "F.Cu")
		(net "TP_BMC_GPIOU2")
	)
	(segment
		(start 294.82034 -168.654476)
		(end 294.82034 -168.65092)
		(width 0.127)
		(layer "F.Cu")
		(net "TP_BMC_GPIOU2")
	)
	(segment
		(start 294.82034 -168.65092)
		(end 294.828214 -168.643046)
		(width 0.127)
		(layer "F.Cu")
		(net "TP_BMC_GPIOU2")
	)
	(via
		(at 294.828214 -168.643046)
		(size 0.508)
		(drill 0.254)
		(layers "F.Cu" "B.Cu")
		(net "TP_BMC_GPIOU2")
	)
	(segment
		(start 294.912034 -166.37)
		(end 294.410892 -166.871142)
		(width 0.127)
		(layer "B.Cu")
		(net "TP_BMC_GPIOU2")
	)
	(segment
		(start 294.410892 -168.275)
		(end 294.778938 -168.643046)
		(width 0.127)
		(layer "B.Cu")
		(net "TP_BMC_GPIOU2")
	)
	(segment
		(start 295.656 -166.37)
		(end 294.912034 -166.37)
		(width 0.127)
		(layer "B.Cu")
		(net "TP_BMC_GPIOU2")
	)
	(segment
		(start 294.778938 -168.643046)
		(end 294.828214 -168.643046)
		(width 0.127)
		(layer "B.Cu")
		(net "TP_BMC_GPIOU2")
	)
	(segment
		(start 294.410892 -166.871142)
		(end 294.410892 -168.275)
		(width 0.127)
		(layer "B.Cu")
		(net "TP_BMC_GPIOU2")
	)
	(segment
		(start 305.562 -163.957)
		(end 305.50485 -164.01415)
		(width 0.127)
		(layer "F.Cu")
		(net "TP_BMC_GPIOA6")
	)
	(segment
		(start 301.85868 -165.37559)
		(end 301.85868 -165.398704)
		(width 0.127)
		(layer "F.Cu")
		(net "TP_BMC_GPIOA6")
	)
	(segment
		(start 303.22012 -164.01415)
		(end 301.85868 -165.37559)
		(width 0.127)
		(layer "F.Cu")
		(net "TP_BMC_GPIOA6")
	)
	(segment
		(start 305.50485 -164.01415)
		(end 303.22012 -164.01415)
		(width 0.127)
		(layer "F.Cu")
		(net "TP_BMC_GPIOA6")
	)
	(segment
		(start 300.225206 -167.033194)
		(end 300.03496 -167.22344)
		(width 0.127)
		(layer "F.Cu")
		(net "TP_BMC_GPIOA6")
	)
	(segment
		(start 300.225206 -167.032178)
		(end 300.225206 -167.033194)
		(width 0.127)
		(layer "F.Cu")
		(net "TP_BMC_GPIOA6")
	)
	(segment
		(start 300.03496 -167.22344)
		(end 300.03496 -167.440102)
		(width 0.127)
		(layer "F.Cu")
		(net "TP_BMC_GPIOA6")
	)
	(segment
		(start 301.85868 -165.398704)
		(end 300.225206 -167.032178)
		(width 0.127)
		(layer "F.Cu")
		(net "TP_BMC_GPIOA6")
	)
	(segment
		(start 281.10942 -183.80202)
		(end 282.22702 -183.80202)
		(width 0.127)
		(layer "F.Cu")
		(net "TP_BMC_GPIOR2")
	)
	(segment
		(start 282.22702 -183.80202)
		(end 283.27604 -182.753)
		(width 0.127)
		(layer "F.Cu")
		(net "TP_BMC_GPIOR2")
	)
	(segment
		(start 283.27604 -182.753)
		(end 284.722062 -182.753)
		(width 0.127)
		(layer "F.Cu")
		(net "TP_BMC_GPIOR2")
	)
	(segment
		(start 284.722062 -182.753)
		(end 284.834838 -182.640224)
		(width 0.127)
		(layer "F.Cu")
		(net "TP_BMC_GPIOR2")
	)
	(segment
		(start 280.9748 -183.6674)
		(end 281.10942 -183.80202)
		(width 0.127)
		(layer "F.Cu")
		(net "TP_BMC_GPIOR2")
	)
	(segment
		(start 284.813756 -181.840124)
		(end 284.6705 -181.98338)
		(width 0.127)
		(layer "F.Cu")
		(net "TP_BMC_GPIOR5")
	)
	(segment
		(start 280.4033 -181.7497)
		(end 279.781 -182.372)
		(width 0.127)
		(layer "F.Cu")
		(net "TP_BMC_GPIOR5")
	)
	(segment
		(start 283.60497 -181.98338)
		(end 283.37129 -181.7497)
		(width 0.127)
		(layer "F.Cu")
		(net "TP_BMC_GPIOR5")
	)
	(segment
		(start 284.6705 -181.98338)
		(end 283.60497 -181.98338)
		(width 0.127)
		(layer "F.Cu")
		(net "TP_BMC_GPIOR5")
	)
	(segment
		(start 277.296626 -175.7172)
		(end 277.114 -175.899826)
		(width 0.127)
		(layer "F.Cu")
		(net "TP_BMC_GPIOR5")
	)
	(segment
		(start 284.834838 -181.840124)
		(end 284.813756 -181.840124)
		(width 0.127)
		(layer "F.Cu")
		(net "TP_BMC_GPIOR5")
	)
	(segment
		(start 278.802338 -184.620662)
		(end 278.092662 -184.620662)
		(width 0.127)
		(layer "F.Cu")
		(net "TP_BMC_GPIOR5")
	)
	(segment
		(start 285.634938 -177.040032)
		(end 285.644336 -177.040032)
		(width 0.127)
		(layer "F.Cu")
		(net "TP_BMC_GPIOR5")
	)
	(segment
		(start 279.6794 -183.642)
		(end 278.802338 -184.620662)
		(width 0.127)
		(layer "F.Cu")
		(net "TP_BMC_GPIOR5")
	)
	(segment
		(start 279.781 -183.5404)
		(end 279.6794 -183.642)
		(width 0.127)
		(layer "F.Cu")
		(net "TP_BMC_GPIOR5")
	)
	(segment
		(start 278.0792 -175.7172)
		(end 277.296626 -175.7172)
		(width 0.127)
		(layer "F.Cu")
		(net "TP_BMC_GPIOR5")
	)
	(segment
		(start 283.37129 -181.7497)
		(end 280.4033 -181.7497)
		(width 0.127)
		(layer "F.Cu")
		(net "TP_BMC_GPIOR5")
	)
	(segment
		(start 279.781 -182.372)
		(end 279.781 -183.5404)
		(width 0.127)
		(layer "F.Cu")
		(net "TP_BMC_GPIOR5")
	)
	(segment
		(start 285.644336 -177.040032)
		(end 286.043878 -176.64049)
		(width 0.127)
		(layer "F.Cu")
		(net "TP_BMC_GPIOR5")
	)
	(via
		(at 278.092662 -184.620662)
		(size 0.5588)
		(drill 0.3048)
		(layers "F.Cu" "B.Cu")
		(net "TP_BMC_GPIOR5")
	)
	(via
		(at 278.0792 -175.7172)
		(size 0.7112)
		(drill 0.3556)
		(layers "F.Cu" "B.Cu")
		(net "TP_BMC_GPIOR5")
	)
	(via
		(at 286.043878 -176.64049)
		(size 0.508)
		(drill 0.254)
		(layers "F.Cu" "B.Cu")
		(net "TP_BMC_GPIOR5")
	)
	(via
		(at 277.114 -175.899826)
		(size 0.5588)
		(drill 0.3048)
		(layers "F.Cu" "B.Cu")
		(net "TP_BMC_GPIOR5")
	)
	(segment
		(start 277.854664 -176.64049)
		(end 286.043878 -176.64049)
		(width 0.127)
		(layer "In2.Cu")
		(net "TP_BMC_GPIOR5")
	)
	(segment
		(start 277.114 -175.899826)
		(end 277.854664 -176.64049)
		(width 0.127)
		(layer "In2.Cu")
		(net "TP_BMC_GPIOR5")
	)
	(segment
		(start 277.114 -180.7972)
		(end 277.114 -175.899826)
		(width 0.127)
		(layer "In5.Cu")
		(net "TP_BMC_GPIOR5")
	)
	(segment
		(start 275.7551 -184.870598)
		(end 275.7551 -182.1561)
		(width 0.127)
		(layer "In5.Cu")
		(net "TP_BMC_GPIOR5")
	)
	(segment
		(start 278.092662 -184.620662)
		(end 277.552658 -185.160666)
		(width 0.127)
		(layer "In5.Cu")
		(net "TP_BMC_GPIOR5")
	)
	(segment
		(start 277.552658 -185.160666)
		(end 276.045168 -185.160666)
		(width 0.127)
		(layer "In5.Cu")
		(net "TP_BMC_GPIOR5")
	)
	(segment
		(start 276.045168 -185.160666)
		(end 275.7551 -184.870598)
		(width 0.127)
		(layer "In5.Cu")
		(net "TP_BMC_GPIOR5")
	)
	(segment
		(start 275.7551 -182.1561)
		(end 277.114 -180.7972)
		(width 0.127)
		(layer "In5.Cu")
		(net "TP_BMC_GPIOR5")
	)
	(segment
		(start 283.325824 -182.271924)
		(end 284.888178 -182.271924)
		(width 0.127)
		(layer "F.Cu")
		(net "TP_BMC_GPIOR1")
	)
	(segment
		(start 284.888178 -182.271924)
		(end 285.319978 -181.840124)
		(width 0.127)
		(layer "F.Cu")
		(net "TP_BMC_GPIOR1")
	)
	(segment
		(start 281.6479 -182.9943)
		(end 282.603448 -182.9943)
		(width 0.127)
		(layer "F.Cu")
		(net "TP_BMC_GPIOR1")
	)
	(segment
		(start 281.051 -182.3974)
		(end 281.6479 -182.9943)
		(width 0.127)
		(layer "F.Cu")
		(net "TP_BMC_GPIOR1")
	)
	(segment
		(start 282.603448 -182.9943)
		(end 283.325824 -182.271924)
		(width 0.127)
		(layer "F.Cu")
		(net "TP_BMC_GPIOR1")
	)
	(segment
		(start 285.319978 -181.840124)
		(end 285.634938 -181.840124)
		(width 0.127)
		(layer "F.Cu")
		(net "TP_BMC_GPIOR1")
	)
	(segment
		(start 288.5948 -179.72659)
		(end 288.595054 -179.72659)
		(width 0.127)
		(layer "F.Cu")
		(net "TP_BMC_GPIOR3")
	)
	(segment
		(start 288.424112 -179.897278)
		(end 288.5948 -179.72659)
		(width 0.127)
		(layer "F.Cu")
		(net "TP_BMC_GPIOR3")
	)
	(segment
		(start 287.577784 -179.897278)
		(end 288.424112 -179.897278)
		(width 0.127)
		(layer "F.Cu")
		(net "TP_BMC_GPIOR3")
	)
	(segment
		(start 287.234884 -180.240178)
		(end 287.577784 -179.897278)
		(width 0.127)
		(layer "F.Cu")
		(net "TP_BMC_GPIOR3")
	)
	(segment
		(start 288.595054 -179.72659)
		(end 288.621216 -179.700428)
		(width 0.127)
		(layer "F.Cu")
		(net "TP_BMC_GPIOR3")
	)
	(via
		(at 288.621216 -179.700428)
		(size 0.508)
		(drill 0.254)
		(layers "F.Cu" "B.Cu")
		(net "TP_BMC_GPIOR3")
	)
	(segment
		(start 290.2966 -179.1462)
		(end 289.769804 -179.1462)
		(width 0.127)
		(layer "B.Cu")
		(net "TP_BMC_GPIOR3")
	)
	(segment
		(start 289.261804 -179.6542)
		(end 288.667444 -179.6542)
		(width 0.127)
		(layer "B.Cu")
		(net "TP_BMC_GPIOR3")
	)
	(segment
		(start 289.769804 -179.1462)
		(end 289.261804 -179.6542)
		(width 0.127)
		(layer "B.Cu")
		(net "TP_BMC_GPIOR3")
	)
	(segment
		(start 288.667444 -179.6542)
		(end 288.621216 -179.700428)
		(width 0.127)
		(layer "B.Cu")
		(net "TP_BMC_GPIOR3")
	)
	(segment
		(start 285.634938 -181.040024)
		(end 285.177738 -181.497224)
		(width 0.127)
		(layer "F.Cu")
		(net "TP_BMC_GPIOR4")
	)
	(segment
		(start 284.01264 -181.4449)
		(end 279.1841 -181.4449)
		(width 0.127)
		(layer "F.Cu")
		(net "TP_BMC_GPIOR4")
	)
	(segment
		(start 289.039046 -179.031646)
		(end 289.1536 -179.1462)
		(width 0.127)
		(layer "F.Cu")
		(net "TP_BMC_GPIOR4")
	)
	(segment
		(start 288.034984 -178.640232)
		(end 288.426398 -179.031646)
		(width 0.127)
		(layer "F.Cu")
		(net "TP_BMC_GPIOR4")
	)
	(segment
		(start 278.511 -183.2356)
		(end 278.511 -182.118)
		(width 0.127)
		(layer "F.Cu")
		(net "TP_BMC_GPIOR4")
	)
	(segment
		(start 285.177738 -181.497224)
		(end 284.692598 -181.497224)
		(width 0.127)
		(layer "F.Cu")
		(net "TP_BMC_GPIOR4")
	)
	(segment
		(start 284.692598 -181.497224)
		(end 284.625542 -181.56428)
		(width 0.127)
		(layer "F.Cu")
		(net "TP_BMC_GPIOR4")
	)
	(segment
		(start 279.1841 -181.4449)
		(end 278.511 -182.118)
		(width 0.127)
		(layer "F.Cu")
		(net "TP_BMC_GPIOR4")
	)
	(segment
		(start 288.426398 -179.031646)
		(end 289.039046 -179.031646)
		(width 0.127)
		(layer "F.Cu")
		(net "TP_BMC_GPIOR4")
	)
	(segment
		(start 284.13202 -181.56428)
		(end 284.01264 -181.4449)
		(width 0.127)
		(layer "F.Cu")
		(net "TP_BMC_GPIOR4")
	)
	(segment
		(start 284.625542 -181.56428)
		(end 284.13202 -181.56428)
		(width 0.127)
		(layer "F.Cu")
		(net "TP_BMC_GPIOR4")
	)
	(segment
		(start 278.3586 -183.388)
		(end 278.511 -183.2356)
		(width 0.127)
		(layer "F.Cu")
		(net "TP_BMC_GPIOR4")
	)
	(via
		(at 289.1536 -179.1462)
		(size 0.508)
		(drill 0.254)
		(layers "F.Cu" "B.Cu")
		(net "TP_BMC_GPIOR4")
	)
	(via
		(at 284.13202 -181.56428)
		(size 0.508)
		(drill 0.254)
		(layers "F.Cu" "B.Cu")
		(net "TP_BMC_GPIOR4")
	)
	(segment
		(start 287.23844 -180.012086)
		(end 287.23844 -179.680362)
		(width 0.0889)
		(layer "B.Cu")
		(net "TP_BMC_GPIOR4")
	)
	(segment
		(start 287.23844 -179.680362)
		(end 287.231074 -179.672996)
		(width 0.0889)
		(layer "B.Cu")
		(net "TP_BMC_GPIOR4")
	)
	(segment
		(start 285.488126 -181.059074)
		(end 285.85922 -181.059074)
		(width 0.0889)
		(layer "B.Cu")
		(net "TP_BMC_GPIOR4")
	)
	(segment
		(start 285.069026 -181.147974)
		(end 285.399226 -181.147974)
		(width 0.0889)
		(layer "B.Cu")
		(net "TP_BMC_GPIOR4")
	)
	(segment
		(start 286.671512 -180.246274)
		(end 287.004252 -180.246274)
		(width 0.0889)
		(layer "B.Cu")
		(net "TP_BMC_GPIOR4")
	)
	(segment
		(start 286.200596 -181.049422)
		(end 286.434784 -180.815234)
		(width 0.0889)
		(layer "B.Cu")
		(net "TP_BMC_GPIOR4")
	)
	(segment
		(start 284.13202 -181.56428)
		(end 284.65272 -181.56428)
		(width 0.127)
		(layer "B.Cu")
		(net "TP_BMC_GPIOR4")
	)
	(segment
		(start 285.399226 -181.147974)
		(end 285.488126 -181.059074)
		(width 0.0889)
		(layer "B.Cu")
		(net "TP_BMC_GPIOR4")
	)
	(segment
		(start 285.85922 -181.059074)
		(end 285.868872 -181.049422)
		(width 0.0889)
		(layer "B.Cu")
		(net "TP_BMC_GPIOR4")
	)
	(segment
		(start 286.434784 -180.815234)
		(end 286.434784 -180.483002)
		(width 0.0889)
		(layer "B.Cu")
		(net "TP_BMC_GPIOR4")
	)
	(segment
		(start 288.247836 -178.645566)
		(end 288.263076 -178.660806)
		(width 0.0889)
		(layer "B.Cu")
		(net "TP_BMC_GPIOR4")
	)
	(segment
		(start 287.231074 -179.672996)
		(end 287.231074 -178.879754)
		(width 0.0889)
		(layer "B.Cu")
		(net "TP_BMC_GPIOR4")
	)
	(segment
		(start 285.868872 -181.049422)
		(end 286.200596 -181.049422)
		(width 0.0889)
		(layer "B.Cu")
		(net "TP_BMC_GPIOR4")
	)
	(segment
		(start 287.231074 -178.879754)
		(end 287.465262 -178.645566)
		(width 0.0889)
		(layer "B.Cu")
		(net "TP_BMC_GPIOR4")
	)
	(segment
		(start 288.263076 -178.660806)
		(end 288.668206 -178.660806)
		(width 0.0889)
		(layer "B.Cu")
		(net "TP_BMC_GPIOR4")
	)
	(segment
		(start 287.004252 -180.246274)
		(end 287.23844 -180.012086)
		(width 0.0889)
		(layer "B.Cu")
		(net "TP_BMC_GPIOR4")
	)
	(segment
		(start 286.434784 -180.483002)
		(end 286.671512 -180.246274)
		(width 0.0889)
		(layer "B.Cu")
		(net "TP_BMC_GPIOR4")
	)
	(segment
		(start 287.465262 -178.645566)
		(end 288.247836 -178.645566)
		(width 0.0889)
		(layer "B.Cu")
		(net "TP_BMC_GPIOR4")
	)
	(segment
		(start 288.668206 -178.660806)
		(end 289.1536 -179.1462)
		(width 0.0889)
		(layer "B.Cu")
		(net "TP_BMC_GPIOR4")
	)
	(segment
		(start 284.65272 -181.56428)
		(end 285.069026 -181.147974)
		(width 0.127)
		(layer "B.Cu")
		(net "TP_BMC_GPIOR4")
	)
	(segment
		(start 197.039992 -45.9105)
		(end 196.826378 -45.696886)
		(width 0.1143)
		(layer "F.Cu")
		(net "PRSNT_MSB_B81")
	)
	(segment
		(start 192.832482 -44.35729)
		(end 194.172078 -45.696886)
		(width 0.1143)
		(layer "F.Cu")
		(net "PRSNT_MSB_B81")
	)
	(segment
		(start 196.826378 -45.696886)
		(end 195.444364 -45.696886)
		(width 0.1143)
		(layer "F.Cu")
		(net "PRSNT_MSB_B81")
	)
	(segment
		(start 181.93131 -44.35729)
		(end 192.832482 -44.35729)
		(width 0.1143)
		(layer "F.Cu")
		(net "PRSNT_MSB_B81")
	)
	(segment
		(start 180.721 -45.5676)
		(end 181.93131 -44.35729)
		(width 0.1143)
		(layer "F.Cu")
		(net "PRSNT_MSB_B81")
	)
	(segment
		(start 194.172078 -45.696886)
		(end 195.444364 -45.696886)
		(width 0.1143)
		(layer "F.Cu")
		(net "PRSNT_MSB_B81")
	)
	(via
		(at 180.721 -45.5676)
		(size 0.5588)
		(drill 0.3048)
		(layers "F.Cu" "B.Cu")
		(net "PRSNT_MSB_B81")
	)
	(via
		(at 143.180816 -69.088)
		(size 0.5588)
		(drill 0.3048)
		(layers "F.Cu" "B.Cu")
		(net "PRSNT_MSB_B81")
	)
	(segment
		(start 142.602966 -75.630024)
		(end 142.602966 -74.948034)
		(width 0.1143)
		(layer "B.Cu")
		(net "PRSNT_MSB_B81")
	)
	(segment
		(start 139.449556 -78.24978)
		(end 139.98321 -78.24978)
		(width 0.1143)
		(layer "B.Cu")
		(net "PRSNT_MSB_B81")
	)
	(segment
		(start 143.180816 -74.370184)
		(end 143.180816 -69.088)
		(width 0.1143)
		(layer "B.Cu")
		(net "PRSNT_MSB_B81")
	)
	(segment
		(start 139.98321 -78.24978)
		(end 142.602966 -75.630024)
		(width 0.1143)
		(layer "B.Cu")
		(net "PRSNT_MSB_B81")
	)
	(segment
		(start 142.602966 -74.948034)
		(end 143.180816 -74.370184)
		(width 0.1143)
		(layer "B.Cu")
		(net "PRSNT_MSB_B81")
	)
	(segment
		(start 162.814 -61.849)
		(end 150.419816 -61.849)
		(width 0.127)
		(layer "In5.Cu")
		(net "PRSNT_MSB_B81")
	)
	(segment
		(start 180.721 -45.5676)
		(end 180.6702 -45.6184)
		(width 0.127)
		(layer "In5.Cu")
		(net "PRSNT_MSB_B81")
	)
	(segment
		(start 180.6702 -45.6184)
		(end 179.0446 -45.6184)
		(width 0.127)
		(layer "In5.Cu")
		(net "PRSNT_MSB_B81")
	)
	(segment
		(start 179.0446 -45.6184)
		(end 162.814 -61.849)
		(width 0.127)
		(layer "In5.Cu")
		(net "PRSNT_MSB_B81")
	)
	(segment
		(start 150.419816 -61.849)
		(end 143.180816 -69.088)
		(width 0.127)
		(layer "In5.Cu")
		(net "PRSNT_MSB_B81")
	)
	(segment
		(start 284.360874 -174.20209)
		(end 284.27299 -174.114206)
		(width 0.1143)
		(layer "F.Cu")
		(net "BMC_MSB_I2C_E_ALERT_#")
	)
	(segment
		(start 285.272988 -174.20209)
		(end 284.360874 -174.20209)
		(width 0.1143)
		(layer "F.Cu")
		(net "BMC_MSB_I2C_E_ALERT_#")
	)
	(segment
		(start 281.888438 -173.491906)
		(end 277.281132 -168.8846)
		(width 0.1143)
		(layer "F.Cu")
		(net "BMC_MSB_I2C_E_ALERT_#")
	)
	(segment
		(start 259.3721 -122.527568)
		(end 260.5659 -123.721368)
		(width 0.1143)
		(layer "F.Cu")
		(net "BMC_MSB_I2C_E_ALERT_#")
	)
	(segment
		(start 274.6375 -169.545)
		(end 274.9804 -169.545)
		(width 0.1143)
		(layer "F.Cu")
		(net "BMC_MSB_I2C_E_ALERT_#")
	)
	(segment
		(start 271.164558 -168.336722)
		(end 271.26311 -168.420796)
		(width 0.1143)
		(layer "F.Cu")
		(net "BMC_MSB_I2C_E_ALERT_#")
	)
	(segment
		(start 254.0762 -95.203264)
		(end 254.0762 -96.603058)
		(width 0.1143)
		(layer "F.Cu")
		(net "BMC_MSB_I2C_E_ALERT_#")
	)
	(segment
		(start 247.500394 -88.627458)
		(end 254.0762 -95.203264)
		(width 0.1143)
		(layer "F.Cu")
		(net "BMC_MSB_I2C_E_ALERT_#")
	)
	(segment
		(start 254.0762 -96.603058)
		(end 259.3721 -101.898958)
		(width 0.1143)
		(layer "F.Cu")
		(net "BMC_MSB_I2C_E_ALERT_#")
	)
	(segment
		(start 260.5659 -123.721368)
		(end 260.5659 -147.4851)
		(width 0.1143)
		(layer "F.Cu")
		(net "BMC_MSB_I2C_E_ALERT_#")
	)
	(segment
		(start 242.189 -88.627458)
		(end 247.500394 -88.627458)
		(width 0.1143)
		(layer "F.Cu")
		(net "BMC_MSB_I2C_E_ALERT_#")
	)
	(segment
		(start 261.3406 -148.2598)
		(end 261.8359 -148.7551)
		(width 0.1143)
		(layer "F.Cu")
		(net "BMC_MSB_I2C_E_ALERT_#")
	)
	(segment
		(start 273.178016 -168.420796)
		(end 273.417284 -168.660064)
		(width 0.1143)
		(layer "F.Cu")
		(net "BMC_MSB_I2C_E_ALERT_#")
	)
	(segment
		(start 284.27299 -174.114206)
		(end 284.096206 -174.114206)
		(width 0.1143)
		(layer "F.Cu")
		(net "BMC_MSB_I2C_E_ALERT_#")
	)
	(segment
		(start 274.9804 -169.545)
		(end 275.6281 -168.8973)
		(width 0.1143)
		(layer "F.Cu")
		(net "BMC_MSB_I2C_E_ALERT_#")
	)
	(segment
		(start 261.8359 -162.464242)
		(end 267.729208 -168.35755)
		(width 0.1143)
		(layer "F.Cu")
		(net "BMC_MSB_I2C_E_ALERT_#")
	)
	(segment
		(start 270.326104 -168.35755)
		(end 270.343884 -168.336722)
		(width 0.1143)
		(layer "F.Cu")
		(net "BMC_MSB_I2C_E_ALERT_#")
	)
	(segment
		(start 283.473906 -173.491906)
		(end 281.888438 -173.491906)
		(width 0.1143)
		(layer "F.Cu")
		(net "BMC_MSB_I2C_E_ALERT_#")
	)
	(segment
		(start 273.417284 -168.660064)
		(end 273.752564 -168.660064)
		(width 0.1143)
		(layer "F.Cu")
		(net "BMC_MSB_I2C_E_ALERT_#")
	)
	(segment
		(start 259.3721 -101.898958)
		(end 259.3721 -122.527568)
		(width 0.1143)
		(layer "F.Cu")
		(net "BMC_MSB_I2C_E_ALERT_#")
	)
	(segment
		(start 277.281132 -168.8846)
		(end 276.1488 -168.8846)
		(width 0.1143)
		(layer "F.Cu")
		(net "BMC_MSB_I2C_E_ALERT_#")
	)
	(segment
		(start 284.096206 -174.114206)
		(end 283.473906 -173.491906)
		(width 0.1143)
		(layer "F.Cu")
		(net "BMC_MSB_I2C_E_ALERT_#")
	)
	(segment
		(start 260.5659 -147.4851)
		(end 261.3406 -148.2598)
		(width 0.1143)
		(layer "F.Cu")
		(net "BMC_MSB_I2C_E_ALERT_#")
	)
	(segment
		(start 275.6281 -168.8973)
		(end 276.073108 -168.8973)
		(width 0.1143)
		(layer "F.Cu")
		(net "BMC_MSB_I2C_E_ALERT_#")
	)
	(segment
		(start 271.26311 -168.420796)
		(end 273.178016 -168.420796)
		(width 0.1143)
		(layer "F.Cu")
		(net "BMC_MSB_I2C_E_ALERT_#")
	)
	(segment
		(start 273.752564 -168.660064)
		(end 274.6375 -169.545)
		(width 0.1143)
		(layer "F.Cu")
		(net "BMC_MSB_I2C_E_ALERT_#")
	)
	(segment
		(start 276.085808 -168.8846)
		(end 276.1488 -168.8846)
		(width 0.1143)
		(layer "F.Cu")
		(net "BMC_MSB_I2C_E_ALERT_#")
	)
	(segment
		(start 261.8359 -148.7551)
		(end 261.8359 -162.464242)
		(width 0.1143)
		(layer "F.Cu")
		(net "BMC_MSB_I2C_E_ALERT_#")
	)
	(segment
		(start 267.729208 -168.35755)
		(end 270.326104 -168.35755)
		(width 0.1143)
		(layer "F.Cu")
		(net "BMC_MSB_I2C_E_ALERT_#")
	)
	(segment
		(start 276.073108 -168.8973)
		(end 276.085808 -168.8846)
		(width 0.1143)
		(layer "F.Cu")
		(net "BMC_MSB_I2C_E_ALERT_#")
	)
	(segment
		(start 270.343884 -168.336722)
		(end 271.164558 -168.336722)
		(width 0.1143)
		(layer "F.Cu")
		(net "BMC_MSB_I2C_E_ALERT_#")
	)
	(segment
		(start 285.634938 -173.84014)
		(end 285.272988 -174.20209)
		(width 0.1143)
		(layer "F.Cu")
		(net "BMC_MSB_I2C_E_ALERT_#")
	)
	(via
		(at 261.3406 -148.2598)
		(size 0.7112)
		(drill 0.3556)
		(layers "F.Cu" "B.Cu")
		(net "BMC_MSB_I2C_E_ALERT_#")
	)
	(via
		(at 242.189 -88.627458)
		(size 0.5588)
		(drill 0.3048)
		(layers "F.Cu" "B.Cu")
		(net "BMC_MSB_I2C_E_ALERT_#")
	)
	(segment
		(start 229.953566 -84.582)
		(end 233.903266 -88.5317)
		(width 0.127)
		(layer "In2.Cu")
		(net "BMC_MSB_I2C_E_ALERT_#")
	)
	(segment
		(start 219.739718 -84.582)
		(end 229.953566 -84.582)
		(width 0.127)
		(layer "In2.Cu")
		(net "BMC_MSB_I2C_E_ALERT_#")
	)
	(segment
		(start 209.40141 -81.201514)
		(end 216.359232 -81.201514)
		(width 0.127)
		(layer "In2.Cu")
		(net "BMC_MSB_I2C_E_ALERT_#")
	)
	(segment
		(start 242.093242 -88.5317)
		(end 242.189 -88.627458)
		(width 0.127)
		(layer "In2.Cu")
		(net "BMC_MSB_I2C_E_ALERT_#")
	)
	(segment
		(start 216.359232 -81.201514)
		(end 219.739718 -84.582)
		(width 0.127)
		(layer "In2.Cu")
		(net "BMC_MSB_I2C_E_ALERT_#")
	)
	(segment
		(start 233.903266 -88.5317)
		(end 242.093242 -88.5317)
		(width 0.127)
		(layer "In2.Cu")
		(net "BMC_MSB_I2C_E_ALERT_#")
	)
	(segment
		(start 208.449926 -80.25003)
		(end 209.40141 -81.201514)
		(width 0.127)
		(layer "In2.Cu")
		(net "BMC_MSB_I2C_E_ALERT_#")
	)
	(segment
		(start 290.434776 -167.925242)
		(end 290.434776 -168.240202)
		(width 0.127)
		(layer "F.Cu")
		(net "TP_BMC_GPIOE2")
	)
	(segment
		(start 290.091876 -167.582342)
		(end 290.434776 -167.925242)
		(width 0.127)
		(layer "F.Cu")
		(net "TP_BMC_GPIOE2")
	)
	(segment
		(start 290.091876 -164.64788)
		(end 290.091876 -167.582342)
		(width 0.127)
		(layer "F.Cu")
		(net "TP_BMC_GPIOE2")
	)
	(segment
		(start 289.433 -163.703)
		(end 289.433 -163.989004)
		(width 0.127)
		(layer "F.Cu")
		(net "TP_BMC_GPIOE2")
	)
	(segment
		(start 289.433 -163.989004)
		(end 290.091876 -164.64788)
		(width 0.127)
		(layer "F.Cu")
		(net "TP_BMC_GPIOE2")
	)
	(segment
		(start 290.434776 -169.040048)
		(end 290.05022 -168.655492)
		(width 0.127)
		(layer "F.Cu")
		(net "TP_BMC_GPIOE1")
	)
	(segment
		(start 290.05022 -168.649396)
		(end 290.0426 -168.641776)
		(width 0.127)
		(layer "F.Cu")
		(net "TP_BMC_GPIOE1")
	)
	(segment
		(start 290.05022 -168.655492)
		(end 290.05022 -168.649396)
		(width 0.127)
		(layer "F.Cu")
		(net "TP_BMC_GPIOE1")
	)
	(via
		(at 290.0426 -168.641776)
		(size 0.508)
		(drill 0.254)
		(layers "F.Cu" "B.Cu")
		(net "TP_BMC_GPIOE1")
	)
	(segment
		(start 290.449 -166.497)
		(end 289.617912 -167.328088)
		(width 0.127)
		(layer "B.Cu")
		(net "TP_BMC_GPIOE1")
	)
	(segment
		(start 289.617912 -168.217088)
		(end 290.0426 -168.641776)
		(width 0.127)
		(layer "B.Cu")
		(net "TP_BMC_GPIOE1")
	)
	(segment
		(start 289.617912 -167.328088)
		(end 289.617912 -168.217088)
		(width 0.127)
		(layer "B.Cu")
		(net "TP_BMC_GPIOE1")
	)
	(segment
		(start 290.84016 -170.245532)
		(end 290.84016 -170.23588)
		(width 0.127)
		(layer "F.Cu")
		(net "TP_BMC_GPIOE4")
	)
	(segment
		(start 290.84016 -170.23588)
		(end 290.83508 -170.2308)
		(width 0.127)
		(layer "F.Cu")
		(net "TP_BMC_GPIOE4")
	)
	(segment
		(start 291.234876 -170.640248)
		(end 290.84016 -170.245532)
		(width 0.127)
		(layer "F.Cu")
		(net "TP_BMC_GPIOE4")
	)
	(via
		(at 290.83508 -170.2308)
		(size 0.508)
		(drill 0.254)
		(layers "F.Cu" "B.Cu")
		(net "TP_BMC_GPIOE4")
	)
	(segment
		(start 290.79444 -170.2308)
		(end 290.83508 -170.2308)
		(width 0.127)
		(layer "B.Cu")
		(net "TP_BMC_GPIOE4")
	)
	(segment
		(start 290.01466 -169.45102)
		(end 290.79444 -170.2308)
		(width 0.127)
		(layer "B.Cu")
		(net "TP_BMC_GPIOE4")
	)
	(segment
		(start 290.37915 -163.12515)
		(end 290.37915 -164.34435)
		(width 0.127)
		(layer "F.Cu")
		(net "TP_BMC_GPIOE3")
	)
	(segment
		(start 290.434776 -164.399976)
		(end 290.434776 -167.440102)
		(width 0.127)
		(layer "F.Cu")
		(net "TP_BMC_GPIOE3")
	)
	(segment
		(start 289.433 -162.433)
		(end 290.37915 -163.12515)
		(width 0.127)
		(layer "F.Cu")
		(net "TP_BMC_GPIOE3")
	)
	(segment
		(start 290.37915 -164.34435)
		(end 290.434776 -164.399976)
		(width 0.127)
		(layer "F.Cu")
		(net "TP_BMC_GPIOE3")
	)
	(segment
		(start 290.82619 -169.43959)
		(end 290.825682 -169.43959)
		(width 0.127)
		(layer "F.Cu")
		(net "TP_BMC_GPIOE5")
	)
	(segment
		(start 291.234876 -169.840148)
		(end 291.226748 -169.840148)
		(width 0.127)
		(layer "F.Cu")
		(net "TP_BMC_GPIOE5")
	)
	(segment
		(start 291.226748 -169.840148)
		(end 290.82619 -169.43959)
		(width 0.127)
		(layer "F.Cu")
		(net "TP_BMC_GPIOE5")
	)
	(via
		(at 290.825682 -169.43959)
		(size 0.508)
		(drill 0.254)
		(layers "F.Cu" "B.Cu")
		(net "TP_BMC_GPIOE5")
	)
	(segment
		(start 290.449 -167.767)
		(end 290.825682 -168.143682)
		(width 0.127)
		(layer "B.Cu")
		(net "TP_BMC_GPIOE5")
	)
	(segment
		(start 290.825682 -168.143682)
		(end 290.825682 -169.43959)
		(width 0.127)
		(layer "B.Cu")
		(net "TP_BMC_GPIOE5")
	)
	(segment
		(start 317.735458 -62.357)
		(end 320.465958 -62.357)
		(width 0.1143)
		(layer "F.Cu")
		(net "BMC_MBC_I2C_E_SDA")
	)
	(segment
		(start 266.7 -168.529)
		(end 261.3406 -163.1696)
		(width 0.1143)
		(layer "F.Cu")
		(net "BMC_MBC_I2C_E_SDA")
	)
	(segment
		(start 261.3406 -149.5552)
		(end 260.4008 -148.6154)
		(width 0.1143)
		(layer "F.Cu")
		(net "BMC_MBC_I2C_E_SDA")
	)
	(segment
		(start 272.20545 -170.16095)
		(end 271.7165 -169.672)
		(width 0.1143)
		(layer "F.Cu")
		(net "BMC_MBC_I2C_E_SDA")
	)
	(segment
		(start 258.8768 -122.7328)
		(end 258.8768 -112.3442)
		(width 0.1143)
		(layer "F.Cu")
		(net "BMC_MBC_I2C_E_SDA")
	)
	(segment
		(start 271.7165 -169.672)
		(end 271.0815 -170.307)
		(width 0.1143)
		(layer "F.Cu")
		(net "BMC_MBC_I2C_E_SDA")
	)
	(segment
		(start 260.4008 -148.02104)
		(end 260.0706 -147.69084)
		(width 0.1143)
		(layer "F.Cu")
		(net "BMC_MBC_I2C_E_SDA")
	)
	(segment
		(start 321.437 -62.611)
		(end 320.719958 -62.611)
		(width 0.1143)
		(layer "F.Cu")
		(net "BMC_MBC_I2C_E_SDA")
	)
	(segment
		(start 252.984 -94.811596)
		(end 247.501156 -89.328752)
		(width 0.1143)
		(layer "F.Cu")
		(net "BMC_MBC_I2C_E_SDA")
	)
	(segment
		(start 247.501156 -89.328752)
		(end 243.713 -89.328752)
		(width 0.1143)
		(layer "F.Cu")
		(net "BMC_MBC_I2C_E_SDA")
	)
	(segment
		(start 320.719958 -62.611)
		(end 320.465958 -62.357)
		(width 0.1143)
		(layer "F.Cu")
		(net "BMC_MBC_I2C_E_SDA")
	)
	(segment
		(start 266.954 -170.307)
		(end 266.7 -170.053)
		(width 0.1143)
		(layer "F.Cu")
		(net "BMC_MBC_I2C_E_SDA")
	)
	(segment
		(start 252.984 -106.4514)
		(end 252.984 -94.811596)
		(width 0.1143)
		(layer "F.Cu")
		(net "BMC_MBC_I2C_E_SDA")
	)
	(segment
		(start 273.7485 -170.561)
		(end 273.34845 -170.16095)
		(width 0.1143)
		(layer "F.Cu")
		(net "BMC_MBC_I2C_E_SDA")
	)
	(segment
		(start 273.34845 -170.16095)
		(end 272.20545 -170.16095)
		(width 0.1143)
		(layer "F.Cu")
		(net "BMC_MBC_I2C_E_SDA")
	)
	(segment
		(start 271.0815 -170.307)
		(end 266.954 -170.307)
		(width 0.1143)
		(layer "F.Cu")
		(net "BMC_MBC_I2C_E_SDA")
	)
	(segment
		(start 258.8768 -112.3442)
		(end 252.984 -106.4514)
		(width 0.1143)
		(layer "F.Cu")
		(net "BMC_MBC_I2C_E_SDA")
	)
	(segment
		(start 266.7 -170.053)
		(end 266.7 -168.529)
		(width 0.1143)
		(layer "F.Cu")
		(net "BMC_MBC_I2C_E_SDA")
	)
	(segment
		(start 260.0706 -147.69084)
		(end 260.0706 -123.9266)
		(width 0.1143)
		(layer "F.Cu")
		(net "BMC_MBC_I2C_E_SDA")
	)
	(segment
		(start 261.3406 -163.1696)
		(end 261.3406 -149.5552)
		(width 0.1143)
		(layer "F.Cu")
		(net "BMC_MBC_I2C_E_SDA")
	)
	(segment
		(start 260.0706 -123.9266)
		(end 258.8768 -122.7328)
		(width 0.1143)
		(layer "F.Cu")
		(net "BMC_MBC_I2C_E_SDA")
	)
	(segment
		(start 260.4008 -148.6154)
		(end 260.4008 -148.02104)
		(width 0.1143)
		(layer "F.Cu")
		(net "BMC_MBC_I2C_E_SDA")
	)
	(via
		(at 320.465958 -62.357)
		(size 0.5588)
		(drill 0.3048)
		(layers "F.Cu" "B.Cu")
		(net "BMC_MBC_I2C_E_SDA")
	)
	(via
		(at 243.713 -89.328752)
		(size 0.5588)
		(drill 0.3048)
		(layers "F.Cu" "B.Cu")
		(net "BMC_MBC_I2C_E_SDA")
	)
	(via
		(at 321.437 -62.611)
		(size 0.7112)
		(drill 0.3556)
		(layers "F.Cu" "B.Cu")
		(net "BMC_MBC_I2C_E_SDA")
	)
	(segment
		(start 216.449656 -80.25003)
		(end 216.449656 -80.573372)
		(width 0.127)
		(layer "In2.Cu")
		(net "BMC_MBC_I2C_E_SDA")
	)
	(segment
		(start 234.101132 -88.011)
		(end 242.395248 -88.011)
		(width 0.127)
		(layer "In2.Cu")
		(net "BMC_MBC_I2C_E_SDA")
	)
	(segment
		(start 216.449656 -80.573372)
		(end 219.950284 -84.074)
		(width 0.127)
		(layer "In2.Cu")
		(net "BMC_MBC_I2C_E_SDA")
	)
	(segment
		(start 230.164132 -84.074)
		(end 234.101132 -88.011)
		(width 0.127)
		(layer "In2.Cu")
		(net "BMC_MBC_I2C_E_SDA")
	)
	(segment
		(start 242.395248 -88.011)
		(end 243.713 -89.328752)
		(width 0.127)
		(layer "In2.Cu")
		(net "BMC_MBC_I2C_E_SDA")
	)
	(segment
		(start 219.950284 -84.074)
		(end 230.164132 -84.074)
		(width 0.127)
		(layer "In2.Cu")
		(net "BMC_MBC_I2C_E_SDA")
	)
	(segment
		(start 316.992 -84.582)
		(end 320.167 -84.582)
		(width 0.127)
		(layer "In5.Cu")
		(net "BMC_MBC_I2C_E_SDA")
	)
	(segment
		(start 313.944 -86.614)
		(end 314.96 -86.614)
		(width 0.127)
		(layer "In5.Cu")
		(net "BMC_MBC_I2C_E_SDA")
	)
	(segment
		(start 319.686432 -63.136526)
		(end 320.465958 -62.357)
		(width 0.127)
		(layer "In5.Cu")
		(net "BMC_MBC_I2C_E_SDA")
	)
	(segment
		(start 321.583558 -83.165442)
		(end 321.583558 -68.175124)
		(width 0.127)
		(layer "In5.Cu")
		(net "BMC_MBC_I2C_E_SDA")
	)
	(segment
		(start 301.385732 -89.2302)
		(end 311.3278 -89.2302)
		(width 0.127)
		(layer "In5.Cu")
		(net "BMC_MBC_I2C_E_SDA")
	)
	(segment
		(start 314.96 -86.614)
		(end 316.992 -84.582)
		(width 0.127)
		(layer "In5.Cu")
		(net "BMC_MBC_I2C_E_SDA")
	)
	(segment
		(start 321.583558 -68.175124)
		(end 319.686432 -66.277998)
		(width 0.127)
		(layer "In5.Cu")
		(net "BMC_MBC_I2C_E_SDA")
	)
	(segment
		(start 300.941232 -88.7857)
		(end 301.385732 -89.2302)
		(width 0.127)
		(layer "In5.Cu")
		(net "BMC_MBC_I2C_E_SDA")
	)
	(segment
		(start 319.686432 -66.277998)
		(end 319.686432 -63.136526)
		(width 0.127)
		(layer "In5.Cu")
		(net "BMC_MBC_I2C_E_SDA")
	)
	(segment
		(start 265.61542 -89.328752)
		(end 266.158472 -88.7857)
		(width 0.127)
		(layer "In5.Cu")
		(net "BMC_MBC_I2C_E_SDA")
	)
	(segment
		(start 320.167 -84.582)
		(end 321.583558 -83.165442)
		(width 0.127)
		(layer "In5.Cu")
		(net "BMC_MBC_I2C_E_SDA")
	)
	(segment
		(start 311.3278 -89.2302)
		(end 313.944 -86.614)
		(width 0.127)
		(layer "In5.Cu")
		(net "BMC_MBC_I2C_E_SDA")
	)
	(segment
		(start 243.713 -89.328752)
		(end 265.61542 -89.328752)
		(width 0.127)
		(layer "In5.Cu")
		(net "BMC_MBC_I2C_E_SDA")
	)
	(segment
		(start 266.158472 -88.7857)
		(end 300.941232 -88.7857)
		(width 0.127)
		(layer "In5.Cu")
		(net "BMC_MBC_I2C_E_SDA")
	)
	(segment
		(start 252.4887 -95.016828)
		(end 252.4887 -106.656632)
		(width 0.1143)
		(layer "F.Cu")
		(net "BMC_MBC_I2C_E_SCL")
	)
	(segment
		(start 244.982746 -90.042746)
		(end 247.514618 -90.042746)
		(width 0.1143)
		(layer "F.Cu")
		(net "BMC_MBC_I2C_E_SCL")
	)
	(segment
		(start 258.3815 -124.544328)
		(end 259.5753 -125.738128)
		(width 0.1143)
		(layer "F.Cu")
		(net "BMC_MBC_I2C_E_SCL")
	)
	(segment
		(start 273.393916 -171.577)
		(end 273.7485 -171.577)
		(width 0.1143)
		(layer "F.Cu")
		(net "BMC_MBC_I2C_E_SCL")
	)
	(segment
		(start 260.8453 -164.961824)
		(end 266.685776 -170.8023)
		(width 0.1143)
		(layer "F.Cu")
		(net "BMC_MBC_I2C_E_SCL")
	)
	(segment
		(start 247.514618 -90.042746)
		(end 252.4887 -95.016828)
		(width 0.1143)
		(layer "F.Cu")
		(net "BMC_MBC_I2C_E_SCL")
	)
	(segment
		(start 271.7165 -170.942)
		(end 271.7165 -171.0055)
		(width 0.1143)
		(layer "F.Cu")
		(net "BMC_MBC_I2C_E_SCL")
	)
	(segment
		(start 272.161 -171.45)
		(end 273.266916 -171.45)
		(width 0.1143)
		(layer "F.Cu")
		(net "BMC_MBC_I2C_E_SCL")
	)
	(segment
		(start 268.224 -171.069)
		(end 268.71295 -171.55795)
		(width 0.1143)
		(layer "F.Cu")
		(net "BMC_MBC_I2C_E_SCL")
	)
	(segment
		(start 268.71295 -171.55795)
		(end 271.021048 -171.55795)
		(width 0.1143)
		(layer "F.Cu")
		(net "BMC_MBC_I2C_E_SCL")
	)
	(segment
		(start 320.5226 -61.341)
		(end 320.465958 -61.341)
		(width 0.1143)
		(layer "F.Cu")
		(net "BMC_MBC_I2C_E_SCL")
	)
	(segment
		(start 259.9055 -150.492968)
		(end 260.8453 -151.432768)
		(width 0.1143)
		(layer "F.Cu")
		(net "BMC_MBC_I2C_E_SCL")
	)
	(segment
		(start 267.9573 -170.8023)
		(end 268.224 -171.069)
		(width 0.1143)
		(layer "F.Cu")
		(net "BMC_MBC_I2C_E_SCL")
	)
	(segment
		(start 259.5753 -147.896072)
		(end 259.9055 -148.226272)
		(width 0.1143)
		(layer "F.Cu")
		(net "BMC_MBC_I2C_E_SCL")
	)
	(segment
		(start 317.735458 -61.341)
		(end 320.465958 -61.341)
		(width 0.1143)
		(layer "F.Cu")
		(net "BMC_MBC_I2C_E_SCL")
	)
	(segment
		(start 244.856 -89.916)
		(end 244.982746 -90.042746)
		(width 0.1143)
		(layer "F.Cu")
		(net "BMC_MBC_I2C_E_SCL")
	)
	(segment
		(start 258.3815 -112.549432)
		(end 258.3815 -124.544328)
		(width 0.1143)
		(layer "F.Cu")
		(net "BMC_MBC_I2C_E_SCL")
	)
	(segment
		(start 266.685776 -170.8023)
		(end 267.9573 -170.8023)
		(width 0.1143)
		(layer "F.Cu")
		(net "BMC_MBC_I2C_E_SCL")
	)
	(segment
		(start 273.266916 -171.45)
		(end 273.393916 -171.577)
		(width 0.1143)
		(layer "F.Cu")
		(net "BMC_MBC_I2C_E_SCL")
	)
	(segment
		(start 271.021048 -171.55795)
		(end 271.38884 -171.302426)
		(width 0.1143)
		(layer "F.Cu")
		(net "BMC_MBC_I2C_E_SCL")
	)
	(segment
		(start 271.7165 -171.0055)
		(end 272.161 -171.45)
		(width 0.1143)
		(layer "F.Cu")
		(net "BMC_MBC_I2C_E_SCL")
	)
	(segment
		(start 252.4887 -106.656632)
		(end 258.3815 -112.549432)
		(width 0.1143)
		(layer "F.Cu")
		(net "BMC_MBC_I2C_E_SCL")
	)
	(segment
		(start 271.38884 -171.302426)
		(end 271.396206 -171.262548)
		(width 0.1143)
		(layer "F.Cu")
		(net "BMC_MBC_I2C_E_SCL")
	)
	(segment
		(start 271.396206 -171.262548)
		(end 271.7165 -170.942)
		(width 0.1143)
		(layer "F.Cu")
		(net "BMC_MBC_I2C_E_SCL")
	)
	(segment
		(start 321.2084 -60.6552)
		(end 320.5226 -61.341)
		(width 0.1143)
		(layer "F.Cu")
		(net "BMC_MBC_I2C_E_SCL")
	)
	(segment
		(start 259.5753 -125.738128)
		(end 259.5753 -147.896072)
		(width 0.1143)
		(layer "F.Cu")
		(net "BMC_MBC_I2C_E_SCL")
	)
	(segment
		(start 260.8453 -151.432768)
		(end 260.8453 -164.961824)
		(width 0.1143)
		(layer "F.Cu")
		(net "BMC_MBC_I2C_E_SCL")
	)
	(segment
		(start 259.9055 -148.226272)
		(end 259.9055 -150.492968)
		(width 0.1143)
		(layer "F.Cu")
		(net "BMC_MBC_I2C_E_SCL")
	)
	(via
		(at 244.856 -89.916)
		(size 0.5588)
		(drill 0.3048)
		(layers "F.Cu" "B.Cu")
		(net "BMC_MBC_I2C_E_SCL")
	)
	(via
		(at 321.2084 -60.6552)
		(size 0.7112)
		(drill 0.3556)
		(layers "F.Cu" "B.Cu")
		(net "BMC_MBC_I2C_E_SCL")
	)
	(via
		(at 320.465958 -61.341)
		(size 0.5588)
		(drill 0.3048)
		(layers "F.Cu" "B.Cu")
		(net "BMC_MBC_I2C_E_SCL")
	)
	(segment
		(start 242.605814 -87.503)
		(end 244.856 -89.753186)
		(width 0.127)
		(layer "In2.Cu")
		(net "BMC_MBC_I2C_E_SCL")
	)
	(segment
		(start 217.450416 -80.855566)
		(end 219.70873 -83.11388)
		(width 0.127)
		(layer "In2.Cu")
		(net "BMC_MBC_I2C_E_SCL")
	)
	(segment
		(start 244.856 -89.753186)
		(end 244.856 -89.916)
		(width 0.127)
		(layer "In2.Cu")
		(net "BMC_MBC_I2C_E_SCL")
	)
	(segment
		(start 217.450416 -78.24978)
		(end 217.450416 -80.855566)
		(width 0.127)
		(layer "In2.Cu")
		(net "BMC_MBC_I2C_E_SCL")
	)
	(segment
		(start 219.70873 -83.11388)
		(end 229.922578 -83.11388)
		(width 0.127)
		(layer "In2.Cu")
		(net "BMC_MBC_I2C_E_SCL")
	)
	(segment
		(start 234.311698 -87.503)
		(end 242.605814 -87.503)
		(width 0.127)
		(layer "In2.Cu")
		(net "BMC_MBC_I2C_E_SCL")
	)
	(segment
		(start 229.922578 -83.11388)
		(end 234.311698 -87.503)
		(width 0.127)
		(layer "In2.Cu")
		(net "BMC_MBC_I2C_E_SCL")
	)
	(segment
		(start 265.746738 -89.916)
		(end 266.059158 -89.60358)
		(width 0.127)
		(layer "In5.Cu")
		(net "BMC_MBC_I2C_E_SCL")
	)
	(segment
		(start 320.194432 -66.067432)
		(end 320.194432 -64.532002)
		(width 0.127)
		(layer "In5.Cu")
		(net "BMC_MBC_I2C_E_SCL")
	)
	(segment
		(start 295.734486 -89.7763)
		(end 297.488356 -89.7763)
		(width 0.127)
		(layer "In5.Cu")
		(net "BMC_MBC_I2C_E_SCL")
	)
	(segment
		(start 297.488356 -89.7763)
		(end 297.729656 -90.0176)
		(width 0.127)
		(layer "In5.Cu")
		(net "BMC_MBC_I2C_E_SCL")
	)
	(segment
		(start 244.856 -89.916)
		(end 265.746738 -89.916)
		(width 0.127)
		(layer "In5.Cu")
		(net "BMC_MBC_I2C_E_SCL")
	)
	(segment
		(start 311.7977 -89.7763)
		(end 314.452 -87.122)
		(width 0.127)
		(layer "In5.Cu")
		(net "BMC_MBC_I2C_E_SCL")
	)
	(segment
		(start 322.199 -83.268566)
		(end 322.199 -68.072)
		(width 0.127)
		(layer "In5.Cu")
		(net "BMC_MBC_I2C_E_SCL")
	)
	(segment
		(start 320.961258 -63.765176)
		(end 320.961258 -61.8363)
		(width 0.127)
		(layer "In5.Cu")
		(net "BMC_MBC_I2C_E_SCL")
	)
	(segment
		(start 320.194432 -64.532002)
		(end 320.961258 -63.765176)
		(width 0.127)
		(layer "In5.Cu")
		(net "BMC_MBC_I2C_E_SCL")
	)
	(segment
		(start 314.452 -87.122)
		(end 315.214 -87.122)
		(width 0.127)
		(layer "In5.Cu")
		(net "BMC_MBC_I2C_E_SCL")
	)
	(segment
		(start 317.246 -85.09)
		(end 320.377566 -85.09)
		(width 0.127)
		(layer "In5.Cu")
		(net "BMC_MBC_I2C_E_SCL")
	)
	(segment
		(start 309.047134 -89.7763)
		(end 311.7977 -89.7763)
		(width 0.127)
		(layer "In5.Cu")
		(net "BMC_MBC_I2C_E_SCL")
	)
	(segment
		(start 315.214 -87.122)
		(end 317.246 -85.09)
		(width 0.127)
		(layer "In5.Cu")
		(net "BMC_MBC_I2C_E_SCL")
	)
	(segment
		(start 320.961258 -61.8363)
		(end 320.465958 -61.341)
		(width 0.127)
		(layer "In5.Cu")
		(net "BMC_MBC_I2C_E_SCL")
	)
	(segment
		(start 320.377566 -85.09)
		(end 322.199 -83.268566)
		(width 0.127)
		(layer "In5.Cu")
		(net "BMC_MBC_I2C_E_SCL")
	)
	(segment
		(start 297.729656 -90.0176)
		(end 308.805834 -90.0176)
		(width 0.127)
		(layer "In5.Cu")
		(net "BMC_MBC_I2C_E_SCL")
	)
	(segment
		(start 295.561766 -89.60358)
		(end 295.734486 -89.7763)
		(width 0.127)
		(layer "In5.Cu")
		(net "BMC_MBC_I2C_E_SCL")
	)
	(segment
		(start 266.059158 -89.60358)
		(end 295.561766 -89.60358)
		(width 0.127)
		(layer "In5.Cu")
		(net "BMC_MBC_I2C_E_SCL")
	)
	(segment
		(start 322.199 -68.072)
		(end 320.194432 -66.067432)
		(width 0.127)
		(layer "In5.Cu")
		(net "BMC_MBC_I2C_E_SCL")
	)
	(segment
		(start 308.805834 -90.0176)
		(end 309.047134 -89.7763)
		(width 0.127)
		(layer "In5.Cu")
		(net "BMC_MBC_I2C_E_SCL")
	)
	(segment
		(start 333.375 -210.058)
		(end 333.375 -211.0105)
		(width 0.1143)
		(layer "F.Cu")
		(net "EEPROM_SCL")
	)
	(segment
		(start 333.701136 -209.731864)
		(end 333.375 -210.058)
		(width 0.1143)
		(layer "F.Cu")
		(net "EEPROM_SCL")
	)
	(segment
		(start 333.375 -211.0105)
		(end 332.359 -211.0105)
		(width 0.1143)
		(layer "F.Cu")
		(net "EEPROM_SCL")
	)
	(segment
		(start 333.701136 -208.542128)
		(end 333.701136 -209.731864)
		(width 0.1143)
		(layer "F.Cu")
		(net "EEPROM_SCL")
	)
	(via
		(at 333.375 -210.058)
		(size 0.7112)
		(drill 0.3556)
		(layers "F.Cu" "B.Cu")
		(net "EEPROM_SCL")
	)
	(segment
		(start 313.125104 -62.80023)
		(end 315.337698 -62.80023)
		(width 0.1143)
		(layer "F.Cu")
		(net "I2C_BMC_MSB_DATA_R")
	)
	(segment
		(start 316.846458 -62.357)
		(end 316.330076 -62.357)
		(width 0.1143)
		(layer "F.Cu")
		(net "I2C_BMC_MSB_DATA_R")
	)
	(segment
		(start 315.595 -63.057532)
		(end 315.629544 -63.057532)
		(width 0.1143)
		(layer "F.Cu")
		(net "I2C_BMC_MSB_DATA_R")
	)
	(segment
		(start 315.337698 -62.80023)
		(end 315.595 -63.057532)
		(width 0.1143)
		(layer "F.Cu")
		(net "I2C_BMC_MSB_DATA_R")
	)
	(segment
		(start 316.330076 -62.357)
		(end 315.629544 -63.057532)
		(width 0.1143)
		(layer "F.Cu")
		(net "I2C_BMC_MSB_DATA_R")
	)
	(via
		(at 315.629544 -63.057532)
		(size 0.7112)
		(drill 0.3556)
		(layers "F.Cu" "B.Cu")
		(net "I2C_BMC_MSB_DATA_R")
	)
	(segment
		(start 334.391 -210.312)
		(end 334.391 -211.0105)
		(width 0.1143)
		(layer "F.Cu")
		(net "EEPROM_SDA")
	)
	(segment
		(start 334.971136 -209.731864)
		(end 334.645 -210.058)
		(width 0.1143)
		(layer "F.Cu")
		(net "EEPROM_SDA")
	)
	(segment
		(start 334.645 -210.058)
		(end 334.391 -210.312)
		(width 0.1143)
		(layer "F.Cu")
		(net "EEPROM_SDA")
	)
	(segment
		(start 334.971136 -208.542128)
		(end 334.971136 -209.731864)
		(width 0.1143)
		(layer "F.Cu")
		(net "EEPROM_SDA")
	)
	(segment
		(start 334.391 -211.0105)
		(end 335.407 -211.0105)
		(width 0.1143)
		(layer "F.Cu")
		(net "EEPROM_SDA")
	)
	(via
		(at 334.645 -210.058)
		(size 0.7112)
		(drill 0.3556)
		(layers "F.Cu" "B.Cu")
		(net "EEPROM_SDA")
	)
	(segment
		(start 313.125104 -62.00013)
		(end 315.31687 -62.00013)
		(width 0.1143)
		(layer "F.Cu")
		(net "I2C_BMC_MSB_CLK_R")
	)
	(segment
		(start 316.846458 -61.341)
		(end 316.338458 -61.849)
		(width 0.1143)
		(layer "F.Cu")
		(net "I2C_BMC_MSB_CLK_R")
	)
	(segment
		(start 316.338458 -61.849)
		(end 315.468 -61.849)
		(width 0.1143)
		(layer "F.Cu")
		(net "I2C_BMC_MSB_CLK_R")
	)
	(segment
		(start 315.31687 -62.00013)
		(end 315.468 -61.849)
		(width 0.1143)
		(layer "F.Cu")
		(net "I2C_BMC_MSB_CLK_R")
	)
	(via
		(at 315.468 -61.849)
		(size 0.7112)
		(drill 0.3556)
		(layers "F.Cu" "B.Cu")
		(net "I2C_BMC_MSB_CLK_R")
	)
	(segment
		(start 92.060522 -253.29642)
		(end 92.060522 -252.28931)
		(width 0.1143)
		(layer "F.Cu")
		(net "ID_I2C_ADD")
	)
	(segment
		(start 91.739212 -251.968)
		(end 91.739212 -251.714)
		(width 0.1143)
		(layer "F.Cu")
		(net "ID_I2C_ADD")
	)
	(segment
		(start 92.060522 -252.28931)
		(end 91.739212 -251.968)
		(width 0.1143)
		(layer "F.Cu")
		(net "ID_I2C_ADD")
	)
	(segment
		(start 91.999562 -253.35738)
		(end 92.060522 -253.29642)
		(width 0.1143)
		(layer "F.Cu")
		(net "ID_I2C_ADD")
	)
	(segment
		(start 91.999562 -256.25044)
		(end 91.999562 -253.35738)
		(width 0.1143)
		(layer "F.Cu")
		(net "ID_I2C_ADD")
	)
	(segment
		(start 91.739212 -251.714)
		(end 91.739212 -250.3805)
		(width 0.1143)
		(layer "F.Cu")
		(net "ID_I2C_ADD")
	)
	(via
		(at 91.739212 -251.714)
		(size 0.7112)
		(drill 0.3556)
		(layers "F.Cu" "B.Cu")
		(net "ID_I2C_ADD")
	)
	(segment
		(start 292.9763 -157.7467)
		(end 292.9763 -156.512768)
		(width 0.1143)
		(layer "F.Cu")
		(net "HDD_PRE_IO_INT_N")
	)
	(segment
		(start 271.8689 -152.1841)
		(end 271.3482 -152.7048)
		(width 0.1143)
		(layer "F.Cu")
		(net "HDD_PRE_IO_INT_N")
	)
	(segment
		(start 14.047216 -189.53988)
		(end 14.047216 -190.61938)
		(width 0.1143)
		(layer "F.Cu")
		(net "HDD_PRE_IO_INT_N")
	)
	(segment
		(start 292.5445 -158.1785)
		(end 292.9763 -157.7467)
		(width 0.1143)
		(layer "F.Cu")
		(net "HDD_PRE_IO_INT_N")
	)
	(segment
		(start 14.047216 -190.61938)
		(end 14.936216 -190.61938)
		(width 0.1143)
		(layer "F.Cu")
		(net "HDD_PRE_IO_INT_N")
	)
	(segment
		(start 292.481 -159.1945)
		(end 292.481 -158.1785)
		(width 0.1143)
		(layer "F.Cu")
		(net "HDD_PRE_IO_INT_N")
	)
	(segment
		(start 14.936216 -190.61938)
		(end 15.337282 -191.020446)
		(width 0.1143)
		(layer "F.Cu")
		(net "HDD_PRE_IO_INT_N")
	)
	(segment
		(start 269.1638 -152.7048)
		(end 268.732 -152.273)
		(width 0.1143)
		(layer "F.Cu")
		(net "HDD_PRE_IO_INT_N")
	)
	(segment
		(start 14.047216 -188.65088)
		(end 14.047216 -189.53988)
		(width 0.1143)
		(layer "F.Cu")
		(net "HDD_PRE_IO_INT_N")
	)
	(segment
		(start 15.337282 -191.020446)
		(end 15.909798 -191.020446)
		(width 0.1143)
		(layer "F.Cu")
		(net "HDD_PRE_IO_INT_N")
	)
	(segment
		(start 271.3482 -152.7048)
		(end 269.1638 -152.7048)
		(width 0.1143)
		(layer "F.Cu")
		(net "HDD_PRE_IO_INT_N")
	)
	(segment
		(start 292.9763 -156.512768)
		(end 288.647632 -152.1841)
		(width 0.1143)
		(layer "F.Cu")
		(net "HDD_PRE_IO_INT_N")
	)
	(segment
		(start 292.481 -158.1785)
		(end 292.5445 -158.1785)
		(width 0.1143)
		(layer "F.Cu")
		(net "HDD_PRE_IO_INT_N")
	)
	(segment
		(start 288.647632 -152.1841)
		(end 271.8689 -152.1841)
		(width 0.1143)
		(layer "F.Cu")
		(net "HDD_PRE_IO_INT_N")
	)
	(via
		(at 273.558 -239.54105)
		(size 0.5588)
		(drill 0.3048)
		(layers "F.Cu" "B.Cu")
		(net "HDD_PRE_IO_INT_N")
	)
	(via
		(at 14.047216 -188.65088)
		(size 0.7112)
		(drill 0.3556)
		(layers "F.Cu" "B.Cu")
		(net "HDD_PRE_IO_INT_N")
	)
	(via
		(at 268.732 -152.273)
		(size 0.5588)
		(drill 0.3048)
		(layers "F.Cu" "B.Cu")
		(net "HDD_PRE_IO_INT_N")
	)
	(via
		(at 14.047216 -189.53988)
		(size 0.5588)
		(drill 0.3048)
		(layers "F.Cu" "B.Cu")
		(net "HDD_PRE_IO_INT_N")
	)
	(segment
		(start 170.6245 -204.9145)
		(end 151.3205 -204.9145)
		(width 0.127)
		(layer "In2.Cu")
		(net "HDD_PRE_IO_INT_N")
	)
	(segment
		(start 182.710836 -205.443836)
		(end 181.906164 -205.443836)
		(width 0.127)
		(layer "In2.Cu")
		(net "HDD_PRE_IO_INT_N")
	)
	(segment
		(start 171.2722 -205.5622)
		(end 170.6245 -204.9145)
		(width 0.127)
		(layer "In2.Cu")
		(net "HDD_PRE_IO_INT_N")
	)
	(segment
		(start 18.690336 -191.262)
		(end 16.968216 -189.53988)
		(width 0.127)
		(layer "In2.Cu")
		(net "HDD_PRE_IO_INT_N")
	)
	(segment
		(start 19.019266 -191.4398)
		(end 18.841466 -191.262)
		(width 0.127)
		(layer "In2.Cu")
		(net "HDD_PRE_IO_INT_N")
	)
	(segment
		(start 257.640328 -228.73081)
		(end 257.8481 -228.523038)
		(width 0.127)
		(layer "In2.Cu")
		(net "HDD_PRE_IO_INT_N")
	)
	(segment
		(start 231.666034 -188.849)
		(end 215.156034 -205.359)
		(width 0.127)
		(layer "In2.Cu")
		(net "HDD_PRE_IO_INT_N")
	)
	(segment
		(start 215.156034 -205.359)
		(end 184.15 -205.359)
		(width 0.127)
		(layer "In2.Cu")
		(net "HDD_PRE_IO_INT_N")
	)
	(segment
		(start 257.640328 -233.725212)
		(end 257.640328 -228.73081)
		(width 0.127)
		(layer "In2.Cu")
		(net "HDD_PRE_IO_INT_N")
	)
	(segment
		(start 273.558 -239.54105)
		(end 263.456166 -239.54105)
		(width 0.127)
		(layer "In2.Cu")
		(net "HDD_PRE_IO_INT_N")
	)
	(segment
		(start 137.8458 -191.4398)
		(end 19.019266 -191.4398)
		(width 0.127)
		(layer "In2.Cu")
		(net "HDD_PRE_IO_INT_N")
	)
	(segment
		(start 18.841466 -191.262)
		(end 18.690336 -191.262)
		(width 0.127)
		(layer "In2.Cu")
		(net "HDD_PRE_IO_INT_N")
	)
	(segment
		(start 263.456166 -239.54105)
		(end 257.640328 -233.725212)
		(width 0.127)
		(layer "In2.Cu")
		(net "HDD_PRE_IO_INT_N")
	)
	(segment
		(start 252.244098 -188.849)
		(end 231.666034 -188.849)
		(width 0.127)
		(layer "In2.Cu")
		(net "HDD_PRE_IO_INT_N")
	)
	(segment
		(start 183.1213 -205.8543)
		(end 182.710836 -205.443836)
		(width 0.127)
		(layer "In2.Cu")
		(net "HDD_PRE_IO_INT_N")
	)
	(segment
		(start 257.8481 -228.523038)
		(end 257.8481 -194.453002)
		(width 0.127)
		(layer "In2.Cu")
		(net "HDD_PRE_IO_INT_N")
	)
	(segment
		(start 181.906164 -205.443836)
		(end 181.7878 -205.5622)
		(width 0.127)
		(layer "In2.Cu")
		(net "HDD_PRE_IO_INT_N")
	)
	(segment
		(start 181.7878 -205.5622)
		(end 171.2722 -205.5622)
		(width 0.127)
		(layer "In2.Cu")
		(net "HDD_PRE_IO_INT_N")
	)
	(segment
		(start 183.6547 -205.8543)
		(end 183.1213 -205.8543)
		(width 0.127)
		(layer "In2.Cu")
		(net "HDD_PRE_IO_INT_N")
	)
	(segment
		(start 16.968216 -189.53988)
		(end 14.047216 -189.53988)
		(width 0.127)
		(layer "In2.Cu")
		(net "HDD_PRE_IO_INT_N")
	)
	(segment
		(start 257.8481 -194.453002)
		(end 252.244098 -188.849)
		(width 0.127)
		(layer "In2.Cu")
		(net "HDD_PRE_IO_INT_N")
	)
	(segment
		(start 151.3205 -204.9145)
		(end 137.8458 -191.4398)
		(width 0.127)
		(layer "In2.Cu")
		(net "HDD_PRE_IO_INT_N")
	)
	(segment
		(start 184.15 -205.359)
		(end 183.6547 -205.8543)
		(width 0.127)
		(layer "In2.Cu")
		(net "HDD_PRE_IO_INT_N")
	)
	(segment
		(start 266.4079 -167.6273)
		(end 266.4079 -180.767736)
		(width 0.127)
		(layer "In5.Cu")
		(net "HDD_PRE_IO_INT_N")
	)
	(segment
		(start 267.716 -159.004)
		(end 267.716 -166.3192)
		(width 0.127)
		(layer "In5.Cu")
		(net "HDD_PRE_IO_INT_N")
	)
	(segment
		(start 267.97 -207.137)
		(end 273.558 -212.725)
		(width 0.127)
		(layer "In5.Cu")
		(net "HDD_PRE_IO_INT_N")
	)
	(segment
		(start 267.2842 -186.421268)
		(end 267.2207 -186.484768)
		(width 0.127)
		(layer "In5.Cu")
		(net "HDD_PRE_IO_INT_N")
	)
	(segment
		(start 267.97 -189.634368)
		(end 267.8176 -189.786768)
		(width 0.127)
		(layer "In5.Cu")
		(net "HDD_PRE_IO_INT_N")
	)
	(segment
		(start 267.97 -187.644532)
		(end 267.97 -189.634368)
		(width 0.127)
		(layer "In5.Cu")
		(net "HDD_PRE_IO_INT_N")
	)
	(segment
		(start 269.24 -152.908)
		(end 269.24 -157.48)
		(width 0.127)
		(layer "In5.Cu")
		(net "HDD_PRE_IO_INT_N")
	)
	(segment
		(start 268.732 -152.273)
		(end 268.732 -152.4)
		(width 0.127)
		(layer "In5.Cu")
		(net "HDD_PRE_IO_INT_N")
	)
	(segment
		(start 267.8176 -189.786768)
		(end 267.8176 -190.197232)
		(width 0.127)
		(layer "In5.Cu")
		(net "HDD_PRE_IO_INT_N")
	)
	(segment
		(start 268.732 -152.4)
		(end 269.24 -152.908)
		(width 0.127)
		(layer "In5.Cu")
		(net "HDD_PRE_IO_INT_N")
	)
	(segment
		(start 267.8811 -206.89697)
		(end 267.97 -206.98587)
		(width 0.127)
		(layer "In5.Cu")
		(net "HDD_PRE_IO_INT_N")
	)
	(segment
		(start 267.2842 -181.644036)
		(end 267.2842 -186.421268)
		(width 0.127)
		(layer "In5.Cu")
		(net "HDD_PRE_IO_INT_N")
	)
	(segment
		(start 269.24 -157.48)
		(end 267.716 -159.004)
		(width 0.127)
		(layer "In5.Cu")
		(net "HDD_PRE_IO_INT_N")
	)
	(segment
		(start 273.558 -212.725)
		(end 273.558 -239.54105)
		(width 0.127)
		(layer "In5.Cu")
		(net "HDD_PRE_IO_INT_N")
	)
	(segment
		(start 267.8176 -190.197232)
		(end 267.8811 -190.260732)
		(width 0.127)
		(layer "In5.Cu")
		(net "HDD_PRE_IO_INT_N")
	)
	(segment
		(start 267.8811 -190.260732)
		(end 267.8811 -206.89697)
		(width 0.127)
		(layer "In5.Cu")
		(net "HDD_PRE_IO_INT_N")
	)
	(segment
		(start 267.2207 -186.895232)
		(end 267.97 -187.644532)
		(width 0.127)
		(layer "In5.Cu")
		(net "HDD_PRE_IO_INT_N")
	)
	(segment
		(start 267.97 -206.98587)
		(end 267.97 -207.137)
		(width 0.127)
		(layer "In5.Cu")
		(net "HDD_PRE_IO_INT_N")
	)
	(segment
		(start 266.4079 -180.767736)
		(end 267.2842 -181.644036)
		(width 0.127)
		(layer "In5.Cu")
		(net "HDD_PRE_IO_INT_N")
	)
	(segment
		(start 267.716 -166.3192)
		(end 266.4079 -167.6273)
		(width 0.127)
		(layer "In5.Cu")
		(net "HDD_PRE_IO_INT_N")
	)
	(segment
		(start 267.2207 -186.484768)
		(end 267.2207 -186.895232)
		(width 0.127)
		(layer "In5.Cu")
		(net "HDD_PRE_IO_INT_N")
	)
	(segment
		(start 25.477216 -214.43188)
		(end 25.667716 -214.43188)
		(width 0.1143)
		(layer "F.Cu")
		(net "HDD_PWR_IO_INT_N")
	)
	(segment
		(start 25.583642 -214.515954)
		(end 25.583642 -216.714578)
		(width 0.1143)
		(layer "F.Cu")
		(net "HDD_PWR_IO_INT_N")
	)
	(segment
		(start 24.588216 -213.54288)
		(end 25.477216 -214.43188)
		(width 0.1143)
		(layer "F.Cu")
		(net "HDD_PWR_IO_INT_N")
	)
	(segment
		(start 25.667716 -214.43188)
		(end 25.583642 -214.515954)
		(width 0.1143)
		(layer "F.Cu")
		(net "HDD_PWR_IO_INT_N")
	)
	(via
		(at 24.588216 -213.54288)
		(size 0.7112)
		(drill 0.3556)
		(layers "F.Cu" "B.Cu")
		(net "HDD_PWR_IO_INT_N")
	)
	(segment
		(start 9.570466 -212.01888)
		(end 8.205216 -212.01888)
		(width 0.1143)
		(layer "F.Cu")
		(net "MATED#")
	)
	(segment
		(start 10.173716 -212.62213)
		(end 9.570466 -212.01888)
		(width 0.1143)
		(layer "F.Cu")
		(net "MATED#")
	)
	(segment
		(start 10.173716 -214.54364)
		(end 10.173716 -212.62213)
		(width 0.1143)
		(layer "F.Cu")
		(net "MATED#")
	)
	(via
		(at 8.205216 -212.01888)
		(size 0.7112)
		(drill 0.3556)
		(layers "F.Cu" "B.Cu")
		(net "MATED#")
	)
	(segment
		(start 6.477 -213.09838)
		(end 6.744716 -213.366096)
		(width 0.1143)
		(layer "F.Cu")
		(net "PRSNT_AND_3")
	)
	(segment
		(start 6.477 -212.344)
		(end 6.477 -213.09838)
		(width 0.1143)
		(layer "F.Cu")
		(net "PRSNT_AND_3")
	)
	(segment
		(start 6.744716 -214.68588)
		(end 7.252716 -215.19388)
		(width 0.1143)
		(layer "F.Cu")
		(net "PRSNT_AND_3")
	)
	(segment
		(start 6.744716 -214.68588)
		(end 6.744716 -215.82888)
		(width 0.1143)
		(layer "F.Cu")
		(net "PRSNT_AND_3")
	)
	(segment
		(start 6.744716 -213.366096)
		(end 6.744716 -213.54288)
		(width 0.1143)
		(layer "F.Cu")
		(net "PRSNT_AND_3")
	)
	(segment
		(start 6.744716 -213.54288)
		(end 6.744716 -214.68588)
		(width 0.1143)
		(layer "F.Cu")
		(net "PRSNT_AND_3")
	)
	(segment
		(start 7.252716 -215.19388)
		(end 8.522716 -215.19388)
		(width 0.1143)
		(layer "F.Cu")
		(net "PRSNT_AND_3")
	)
	(via
		(at 6.477 -212.344)
		(size 0.7112)
		(drill 0.3556)
		(layers "F.Cu" "B.Cu")
		(net "PRSNT_AND_3")
	)
	(segment
		(start 29.000196 -256.25044)
		(end 29.000196 -253.574804)
		(width 0.1143)
		(layer "F.Cu")
		(net "PCIE_MATED#_A")
	)
	(segment
		(start 29.972 -252.603)
		(end 29.972 -251.841)
		(width 0.1143)
		(layer "F.Cu")
		(net "PCIE_MATED#_A")
	)
	(segment
		(start 29.000196 -253.574804)
		(end 29.972 -252.603)
		(width 0.1143)
		(layer "F.Cu")
		(net "PCIE_MATED#_A")
	)
	(segment
		(start 29.972 -249.752358)
		(end 22.027642 -241.808)
		(width 0.1143)
		(layer "F.Cu")
		(net "PCIE_MATED#_A")
	)
	(segment
		(start 50.3555 -202.40625)
		(end 48.79975 -202.40625)
		(width 0.1143)
		(layer "F.Cu")
		(net "PCIE_MATED#_A")
	)
	(segment
		(start 9.157716 -228.84638)
		(end 9.157716 -231.32288)
		(width 0.1143)
		(layer "F.Cu")
		(net "PCIE_MATED#_A")
	)
	(segment
		(start 9.856216 -228.21138)
		(end 9.856216 -227.06838)
		(width 0.1143)
		(layer "F.Cu")
		(net "PCIE_MATED#_A")
	)
	(segment
		(start 11.856466 -219.410534)
		(end 12.446 -218.821)
		(width 0.1143)
		(layer "F.Cu")
		(net "PCIE_MATED#_A")
	)
	(segment
		(start 11.089132 -227.00488)
		(end 11.856466 -226.237546)
		(width 0.1143)
		(layer "F.Cu")
		(net "PCIE_MATED#_A")
	)
	(segment
		(start 9.919716 -227.00488)
		(end 11.089132 -227.00488)
		(width 0.1143)
		(layer "F.Cu")
		(net "PCIE_MATED#_A")
	)
	(segment
		(start 9.792716 -228.21138)
		(end 9.157716 -228.84638)
		(width 0.1143)
		(layer "F.Cu")
		(net "PCIE_MATED#_A")
	)
	(segment
		(start 11.856466 -226.237546)
		(end 11.856466 -219.410534)
		(width 0.1143)
		(layer "F.Cu")
		(net "PCIE_MATED#_A")
	)
	(segment
		(start 12.410694 -241.808)
		(end 9.157716 -238.555022)
		(width 0.1143)
		(layer "F.Cu")
		(net "PCIE_MATED#_A")
	)
	(segment
		(start 9.856216 -228.21138)
		(end 9.792716 -228.21138)
		(width 0.1143)
		(layer "F.Cu")
		(net "PCIE_MATED#_A")
	)
	(segment
		(start 9.856216 -227.06838)
		(end 9.919716 -227.00488)
		(width 0.1143)
		(layer "F.Cu")
		(net "PCIE_MATED#_A")
	)
	(segment
		(start 43.307 -207.899)
		(end 43.307 -212.217)
		(width 0.1143)
		(layer "F.Cu")
		(net "PCIE_MATED#_A")
	)
	(segment
		(start 29.972 -251.841)
		(end 29.972 -249.752358)
		(width 0.1143)
		(layer "F.Cu")
		(net "PCIE_MATED#_A")
	)
	(segment
		(start 48.79975 -202.40625)
		(end 43.307 -207.899)
		(width 0.1143)
		(layer "F.Cu")
		(net "PCIE_MATED#_A")
	)
	(segment
		(start 22.027642 -241.808)
		(end 12.410694 -241.808)
		(width 0.1143)
		(layer "F.Cu")
		(net "PCIE_MATED#_A")
	)
	(segment
		(start 9.157716 -238.555022)
		(end 9.157716 -231.32288)
		(width 0.1143)
		(layer "F.Cu")
		(net "PCIE_MATED#_A")
	)
	(via
		(at 12.446 -218.821)
		(size 0.5588)
		(drill 0.3048)
		(layers "F.Cu" "B.Cu")
		(net "PCIE_MATED#_A")
	)
	(via
		(at 9.157716 -231.32288)
		(size 0.7112)
		(drill 0.3556)
		(layers "F.Cu" "B.Cu")
		(net "PCIE_MATED#_A")
	)
	(via
		(at 43.307 -212.217)
		(size 0.5588)
		(drill 0.3048)
		(layers "F.Cu" "B.Cu")
		(net "PCIE_MATED#_A")
	)
	(via
		(at 29.972 -251.841)
		(size 0.5588)
		(drill 0.3048)
		(layers "F.Cu" "B.Cu")
		(net "PCIE_MATED#_A")
	)
	(segment
		(start 37.973 -217.551)
		(end 13.716 -217.551)
		(width 0.127)
		(layer "In2.Cu")
		(net "PCIE_MATED#_A")
	)
	(segment
		(start 13.716 -217.551)
		(end 12.446 -218.821)
		(width 0.127)
		(layer "In2.Cu")
		(net "PCIE_MATED#_A")
	)
	(segment
		(start 43.307 -212.217)
		(end 37.973 -217.551)
		(width 0.127)
		(layer "In2.Cu")
		(net "PCIE_MATED#_A")
	)
	(segment
		(start 44.196 -210.82)
		(end 47.244 -207.772)
		(width 0.1143)
		(layer "F.Cu")
		(net "PCIE_MATED#_B")
	)
	(segment
		(start 49.05375 -205.96225)
		(end 47.244 -207.772)
		(width 0.1143)
		(layer "F.Cu")
		(net "PCIE_MATED#_B")
	)
	(segment
		(start 44.196 -210.947)
		(end 44.196 -210.82)
		(width 0.1143)
		(layer "F.Cu")
		(net "PCIE_MATED#_B")
	)
	(segment
		(start 50.3555 -205.96225)
		(end 49.05375 -205.96225)
		(width 0.1143)
		(layer "F.Cu")
		(net "PCIE_MATED#_B")
	)
	(via
		(at 199.517 -246.3038)
		(size 0.5588)
		(drill 0.3048)
		(layers "F.Cu" "B.Cu")
		(net "PCIE_MATED#_B")
	)
	(via
		(at 47.244 -207.772)
		(size 0.7112)
		(drill 0.3556)
		(layers "F.Cu" "B.Cu")
		(net "PCIE_MATED#_B")
	)
	(via
		(at 44.196 -210.947)
		(size 0.5588)
		(drill 0.3048)
		(layers "F.Cu" "B.Cu")
		(net "PCIE_MATED#_B")
	)
	(segment
		(start 201.799952 -253.996952)
		(end 201.168 -253.365)
		(width 0.1143)
		(layer "B.Cu")
		(net "PCIE_MATED#_B")
	)
	(segment
		(start 199.2122 -245.999)
		(end 199.517 -246.3038)
		(width 0.1143)
		(layer "B.Cu")
		(net "PCIE_MATED#_B")
	)
	(segment
		(start 201.168 -253.365)
		(end 201.168 -247.9548)
		(width 0.1143)
		(layer "B.Cu")
		(net "PCIE_MATED#_B")
	)
	(segment
		(start 201.168 -247.9548)
		(end 199.517 -246.3038)
		(width 0.1143)
		(layer "B.Cu")
		(net "PCIE_MATED#_B")
	)
	(segment
		(start 198.1835 -247.142)
		(end 198.1835 -245.999)
		(width 0.1143)
		(layer "B.Cu")
		(net "PCIE_MATED#_B")
	)
	(segment
		(start 201.799952 -256.50444)
		(end 201.799952 -253.996952)
		(width 0.1143)
		(layer "B.Cu")
		(net "PCIE_MATED#_B")
	)
	(segment
		(start 198.1835 -245.999)
		(end 199.2122 -245.999)
		(width 0.1143)
		(layer "B.Cu")
		(net "PCIE_MATED#_B")
	)
	(segment
		(start 11.322304 -227.711)
		(end 11.389868 -227.711)
		(width 0.127)
		(layer "In2.Cu")
		(net "PCIE_MATED#_B")
	)
	(segment
		(start 106.7943 -249.936)
		(end 122.555 -249.936)
		(width 0.127)
		(layer "In2.Cu")
		(net "PCIE_MATED#_B")
	)
	(segment
		(start 74.549 -246.888)
		(end 78.979522 -251.318522)
		(width 0.127)
		(layer "In2.Cu")
		(net "PCIE_MATED#_B")
	)
	(segment
		(start 197.2183 -248.6025)
		(end 199.517 -246.3038)
		(width 0.127)
		(layer "In2.Cu")
		(net "PCIE_MATED#_B")
	)
	(segment
		(start 122.555 -249.936)
		(end 123.8885 -248.6025)
		(width 0.127)
		(layer "In2.Cu")
		(net "PCIE_MATED#_B")
	)
	(segment
		(start 13.305282 -217.043)
		(end 8.6741 -221.674182)
		(width 0.127)
		(layer "In2.Cu")
		(net "PCIE_MATED#_B")
	)
	(segment
		(start 78.979522 -251.318522)
		(end 96.661478 -251.318522)
		(width 0.127)
		(layer "In2.Cu")
		(net "PCIE_MATED#_B")
	)
	(segment
		(start 123.8885 -248.6025)
		(end 197.2183 -248.6025)
		(width 0.127)
		(layer "In2.Cu")
		(net "PCIE_MATED#_B")
	)
	(segment
		(start 98.986594 -249.989594)
		(end 100.3173 -251.3203)
		(width 0.127)
		(layer "In2.Cu")
		(net "PCIE_MATED#_B")
	)
	(segment
		(start 8.6741 -225.062796)
		(end 11.322304 -227.711)
		(width 0.127)
		(layer "In2.Cu")
		(net "PCIE_MATED#_B")
	)
	(segment
		(start 100.3173 -251.3203)
		(end 105.41 -251.3203)
		(width 0.127)
		(layer "In2.Cu")
		(net "PCIE_MATED#_B")
	)
	(segment
		(start 44.196 -210.947)
		(end 43.876468 -210.947)
		(width 0.127)
		(layer "In2.Cu")
		(net "PCIE_MATED#_B")
	)
	(segment
		(start 96.661478 -251.318522)
		(end 97.990406 -249.989594)
		(width 0.127)
		(layer "In2.Cu")
		(net "PCIE_MATED#_B")
	)
	(segment
		(start 8.6741 -221.674182)
		(end 8.6741 -225.062796)
		(width 0.127)
		(layer "In2.Cu")
		(net "PCIE_MATED#_B")
	)
	(segment
		(start 13.932916 -230.639112)
		(end 30.181804 -246.888)
		(width 0.127)
		(layer "In2.Cu")
		(net "PCIE_MATED#_B")
	)
	(segment
		(start 13.932916 -230.254048)
		(end 13.932916 -230.639112)
		(width 0.127)
		(layer "In2.Cu")
		(net "PCIE_MATED#_B")
	)
	(segment
		(start 97.990406 -249.989594)
		(end 98.986594 -249.989594)
		(width 0.127)
		(layer "In2.Cu")
		(net "PCIE_MATED#_B")
	)
	(segment
		(start 43.876468 -210.947)
		(end 37.780468 -217.043)
		(width 0.127)
		(layer "In2.Cu")
		(net "PCIE_MATED#_B")
	)
	(segment
		(start 11.389868 -227.711)
		(end 13.932916 -230.254048)
		(width 0.127)
		(layer "In2.Cu")
		(net "PCIE_MATED#_B")
	)
	(segment
		(start 37.780468 -217.043)
		(end 13.305282 -217.043)
		(width 0.127)
		(layer "In2.Cu")
		(net "PCIE_MATED#_B")
	)
	(segment
		(start 30.181804 -246.888)
		(end 74.549 -246.888)
		(width 0.127)
		(layer "In2.Cu")
		(net "PCIE_MATED#_B")
	)
	(segment
		(start 105.41 -251.3203)
		(end 106.7943 -249.936)
		(width 0.127)
		(layer "In2.Cu")
		(net "PCIE_MATED#_B")
	)
	(segment
		(start 321.945 -142.367)
		(end 321.945 -139.573)
		(width 0.508)
		(layer "F.Cu")
		(net "P3V0_BAT_R")
	)
	(segment
		(start 321.34175 -142.97025)
		(end 321.945 -142.367)
		(width 0.508)
		(layer "F.Cu")
		(net "P3V0_BAT_R")
	)
	(segment
		(start 320.9925 -142.97025)
		(end 321.34175 -142.97025)
		(width 0.508)
		(layer "F.Cu")
		(net "P3V0_BAT_R")
	)
	(segment
		(start 322.961 -139.3825)
		(end 322.1355 -139.3825)
		(width 0.508)
		(layer "F.Cu")
		(net "P3V0_BAT_R")
	)
	(segment
		(start 322.1355 -139.3825)
		(end 321.945 -139.573)
		(width 0.508)
		(layer "F.Cu")
		(net "P3V0_BAT_R")
	)
	(via
		(at 321.945 -139.573)
		(size 0.7112)
		(drill 0.3556)
		(layers "F.Cu" "B.Cu")
		(net "P3V0_BAT_R")
	)
	(segment
		(start 318.77 -149.352)
		(end 315.595 -149.352)
		(width 0.127)
		(layer "F.Cu")
		(net "RTC_CLK_OUT")
	)
	(segment
		(start 327.9902 -137.3886)
		(end 327.9902 -138.0998)
		(width 0.508)
		(layer "F.Cu")
		(net "P3V0_BAT")
	)
	(segment
		(start 327.9902 -138.0998)
		(end 327.5965 -138.4935)
		(width 0.508)
		(layer "F.Cu")
		(net "P3V0_BAT")
	)
	(segment
		(start 327.5965 -138.4935)
		(end 322.961 -138.4935)
		(width 0.508)
		(layer "F.Cu")
		(net "P3V0_BAT")
	)
	(via
		(at 327.9902 -137.3886)
		(size 0.5588)
		(drill 0.3048)
		(layers "F.Cu" "B.Cu")
		(net "P3V0_BAT")
	)
	(segment
		(start 319.660016 -83.650074)
		(end 319.660016 -93.650054)
		(width 0.508)
		(layer "In2.Cu")
		(net "P3V0_BAT")
	)
	(segment
		(start 318.457072 -119.32158)
		(end 318.457072 -94.852998)
		(width 0.508)
		(layer "In2.Cu")
		(net "P3V0_BAT")
	)
	(segment
		(start 327.9902 -137.3886)
		(end 327.9902 -137.1346)
		(width 0.508)
		(layer "In2.Cu")
		(net "P3V0_BAT")
	)
	(segment
		(start 327.9902 -137.1346)
		(end 324.8914 -134.0358)
		(width 0.508)
		(layer "In2.Cu")
		(net "P3V0_BAT")
	)
	(segment
		(start 324.8914 -134.0358)
		(end 324.8914 -125.755908)
		(width 0.508)
		(layer "In2.Cu")
		(net "P3V0_BAT")
	)
	(segment
		(start 318.457072 -94.852998)
		(end 319.660016 -93.650054)
		(width 0.508)
		(layer "In2.Cu")
		(net "P3V0_BAT")
	)
	(segment
		(start 324.8914 -125.755908)
		(end 318.457072 -119.32158)
		(width 0.508)
		(layer "In2.Cu")
		(net "P3V0_BAT")
	)
	(segment
		(start 319.0875 -142.8115)
		(end 318.516 -143.383)
		(width 0.508)
		(layer "F.Cu")
		(net "P3V3_RTC")
	)
	(segment
		(start 319.4685 -146.558)
		(end 318.77 -147.2565)
		(width 0.508)
		(layer "F.Cu")
		(net "P3V3_RTC")
	)
	(segment
		(start 318.516 -144.0942)
		(end 319.3288 -144.907)
		(width 0.508)
		(layer "F.Cu")
		(net "P3V3_RTC")
	)
	(segment
		(start 318.77 -147.2565)
		(end 318.77 -148.082)
		(width 0.508)
		(layer "F.Cu")
		(net "P3V3_RTC")
	)
	(segment
		(start 319.3288 -144.907)
		(end 319.4685 -145.0467)
		(width 0.508)
		(layer "F.Cu")
		(net "P3V3_RTC")
	)
	(segment
		(start 319.0875 -141.986)
		(end 319.0875 -142.8115)
		(width 0.508)
		(layer "F.Cu")
		(net "P3V3_RTC")
	)
	(segment
		(start 319.4685 -145.0467)
		(end 319.4685 -146.558)
		(width 0.508)
		(layer "F.Cu")
		(net "P3V3_RTC")
	)
	(segment
		(start 318.516 -143.383)
		(end 318.516 -144.0942)
		(width 0.508)
		(layer "F.Cu")
		(net "P3V3_RTC")
	)
	(via
		(at 318.516 -143.383)
		(size 0.7112)
		(drill 0.3556)
		(layers "F.Cu" "B.Cu")
		(net "P3V3_RTC")
	)
	(segment
		(start 20.651216 -183.57088)
		(end 20.651216 -183.44388)
		(width 0.1143)
		(layer "F.Cu")
		(net "IO_EXP_HDD_PRE_A3")
	)
	(segment
		(start 20.651216 -182.36438)
		(end 20.651216 -183.44388)
		(width 0.1143)
		(layer "F.Cu")
		(net "IO_EXP_HDD_PRE_A3")
	)
	(segment
		(start 20.460208 -183.761888)
		(end 20.651216 -183.57088)
		(width 0.1143)
		(layer "F.Cu")
		(net "IO_EXP_HDD_PRE_A3")
	)
	(segment
		(start 19.508216 -182.36438)
		(end 20.651216 -182.36438)
		(width 0.1143)
		(layer "F.Cu")
		(net "IO_EXP_HDD_PRE_A3")
	)
	(segment
		(start 20.460208 -185.409586)
		(end 20.460208 -183.761888)
		(width 0.1143)
		(layer "F.Cu")
		(net "IO_EXP_HDD_PRE_A3")
	)
	(via
		(at 20.651216 -183.44388)
		(size 0.7112)
		(drill 0.3556)
		(layers "F.Cu" "B.Cu")
		(net "IO_EXP_HDD_PRE_A3")
	)
	(segment
		(start 19.889216 -192.96888)
		(end 19.862038 -192.996058)
		(width 0.1143)
		(layer "F.Cu")
		(net "IO_EXP_HDD_PRE_A1")
	)
	(segment
		(start 18.873216 -195.57238)
		(end 19.762216 -194.68338)
		(width 0.1143)
		(layer "F.Cu")
		(net "IO_EXP_HDD_PRE_A1")
	)
	(segment
		(start 18.746216 -195.57238)
		(end 18.873216 -195.57238)
		(width 0.1143)
		(layer "F.Cu")
		(net "IO_EXP_HDD_PRE_A1")
	)
	(segment
		(start 19.862038 -194.583558)
		(end 19.762216 -194.68338)
		(width 0.1143)
		(layer "F.Cu")
		(net "IO_EXP_HDD_PRE_A1")
	)
	(segment
		(start 19.809968 -191.020446)
		(end 19.809968 -192.889632)
		(width 0.1143)
		(layer "F.Cu")
		(net "IO_EXP_HDD_PRE_A1")
	)
	(segment
		(start 19.862038 -192.996058)
		(end 19.862038 -194.583558)
		(width 0.1143)
		(layer "F.Cu")
		(net "IO_EXP_HDD_PRE_A1")
	)
	(segment
		(start 19.809968 -192.889632)
		(end 19.889216 -192.96888)
		(width 0.1143)
		(layer "F.Cu")
		(net "IO_EXP_HDD_PRE_A1")
	)
	(via
		(at 19.889216 -192.96888)
		(size 0.7112)
		(drill 0.3556)
		(layers "F.Cu" "B.Cu")
		(net "IO_EXP_HDD_PRE_A1")
	)
	(segment
		(start 14.936216 -182.36438)
		(end 16.079216 -182.36438)
		(width 0.1143)
		(layer "F.Cu")
		(net "IO_EXP_HDD_PRE_A2")
	)
	(segment
		(start 15.909798 -185.409586)
		(end 15.909798 -183.613298)
		(width 0.1143)
		(layer "F.Cu")
		(net "IO_EXP_HDD_PRE_A2")
	)
	(segment
		(start 15.952216 -182.49138)
		(end 15.952216 -183.57088)
		(width 0.1143)
		(layer "F.Cu")
		(net "IO_EXP_HDD_PRE_A2")
	)
	(segment
		(start 16.079216 -182.36438)
		(end 15.952216 -182.49138)
		(width 0.1143)
		(layer "F.Cu")
		(net "IO_EXP_HDD_PRE_A2")
	)
	(segment
		(start 15.909798 -183.613298)
		(end 15.952216 -183.57088)
		(width 0.1143)
		(layer "F.Cu")
		(net "IO_EXP_HDD_PRE_A2")
	)
	(via
		(at 15.952216 -183.57088)
		(size 0.7112)
		(drill 0.3556)
		(layers "F.Cu" "B.Cu")
		(net "IO_EXP_HDD_PRE_A2")
	)
	(segment
		(start 26.366216 -192.90538)
		(end 25.283668 -192.90538)
		(width 0.1143)
		(layer "F.Cu")
		(net "IO_EXP_HDD_PRE_A0")
	)
	(segment
		(start 24.360378 -191.985138)
		(end 24.360378 -191.020446)
		(width 0.1143)
		(layer "F.Cu")
		(net "IO_EXP_HDD_PRE_A0")
	)
	(segment
		(start 25.282144 -192.906904)
		(end 24.360378 -191.985138)
		(width 0.1143)
		(layer "F.Cu")
		(net "IO_EXP_HDD_PRE_A0")
	)
	(segment
		(start 26.366216 -192.90538)
		(end 26.366216 -191.95288)
		(width 0.1143)
		(layer "F.Cu")
		(net "IO_EXP_HDD_PRE_A0")
	)
	(segment
		(start 25.283668 -192.90538)
		(end 25.282144 -192.906904)
		(width 0.1143)
		(layer "F.Cu")
		(net "IO_EXP_HDD_PRE_A0")
	)
	(via
		(at 26.366216 -191.95288)
		(size 0.7112)
		(drill 0.3556)
		(layers "F.Cu" "B.Cu")
		(net "IO_EXP_HDD_PRE_A0")
	)
	(segment
		(start 322.707 -150.622)
		(end 321.945 -149.86)
		(width 0.1143)
		(layer "F.Cu")
		(net "RTC_INT_N")
	)
	(segment
		(start 321.945 -147.193)
		(end 321.437 -146.685)
		(width 0.1143)
		(layer "F.Cu")
		(net "RTC_INT_N")
	)
	(segment
		(start 320.3575 -146.558)
		(end 321.31 -146.558)
		(width 0.1143)
		(layer "F.Cu")
		(net "RTC_INT_N")
	)
	(segment
		(start 321.31 -146.558)
		(end 321.437 -146.685)
		(width 0.1143)
		(layer "F.Cu")
		(net "RTC_INT_N")
	)
	(segment
		(start 323.85 -150.622)
		(end 322.707 -150.622)
		(width 0.1143)
		(layer "F.Cu")
		(net "RTC_INT_N")
	)
	(segment
		(start 321.945 -149.86)
		(end 321.945 -147.193)
		(width 0.1143)
		(layer "F.Cu")
		(net "RTC_INT_N")
	)
	(via
		(at 321.437 -146.685)
		(size 0.7112)
		(drill 0.3556)
		(layers "F.Cu" "B.Cu")
		(net "RTC_INT_N")
	)
	(segment
		(start 97.663 -221.9325)
		(end 98.806 -221.9325)
		(width 0.1143)
		(layer "F.Cu")
		(net "IO_EXP_HDD_FAULT_A0")
	)
	(segment
		(start 99.3394 -223.4184)
		(end 98.806 -222.885)
		(width 0.1143)
		(layer "F.Cu")
		(net "IO_EXP_HDD_FAULT_A0")
	)
	(segment
		(start 98.806 -221.9325)
		(end 98.806 -222.885)
		(width 0.1143)
		(layer "F.Cu")
		(net "IO_EXP_HDD_FAULT_A0")
	)
	(segment
		(start 99.3394 -224.13468)
		(end 99.3394 -223.4184)
		(width 0.1143)
		(layer "F.Cu")
		(net "IO_EXP_HDD_FAULT_A0")
	)
	(via
		(at 98.806 -222.885)
		(size 0.7112)
		(drill 0.3556)
		(layers "F.Cu" "B.Cu")
		(net "IO_EXP_HDD_FAULT_A0")
	)
	(segment
		(start 100.584 -224.79)
		(end 101.092 -224.79)
		(width 0.1143)
		(layer "F.Cu")
		(net "IO_EXP_HDD_FAULT_A2")
	)
	(segment
		(start 102.1715 -224.79)
		(end 101.092 -224.79)
		(width 0.1143)
		(layer "F.Cu")
		(net "IO_EXP_HDD_FAULT_A2")
	)
	(segment
		(start 99.3394 -225.43516)
		(end 99.93884 -225.43516)
		(width 0.1143)
		(layer "F.Cu")
		(net "IO_EXP_HDD_FAULT_A2")
	)
	(segment
		(start 99.93884 -225.43516)
		(end 100.584 -224.79)
		(width 0.1143)
		(layer "F.Cu")
		(net "IO_EXP_HDD_FAULT_A2")
	)
	(segment
		(start 102.1715 -223.647)
		(end 102.1715 -224.79)
		(width 0.1143)
		(layer "F.Cu")
		(net "IO_EXP_HDD_FAULT_A2")
	)
	(via
		(at 101.092 -224.79)
		(size 0.7112)
		(drill 0.3556)
		(layers "F.Cu" "B.Cu")
		(net "IO_EXP_HDD_FAULT_A2")
	)
	(segment
		(start 99.949 -222.504)
		(end 100.33 -222.885)
		(width 0.1143)
		(layer "F.Cu")
		(net "IO_EXP_HDD_FAULT_A1")
	)
	(segment
		(start 100.457 -223.012)
		(end 100.33 -222.885)
		(width 0.1143)
		(layer "F.Cu")
		(net "IO_EXP_HDD_FAULT_A1")
	)
	(segment
		(start 101.092 -221.9325)
		(end 99.949 -221.9325)
		(width 0.1143)
		(layer "F.Cu")
		(net "IO_EXP_HDD_FAULT_A1")
	)
	(segment
		(start 99.3394 -224.78492)
		(end 99.95408 -224.78492)
		(width 0.1143)
		(layer "F.Cu")
		(net "IO_EXP_HDD_FAULT_A1")
	)
	(segment
		(start 100.457 -224.282)
		(end 100.457 -223.012)
		(width 0.1143)
		(layer "F.Cu")
		(net "IO_EXP_HDD_FAULT_A1")
	)
	(segment
		(start 99.95408 -224.78492)
		(end 100.457 -224.282)
		(width 0.1143)
		(layer "F.Cu")
		(net "IO_EXP_HDD_FAULT_A1")
	)
	(segment
		(start 99.949 -221.9325)
		(end 99.949 -222.504)
		(width 0.1143)
		(layer "F.Cu")
		(net "IO_EXP_HDD_FAULT_A1")
	)
	(via
		(at 100.33 -222.885)
		(size 0.7112)
		(drill 0.3556)
		(layers "F.Cu" "B.Cu")
		(net "IO_EXP_HDD_FAULT_A1")
	)
	(segment
		(start 113.49482 -209.27568)
		(end 112.89157 -208.67243)
		(width 0.1016)
		(layer "F.Cu")
		(net "REDV_TX8_P")
	)
	(segment
		(start 114.323876 -221.492064)
		(end 113.885726 -221.053914)
		(width 0.1016)
		(layer "F.Cu")
		(net "REDV_TX8_P")
	)
	(segment
		(start 112.416336 -206.442564)
		(end 112.487964 -206.370936)
		(width 0.1016)
		(layer "F.Cu")
		(net "REDV_TX8_P")
	)
	(segment
		(start 112.3569 -207.381602)
		(end 112.3569 -206.586074)
		(width 0.1016)
		(layer "F.Cu")
		(net "REDV_TX8_P")
	)
	(segment
		(start 112.357154 -207.381856)
		(end 112.3569 -207.381602)
		(width 0.1016)
		(layer "F.Cu")
		(net "REDV_TX8_P")
	)
	(segment
		(start 113.82629 -220.910404)
		(end 113.82629 -210.076288)
		(width 0.1016)
		(layer "F.Cu")
		(net "REDV_TX8_P")
	)
	(segment
		(start 114.497612 -221.5515)
		(end 114.467386 -221.5515)
		(width 0.1016)
		(layer "F.Cu")
		(net "REDV_TX8_P")
	)
	(segment
		(start 112.631474 -206.3115)
		(end 112.973612 -206.3115)
		(width 0.1016)
		(layer "F.Cu")
		(net "REDV_TX8_P")
	)
	(arc
		(start 114.467386 -221.5515)
		(mid 114.389722 -221.536052)
		(end 114.323876 -221.492064)
		(width 0.1016)
		(layer "F.Cu")
		(net "REDV_TX8_P")
	)
	(arc
		(start 112.3569 -206.586074)
		(mid 112.372348 -206.50841)
		(end 112.416336 -206.442564)
		(width 0.1016)
		(layer "F.Cu")
		(net "REDV_TX8_P")
	)
	(arc
		(start 113.82629 -210.076288)
		(mid 113.740199 -209.643007)
		(end 113.49482 -209.27568)
		(width 0.1016)
		(layer "F.Cu")
		(net "REDV_TX8_P")
	)
	(arc
		(start 113.885726 -221.053914)
		(mid 113.841731 -220.988071)
		(end 113.82629 -220.910404)
		(width 0.1016)
		(layer "F.Cu")
		(net "REDV_TX8_P")
	)
	(arc
		(start 112.89157 -208.67243)
		(mid 112.496011 -208.080295)
		(end 112.357154 -207.381856)
		(width 0.1016)
		(layer "F.Cu")
		(net "REDV_TX8_P")
	)
	(arc
		(start 112.487964 -206.370936)
		(mid 112.553807 -206.326941)
		(end 112.631474 -206.3115)
		(width 0.1016)
		(layer "F.Cu")
		(net "REDV_TX8_P")
	)
	(segment
		(start 173.61027 -72.910954)
		(end 174.449486 -73.75017)
		(width 0.1143)
		(layer "F.Cu")
		(net "TP_MSB_A46_GBE_RX_N")
	)
	(segment
		(start 173.49597 -67.6275)
		(end 173.49597 -71.869046)
		(width 0.1143)
		(layer "F.Cu")
		(net "TP_MSB_A46_GBE_RX_N")
	)
	(segment
		(start 173.61027 -71.983346)
		(end 173.61027 -72.910954)
		(width 0.1143)
		(layer "F.Cu")
		(net "TP_MSB_A46_GBE_RX_N")
	)
	(segment
		(start 173.49597 -71.869046)
		(end 173.61027 -71.983346)
		(width 0.1143)
		(layer "F.Cu")
		(net "TP_MSB_A46_GBE_RX_N")
	)
	(segment
		(start 119.850662 -211.60994)
		(end 119.850662 -206.853536)
		(width 0.1016)
		(layer "F.Cu")
		(net "REDV_TX7_N")
	)
	(segment
		(start 119.791226 -206.710026)
		(end 119.45239 -206.370936)
		(width 0.1016)
		(layer "F.Cu")
		(net "REDV_TX7_N")
	)
	(segment
		(start 119.308626 -206.3115)
		(end 119.196612 -206.3115)
		(width 0.1016)
		(layer "F.Cu")
		(net "REDV_TX7_N")
	)
	(segment
		(start 121.031 -220.860112)
		(end 121.031 -214.459312)
		(width 0.1016)
		(layer "F.Cu")
		(net "REDV_TX7_N")
	)
	(arc
		(start 121.031 -214.459312)
		(mid 120.898983 -213.79562)
		(end 120.523 -213.233)
		(width 0.1016)
		(layer "F.Cu")
		(net "REDV_TX7_N")
	)
	(arc
		(start 119.45239 -206.370936)
		(mid 119.386416 -206.326946)
		(end 119.308626 -206.3115)
		(width 0.1016)
		(layer "F.Cu")
		(net "REDV_TX7_N")
	)
	(arc
		(start 119.850662 -206.853536)
		(mid 119.835214 -206.775872)
		(end 119.791226 -206.710026)
		(width 0.1016)
		(layer "F.Cu")
		(net "REDV_TX7_N")
	)
	(arc
		(start 120.523 -213.233)
		(mid 120.02543 -212.488334)
		(end 119.850662 -211.60994)
		(width 0.1016)
		(layer "F.Cu")
		(net "REDV_TX7_N")
	)
	(arc
		(start 120.339612 -221.5515)
		(mid 120.828497 -221.348997)
		(end 121.031 -220.860112)
		(width 0.1016)
		(layer "F.Cu")
		(net "REDV_TX7_N")
	)
	(segment
		(start 174.51197 -69.977)
		(end 175.450246 -70.915276)
		(width 0.1143)
		(layer "F.Cu")
		(net "TP_MSB_A45_GBE_RX_P")
	)
	(segment
		(start 174.51197 -67.6275)
		(end 174.51197 -69.977)
		(width 0.1143)
		(layer "F.Cu")
		(net "TP_MSB_A45_GBE_RX_P")
	)
	(segment
		(start 175.450246 -70.915276)
		(end 175.450246 -75.75042)
		(width 0.1143)
		(layer "F.Cu")
		(net "TP_MSB_A45_GBE_RX_P")
	)
	(segment
		(start 121.990612 -223.3295)
		(end 121.990612 -224.282)
		(width 0.1016)
		(layer "F.Cu")
		(net "SAS_HDD_CONN_SER_TX7_P")
	)
	(via
		(at 121.990612 -224.282)
		(size 0.5588)
		(drill 0.3048)
		(layers "F.Cu" "B.Cu")
		(net "SAS_HDD_CONN_SER_TX7_P")
	)
	(segment
		(start 121.376948 -223.846136)
		(end 121.753376 -224.222564)
		(width 0.1016)
		(layer "B.Cu")
		(net "SAS_HDD_CONN_SER_TX7_P")
	)
	(segment
		(start 121.317512 -222.000572)
		(end 121.317512 -223.702626)
		(width 0.1016)
		(layer "B.Cu")
		(net "SAS_HDD_CONN_SER_TX7_P")
	)
	(segment
		(start 121.896886 -224.282)
		(end 121.990612 -224.282)
		(width 0.1016)
		(layer "B.Cu")
		(net "SAS_HDD_CONN_SER_TX7_P")
	)
	(segment
		(start 118.053612 -216.800684)
		(end 118.053612 -217.7542)
		(width 0.1016)
		(layer "B.Cu")
		(net "SAS_HDD_CONN_SER_TX7_P")
	)
	(segment
		(start 118.28526 -218.313508)
		(end 120.85447 -220.882718)
		(width 0.1016)
		(layer "B.Cu")
		(net "SAS_HDD_CONN_SER_TX7_P")
	)
	(segment
		(start 118.140734 -216.662)
		(end 118.090188 -216.712546)
		(width 0.1016)
		(layer "B.Cu")
		(net "SAS_HDD_CONN_SER_TX7_P")
	)
	(arc
		(start 118.090188 -216.712546)
		(mid 118.063114 -216.75297)
		(end 118.053612 -216.800684)
		(width 0.1016)
		(layer "B.Cu")
		(net "SAS_HDD_CONN_SER_TX7_P")
	)
	(arc
		(start 121.317512 -223.702626)
		(mid 121.33296 -223.78029)
		(end 121.376948 -223.846136)
		(width 0.1016)
		(layer "B.Cu")
		(net "SAS_HDD_CONN_SER_TX7_P")
	)
	(arc
		(start 120.85447 -220.882718)
		(mid 121.197163 -221.395594)
		(end 121.317512 -222.000572)
		(width 0.1016)
		(layer "B.Cu")
		(net "SAS_HDD_CONN_SER_TX7_P")
	)
	(arc
		(start 118.053612 -217.7542)
		(mid 118.11382 -218.056886)
		(end 118.28526 -218.313508)
		(width 0.1016)
		(layer "B.Cu")
		(net "SAS_HDD_CONN_SER_TX7_P")
	)
	(arc
		(start 121.753376 -224.222564)
		(mid 121.819219 -224.266559)
		(end 121.896886 -224.282)
		(width 0.1016)
		(layer "B.Cu")
		(net "SAS_HDD_CONN_SER_TX7_P")
	)
	(segment
		(start 322.707 -7.62)
		(end 324.099936 -6.227064)
		(width 0.127)
		(layer "F.Cu")
		(net "DEBUG_LED_SW_H")
	)
	(segment
		(start 322.453 -7.62)
		(end 322.707 -7.62)
		(width 0.127)
		(layer "F.Cu")
		(net "DEBUG_LED_SW_H")
	)
	(segment
		(start 321.1195 -7.62)
		(end 322.453 -7.62)
		(width 0.127)
		(layer "F.Cu")
		(net "DEBUG_LED_SW_H")
	)
	(segment
		(start 324.099936 -6.227064)
		(end 324.099936 -4.550156)
		(width 0.127)
		(layer "F.Cu")
		(net "DEBUG_LED_SW_H")
	)
	(via
		(at 322.453 -7.62)
		(size 0.7112)
		(drill 0.3556)
		(layers "F.Cu" "B.Cu")
		(net "DEBUG_LED_SW_H")
	)
	(segment
		(start 119.196612 -204.5335)
		(end 119.196612 -203.7334)
		(width 0.1016)
		(layer "F.Cu")
		(net "SAS_HDD_REDV_SER_TX7_N")
	)
	(via
		(at 119.196612 -203.7334)
		(size 0.5588)
		(drill 0.3048)
		(layers "F.Cu" "B.Cu")
		(net "SAS_HDD_REDV_SER_TX7_N")
	)
	(segment
		(start 119.772176 -204.181964)
		(end 119.383048 -203.792836)
		(width 0.1016)
		(layer "B.Cu")
		(net "SAS_HDD_REDV_SER_TX7_N")
	)
	(segment
		(start 119.239538 -203.7334)
		(end 119.196612 -203.7334)
		(width 0.1016)
		(layer "B.Cu")
		(net "SAS_HDD_REDV_SER_TX7_N")
	)
	(segment
		(start 117.920008 -211.865464)
		(end 119.614442 -210.17103)
		(width 0.1016)
		(layer "B.Cu")
		(net "SAS_HDD_REDV_SER_TX7_N")
	)
	(segment
		(start 117.672866 -212.442806)
		(end 117.686836 -212.428836)
		(width 0.1016)
		(layer "B.Cu")
		(net "SAS_HDD_REDV_SER_TX7_N")
	)
	(segment
		(start 117.719094 -212.351112)
		(end 117.719094 -212.350858)
		(width 0.1016)
		(layer "B.Cu")
		(net "SAS_HDD_REDV_SER_TX7_N")
	)
	(segment
		(start 119.831612 -209.646774)
		(end 119.831612 -204.325474)
		(width 0.1016)
		(layer "B.Cu")
		(net "SAS_HDD_REDV_SER_TX7_N")
	)
	(segment
		(start 117.640608 -213.106)
		(end 117.640608 -212.52053)
		(width 0.1016)
		(layer "B.Cu")
		(net "SAS_HDD_REDV_SER_TX7_N")
	)
	(arc
		(start 117.719094 -212.350858)
		(mid 117.771253 -212.088166)
		(end 117.920008 -211.865464)
		(width 0.1016)
		(layer "B.Cu")
		(net "SAS_HDD_REDV_SER_TX7_N")
	)
	(arc
		(start 119.383048 -203.792836)
		(mid 119.317205 -203.748841)
		(end 119.239538 -203.7334)
		(width 0.1016)
		(layer "B.Cu")
		(net "SAS_HDD_REDV_SER_TX7_N")
	)
	(arc
		(start 117.640608 -212.52053)
		(mid 117.648995 -212.478456)
		(end 117.672866 -212.442806)
		(width 0.1016)
		(layer "B.Cu")
		(net "SAS_HDD_REDV_SER_TX7_N")
	)
	(arc
		(start 119.831612 -204.325474)
		(mid 119.816164 -204.24781)
		(end 119.772176 -204.181964)
		(width 0.1016)
		(layer "B.Cu")
		(net "SAS_HDD_REDV_SER_TX7_N")
	)
	(arc
		(start 117.686836 -212.428836)
		(mid 117.710717 -212.39319)
		(end 117.719094 -212.351112)
		(width 0.1016)
		(layer "B.Cu")
		(net "SAS_HDD_REDV_SER_TX7_N")
	)
	(arc
		(start 119.614442 -210.17103)
		(mid 119.775159 -209.930499)
		(end 119.831612 -209.646774)
		(width 0.1016)
		(layer "B.Cu")
		(net "SAS_HDD_REDV_SER_TX7_N")
	)
	(segment
		(start 109.017562 -215.349582)
		(end 109.017562 -203.8096)
		(width 0.1016)
		(layer "F.Cu")
		(net "REDV_RX8_P")
	)
	(segment
		(start 111.195612 -224.282)
		(end 110.799372 -223.885506)
		(width 0.1016)
		(layer "F.Cu")
		(net "REDV_RX8_P")
	)
	(segment
		(start 109.119162 -203.708)
		(end 109.671612 -203.708)
		(width 0.1016)
		(layer "F.Cu")
		(net "REDV_RX8_P")
	)
	(segment
		(start 110.49 -223.139)
		(end 110.49 -218.904312)
		(width 0.1016)
		(layer "F.Cu")
		(net "REDV_RX8_P")
	)
	(via
		(at 109.671612 -203.708)
		(size 0.5588)
		(drill 0.3048)
		(layers "F.Cu" "B.Cu")
		(net "REDV_RX8_P")
	)
	(via
		(at 111.195612 -224.282)
		(size 0.5588)
		(drill 0.3048)
		(layers "F.Cu" "B.Cu")
		(net "REDV_RX8_P")
	)
	(arc
		(start 109.017562 -203.8096)
		(mid 109.04732 -203.737758)
		(end 109.119162 -203.708)
		(width 0.1016)
		(layer "F.Cu")
		(net "REDV_RX8_P")
	)
	(arc
		(start 110.799372 -223.885506)
		(mid 110.570438 -223.543021)
		(end 110.49 -223.139)
		(width 0.1016)
		(layer "F.Cu")
		(net "REDV_RX8_P")
	)
	(arc
		(start 110.49 -218.904312)
		(mid 110.357983 -218.24062)
		(end 109.982 -217.678)
		(width 0.1016)
		(layer "F.Cu")
		(net "REDV_RX8_P")
	)
	(arc
		(start 109.982 -217.678)
		(mid 109.268193 -216.609713)
		(end 109.017562 -215.349582)
		(width 0.1016)
		(layer "F.Cu")
		(net "REDV_RX8_P")
	)
	(segment
		(start 109.671612 -204.5335)
		(end 109.671612 -203.708)
		(width 0.1016)
		(layer "B.Cu")
		(net "REDV_RX8_P")
	)
	(segment
		(start 111.195612 -224.282)
		(end 111.195612 -223.3295)
		(width 0.1016)
		(layer "B.Cu")
		(net "REDV_RX8_P")
	)
	(segment
		(start 295.021 -131.191)
		(end 282.575 -131.191)
		(width 0.1143)
		(layer "F.Cu")
		(net "DEBUG_LED_SW")
	)
	(segment
		(start 282.575 -131.191)
		(end 282.321 -131.445)
		(width 0.1143)
		(layer "F.Cu")
		(net "DEBUG_LED_SW")
	)
	(segment
		(start 338.328 -11.684)
		(end 340.106 -13.462)
		(width 0.1143)
		(layer "F.Cu")
		(net "DEBUG_LED_SW")
	)
	(segment
		(start 340.106 -13.462)
		(end 340.106 -13.716)
		(width 0.1143)
		(layer "F.Cu")
		(net "DEBUG_LED_SW")
	)
	(segment
		(start 326.600058 -7.155942)
		(end 326.600058 -4.550156)
		(width 0.1143)
		(layer "F.Cu")
		(net "DEBUG_LED_SW")
	)
	(segment
		(start 324.967854 -9.800082)
		(end 324.967854 -8.788146)
		(width 0.1143)
		(layer "F.Cu")
		(net "DEBUG_LED_SW")
	)
	(segment
		(start 287.234884 -173.04004)
		(end 287.234884 -173.030642)
		(width 0.1143)
		(layer "F.Cu")
		(net "DEBUG_LED_SW")
	)
	(segment
		(start 324.967854 -9.800082)
		(end 326.851772 -11.684)
		(width 0.1143)
		(layer "F.Cu")
		(net "DEBUG_LED_SW")
	)
	(segment
		(start 303.53 -108.712)
		(end 303.53 -116.205)
		(width 0.1143)
		(layer "F.Cu")
		(net "DEBUG_LED_SW")
	)
	(segment
		(start 303.53 -116.205)
		(end 298.91355 -120.82145)
		(width 0.1143)
		(layer "F.Cu")
		(net "DEBUG_LED_SW")
	)
	(segment
		(start 298.91355 -127.29845)
		(end 295.021 -131.191)
		(width 0.1143)
		(layer "F.Cu")
		(net "DEBUG_LED_SW")
	)
	(segment
		(start 287.234884 -173.030642)
		(end 287.634934 -172.630592)
		(width 0.1143)
		(layer "F.Cu")
		(net "DEBUG_LED_SW")
	)
	(segment
		(start 298.91355 -120.82145)
		(end 298.91355 -127.29845)
		(width 0.1143)
		(layer "F.Cu")
		(net "DEBUG_LED_SW")
	)
	(segment
		(start 324.967854 -8.788146)
		(end 326.136 -7.62)
		(width 0.1143)
		(layer "F.Cu")
		(net "DEBUG_LED_SW")
	)
	(segment
		(start 326.136 -7.62)
		(end 326.600058 -7.155942)
		(width 0.1143)
		(layer "F.Cu")
		(net "DEBUG_LED_SW")
	)
	(segment
		(start 326.851772 -11.684)
		(end 338.328 -11.684)
		(width 0.1143)
		(layer "F.Cu")
		(net "DEBUG_LED_SW")
	)
	(via
		(at 287.634934 -172.630592)
		(size 0.508)
		(drill 0.254)
		(layers "F.Cu" "B.Cu")
		(net "DEBUG_LED_SW")
	)
	(via
		(at 303.53 -108.712)
		(size 0.5588)
		(drill 0.3048)
		(layers "F.Cu" "B.Cu")
		(net "DEBUG_LED_SW")
	)
	(via
		(at 275.59 -167.894)
		(size 0.5588)
		(drill 0.3048)
		(layers "F.Cu" "B.Cu")
		(net "DEBUG_LED_SW")
	)
	(via
		(at 340.106 -13.716)
		(size 0.5588)
		(drill 0.3048)
		(layers "F.Cu" "B.Cu")
		(net "DEBUG_LED_SW")
	)
	(via
		(at 324.993 -38.227)
		(size 0.5588)
		(drill 0.3048)
		(layers "F.Cu" "B.Cu")
		(net "DEBUG_LED_SW")
	)
	(via
		(at 282.321 -131.445)
		(size 0.5588)
		(drill 0.3048)
		(layers "F.Cu" "B.Cu")
		(net "DEBUG_LED_SW")
	)
	(via
		(at 277.622 -170.18)
		(size 0.7112)
		(drill 0.3556)
		(layers "F.Cu" "B.Cu")
		(net "DEBUG_LED_SW")
	)
	(via
		(at 326.136 -7.62)
		(size 0.7112)
		(drill 0.3556)
		(layers "F.Cu" "B.Cu")
		(net "DEBUG_LED_SW")
	)
	(segment
		(start 280.58872 -172.9486)
		(end 278.60752 -170.9674)
		(width 0.1143)
		(layer "B.Cu")
		(net "DEBUG_LED_SW")
	)
	(segment
		(start 328.236072 -38.227)
		(end 344.35415 -22.108922)
		(width 0.1143)
		(layer "B.Cu")
		(net "DEBUG_LED_SW")
	)
	(segment
		(start 275.59 -168.148)
		(end 275.59 -167.894)
		(width 0.1143)
		(layer "B.Cu")
		(net "DEBUG_LED_SW")
	)
	(segment
		(start 324.993 -38.227)
		(end 328.236072 -38.227)
		(width 0.1143)
		(layer "B.Cu")
		(net "DEBUG_LED_SW")
	)
	(segment
		(start 278.4094 -170.9674)
		(end 277.622 -170.18)
		(width 0.1143)
		(layer "B.Cu")
		(net "DEBUG_LED_SW")
	)
	(segment
		(start 277.622 -170.18)
		(end 275.59 -168.148)
		(width 0.1143)
		(layer "B.Cu")
		(net "DEBUG_LED_SW")
	)
	(segment
		(start 283.70022 -172.9486)
		(end 280.58872 -172.9486)
		(width 0.1143)
		(layer "B.Cu")
		(net "DEBUG_LED_SW")
	)
	(segment
		(start 340.233 -13.843)
		(end 340.106 -13.716)
		(width 0.1143)
		(layer "B.Cu")
		(net "DEBUG_LED_SW")
	)
	(segment
		(start 344.35415 -17.261078)
		(end 340.936072 -13.843)
		(width 0.1143)
		(layer "B.Cu")
		(net "DEBUG_LED_SW")
	)
	(segment
		(start 278.60752 -170.9674)
		(end 278.4094 -170.9674)
		(width 0.1143)
		(layer "B.Cu")
		(net "DEBUG_LED_SW")
	)
	(segment
		(start 286.637476 -172.630592)
		(end 286.20593 -173.062138)
		(width 0.1143)
		(layer "B.Cu")
		(net "DEBUG_LED_SW")
	)
	(segment
		(start 287.634934 -172.630592)
		(end 286.637476 -172.630592)
		(width 0.1143)
		(layer "B.Cu")
		(net "DEBUG_LED_SW")
	)
	(segment
		(start 286.20593 -173.062138)
		(end 283.813758 -173.062138)
		(width 0.1143)
		(layer "B.Cu")
		(net "DEBUG_LED_SW")
	)
	(segment
		(start 283.813758 -173.062138)
		(end 283.70022 -172.9486)
		(width 0.1143)
		(layer "B.Cu")
		(net "DEBUG_LED_SW")
	)
	(segment
		(start 344.35415 -22.108922)
		(end 344.35415 -17.261078)
		(width 0.1143)
		(layer "B.Cu")
		(net "DEBUG_LED_SW")
	)
	(segment
		(start 340.936072 -13.843)
		(end 340.233 -13.843)
		(width 0.1143)
		(layer "B.Cu")
		(net "DEBUG_LED_SW")
	)
	(segment
		(start 303.784 -108.458)
		(end 303.53 -108.712)
		(width 0.127)
		(layer "In2.Cu")
		(net "DEBUG_LED_SW")
	)
	(segment
		(start 307.721 -97.79)
		(end 307.721 -105.733088)
		(width 0.127)
		(layer "In2.Cu")
		(net "DEBUG_LED_SW")
	)
	(segment
		(start 324.993 -38.227)
		(end 318.34836 -38.227)
		(width 0.127)
		(layer "In2.Cu")
		(net "DEBUG_LED_SW")
	)
	(segment
		(start 311.023 -64.897)
		(end 311.023 -94.488)
		(width 0.127)
		(layer "In2.Cu")
		(net "DEBUG_LED_SW")
	)
	(segment
		(start 304.996088 -108.458)
		(end 303.784 -108.458)
		(width 0.127)
		(layer "In2.Cu")
		(net "DEBUG_LED_SW")
	)
	(segment
		(start 314.352432 -42.222928)
		(end 314.352432 -46.763432)
		(width 0.127)
		(layer "In2.Cu")
		(net "DEBUG_LED_SW")
	)
	(segment
		(start 318.34836 -38.227)
		(end 314.352432 -42.222928)
		(width 0.127)
		(layer "In2.Cu")
		(net "DEBUG_LED_SW")
	)
	(segment
		(start 317.1698 -49.5808)
		(end 317.1698 -58.7502)
		(width 0.127)
		(layer "In2.Cu")
		(net "DEBUG_LED_SW")
	)
	(segment
		(start 307.721 -105.733088)
		(end 304.996088 -108.458)
		(width 0.127)
		(layer "In2.Cu")
		(net "DEBUG_LED_SW")
	)
	(segment
		(start 311.023 -94.488)
		(end 307.721 -97.79)
		(width 0.127)
		(layer "In2.Cu")
		(net "DEBUG_LED_SW")
	)
	(segment
		(start 317.1698 -58.7502)
		(end 311.023 -64.897)
		(width 0.127)
		(layer "In2.Cu")
		(net "DEBUG_LED_SW")
	)
	(segment
		(start 314.352432 -46.763432)
		(end 317.1698 -49.5808)
		(width 0.127)
		(layer "In2.Cu")
		(net "DEBUG_LED_SW")
	)
	(segment
		(start 275.209 -151.953468)
		(end 273.2151 -149.959568)
		(width 0.127)
		(layer "In5.Cu")
		(net "DEBUG_LED_SW")
	)
	(segment
		(start 273.2151 -149.959568)
		(end 273.2151 -137.714228)
		(width 0.127)
		(layer "In5.Cu")
		(net "DEBUG_LED_SW")
	)
	(segment
		(start 273.2151 -137.714228)
		(end 278.722328 -132.207)
		(width 0.127)
		(layer "In5.Cu")
		(net "DEBUG_LED_SW")
	)
	(segment
		(start 275.209 -165.354)
		(end 275.209 -151.953468)
		(width 0.127)
		(layer "In5.Cu")
		(net "DEBUG_LED_SW")
	)
	(segment
		(start 275.59 -167.894)
		(end 275.59 -165.735)
		(width 0.127)
		(layer "In5.Cu")
		(net "DEBUG_LED_SW")
	)
	(segment
		(start 281.559 -132.207)
		(end 282.321 -131.445)
		(width 0.127)
		(layer "In5.Cu")
		(net "DEBUG_LED_SW")
	)
	(segment
		(start 278.722328 -132.207)
		(end 281.559 -132.207)
		(width 0.127)
		(layer "In5.Cu")
		(net "DEBUG_LED_SW")
	)
	(segment
		(start 275.59 -165.735)
		(end 275.209 -165.354)
		(width 0.127)
		(layer "In5.Cu")
		(net "DEBUG_LED_SW")
	)
	(segment
		(start 182.38597 -67.6275)
		(end 182.38597 -69.026024)
		(width 0.1143)
		(layer "F.Cu")
		(net "TP_MSB_A34_CPU_SATA_RX_N")
	)
	(segment
		(start 182.38597 -69.026024)
		(end 185.916316 -72.55637)
		(width 0.1143)
		(layer "F.Cu")
		(net "TP_MSB_A34_CPU_SATA_RX_N")
	)
	(segment
		(start 185.916316 -72.55637)
		(end 185.916316 -73.21677)
		(width 0.1143)
		(layer "F.Cu")
		(net "TP_MSB_A34_CPU_SATA_RX_N")
	)
	(segment
		(start 185.916316 -73.21677)
		(end 186.449716 -73.75017)
		(width 0.1143)
		(layer "F.Cu")
		(net "TP_MSB_A34_CPU_SATA_RX_N")
	)
	(segment
		(start 116.993162 -203.7334)
		(end 117.545612 -203.7334)
		(width 0.1016)
		(layer "F.Cu")
		(net "REDV_RX7_P")
	)
	(segment
		(start 118.688612 -224.282)
		(end 118.213124 -223.806512)
		(width 0.1016)
		(layer "F.Cu")
		(net "REDV_RX7_P")
	)
	(segment
		(start 116.891562 -210.900264)
		(end 116.891562 -203.835)
		(width 0.1016)
		(layer "F.Cu")
		(net "REDV_RX7_P")
	)
	(segment
		(start 118.0719 -223.465644)
		(end 118.0719 -213.750398)
		(width 0.1016)
		(layer "F.Cu")
		(net "REDV_RX7_P")
	)
	(via
		(at 117.545612 -203.7334)
		(size 0.5588)
		(drill 0.3048)
		(layers "F.Cu" "B.Cu")
		(net "REDV_RX7_P")
	)
	(via
		(at 118.688612 -224.282)
		(size 0.5588)
		(drill 0.3048)
		(layers "F.Cu" "B.Cu")
		(net "REDV_RX7_P")
	)
	(arc
		(start 117.33657 -211.97443)
		(mid 117.007217 -211.481613)
		(end 116.891562 -210.900264)
		(width 0.1016)
		(layer "F.Cu")
		(net "REDV_RX7_P")
	)
	(arc
		(start 116.891562 -203.835)
		(mid 116.92132 -203.763158)
		(end 116.993162 -203.7334)
		(width 0.1016)
		(layer "F.Cu")
		(net "REDV_RX7_P")
	)
	(arc
		(start 118.213124 -223.806512)
		(mid 118.108626 -223.65012)
		(end 118.0719 -223.465644)
		(width 0.1016)
		(layer "F.Cu")
		(net "REDV_RX7_P")
	)
	(arc
		(start 118.0719 -213.750398)
		(mid 117.88089 -212.789273)
		(end 117.33657 -211.97443)
		(width 0.1016)
		(layer "F.Cu")
		(net "REDV_RX7_P")
	)
	(segment
		(start 118.688612 -223.3295)
		(end 118.688612 -224.282)
		(width 0.1016)
		(layer "B.Cu")
		(net "REDV_RX7_P")
	)
	(segment
		(start 117.545612 -204.5335)
		(end 117.545612 -203.7334)
		(width 0.1016)
		(layer "B.Cu")
		(net "REDV_RX7_P")
	)
	(segment
		(start 181.36997 -68.530978)
		(end 185.548016 -72.709024)
		(width 0.1143)
		(layer "F.Cu")
		(net "TP_MSB_A33_CPU_SATA_RX_P")
	)
	(segment
		(start 186.503056 -74.803)
		(end 187.450476 -75.75042)
		(width 0.1143)
		(layer "F.Cu")
		(net "TP_MSB_A33_CPU_SATA_RX_P")
	)
	(segment
		(start 186.32297 -74.803)
		(end 186.503056 -74.803)
		(width 0.1143)
		(layer "F.Cu")
		(net "TP_MSB_A33_CPU_SATA_RX_P")
	)
	(segment
		(start 185.548016 -74.028046)
		(end 186.32297 -74.803)
		(width 0.1143)
		(layer "F.Cu")
		(net "TP_MSB_A33_CPU_SATA_RX_P")
	)
	(segment
		(start 185.548016 -72.709024)
		(end 185.548016 -74.028046)
		(width 0.1143)
		(layer "F.Cu")
		(net "TP_MSB_A33_CPU_SATA_RX_P")
	)
	(segment
		(start 181.36997 -67.6275)
		(end 181.36997 -68.530978)
		(width 0.1143)
		(layer "F.Cu")
		(net "TP_MSB_A33_CPU_SATA_RX_P")
	)
	(segment
		(start 184.41797 -76.073)
		(end 186.57697 -78.232)
		(width 0.1143)
		(layer "F.Cu")
		(net "TP_MSB_B32_CPU_SATA_TX_N")
	)
	(segment
		(start 183.40197 -74.168)
		(end 184.41797 -75.184)
		(width 0.1143)
		(layer "F.Cu")
		(net "TP_MSB_B32_CPU_SATA_TX_N")
	)
	(segment
		(start 183.40197 -72.517)
		(end 183.40197 -74.168)
		(width 0.1143)
		(layer "F.Cu")
		(net "TP_MSB_B32_CPU_SATA_TX_N")
	)
	(segment
		(start 179.33797 -68.453)
		(end 183.40197 -72.517)
		(width 0.1143)
		(layer "F.Cu")
		(net "TP_MSB_B32_CPU_SATA_TX_N")
	)
	(segment
		(start 186.57697 -78.232)
		(end 186.57697 -78.613)
		(width 0.1143)
		(layer "F.Cu")
		(net "TP_MSB_B32_CPU_SATA_TX_N")
	)
	(segment
		(start 188.214 -80.25003)
		(end 188.449966 -80.25003)
		(width 0.1143)
		(layer "F.Cu")
		(net "TP_MSB_B32_CPU_SATA_TX_N")
	)
	(segment
		(start 184.41797 -75.184)
		(end 184.41797 -76.073)
		(width 0.1143)
		(layer "F.Cu")
		(net "TP_MSB_B32_CPU_SATA_TX_N")
	)
	(segment
		(start 179.33797 -67.6275)
		(end 179.33797 -68.453)
		(width 0.1143)
		(layer "F.Cu")
		(net "TP_MSB_B32_CPU_SATA_TX_N")
	)
	(segment
		(start 186.57697 -78.613)
		(end 188.214 -80.25003)
		(width 0.1143)
		(layer "F.Cu")
		(net "TP_MSB_B32_CPU_SATA_TX_N")
	)
	(segment
		(start 180.35397 -67.6275)
		(end 180.35397 -68.035932)
		(width 0.1143)
		(layer "F.Cu")
		(net "TP_MSB_B31_CPU_SATA_TX_P")
	)
	(segment
		(start 186.44997 -76.073)
		(end 188.62675 -78.24978)
		(width 0.1143)
		(layer "F.Cu")
		(net "TP_MSB_B31_CPU_SATA_TX_P")
	)
	(segment
		(start 186.44997 -75.565)
		(end 186.44997 -76.073)
		(width 0.1143)
		(layer "F.Cu")
		(net "TP_MSB_B31_CPU_SATA_TX_P")
	)
	(segment
		(start 188.62675 -78.24978)
		(end 189.449456 -78.24978)
		(width 0.1143)
		(layer "F.Cu")
		(net "TP_MSB_B31_CPU_SATA_TX_P")
	)
	(segment
		(start 180.35397 -68.035932)
		(end 185.179716 -72.861678)
		(width 0.1143)
		(layer "F.Cu")
		(net "TP_MSB_B31_CPU_SATA_TX_P")
	)
	(segment
		(start 185.179716 -72.861678)
		(end 185.179716 -74.294746)
		(width 0.1143)
		(layer "F.Cu")
		(net "TP_MSB_B31_CPU_SATA_TX_P")
	)
	(segment
		(start 185.179716 -74.294746)
		(end 186.44997 -75.565)
		(width 0.1143)
		(layer "F.Cu")
		(net "TP_MSB_B31_CPU_SATA_TX_P")
	)
	(via
		(at 109.468412 -212.725)
		(size 0.7112)
		(drill 0.3556)
		(layers "F.Cu" "B.Cu")
		(net "REDV_I2C_A4")
	)
	(segment
		(start 108.465112 -212.725)
		(end 109.468412 -212.725)
		(width 0.1143)
		(layer "B.Cu")
		(net "REDV_I2C_A4")
	)
	(segment
		(start 109.544612 -212.725)
		(end 109.468412 -212.725)
		(width 0.1143)
		(layer "B.Cu")
		(net "REDV_I2C_A4")
	)
	(segment
		(start 111.64062 -213.106)
		(end 109.925612 -213.106)
		(width 0.1143)
		(layer "B.Cu")
		(net "REDV_I2C_A4")
	)
	(segment
		(start 109.925612 -213.106)
		(end 109.544612 -212.725)
		(width 0.1143)
		(layer "B.Cu")
		(net "REDV_I2C_A4")
	)
	(segment
		(start 112.846612 -223.3295)
		(end 112.846612 -224.282)
		(width 0.1016)
		(layer "F.Cu")
		(net "SAS_HDD_CONN_SER_TX8_N")
	)
	(via
		(at 112.846612 -224.282)
		(size 0.5588)
		(drill 0.3048)
		(layers "F.Cu" "B.Cu")
		(net "SAS_HDD_CONN_SER_TX8_N")
	)
	(segment
		(start 113.460276 -223.871536)
		(end 113.109248 -224.222564)
		(width 0.1016)
		(layer "B.Cu")
		(net "SAS_HDD_CONN_SER_TX8_N")
	)
	(segment
		(start 113.519712 -220.852746)
		(end 113.519712 -223.728026)
		(width 0.1016)
		(layer "B.Cu")
		(net "SAS_HDD_CONN_SER_TX8_N")
	)
	(segment
		(start 114.445542 -219.40393)
		(end 113.887758 -219.961714)
		(width 0.1016)
		(layer "B.Cu")
		(net "SAS_HDD_CONN_SER_TX8_N")
	)
	(segment
		(start 114.7191 -217.416634)
		(end 114.7191 -218.74353)
		(width 0.1016)
		(layer "B.Cu")
		(net "SAS_HDD_CONN_SER_TX8_N")
	)
	(segment
		(start 112.965738 -224.282)
		(end 112.846612 -224.282)
		(width 0.1016)
		(layer "B.Cu")
		(net "SAS_HDD_CONN_SER_TX8_N")
	)
	(segment
		(start 114.640614 -216.662)
		(end 114.640614 -217.247216)
		(width 0.1016)
		(layer "B.Cu")
		(net "SAS_HDD_CONN_SER_TX8_N")
	)
	(segment
		(start 114.672872 -217.32494)
		(end 114.686842 -217.33891)
		(width 0.1016)
		(layer "B.Cu")
		(net "SAS_HDD_CONN_SER_TX8_N")
	)
	(arc
		(start 113.519712 -223.728026)
		(mid 113.504264 -223.80569)
		(end 113.460276 -223.871536)
		(width 0.1016)
		(layer "B.Cu")
		(net "SAS_HDD_CONN_SER_TX8_N")
	)
	(arc
		(start 113.887758 -219.961714)
		(mid 113.615351 -220.370722)
		(end 113.519712 -220.852746)
		(width 0.1016)
		(layer "B.Cu")
		(net "SAS_HDD_CONN_SER_TX8_N")
	)
	(arc
		(start 114.686842 -217.33891)
		(mid 114.710723 -217.374556)
		(end 114.7191 -217.416634)
		(width 0.1016)
		(layer "B.Cu")
		(net "SAS_HDD_CONN_SER_TX8_N")
	)
	(arc
		(start 114.7191 -218.74353)
		(mid 114.648007 -219.10094)
		(end 114.445542 -219.40393)
		(width 0.1016)
		(layer "B.Cu")
		(net "SAS_HDD_CONN_SER_TX8_N")
	)
	(arc
		(start 114.640614 -217.247216)
		(mid 114.649001 -217.28929)
		(end 114.672872 -217.32494)
		(width 0.1016)
		(layer "B.Cu")
		(net "SAS_HDD_CONN_SER_TX8_N")
	)
	(arc
		(start 113.109248 -224.222564)
		(mid 113.043405 -224.266559)
		(end 112.965738 -224.282)
		(width 0.1016)
		(layer "B.Cu")
		(net "SAS_HDD_CONN_SER_TX8_N")
	)
	(via
		(at 110.992412 -211.074)
		(size 0.7112)
		(drill 0.3556)
		(layers "F.Cu" "B.Cu")
		(net "REDV_MODE")
	)
	(segment
		(start 112.640618 -213.106)
		(end 112.640618 -212.265006)
		(width 0.1143)
		(layer "B.Cu")
		(net "REDV_MODE")
	)
	(segment
		(start 108.465112 -210.439)
		(end 108.820712 -210.7946)
		(width 0.1143)
		(layer "B.Cu")
		(net "REDV_MODE")
	)
	(segment
		(start 108.820712 -210.7946)
		(end 110.713012 -210.7946)
		(width 0.1143)
		(layer "B.Cu")
		(net "REDV_MODE")
	)
	(segment
		(start 112.640618 -212.265006)
		(end 111.449612 -211.074)
		(width 0.1143)
		(layer "B.Cu")
		(net "REDV_MODE")
	)
	(segment
		(start 111.449612 -211.074)
		(end 110.992412 -211.074)
		(width 0.1143)
		(layer "B.Cu")
		(net "REDV_MODE")
	)
	(segment
		(start 110.713012 -210.7946)
		(end 110.992412 -211.074)
		(width 0.1143)
		(layer "B.Cu")
		(net "REDV_MODE")
	)
	(via
		(at 122.066812 -217.424)
		(size 0.7112)
		(drill 0.3556)
		(layers "F.Cu" "B.Cu")
		(net "REDV_I2C_SDA")
	)
	(segment
		(start 119.640604 -216.662)
		(end 121.304812 -216.662)
		(width 0.1143)
		(layer "B.Cu")
		(net "REDV_I2C_SDA")
	)
	(segment
		(start 121.304812 -216.662)
		(end 122.066812 -217.424)
		(width 0.1143)
		(layer "B.Cu")
		(net "REDV_I2C_SDA")
	)
	(segment
		(start 123.959112 -217.678)
		(end 122.320812 -217.678)
		(width 0.1143)
		(layer "B.Cu")
		(net "REDV_I2C_SDA")
	)
	(segment
		(start 122.320812 -217.678)
		(end 122.066812 -217.424)
		(width 0.1143)
		(layer "B.Cu")
		(net "REDV_I2C_SDA")
	)
	(segment
		(start 171.46397 -67.6275)
		(end 171.46397 -74.422)
		(width 0.1143)
		(layer "F.Cu")
		(net "TP_MSB_B47_CPU_GBE_TX_N")
	)
	(segment
		(start 172.450506 -75.408536)
		(end 172.450506 -80.25003)
		(width 0.1143)
		(layer "F.Cu")
		(net "TP_MSB_B47_CPU_GBE_TX_N")
	)
	(segment
		(start 171.46397 -74.422)
		(end 172.450506 -75.408536)
		(width 0.1143)
		(layer "F.Cu")
		(net "TP_MSB_B47_CPU_GBE_TX_N")
	)
	(segment
		(start 21.783802 -215.628474)
		(end 21.717762 -215.694514)
		(width 0.1143)
		(layer "F.Cu")
		(net "IO_EXP_HDD_PWR_A1")
	)
	(segment
		(start 21.758656 -214.72144)
		(end 21.758656 -215.197944)
		(width 0.1143)
		(layer "F.Cu")
		(net "IO_EXP_HDD_PWR_A1")
	)
	(segment
		(start 24.270716 -215.06688)
		(end 24.461216 -215.06688)
		(width 0.1143)
		(layer "F.Cu")
		(net "IO_EXP_HDD_PWR_A1")
	)
	(segment
		(start 23.445216 -214.24138)
		(end 24.270716 -215.06688)
		(width 0.1143)
		(layer "F.Cu")
		(net "IO_EXP_HDD_PWR_A1")
	)
	(segment
		(start 22.238716 -214.24138)
		(end 21.758656 -214.72144)
		(width 0.1143)
		(layer "F.Cu")
		(net "IO_EXP_HDD_PWR_A1")
	)
	(segment
		(start 21.758656 -215.197944)
		(end 21.783802 -215.22309)
		(width 0.1143)
		(layer "F.Cu")
		(net "IO_EXP_HDD_PWR_A1")
	)
	(segment
		(start 22.302216 -214.24138)
		(end 22.238716 -214.24138)
		(width 0.1143)
		(layer "F.Cu")
		(net "IO_EXP_HDD_PWR_A1")
	)
	(segment
		(start 21.783802 -215.22309)
		(end 21.783802 -215.628474)
		(width 0.1143)
		(layer "F.Cu")
		(net "IO_EXP_HDD_PWR_A1")
	)
	(segment
		(start 21.717762 -215.694514)
		(end 21.717762 -216.680288)
		(width 0.1143)
		(layer "F.Cu")
		(net "IO_EXP_HDD_PWR_A1")
	)
	(segment
		(start 21.717762 -216.680288)
		(end 21.683472 -216.714578)
		(width 0.1143)
		(layer "F.Cu")
		(net "IO_EXP_HDD_PWR_A1")
	)
	(segment
		(start 23.445216 -214.24138)
		(end 22.302216 -214.24138)
		(width 0.1143)
		(layer "F.Cu")
		(net "IO_EXP_HDD_PWR_A1")
	)
	(via
		(at 24.461216 -215.06688)
		(size 0.7112)
		(drill 0.3556)
		(layers "F.Cu" "B.Cu")
		(net "IO_EXP_HDD_PWR_A1")
	)
	(segment
		(start 172.47997 -67.6275)
		(end 172.47997 -71.374)
		(width 0.1143)
		(layer "F.Cu")
		(net "TP_MSB_B47_CPU_GBE_TX_P")
	)
	(segment
		(start 174.38497 -76.376276)
		(end 173.449996 -77.31125)
		(width 0.1143)
		(layer "F.Cu")
		(net "TP_MSB_B47_CPU_GBE_TX_P")
	)
	(segment
		(start 173.24197 -72.136)
		(end 173.24197 -74.168)
		(width 0.1143)
		(layer "F.Cu")
		(net "TP_MSB_B47_CPU_GBE_TX_P")
	)
	(segment
		(start 173.449996 -77.31125)
		(end 173.449996 -78.24978)
		(width 0.1143)
		(layer "F.Cu")
		(net "TP_MSB_B47_CPU_GBE_TX_P")
	)
	(segment
		(start 174.38497 -75.311)
		(end 174.38497 -76.376276)
		(width 0.1143)
		(layer "F.Cu")
		(net "TP_MSB_B47_CPU_GBE_TX_P")
	)
	(segment
		(start 172.47997 -71.374)
		(end 173.24197 -72.136)
		(width 0.1143)
		(layer "F.Cu")
		(net "TP_MSB_B47_CPU_GBE_TX_P")
	)
	(segment
		(start 173.24197 -74.168)
		(end 174.38497 -75.311)
		(width 0.1143)
		(layer "F.Cu")
		(net "TP_MSB_B47_CPU_GBE_TX_P")
	)
	(segment
		(start 17.857216 -225.98888)
		(end 18.936716 -225.98888)
		(width 0.1143)
		(layer "F.Cu")
		(net "IO_EXP_HDD_PWR_A3")
	)
	(segment
		(start 18.936716 -225.98888)
		(end 18.936716 -224.97288)
		(width 0.1143)
		(layer "F.Cu")
		(net "IO_EXP_HDD_PWR_A3")
	)
	(segment
		(start 21.033232 -223.294448)
		(end 21.033232 -222.325438)
		(width 0.1143)
		(layer "F.Cu")
		(net "IO_EXP_HDD_PWR_A3")
	)
	(segment
		(start 18.936716 -224.88271)
		(end 19.538696 -224.28073)
		(width 0.1143)
		(layer "F.Cu")
		(net "IO_EXP_HDD_PWR_A3")
	)
	(segment
		(start 20.04695 -224.28073)
		(end 21.033232 -223.294448)
		(width 0.1143)
		(layer "F.Cu")
		(net "IO_EXP_HDD_PWR_A3")
	)
	(segment
		(start 19.538696 -224.28073)
		(end 20.04695 -224.28073)
		(width 0.1143)
		(layer "F.Cu")
		(net "IO_EXP_HDD_PWR_A3")
	)
	(segment
		(start 18.936716 -224.97288)
		(end 18.936716 -224.88271)
		(width 0.1143)
		(layer "F.Cu")
		(net "IO_EXP_HDD_PWR_A3")
	)
	(via
		(at 17.857216 -225.98888)
		(size 0.7112)
		(drill 0.3556)
		(layers "F.Cu" "B.Cu")
		(net "IO_EXP_HDD_PWR_A3")
	)
	(segment
		(start 178.44897 -78.486)
		(end 180.213 -80.25003)
		(width 0.127)
		(layer "F.Cu")
		(net "TP_MSB_B40")
	)
	(segment
		(start 178.44897 -75.438)
		(end 178.44897 -78.486)
		(width 0.127)
		(layer "F.Cu")
		(net "TP_MSB_B40")
	)
	(segment
		(start 177.281586 -71.170292)
		(end 177.281586 -74.270616)
		(width 0.127)
		(layer "F.Cu")
		(net "TP_MSB_B40")
	)
	(segment
		(start 175.90897 -69.797676)
		(end 177.281586 -71.170292)
		(width 0.127)
		(layer "F.Cu")
		(net "TP_MSB_B40")
	)
	(segment
		(start 177.281586 -74.270616)
		(end 178.44897 -75.438)
		(width 0.127)
		(layer "F.Cu")
		(net "TP_MSB_B40")
	)
	(segment
		(start 180.213 -80.25003)
		(end 180.450236 -80.25003)
		(width 0.127)
		(layer "F.Cu")
		(net "TP_MSB_B40")
	)
	(segment
		(start 175.90897 -67.945)
		(end 175.90897 -69.797676)
		(width 0.127)
		(layer "F.Cu")
		(net "TP_MSB_B40")
	)
	(segment
		(start 108.573062 -203.708)
		(end 108.020612 -203.708)
		(width 0.1016)
		(layer "F.Cu")
		(net "REDV_RX8_N")
	)
	(segment
		(start 109.544612 -224.282)
		(end 109.956092 -223.87052)
		(width 0.1016)
		(layer "F.Cu")
		(net "REDV_RX8_N")
	)
	(segment
		(start 108.674662 -215.349582)
		(end 108.674662 -203.8096)
		(width 0.1016)
		(layer "F.Cu")
		(net "REDV_RX8_N")
	)
	(segment
		(start 110.1471 -223.409256)
		(end 110.1471 -218.904566)
		(width 0.1016)
		(layer "F.Cu")
		(net "REDV_RX8_N")
	)
	(via
		(at 109.544612 -224.282)
		(size 0.5588)
		(drill 0.3048)
		(layers "F.Cu" "B.Cu")
		(net "REDV_RX8_N")
	)
	(via
		(at 108.020612 -203.708)
		(size 0.5588)
		(drill 0.3048)
		(layers "F.Cu" "B.Cu")
		(net "REDV_RX8_N")
	)
	(arc
		(start 109.73943 -217.92057)
		(mid 108.951343 -216.740976)
		(end 108.674662 -215.349582)
		(width 0.1016)
		(layer "F.Cu")
		(net "REDV_RX8_N")
	)
	(arc
		(start 108.674662 -203.8096)
		(mid 108.644904 -203.737758)
		(end 108.573062 -203.708)
		(width 0.1016)
		(layer "F.Cu")
		(net "REDV_RX8_N")
	)
	(arc
		(start 110.1471 -218.904566)
		(mid 110.041151 -218.372013)
		(end 109.73943 -217.92057)
		(width 0.1016)
		(layer "F.Cu")
		(net "REDV_RX8_N")
	)
	(arc
		(start 109.956092 -223.87052)
		(mid 110.097445 -223.658876)
		(end 110.1471 -223.409256)
		(width 0.1016)
		(layer "F.Cu")
		(net "REDV_RX8_N")
	)
	(segment
		(start 108.020612 -204.5335)
		(end 108.020612 -203.708)
		(width 0.1016)
		(layer "B.Cu")
		(net "REDV_RX8_N")
	)
	(segment
		(start 109.544612 -224.282)
		(end 109.544612 -223.3295)
		(width 0.1016)
		(layer "B.Cu")
		(net "REDV_RX8_N")
	)
	(segment
		(start 17.133062 -214.840058)
		(end 17.133062 -216.714578)
		(width 0.1143)
		(layer "F.Cu")
		(net "IO_EXP_HDD_PWR_A0")
	)
	(segment
		(start 15.444216 -214.30488)
		(end 15.507716 -214.24138)
		(width 0.1143)
		(layer "F.Cu")
		(net "IO_EXP_HDD_PWR_A0")
	)
	(segment
		(start 15.507716 -214.24138)
		(end 16.714216 -214.24138)
		(width 0.1143)
		(layer "F.Cu")
		(net "IO_EXP_HDD_PWR_A0")
	)
	(segment
		(start 16.714216 -214.24138)
		(end 17.730216 -214.24138)
		(width 0.1143)
		(layer "F.Cu")
		(net "IO_EXP_HDD_PWR_A0")
	)
	(segment
		(start 17.730216 -214.24138)
		(end 17.133062 -214.840058)
		(width 0.1143)
		(layer "F.Cu")
		(net "IO_EXP_HDD_PWR_A0")
	)
	(via
		(at 15.444216 -214.30488)
		(size 0.7112)
		(drill 0.3556)
		(layers "F.Cu" "B.Cu")
		(net "IO_EXP_HDD_PWR_A0")
	)
	(segment
		(start 120.339612 -223.3295)
		(end 120.339612 -224.282)
		(width 0.1016)
		(layer "F.Cu")
		(net "SAS_HDD_CONN_SER_TX7_N")
	)
	(via
		(at 120.339612 -224.282)
		(size 0.5588)
		(drill 0.3048)
		(layers "F.Cu" "B.Cu")
		(net "SAS_HDD_CONN_SER_TX7_N")
	)
	(segment
		(start 118.231158 -218.7448)
		(end 120.471946 -220.985588)
		(width 0.1016)
		(layer "B.Cu")
		(net "SAS_HDD_CONN_SER_TX7_N")
	)
	(segment
		(start 120.471946 -220.985588)
		(end 120.543828 -221.057216)
		(width 0.1016)
		(layer "B.Cu")
		(net "SAS_HDD_CONN_SER_TX7_N")
	)
	(segment
		(start 118.04269 -218.556078)
		(end 118.231412 -218.7448)
		(width 0.1016)
		(layer "B.Cu")
		(net "SAS_HDD_CONN_SER_TX7_N")
	)
	(segment
		(start 120.484138 -224.282)
		(end 120.339612 -224.282)
		(width 0.1016)
		(layer "B.Cu")
		(net "SAS_HDD_CONN_SER_TX7_N")
	)
	(segment
		(start 120.974612 -222.000826)
		(end 120.974612 -223.791526)
		(width 0.1016)
		(layer "B.Cu")
		(net "SAS_HDD_CONN_SER_TX7_N")
	)
	(segment
		(start 118.231412 -218.7448)
		(end 118.231158 -218.7448)
		(width 0.1016)
		(layer "B.Cu")
		(net "SAS_HDD_CONN_SER_TX7_N")
	)
	(segment
		(start 120.543828 -221.057216)
		(end 120.6119 -221.125288)
		(width 0.1016)
		(layer "B.Cu")
		(net "SAS_HDD_CONN_SER_TX7_N")
	)
	(segment
		(start 117.640608 -216.682828)
		(end 117.710712 -216.752932)
		(width 0.1016)
		(layer "B.Cu")
		(net "SAS_HDD_CONN_SER_TX7_N")
	)
	(segment
		(start 117.710712 -216.752932)
		(end 117.710712 -217.753946)
		(width 0.1016)
		(layer "B.Cu")
		(net "SAS_HDD_CONN_SER_TX7_N")
	)
	(segment
		(start 117.640608 -216.662)
		(end 117.640608 -216.682828)
		(width 0.1016)
		(layer "B.Cu")
		(net "SAS_HDD_CONN_SER_TX7_N")
	)
	(segment
		(start 120.915176 -223.935036)
		(end 120.627648 -224.222564)
		(width 0.1016)
		(layer "B.Cu")
		(net "SAS_HDD_CONN_SER_TX7_N")
	)
	(arc
		(start 117.710712 -217.753946)
		(mid 117.79689 -218.188044)
		(end 118.04269 -218.556078)
		(width 0.1016)
		(layer "B.Cu")
		(net "SAS_HDD_CONN_SER_TX7_N")
	)
	(arc
		(start 120.627648 -224.222564)
		(mid 120.561805 -224.266559)
		(end 120.484138 -224.282)
		(width 0.1016)
		(layer "B.Cu")
		(net "SAS_HDD_CONN_SER_TX7_N")
	)
	(arc
		(start 120.974612 -223.791526)
		(mid 120.959164 -223.86919)
		(end 120.915176 -223.935036)
		(width 0.1016)
		(layer "B.Cu")
		(net "SAS_HDD_CONN_SER_TX7_N")
	)
	(arc
		(start 120.6119 -221.125288)
		(mid 120.880361 -221.526974)
		(end 120.974612 -222.000826)
		(width 0.1016)
		(layer "B.Cu")
		(net "SAS_HDD_CONN_SER_TX7_N")
	)
	(segment
		(start 26.048716 -225.22688)
		(end 26.048716 -224.21088)
		(width 0.1143)
		(layer "F.Cu")
		(net "IO_EXP_HDD_PWR_A2")
	)
	(segment
		(start 25.583642 -223.745806)
		(end 25.583642 -222.325438)
		(width 0.1143)
		(layer "F.Cu")
		(net "IO_EXP_HDD_PWR_A2")
	)
	(segment
		(start 26.048716 -224.21088)
		(end 25.583642 -223.745806)
		(width 0.1143)
		(layer "F.Cu")
		(net "IO_EXP_HDD_PWR_A2")
	)
	(segment
		(start 26.925016 -225.29038)
		(end 25.985216 -225.29038)
		(width 0.1143)
		(layer "F.Cu")
		(net "IO_EXP_HDD_PWR_A2")
	)
	(segment
		(start 25.985216 -225.29038)
		(end 26.048716 -225.22688)
		(width 0.1143)
		(layer "F.Cu")
		(net "IO_EXP_HDD_PWR_A2")
	)
	(via
		(at 26.925016 -225.29038)
		(size 0.7112)
		(drill 0.3556)
		(layers "F.Cu" "B.Cu")
		(net "IO_EXP_HDD_PWR_A2")
	)
	(segment
		(start 120.847612 -204.5335)
		(end 120.847612 -203.7334)
		(width 0.1016)
		(layer "F.Cu")
		(net "SAS_HDD_REDV_SER_TX7_P")
	)
	(via
		(at 120.847612 -203.7334)
		(size 0.5588)
		(drill 0.3048)
		(layers "F.Cu" "B.Cu")
		(net "SAS_HDD_REDV_SER_TX7_P")
	)
	(segment
		(start 120.233948 -204.245464)
		(end 120.686576 -203.792836)
		(width 0.1016)
		(layer "B.Cu")
		(net "SAS_HDD_REDV_SER_TX7_P")
	)
	(segment
		(start 118.108476 -212.44306)
		(end 118.094252 -212.428836)
		(width 0.1016)
		(layer "B.Cu")
		(net "SAS_HDD_REDV_SER_TX7_P")
	)
	(segment
		(start 118.140734 -213.106)
		(end 118.140734 -212.521038)
		(width 0.1016)
		(layer "B.Cu")
		(net "SAS_HDD_REDV_SER_TX7_P")
	)
	(segment
		(start 118.162578 -212.108034)
		(end 119.857012 -210.4136)
		(width 0.1016)
		(layer "B.Cu")
		(net "SAS_HDD_REDV_SER_TX7_P")
	)
	(segment
		(start 120.830086 -203.7334)
		(end 120.847612 -203.7334)
		(width 0.1016)
		(layer "B.Cu")
		(net "SAS_HDD_REDV_SER_TX7_P")
	)
	(segment
		(start 120.174512 -209.647028)
		(end 120.174512 -204.388974)
		(width 0.1016)
		(layer "B.Cu")
		(net "SAS_HDD_REDV_SER_TX7_P")
	)
	(arc
		(start 120.174512 -204.388974)
		(mid 120.18996 -204.31131)
		(end 120.233948 -204.245464)
		(width 0.1016)
		(layer "B.Cu")
		(net "SAS_HDD_REDV_SER_TX7_P")
	)
	(arc
		(start 120.686576 -203.792836)
		(mid 120.752419 -203.748841)
		(end 120.830086 -203.7334)
		(width 0.1016)
		(layer "B.Cu")
		(net "SAS_HDD_REDV_SER_TX7_P")
	)
	(arc
		(start 118.061994 -212.350858)
		(mid 118.088134 -212.219441)
		(end 118.162578 -212.108034)
		(width 0.1016)
		(layer "B.Cu")
		(net "SAS_HDD_REDV_SER_TX7_P")
	)
	(arc
		(start 118.094252 -212.428836)
		(mid 118.0704 -212.393045)
		(end 118.061994 -212.350858)
		(width 0.1016)
		(layer "B.Cu")
		(net "SAS_HDD_REDV_SER_TX7_P")
	)
	(arc
		(start 118.140734 -212.521038)
		(mid 118.132358 -212.478838)
		(end 118.108476 -212.44306)
		(width 0.1016)
		(layer "B.Cu")
		(net "SAS_HDD_REDV_SER_TX7_P")
	)
	(arc
		(start 119.857012 -210.4136)
		(mid 120.091961 -210.06188)
		(end 120.174512 -209.647028)
		(width 0.1016)
		(layer "B.Cu")
		(net "SAS_HDD_REDV_SER_TX7_P")
	)
	(segment
		(start 286.385 -173.04004)
		(end 286.034734 -172.689774)
		(width 0.1143)
		(layer "F.Cu")
		(net "HSC_MSB_ALERT_N")
	)
	(segment
		(start 286.160972 -69.016626)
		(end 286.160972 -70.391528)
		(width 0.1143)
		(layer "F.Cu")
		(net "HSC_MSB_ALERT_N")
	)
	(segment
		(start 290.23056 -91.40444)
		(end 289.7251 -90.89898)
		(width 0.1143)
		(layer "F.Cu")
		(net "HSC_MSB_ALERT_N")
	)
	(segment
		(start 286.434784 -173.04004)
		(end 286.385 -173.04004)
		(width 0.1143)
		(layer "F.Cu")
		(net "HSC_MSB_ALERT_N")
	)
	(segment
		(start 286.034734 -172.689774)
		(end 286.034734 -172.649388)
		(width 0.1143)
		(layer "F.Cu")
		(net "HSC_MSB_ALERT_N")
	)
	(segment
		(start 285.9405 -73.5965)
		(end 285.9405 -70.612)
		(width 0.1143)
		(layer "F.Cu")
		(net "HSC_MSB_ALERT_N")
	)
	(segment
		(start 289.7251 -90.89898)
		(end 289.7251 -77.3811)
		(width 0.1143)
		(layer "F.Cu")
		(net "HSC_MSB_ALERT_N")
	)
	(segment
		(start 289.7251 -77.3811)
		(end 285.9405 -73.5965)
		(width 0.1143)
		(layer "F.Cu")
		(net "HSC_MSB_ALERT_N")
	)
	(segment
		(start 286.160972 -70.391528)
		(end 285.9405 -70.612)
		(width 0.1143)
		(layer "F.Cu")
		(net "HSC_MSB_ALERT_N")
	)
	(via
		(at 266.723368 -166.383208)
		(size 0.5588)
		(drill 0.3048)
		(layers "F.Cu" "B.Cu")
		(net "HSC_MSB_ALERT_N")
	)
	(via
		(at 290.23056 -91.40444)
		(size 0.5588)
		(drill 0.3048)
		(layers "F.Cu" "B.Cu")
		(net "HSC_MSB_ALERT_N")
	)
	(via
		(at 286.034734 -172.649388)
		(size 0.508)
		(drill 0.254)
		(layers "F.Cu" "B.Cu")
		(net "HSC_MSB_ALERT_N")
	)
	(via
		(at 282.5496 -172.339)
		(size 0.7112)
		(drill 0.3556)
		(layers "F.Cu" "B.Cu")
		(net "HSC_MSB_ALERT_N")
	)
	(segment
		(start 280.74874 -172.339)
		(end 274.792948 -166.383208)
		(width 0.1143)
		(layer "B.Cu")
		(net "HSC_MSB_ALERT_N")
	)
	(segment
		(start 274.792948 -166.383208)
		(end 266.723368 -166.383208)
		(width 0.1143)
		(layer "B.Cu")
		(net "HSC_MSB_ALERT_N")
	)
	(segment
		(start 282.5496 -172.339)
		(end 280.74874 -172.339)
		(width 0.1143)
		(layer "B.Cu")
		(net "HSC_MSB_ALERT_N")
	)
	(segment
		(start 283.730446 -172.649388)
		(end 286.034734 -172.649388)
		(width 0.1143)
		(layer "B.Cu")
		(net "HSC_MSB_ALERT_N")
	)
	(segment
		(start 283.420058 -172.339)
		(end 283.730446 -172.649388)
		(width 0.1143)
		(layer "B.Cu")
		(net "HSC_MSB_ALERT_N")
	)
	(segment
		(start 282.5496 -172.339)
		(end 283.420058 -172.339)
		(width 0.1143)
		(layer "B.Cu")
		(net "HSC_MSB_ALERT_N")
	)
	(segment
		(start 288.29 -112.522)
		(end 267.97 -132.842)
		(width 0.127)
		(layer "In5.Cu")
		(net "HSC_MSB_ALERT_N")
	)
	(segment
		(start 268.732 -153.162)
		(end 268.732 -157.226)
		(width 0.127)
		(layer "In5.Cu")
		(net "HSC_MSB_ALERT_N")
	)
	(segment
		(start 288.29 -93.345)
		(end 288.29 -112.522)
		(width 0.127)
		(layer "In5.Cu")
		(net "HSC_MSB_ALERT_N")
	)
	(segment
		(start 267.97 -132.842)
		(end 267.97 -152.4)
		(width 0.127)
		(layer "In5.Cu")
		(net "HSC_MSB_ALERT_N")
	)
	(segment
		(start 267.97 -152.4)
		(end 268.732 -153.162)
		(width 0.127)
		(layer "In5.Cu")
		(net "HSC_MSB_ALERT_N")
	)
	(segment
		(start 290.23056 -91.40444)
		(end 288.29 -93.345)
		(width 0.127)
		(layer "In5.Cu")
		(net "HSC_MSB_ALERT_N")
	)
	(segment
		(start 266.723368 -159.234632)
		(end 266.723368 -166.383208)
		(width 0.127)
		(layer "In5.Cu")
		(net "HSC_MSB_ALERT_N")
	)
	(segment
		(start 268.732 -157.226)
		(end 266.723368 -159.234632)
		(width 0.127)
		(layer "In5.Cu")
		(net "HSC_MSB_ALERT_N")
	)
	(segment
		(start 121.990612 -221.5515)
		(end 121.871994 -221.5515)
		(width 0.1016)
		(layer "F.Cu")
		(net "REDV_TX7_P")
	)
	(segment
		(start 120.193562 -211.609686)
		(end 120.193562 -206.941166)
		(width 0.1016)
		(layer "F.Cu")
		(net "REDV_TX7_P")
	)
	(segment
		(start 121.3739 -221.269052)
		(end 121.3739 -214.459058)
		(width 0.1016)
		(layer "F.Cu")
		(net "REDV_TX7_P")
	)
	(segment
		(start 120.822974 -206.3115)
		(end 120.847612 -206.3115)
		(width 0.1016)
		(layer "F.Cu")
		(net "REDV_TX7_P")
	)
	(segment
		(start 120.252998 -206.797656)
		(end 120.67921 -206.37119)
		(width 0.1016)
		(layer "F.Cu")
		(net "REDV_TX7_P")
	)
	(arc
		(start 120.67921 -206.37119)
		(mid 120.745141 -206.32701)
		(end 120.822974 -206.3115)
		(width 0.1016)
		(layer "F.Cu")
		(net "REDV_TX7_P")
	)
	(arc
		(start 121.412 -221.361)
		(mid 121.383812 -221.318814)
		(end 121.3739 -221.269052)
		(width 0.1016)
		(layer "F.Cu")
		(net "REDV_TX7_P")
	)
	(arc
		(start 121.871994 -221.5515)
		(mid 121.623061 -221.501984)
		(end 121.412 -221.361)
		(width 0.1016)
		(layer "F.Cu")
		(net "REDV_TX7_P")
	)
	(arc
		(start 120.193562 -206.941166)
		(mid 120.20901 -206.863502)
		(end 120.252998 -206.797656)
		(width 0.1016)
		(layer "F.Cu")
		(net "REDV_TX7_P")
	)
	(arc
		(start 121.3739 -214.459058)
		(mid 121.215733 -213.66428)
		(end 120.76557 -212.99043)
		(width 0.1016)
		(layer "F.Cu")
		(net "REDV_TX7_P")
	)
	(arc
		(start 120.76557 -212.99043)
		(mid 120.342231 -212.356954)
		(end 120.193562 -211.609686)
		(width 0.1016)
		(layer "F.Cu")
		(net "REDV_TX7_P")
	)
	(segment
		(start 117.729 -223.266)
		(end 117.729 -213.750144)
		(width 0.1016)
		(layer "F.Cu")
		(net "REDV_RX7_N")
	)
	(segment
		(start 117.037612 -224.282)
		(end 117.499384 -223.819974)
		(width 0.1016)
		(layer "F.Cu")
		(net "REDV_RX7_N")
	)
	(segment
		(start 116.548662 -210.900518)
		(end 116.548662 -203.835)
		(width 0.1016)
		(layer "F.Cu")
		(net "REDV_RX7_N")
	)
	(segment
		(start 116.447062 -203.7334)
		(end 115.894612 -203.7334)
		(width 0.1016)
		(layer "F.Cu")
		(net "REDV_RX7_N")
	)
	(via
		(at 115.894612 -203.7334)
		(size 0.5588)
		(drill 0.3048)
		(layers "F.Cu" "B.Cu")
		(net "REDV_RX7_N")
	)
	(via
		(at 117.037612 -224.282)
		(size 0.5588)
		(drill 0.3048)
		(layers "F.Cu" "B.Cu")
		(net "REDV_RX7_N")
	)
	(arc
		(start 117.499384 -223.819974)
		(mid 117.669295 -223.565824)
		(end 117.729 -223.266)
		(width 0.1016)
		(layer "F.Cu")
		(net "REDV_RX7_N")
	)
	(arc
		(start 117.729 -213.750144)
		(mid 117.56396 -212.920431)
		(end 117.094 -212.217)
		(width 0.1016)
		(layer "F.Cu")
		(net "REDV_RX7_N")
	)
	(arc
		(start 116.548662 -203.835)
		(mid 116.518904 -203.763158)
		(end 116.447062 -203.7334)
		(width 0.1016)
		(layer "F.Cu")
		(net "REDV_RX7_N")
	)
	(arc
		(start 117.094 -212.217)
		(mid 116.690415 -211.612993)
		(end 116.548662 -210.900518)
		(width 0.1016)
		(layer "F.Cu")
		(net "REDV_RX7_N")
	)
	(segment
		(start 117.037612 -223.3295)
		(end 117.037612 -224.282)
		(width 0.1016)
		(layer "B.Cu")
		(net "REDV_RX7_N")
	)
	(segment
		(start 115.894612 -204.5335)
		(end 115.894612 -203.7334)
		(width 0.1016)
		(layer "B.Cu")
		(net "REDV_RX7_N")
	)
	(segment
		(start 113.669572 -243.372132)
		(end 113.669572 -243.067332)
		(width 0.1016)
		(layer "F.Cu")
		(net "SAS_HDD_CONN_TX8_P")
	)
	(segment
		(start 113.908332 -238.284258)
		(end 113.908332 -237.979458)
		(width 0.1016)
		(layer "F.Cu")
		(net "SAS_HDD_CONN_TX8_P")
	)
	(segment
		(start 113.669572 -253.595378)
		(end 113.669572 -250.453652)
		(width 0.1016)
		(layer "F.Cu")
		(net "SAS_HDD_CONN_TX8_P")
	)
	(segment
		(start 114.362738 -222.4405)
		(end 114.497612 -222.4405)
		(width 0.1016)
		(layer "F.Cu")
		(net "SAS_HDD_CONN_TX8_P")
	)
	(segment
		(start 113.908332 -249.976132)
		(end 113.908332 -249.671332)
		(width 0.1016)
		(layer "F.Cu")
		(net "SAS_HDD_CONN_TX8_P")
	)
	(segment
		(start 113.837212 -225.38563)
		(end 113.837212 -223.000824)
		(width 0.1016)
		(layer "F.Cu")
		(net "SAS_HDD_CONN_TX8_P")
	)
	(segment
		(start 113.669572 -247.629172)
		(end 113.669572 -246.196612)
		(width 0.1016)
		(layer "F.Cu")
		(net "SAS_HDD_CONN_TX8_P")
	)
	(segment
		(start 113.999772 -256.25044)
		(end 113.999772 -254.39243)
		(width 0.1016)
		(layer "F.Cu")
		(net "SAS_HDD_CONN_TX8_P")
	)
	(segment
		(start 113.908332 -248.411492)
		(end 113.908332 -248.106692)
		(width 0.1016)
		(layer "F.Cu")
		(net "SAS_HDD_CONN_TX8_P")
	)
	(segment
		(start 113.669572 -237.501938)
		(end 113.669572 -237.197138)
		(width 0.1016)
		(layer "F.Cu")
		(net "SAS_HDD_CONN_TX8_P")
	)
	(segment
		(start 113.908332 -242.589812)
		(end 113.908332 -242.285012)
		(width 0.1016)
		(layer "F.Cu")
		(net "SAS_HDD_CONN_TX8_P")
	)
	(segment
		(start 113.908332 -236.719618)
		(end 113.908332 -236.414818)
		(width 0.1016)
		(layer "F.Cu")
		(net "SAS_HDD_CONN_TX8_P")
	)
	(segment
		(start 113.669572 -235.937298)
		(end 113.669572 -226.022154)
		(width 0.1016)
		(layer "F.Cu")
		(net "SAS_HDD_CONN_TX8_P")
	)
	(segment
		(start 113.709704 -225.819716)
		(end 113.788698 -225.628962)
		(width 0.1016)
		(layer "F.Cu")
		(net "SAS_HDD_CONN_TX8_P")
	)
	(segment
		(start 113.908332 -244.154452)
		(end 113.908332 -243.849652)
		(width 0.1016)
		(layer "F.Cu")
		(net "SAS_HDD_CONN_TX8_P")
	)
	(segment
		(start 113.669572 -249.193812)
		(end 113.669572 -248.889012)
		(width 0.1016)
		(layer "F.Cu")
		(net "SAS_HDD_CONN_TX8_P")
	)
	(segment
		(start 113.669572 -244.936772)
		(end 113.669572 -244.631972)
		(width 0.1016)
		(layer "F.Cu")
		(net "SAS_HDD_CONN_TX8_P")
	)
	(segment
		(start 113.908332 -245.719092)
		(end 113.908332 -245.414292)
		(width 0.1016)
		(layer "F.Cu")
		(net "SAS_HDD_CONN_TX8_P")
	)
	(segment
		(start 113.669572 -241.807492)
		(end 113.669572 -238.761778)
		(width 0.1016)
		(layer "F.Cu")
		(net "SAS_HDD_CONN_TX8_P")
	)
	(arc
		(start 113.669572 -243.067332)
		(mid 113.700064 -242.933339)
		(end 113.788952 -242.828572)
		(width 0.1016)
		(layer "F.Cu")
		(net "SAS_HDD_CONN_TX8_P")
	)
	(arc
		(start 113.669572 -246.196612)
		(mid 113.700064 -246.062619)
		(end 113.788952 -245.957852)
		(width 0.1016)
		(layer "F.Cu")
		(net "SAS_HDD_CONN_TX8_P")
	)
	(arc
		(start 113.999772 -254.39243)
		(mid 113.957526 -254.180045)
		(end 113.837212 -254)
		(width 0.1016)
		(layer "F.Cu")
		(net "SAS_HDD_CONN_TX8_P")
	)
	(arc
		(start 113.788952 -242.828572)
		(mid 113.87784 -242.723777)
		(end 113.908332 -242.589812)
		(width 0.1016)
		(layer "F.Cu")
		(net "SAS_HDD_CONN_TX8_P")
	)
	(arc
		(start 113.908332 -237.979458)
		(mid 113.87784 -237.845465)
		(end 113.788952 -237.740698)
		(width 0.1016)
		(layer "F.Cu")
		(net "SAS_HDD_CONN_TX8_P")
	)
	(arc
		(start 113.837212 -223.000824)
		(mid 113.885142 -222.759861)
		(end 114.021616 -222.555562)
		(width 0.1016)
		(layer "F.Cu")
		(net "SAS_HDD_CONN_TX8_P")
	)
	(arc
		(start 113.788952 -243.610892)
		(mid 113.700064 -243.506097)
		(end 113.669572 -243.372132)
		(width 0.1016)
		(layer "F.Cu")
		(net "SAS_HDD_CONN_TX8_P")
	)
	(arc
		(start 113.788952 -237.740698)
		(mid 113.700158 -237.635884)
		(end 113.669572 -237.501938)
		(width 0.1016)
		(layer "F.Cu")
		(net "SAS_HDD_CONN_TX8_P")
	)
	(arc
		(start 113.788952 -248.650252)
		(mid 113.87784 -248.545457)
		(end 113.908332 -248.411492)
		(width 0.1016)
		(layer "F.Cu")
		(net "SAS_HDD_CONN_TX8_P")
	)
	(arc
		(start 113.788952 -244.393212)
		(mid 113.87784 -244.288417)
		(end 113.908332 -244.154452)
		(width 0.1016)
		(layer "F.Cu")
		(net "SAS_HDD_CONN_TX8_P")
	)
	(arc
		(start 113.788952 -247.867932)
		(mid 113.700064 -247.763137)
		(end 113.669572 -247.629172)
		(width 0.1016)
		(layer "F.Cu")
		(net "SAS_HDD_CONN_TX8_P")
	)
	(arc
		(start 113.669572 -250.453652)
		(mid 113.700064 -250.319659)
		(end 113.788952 -250.214892)
		(width 0.1016)
		(layer "F.Cu")
		(net "SAS_HDD_CONN_TX8_P")
	)
	(arc
		(start 113.669572 -237.197138)
		(mid 113.700064 -237.063145)
		(end 113.788952 -236.958378)
		(width 0.1016)
		(layer "F.Cu")
		(net "SAS_HDD_CONN_TX8_P")
	)
	(arc
		(start 113.788952 -242.046252)
		(mid 113.700064 -241.941457)
		(end 113.669572 -241.807492)
		(width 0.1016)
		(layer "F.Cu")
		(net "SAS_HDD_CONN_TX8_P")
	)
	(arc
		(start 113.788952 -249.432572)
		(mid 113.700064 -249.327777)
		(end 113.669572 -249.193812)
		(width 0.1016)
		(layer "F.Cu")
		(net "SAS_HDD_CONN_TX8_P")
	)
	(arc
		(start 113.788698 -225.628962)
		(mid 113.824937 -225.509687)
		(end 113.837212 -225.38563)
		(width 0.1016)
		(layer "F.Cu")
		(net "SAS_HDD_CONN_TX8_P")
	)
	(arc
		(start 113.717832 -253.825756)
		(mid 113.695363 -253.765736)
		(end 113.679732 -253.703582)
		(width 0.1016)
		(layer "F.Cu")
		(net "SAS_HDD_CONN_TX8_P")
	)
	(arc
		(start 113.7285 -253.848616)
		(mid 113.727608 -253.846713)
		(end 113.726722 -253.844806)
		(width 0.1016)
		(layer "F.Cu")
		(net "SAS_HDD_CONN_TX8_P")
	)
	(arc
		(start 113.837212 -254)
		(mid 113.776651 -253.928764)
		(end 113.7285 -253.848616)
		(width 0.1016)
		(layer "F.Cu")
		(net "SAS_HDD_CONN_TX8_P")
	)
	(arc
		(start 113.669572 -238.761778)
		(mid 113.700064 -238.627785)
		(end 113.788952 -238.523018)
		(width 0.1016)
		(layer "F.Cu")
		(net "SAS_HDD_CONN_TX8_P")
	)
	(arc
		(start 113.908332 -243.849652)
		(mid 113.87784 -243.715659)
		(end 113.788952 -243.610892)
		(width 0.1016)
		(layer "F.Cu")
		(net "SAS_HDD_CONN_TX8_P")
	)
	(arc
		(start 114.021616 -222.555562)
		(mid 114.182739 -222.470032)
		(end 114.362738 -222.4405)
		(width 0.1016)
		(layer "F.Cu")
		(net "SAS_HDD_CONN_TX8_P")
	)
	(arc
		(start 113.788952 -238.523018)
		(mid 113.877746 -238.418204)
		(end 113.908332 -238.284258)
		(width 0.1016)
		(layer "F.Cu")
		(net "SAS_HDD_CONN_TX8_P")
	)
	(arc
		(start 113.679732 -253.703582)
		(mid 113.678287 -253.696098)
		(end 113.676938 -253.688596)
		(width 0.1016)
		(layer "F.Cu")
		(net "SAS_HDD_CONN_TX8_P")
	)
	(arc
		(start 113.726722 -253.844806)
		(mid 113.72219 -253.835321)
		(end 113.717832 -253.825756)
		(width 0.1016)
		(layer "F.Cu")
		(net "SAS_HDD_CONN_TX8_P")
	)
	(arc
		(start 113.669572 -226.022154)
		(mid 113.679682 -225.918962)
		(end 113.709704 -225.819716)
		(width 0.1016)
		(layer "F.Cu")
		(net "SAS_HDD_CONN_TX8_P")
	)
	(arc
		(start 113.788952 -236.176058)
		(mid 113.700158 -236.071244)
		(end 113.669572 -235.937298)
		(width 0.1016)
		(layer "F.Cu")
		(net "SAS_HDD_CONN_TX8_P")
	)
	(arc
		(start 113.908332 -236.414818)
		(mid 113.87784 -236.280825)
		(end 113.788952 -236.176058)
		(width 0.1016)
		(layer "F.Cu")
		(net "SAS_HDD_CONN_TX8_P")
	)
	(arc
		(start 113.788952 -236.958378)
		(mid 113.877746 -236.853564)
		(end 113.908332 -236.719618)
		(width 0.1016)
		(layer "F.Cu")
		(net "SAS_HDD_CONN_TX8_P")
	)
	(arc
		(start 113.676938 -253.688596)
		(mid 113.671358 -253.642137)
		(end 113.669572 -253.595378)
		(width 0.1016)
		(layer "F.Cu")
		(net "SAS_HDD_CONN_TX8_P")
	)
	(arc
		(start 113.908332 -248.106692)
		(mid 113.87784 -247.972699)
		(end 113.788952 -247.867932)
		(width 0.1016)
		(layer "F.Cu")
		(net "SAS_HDD_CONN_TX8_P")
	)
	(arc
		(start 113.908332 -242.285012)
		(mid 113.87784 -242.151019)
		(end 113.788952 -242.046252)
		(width 0.1016)
		(layer "F.Cu")
		(net "SAS_HDD_CONN_TX8_P")
	)
	(arc
		(start 113.669572 -248.889012)
		(mid 113.700064 -248.755019)
		(end 113.788952 -248.650252)
		(width 0.1016)
		(layer "F.Cu")
		(net "SAS_HDD_CONN_TX8_P")
	)
	(arc
		(start 113.788952 -245.957852)
		(mid 113.87784 -245.853057)
		(end 113.908332 -245.719092)
		(width 0.1016)
		(layer "F.Cu")
		(net "SAS_HDD_CONN_TX8_P")
	)
	(arc
		(start 113.669572 -244.631972)
		(mid 113.700064 -244.497979)
		(end 113.788952 -244.393212)
		(width 0.1016)
		(layer "F.Cu")
		(net "SAS_HDD_CONN_TX8_P")
	)
	(arc
		(start 113.788952 -250.214892)
		(mid 113.87784 -250.110097)
		(end 113.908332 -249.976132)
		(width 0.1016)
		(layer "F.Cu")
		(net "SAS_HDD_CONN_TX8_P")
	)
	(arc
		(start 113.908332 -249.671332)
		(mid 113.87784 -249.537339)
		(end 113.788952 -249.432572)
		(width 0.1016)
		(layer "F.Cu")
		(net "SAS_HDD_CONN_TX8_P")
	)
	(arc
		(start 113.908332 -245.414292)
		(mid 113.87784 -245.280299)
		(end 113.788952 -245.175532)
		(width 0.1016)
		(layer "F.Cu")
		(net "SAS_HDD_CONN_TX8_P")
	)
	(arc
		(start 113.788952 -245.175532)
		(mid 113.700064 -245.070737)
		(end 113.669572 -244.936772)
		(width 0.1016)
		(layer "F.Cu")
		(net "SAS_HDD_CONN_TX8_P")
	)
	(segment
		(start 113.494312 -225.385376)
		(end 113.494312 -222.824548)
		(width 0.1016)
		(layer "F.Cu")
		(net "SAS_HDD_CONN_TX8_N")
	)
	(segment
		(start 113.155222 -254.047244)
		(end 113.227612 -253.9746)
		(width 0.1016)
		(layer "F.Cu")
		(net "SAS_HDD_CONN_TX8_N")
	)
	(segment
		(start 113.227612 -253.9746)
		(end 113.234978 -253.96698)
		(width 0.1016)
		(layer "F.Cu")
		(net "SAS_HDD_CONN_TX8_N")
	)
	(segment
		(start 113.000282 -256.25044)
		(end 113.000282 -254.420878)
		(width 0.1016)
		(layer "F.Cu")
		(net "SAS_HDD_CONN_TX8_N")
	)
	(segment
		(start 113.392712 -225.688398)
		(end 113.471706 -225.497644)
		(width 0.1016)
		(layer "F.Cu")
		(net "SAS_HDD_CONN_TX8_N")
	)
	(segment
		(start 113.471706 -225.497644)
		(end 113.47196 -225.49739)
		(width 0.1016)
		(layer "F.Cu")
		(net "SAS_HDD_CONN_TX8_N")
	)
	(segment
		(start 113.326672 -253.746)
		(end 113.326672 -226.022154)
		(width 0.1016)
		(layer "F.Cu")
		(net "SAS_HDD_CONN_TX8_N")
	)
	(segment
		(start 113.478818 -222.746824)
		(end 113.444528 -222.66402)
		(width 0.1016)
		(layer "F.Cu")
		(net "SAS_HDD_CONN_TX8_N")
	)
	(segment
		(start 112.953292 -222.4405)
		(end 112.846612 -222.4405)
		(width 0.1016)
		(layer "F.Cu")
		(net "SAS_HDD_CONN_TX8_N")
	)
	(segment
		(start 113.318036 -222.548196)
		(end 113.001044 -222.447866)
		(width 0.1016)
		(layer "F.Cu")
		(net "SAS_HDD_CONN_TX8_N")
	)
	(arc
		(start 113.47196 -225.49739)
		(mid 113.488655 -225.442485)
		(end 113.494312 -225.385376)
		(width 0.1016)
		(layer "F.Cu")
		(net "SAS_HDD_CONN_TX8_N")
	)
	(arc
		(start 113.000282 -254.420878)
		(mid 113.017937 -254.292896)
		(end 113.069624 -254.174498)
		(width 0.1016)
		(layer "F.Cu")
		(net "SAS_HDD_CONN_TX8_N")
	)
	(arc
		(start 113.494312 -222.824548)
		(mid 113.49041 -222.784918)
		(end 113.478818 -222.746824)
		(width 0.1016)
		(layer "F.Cu")
		(net "SAS_HDD_CONN_TX8_N")
	)
	(arc
		(start 113.234978 -253.96698)
		(mid 113.302805 -253.865609)
		(end 113.326672 -253.746)
		(width 0.1016)
		(layer "F.Cu")
		(net "SAS_HDD_CONN_TX8_N")
	)
	(arc
		(start 113.138712 -254.086614)
		(mid 113.143048 -254.065283)
		(end 113.155222 -254.047244)
		(width 0.1016)
		(layer "F.Cu")
		(net "SAS_HDD_CONN_TX8_N")
	)
	(arc
		(start 113.069624 -254.174498)
		(mid 113.101557 -254.128503)
		(end 113.138712 -254.086614)
		(width 0.1016)
		(layer "F.Cu")
		(net "SAS_HDD_CONN_TX8_N")
	)
	(arc
		(start 113.001044 -222.447866)
		(mid 112.97745 -222.442353)
		(end 112.953292 -222.4405)
		(width 0.1016)
		(layer "F.Cu")
		(net "SAS_HDD_CONN_TX8_N")
	)
	(arc
		(start 113.326672 -226.022154)
		(mid 113.343277 -225.85203)
		(end 113.392712 -225.688398)
		(width 0.1016)
		(layer "F.Cu")
		(net "SAS_HDD_CONN_TX8_N")
	)
	(arc
		(start 113.444528 -222.66402)
		(mid 113.394102 -222.592104)
		(end 113.318036 -222.548196)
		(width 0.1016)
		(layer "F.Cu")
		(net "SAS_HDD_CONN_TX8_N")
	)
	(segment
		(start 114.497612 -223.3295)
		(end 114.497612 -224.282)
		(width 0.1016)
		(layer "F.Cu")
		(net "SAS_HDD_CONN_SER_TX8_P")
	)
	(via
		(at 114.497612 -224.282)
		(size 0.5588)
		(drill 0.3048)
		(layers "F.Cu" "B.Cu")
		(net "SAS_HDD_CONN_SER_TX8_P")
	)
	(segment
		(start 113.922048 -223.935036)
		(end 114.209576 -224.222564)
		(width 0.1016)
		(layer "B.Cu")
		(net "SAS_HDD_CONN_SER_TX8_P")
	)
	(segment
		(start 115.140486 -216.662)
		(end 115.140486 -217.247216)
		(width 0.1016)
		(layer "B.Cu")
		(net "SAS_HDD_CONN_SER_TX8_P")
	)
	(segment
		(start 114.688112 -219.6465)
		(end 114.130582 -220.20403)
		(width 0.1016)
		(layer "B.Cu")
		(net "SAS_HDD_CONN_SER_TX8_P")
	)
	(segment
		(start 113.862612 -220.853)
		(end 113.862612 -223.753426)
		(width 0.1016)
		(layer "B.Cu")
		(net "SAS_HDD_CONN_SER_TX8_P")
	)
	(segment
		(start 114.353086 -224.282)
		(end 114.497612 -224.282)
		(width 0.1016)
		(layer "B.Cu")
		(net "SAS_HDD_CONN_SER_TX8_P")
	)
	(segment
		(start 115.062 -217.416634)
		(end 115.062 -218.743784)
		(width 0.1016)
		(layer "B.Cu")
		(net "SAS_HDD_CONN_SER_TX8_P")
	)
	(segment
		(start 113.862104 -223.753426)
		(end 113.862612 -223.778826)
		(width 0.1016)
		(layer "B.Cu")
		(net "SAS_HDD_CONN_SER_TX8_P")
	)
	(segment
		(start 113.862612 -223.778826)
		(end 113.862104 -223.778826)
		(width 0.1016)
		(layer "B.Cu")
		(net "SAS_HDD_CONN_SER_TX8_P")
	)
	(segment
		(start 113.862104 -223.778826)
		(end 113.862612 -223.791526)
		(width 0.1016)
		(layer "B.Cu")
		(net "SAS_HDD_CONN_SER_TX8_P")
	)
	(segment
		(start 113.862612 -223.753426)
		(end 113.862104 -223.753426)
		(width 0.1016)
		(layer "B.Cu")
		(net "SAS_HDD_CONN_SER_TX8_P")
	)
	(segment
		(start 115.108228 -217.32494)
		(end 115.094258 -217.33891)
		(width 0.1016)
		(layer "B.Cu")
		(net "SAS_HDD_CONN_SER_TX8_P")
	)
	(arc
		(start 115.140486 -217.247216)
		(mid 115.132099 -217.28929)
		(end 115.108228 -217.32494)
		(width 0.1016)
		(layer "B.Cu")
		(net "SAS_HDD_CONN_SER_TX8_P")
	)
	(arc
		(start 114.209576 -224.222564)
		(mid 114.275419 -224.266559)
		(end 114.353086 -224.282)
		(width 0.1016)
		(layer "B.Cu")
		(net "SAS_HDD_CONN_SER_TX8_P")
	)
	(arc
		(start 115.062 -218.743784)
		(mid 114.964839 -219.232333)
		(end 114.688112 -219.6465)
		(width 0.1016)
		(layer "B.Cu")
		(net "SAS_HDD_CONN_SER_TX8_P")
	)
	(arc
		(start 115.094258 -217.33891)
		(mid 115.070377 -217.374556)
		(end 115.062 -217.416634)
		(width 0.1016)
		(layer "B.Cu")
		(net "SAS_HDD_CONN_SER_TX8_P")
	)
	(arc
		(start 113.862612 -223.791526)
		(mid 113.87806 -223.86919)
		(end 113.922048 -223.935036)
		(width 0.1016)
		(layer "B.Cu")
		(net "SAS_HDD_CONN_SER_TX8_P")
	)
	(arc
		(start 114.130582 -220.20403)
		(mid 113.932221 -220.501936)
		(end 113.862612 -220.853)
		(width 0.1016)
		(layer "B.Cu")
		(net "SAS_HDD_CONN_SER_TX8_P")
	)
	(segment
		(start 112.014 -207.381856)
		(end 112.014 -206.883)
		(width 0.1016)
		(layer "F.Cu")
		(net "REDV_TX8_N")
	)
	(segment
		(start 113.48339 -221.021148)
		(end 113.48339 -210.076288)
		(width 0.1016)
		(layer "F.Cu")
		(net "REDV_TX8_N")
	)
	(segment
		(start 111.4425 -206.3115)
		(end 111.322612 -206.3115)
		(width 0.1016)
		(layer "F.Cu")
		(net "REDV_TX8_N")
	)
	(segment
		(start 113.25225 -209.51825)
		(end 112.649 -208.915)
		(width 0.1016)
		(layer "F.Cu")
		(net "REDV_TX8_N")
	)
	(segment
		(start 113.096548 -221.492064)
		(end 113.423954 -221.164658)
		(width 0.1016)
		(layer "F.Cu")
		(net "REDV_TX8_N")
	)
	(segment
		(start 112.846612 -221.5515)
		(end 112.953038 -221.5515)
		(width 0.1016)
		(layer "F.Cu")
		(net "REDV_TX8_N")
	)
	(arc
		(start 113.48339 -210.076288)
		(mid 113.423317 -209.774283)
		(end 113.25225 -209.51825)
		(width 0.1016)
		(layer "F.Cu")
		(net "REDV_TX8_N")
	)
	(arc
		(start 113.423954 -221.164658)
		(mid 113.467949 -221.098815)
		(end 113.48339 -221.021148)
		(width 0.1016)
		(layer "F.Cu")
		(net "REDV_TX8_N")
	)
	(arc
		(start 112.953038 -221.5515)
		(mid 113.030702 -221.536052)
		(end 113.096548 -221.492064)
		(width 0.1016)
		(layer "F.Cu")
		(net "REDV_TX8_N")
	)
	(arc
		(start 112.649 -208.915)
		(mid 112.178995 -208.211588)
		(end 112.014 -207.381856)
		(width 0.1016)
		(layer "F.Cu")
		(net "REDV_TX8_N")
	)
	(arc
		(start 112.014 -206.883)
		(mid 111.846612 -206.478888)
		(end 111.4425 -206.3115)
		(width 0.1016)
		(layer "F.Cu")
		(net "REDV_TX8_N")
	)
	(segment
		(start 292.2016 -163.0172)
		(end 292.2016 -163.580826)
		(width 0.1143)
		(layer "F.Cu")
		(net "HDD_PRE_INT_R")
	)
	(segment
		(start 292.481 -161.9885)
		(end 292.481 -162.196272)
		(width 0.1143)
		(layer "F.Cu")
		(net "HDD_PRE_INT_R")
	)
	(segment
		(start 292.079426 -163.703)
		(end 292.079426 -165.965886)
		(width 0.1143)
		(layer "F.Cu")
		(net "HDD_PRE_INT_R")
	)
	(segment
		(start 291.673026 -166.372286)
		(end 291.673026 -167.878252)
		(width 0.1143)
		(layer "F.Cu")
		(net "HDD_PRE_INT_R")
	)
	(segment
		(start 291.673026 -167.878252)
		(end 292.034976 -168.240202)
		(width 0.1143)
		(layer "F.Cu")
		(net "HDD_PRE_INT_R")
	)
	(segment
		(start 292.079426 -165.965886)
		(end 291.673026 -166.372286)
		(width 0.1143)
		(layer "F.Cu")
		(net "HDD_PRE_INT_R")
	)
	(segment
		(start 292.481 -162.196272)
		(end 292.2016 -162.475672)
		(width 0.1143)
		(layer "F.Cu")
		(net "HDD_PRE_INT_R")
	)
	(segment
		(start 292.2016 -163.580826)
		(end 292.079426 -163.703)
		(width 0.1143)
		(layer "F.Cu")
		(net "HDD_PRE_INT_R")
	)
	(segment
		(start 292.2016 -162.475672)
		(end 292.2016 -163.0172)
		(width 0.1143)
		(layer "F.Cu")
		(net "HDD_PRE_INT_R")
	)
	(via
		(at 292.2016 -163.0172)
		(size 0.7112)
		(drill 0.3556)
		(layers "F.Cu" "B.Cu")
		(net "HDD_PRE_INT_R")
	)
	(via
		(at 109.443012 -214.0712)
		(size 0.7112)
		(drill 0.3556)
		(layers "F.Cu" "B.Cu")
		(net "REDV_D1_B")
	)
	(segment
		(start 108.465112 -213.868)
		(end 109.239812 -213.868)
		(width 0.1143)
		(layer "B.Cu")
		(net "REDV_D1_B")
	)
	(segment
		(start 109.239812 -213.868)
		(end 109.443012 -214.0712)
		(width 0.1143)
		(layer "B.Cu")
		(net "REDV_D1_B")
	)
	(segment
		(start 110.005876 -214.634064)
		(end 109.443012 -214.0712)
		(width 0.1143)
		(layer "B.Cu")
		(net "REDV_D1_B")
	)
	(segment
		(start 111.119412 -214.634064)
		(end 110.005876 -214.634064)
		(width 0.1143)
		(layer "B.Cu")
		(net "REDV_D1_B")
	)
	(segment
		(start 293.224204 -158.895796)
		(end 293.497 -158.623)
		(width 0.1143)
		(layer "F.Cu")
		(net "BMC_HDD_PRE_INT_N")
	)
	(segment
		(start 292.481 -160.02)
		(end 293.224204 -159.276796)
		(width 0.1143)
		(layer "F.Cu")
		(net "BMC_HDD_PRE_INT_N")
	)
	(segment
		(start 293.224204 -159.276796)
		(end 293.224204 -158.895796)
		(width 0.1143)
		(layer "F.Cu")
		(net "BMC_HDD_PRE_INT_N")
	)
	(segment
		(start 292.481 -161.0995)
		(end 292.481 -160.0835)
		(width 0.1143)
		(layer "F.Cu")
		(net "BMC_HDD_PRE_INT_N")
	)
	(segment
		(start 292.481 -160.0835)
		(end 292.481 -160.02)
		(width 0.1143)
		(layer "F.Cu")
		(net "BMC_HDD_PRE_INT_N")
	)
	(via
		(at 293.497 -158.623)
		(size 0.7112)
		(drill 0.3556)
		(layers "F.Cu" "B.Cu")
		(net "BMC_HDD_PRE_INT_N")
	)
	(via
		(at 111.246412 -218.186)
		(size 0.7112)
		(drill 0.3556)
		(layers "F.Cu" "B.Cu")
		(net "REDV_I2C_SEL1B")
	)
	(segment
		(start 109.773212 -218.694)
		(end 110.281212 -218.186)
		(width 0.1143)
		(layer "B.Cu")
		(net "REDV_I2C_SEL1B")
	)
	(segment
		(start 112.084612 -218.186)
		(end 111.246412 -218.186)
		(width 0.1143)
		(layer "B.Cu")
		(net "REDV_I2C_SEL1B")
	)
	(segment
		(start 112.640618 -217.629994)
		(end 112.084612 -218.186)
		(width 0.1143)
		(layer "B.Cu")
		(net "REDV_I2C_SEL1B")
	)
	(segment
		(start 110.281212 -218.186)
		(end 111.246412 -218.186)
		(width 0.1143)
		(layer "B.Cu")
		(net "REDV_I2C_SEL1B")
	)
	(segment
		(start 108.719112 -218.694)
		(end 109.773212 -218.694)
		(width 0.1143)
		(layer "B.Cu")
		(net "REDV_I2C_SEL1B")
	)
	(segment
		(start 112.640618 -216.662)
		(end 112.640618 -217.629994)
		(width 0.1143)
		(layer "B.Cu")
		(net "REDV_I2C_SEL1B")
	)
	(segment
		(start 108.465112 -218.44)
		(end 108.719112 -218.694)
		(width 0.1143)
		(layer "B.Cu")
		(net "REDV_I2C_SEL1B")
	)
	(segment
		(start 114.062002 -211.88807)
		(end 114.062002 -212.351366)
		(width 0.1016)
		(layer "B.Cu")
		(net "SAS_HDD_REDV_SER_RX8_P")
	)
	(segment
		(start 109.345476 -206.370936)
		(end 109.148118 -206.568294)
		(width 0.1016)
		(layer "B.Cu")
		(net "SAS_HDD_REDV_SER_RX8_P")
	)
	(segment
		(start 109.148118 -207.271366)
		(end 110.638082 -208.76133)
		(width 0.1016)
		(layer "B.Cu")
		(net "SAS_HDD_REDV_SER_RX8_P")
	)
	(segment
		(start 114.140488 -212.520784)
		(end 114.140488 -213.106)
		(width 0.1016)
		(layer "B.Cu")
		(net "SAS_HDD_REDV_SER_RX8_P")
	)
	(segment
		(start 109.088682 -206.711804)
		(end 109.088682 -207.127856)
		(width 0.1016)
		(layer "B.Cu")
		(net "SAS_HDD_REDV_SER_RX8_P")
	)
	(segment
		(start 114.09426 -212.42909)
		(end 114.10823 -212.44306)
		(width 0.1016)
		(layer "B.Cu")
		(net "SAS_HDD_REDV_SER_RX8_P")
	)
	(segment
		(start 111.677704 -209.292952)
		(end 113.913158 -211.528406)
		(width 0.1016)
		(layer "B.Cu")
		(net "SAS_HDD_REDV_SER_RX8_P")
	)
	(segment
		(start 110.638082 -208.76133)
		(end 110.810548 -208.93405)
		(width 0.1016)
		(layer "B.Cu")
		(net "SAS_HDD_REDV_SER_RX8_P")
	)
	(segment
		(start 109.671612 -206.3115)
		(end 109.488986 -206.3115)
		(width 0.1016)
		(layer "B.Cu")
		(net "SAS_HDD_REDV_SER_RX8_P")
	)
	(arc
		(start 109.088682 -207.127856)
		(mid 109.10413 -207.20552)
		(end 109.148118 -207.271366)
		(width 0.1016)
		(layer "B.Cu")
		(net "SAS_HDD_REDV_SER_RX8_P")
	)
	(arc
		(start 114.10823 -212.44306)
		(mid 114.132111 -212.478706)
		(end 114.140488 -212.520784)
		(width 0.1016)
		(layer "B.Cu")
		(net "SAS_HDD_REDV_SER_RX8_P")
	)
	(arc
		(start 109.488986 -206.3115)
		(mid 109.411322 -206.326948)
		(end 109.345476 -206.370936)
		(width 0.1016)
		(layer "B.Cu")
		(net "SAS_HDD_REDV_SER_RX8_P")
	)
	(arc
		(start 113.913158 -211.528406)
		(mid 114.023335 -211.693436)
		(end 114.062002 -211.88807)
		(width 0.1016)
		(layer "B.Cu")
		(net "SAS_HDD_REDV_SER_RX8_P")
	)
	(arc
		(start 109.148118 -206.568294)
		(mid 109.104123 -206.634137)
		(end 109.088682 -206.711804)
		(width 0.1016)
		(layer "B.Cu")
		(net "SAS_HDD_REDV_SER_RX8_P")
	)
	(arc
		(start 110.810548 -208.93405)
		(mid 111.043402 -209.089545)
		(end 111.31804 -209.144108)
		(width 0.1016)
		(layer "B.Cu")
		(net "SAS_HDD_REDV_SER_RX8_P")
	)
	(arc
		(start 114.062002 -212.351366)
		(mid 114.070389 -212.39344)
		(end 114.09426 -212.42909)
		(width 0.1016)
		(layer "B.Cu")
		(net "SAS_HDD_REDV_SER_RX8_P")
	)
	(arc
		(start 111.31804 -209.144108)
		(mid 111.512691 -209.182733)
		(end 111.677704 -209.292952)
		(width 0.1016)
		(layer "B.Cu")
		(net "SAS_HDD_REDV_SER_RX8_P")
	)
	(segment
		(start 305.7525 -151.61768)
		(end 305.77282 -151.59736)
		(width 0.1143)
		(layer "F.Cu")
		(net "125_GTX")
	)
	(segment
		(start 306.7558 -153.797)
		(end 305.7525 -153.797)
		(width 0.1143)
		(layer "F.Cu")
		(net "125_GTX")
	)
	(segment
		(start 305.7525 -153.797)
		(end 305.7525 -151.61768)
		(width 0.1143)
		(layer "F.Cu")
		(net "125_GTX")
	)
	(via
		(at 306.7558 -153.797)
		(size 0.5588)
		(drill 0.3048)
		(layers "F.Cu" "B.Cu")
		(net "125_GTX")
	)
	(via
		(at 306.7558 -152.8572)
		(size 0.7112)
		(drill 0.3556)
		(layers "F.Cu" "B.Cu")
		(net "125_GTX")
	)
	(segment
		(start 306.7558 -152.8572)
		(end 306.7558 -153.797)
		(width 0.1143)
		(layer "B.Cu")
		(net "125_GTX")
	)
	(segment
		(start 309.04688 -144.03832)
		(end 309.04688 -144.40154)
		(width 0.1143)
		(layer "F.Cu")
		(net "OSC_OE")
	)
	(segment
		(start 309.6768 -143.4084)
		(end 309.04688 -144.03832)
		(width 0.1143)
		(layer "F.Cu")
		(net "OSC_OE")
	)
	(segment
		(start 309.97398 -145.32864)
		(end 309.97398 -146.51736)
		(width 0.1143)
		(layer "F.Cu")
		(net "OSC_OE")
	)
	(segment
		(start 309.04688 -144.40154)
		(end 309.97398 -145.32864)
		(width 0.1143)
		(layer "F.Cu")
		(net "OSC_OE")
	)
	(via
		(at 309.6768 -143.4084)
		(size 0.5588)
		(drill 0.3048)
		(layers "F.Cu" "B.Cu")
		(net "OSC_OE")
	)
	(via
		(at 309.7022 -144.2212)
		(size 0.7112)
		(drill 0.3556)
		(layers "F.Cu" "B.Cu")
		(net "OSC_OE")
	)
	(segment
		(start 309.7022 -143.4338)
		(end 309.6768 -143.4084)
		(width 0.1143)
		(layer "B.Cu")
		(net "OSC_OE")
	)
	(segment
		(start 309.7022 -144.2212)
		(end 309.7022 -143.4338)
		(width 0.1143)
		(layer "B.Cu")
		(net "OSC_OE")
	)
	(via
		(at 109.457744 -216.69883)
		(size 0.7112)
		(drill 0.3556)
		(layers "F.Cu" "B.Cu")
		(net "REDV_I2C_A1")
	)
	(segment
		(start 109.189012 -216.154)
		(end 109.468412 -216.4334)
		(width 0.1143)
		(layer "B.Cu")
		(net "REDV_I2C_A1")
	)
	(segment
		(start 109.457744 -216.69883)
		(end 109.468412 -216.688162)
		(width 0.1143)
		(layer "B.Cu")
		(net "REDV_I2C_A1")
	)
	(segment
		(start 111.64062 -216.662)
		(end 109.494574 -216.662)
		(width 0.1143)
		(layer "B.Cu")
		(net "REDV_I2C_A1")
	)
	(segment
		(start 109.468412 -216.4334)
		(end 109.468412 -216.688162)
		(width 0.1143)
		(layer "B.Cu")
		(net "REDV_I2C_A1")
	)
	(segment
		(start 108.465112 -216.154)
		(end 109.189012 -216.154)
		(width 0.1143)
		(layer "B.Cu")
		(net "REDV_I2C_A1")
	)
	(segment
		(start 109.494574 -216.662)
		(end 109.468412 -216.688162)
		(width 0.1143)
		(layer "B.Cu")
		(net "REDV_I2C_A1")
	)
	(segment
		(start 117.545612 -206.3115)
		(end 117.241574 -206.3115)
		(width 0.1016)
		(layer "B.Cu")
		(net "SAS_HDD_REDV_SER_RX7_P")
	)
	(segment
		(start 117.061996 -207.894174)
		(end 117.061996 -212.350858)
		(width 0.1016)
		(layer "B.Cu")
		(net "SAS_HDD_REDV_SER_RX7_P")
	)
	(segment
		(start 117.094254 -212.428836)
		(end 117.108478 -212.44306)
		(width 0.1016)
		(layer "B.Cu")
		(net "SAS_HDD_REDV_SER_RX7_P")
	)
	(segment
		(start 116.8527 -206.700374)
		(end 116.8527 -207.388968)
		(width 0.1016)
		(layer "B.Cu")
		(net "SAS_HDD_REDV_SER_RX7_P")
	)
	(segment
		(start 117.140736 -212.521038)
		(end 117.140736 -213.106)
		(width 0.1016)
		(layer "B.Cu")
		(net "SAS_HDD_REDV_SER_RX7_P")
	)
	(arc
		(start 116.87937 -207.45323)
		(mid 117.014493 -207.655551)
		(end 117.061996 -207.894174)
		(width 0.1016)
		(layer "B.Cu")
		(net "SAS_HDD_REDV_SER_RX7_P")
	)
	(arc
		(start 116.8527 -207.388968)
		(mid 116.859637 -207.423752)
		(end 116.87937 -207.45323)
		(width 0.1016)
		(layer "B.Cu")
		(net "SAS_HDD_REDV_SER_RX7_P")
	)
	(arc
		(start 117.061996 -212.350858)
		(mid 117.070372 -212.393058)
		(end 117.094254 -212.428836)
		(width 0.1016)
		(layer "B.Cu")
		(net "SAS_HDD_REDV_SER_RX7_P")
	)
	(arc
		(start 117.241574 -206.3115)
		(mid 116.966599 -206.425399)
		(end 116.8527 -206.700374)
		(width 0.1016)
		(layer "B.Cu")
		(net "SAS_HDD_REDV_SER_RX7_P")
	)
	(arc
		(start 117.108478 -212.44306)
		(mid 117.13233 -212.478851)
		(end 117.140736 -212.521038)
		(width 0.1016)
		(layer "B.Cu")
		(net "SAS_HDD_REDV_SER_RX7_P")
	)
	(segment
		(start 113.720372 -218.14028)
		(end 113.720372 -217.282268)
		(width 0.1016)
		(layer "B.Cu")
		(net "SAS_HDD_CONN_SER_RX8_N")
	)
	(segment
		(start 110.557056 -220.11767)
		(end 110.942628 -219.731844)
		(width 0.1016)
		(layer "B.Cu")
		(net "SAS_HDD_CONN_SER_RX8_N")
	)
	(segment
		(start 109.94009 -221.448122)
		(end 110.096554 -221.291658)
		(width 0.1016)
		(layer "B.Cu")
		(net "SAS_HDD_CONN_SER_RX8_N")
	)
	(segment
		(start 110.181136 -221.155768)
		(end 110.186978 -221.146878)
		(width 0.1016)
		(layer "B.Cu")
		(net "SAS_HDD_CONN_SER_RX8_N")
	)
	(segment
		(start 110.268512 -220.919548)
		(end 110.268512 -220.632274)
		(width 0.1016)
		(layer "B.Cu")
		(net "SAS_HDD_CONN_SER_RX8_N")
	)
	(segment
		(start 110.268258 -220.919548)
		(end 110.268512 -220.919548)
		(width 0.1016)
		(layer "B.Cu")
		(net "SAS_HDD_CONN_SER_RX8_N")
	)
	(segment
		(start 111.302292 -219.583)
		(end 112.524286 -219.583)
		(width 0.1016)
		(layer "B.Cu")
		(net "SAS_HDD_CONN_SER_RX8_N")
	)
	(segment
		(start 110.20552 -221.11208)
		(end 110.253018 -220.997272)
		(width 0.1016)
		(layer "B.Cu")
		(net "SAS_HDD_CONN_SER_RX8_N")
	)
	(segment
		(start 109.544612 -221.5515)
		(end 109.690662 -221.5515)
		(width 0.1016)
		(layer "B.Cu")
		(net "SAS_HDD_CONN_SER_RX8_N")
	)
	(segment
		(start 112.641126 -219.534486)
		(end 113.497614 -218.677998)
		(width 0.1016)
		(layer "B.Cu")
		(net "SAS_HDD_CONN_SER_RX8_N")
	)
	(segment
		(start 110.428532 -220.246194)
		(end 110.557056 -220.11767)
		(width 0.1016)
		(layer "B.Cu")
		(net "SAS_HDD_CONN_SER_RX8_N")
	)
	(segment
		(start 113.640616 -217.089736)
		(end 113.640616 -216.662)
		(width 0.1016)
		(layer "B.Cu")
		(net "SAS_HDD_CONN_SER_RX8_N")
	)
	(arc
		(start 110.171992 -221.174818)
		(mid 110.175862 -221.164957)
		(end 110.181136 -221.155768)
		(width 0.1016)
		(layer "B.Cu")
		(net "SAS_HDD_CONN_SER_RX8_N")
	)
	(arc
		(start 112.524286 -219.583)
		(mid 112.587511 -219.57033)
		(end 112.641126 -219.534486)
		(width 0.1016)
		(layer "B.Cu")
		(net "SAS_HDD_CONN_SER_RX8_N")
	)
	(arc
		(start 113.680494 -217.186002)
		(mid 113.650982 -217.141835)
		(end 113.640616 -217.089736)
		(width 0.1016)
		(layer "B.Cu")
		(net "SAS_HDD_CONN_SER_RX8_N")
	)
	(arc
		(start 110.186978 -221.146878)
		(mid 110.197099 -221.129932)
		(end 110.20552 -221.11208)
		(width 0.1016)
		(layer "B.Cu")
		(net "SAS_HDD_CONN_SER_RX8_N")
	)
	(arc
		(start 110.268512 -220.632274)
		(mid 110.310096 -220.423305)
		(end 110.428532 -220.246194)
		(width 0.1016)
		(layer "B.Cu")
		(net "SAS_HDD_CONN_SER_RX8_N")
	)
	(arc
		(start 109.690662 -221.5515)
		(mid 109.825661 -221.524629)
		(end 109.94009 -221.448122)
		(width 0.1016)
		(layer "B.Cu")
		(net "SAS_HDD_CONN_SER_RX8_N")
	)
	(arc
		(start 110.942628 -219.731844)
		(mid 111.107658 -219.621667)
		(end 111.302292 -219.583)
		(width 0.1016)
		(layer "B.Cu")
		(net "SAS_HDD_CONN_SER_RX8_N")
	)
	(arc
		(start 110.096554 -221.291658)
		(mid 110.126109 -221.258269)
		(end 110.151418 -221.221554)
		(width 0.1016)
		(layer "B.Cu")
		(net "SAS_HDD_CONN_SER_RX8_N")
	)
	(arc
		(start 113.497614 -218.677998)
		(mid 113.662458 -218.431291)
		(end 113.720372 -218.14028)
		(width 0.1016)
		(layer "B.Cu")
		(net "SAS_HDD_CONN_SER_RX8_N")
	)
	(arc
		(start 113.720372 -217.282268)
		(mid 113.710009 -217.230168)
		(end 113.680494 -217.186002)
		(width 0.1016)
		(layer "B.Cu")
		(net "SAS_HDD_CONN_SER_RX8_N")
	)
	(arc
		(start 110.151418 -221.221554)
		(mid 110.163155 -221.198826)
		(end 110.171992 -221.174818)
		(width 0.1016)
		(layer "B.Cu")
		(net "SAS_HDD_CONN_SER_RX8_N")
	)
	(arc
		(start 110.266226 -220.947742)
		(mid 110.267737 -220.933681)
		(end 110.268258 -220.919548)
		(width 0.1016)
		(layer "B.Cu")
		(net "SAS_HDD_CONN_SER_RX8_N")
	)
	(arc
		(start 110.253018 -220.997272)
		(mid 110.261199 -220.972927)
		(end 110.266226 -220.947742)
		(width 0.1016)
		(layer "B.Cu")
		(net "SAS_HDD_CONN_SER_RX8_N")
	)
	(segment
		(start 176.03597 -66.421)
		(end 176.95037 -67.3354)
		(width 0.127)
		(layer "F.Cu")
		(net "TP_MSB_A41")
	)
	(segment
		(start 179.408328 -71.877682)
		(end 179.408328 -75.709272)
		(width 0.127)
		(layer "F.Cu")
		(net "TP_MSB_A41")
	)
	(segment
		(start 176.95037 -69.419724)
		(end 179.408328 -71.877682)
		(width 0.127)
		(layer "F.Cu")
		(net "TP_MSB_A41")
	)
	(segment
		(start 179.408328 -75.709272)
		(end 179.449476 -75.75042)
		(width 0.127)
		(layer "F.Cu")
		(net "TP_MSB_A41")
	)
	(segment
		(start 176.95037 -67.3354)
		(end 176.95037 -69.419724)
		(width 0.127)
		(layer "F.Cu")
		(net "TP_MSB_A41")
	)
	(via
		(at 122.981212 -215.133936)
		(size 0.7112)
		(drill 0.3556)
		(layers "F.Cu" "B.Cu")
		(net "REDV_D2_A")
	)
	(segment
		(start 120.161812 -215.133936)
		(end 122.981212 -215.133936)
		(width 0.1143)
		(layer "B.Cu")
		(net "REDV_D2_A")
	)
	(segment
		(start 123.574048 -215.133936)
		(end 122.981212 -215.133936)
		(width 0.1143)
		(layer "B.Cu")
		(net "REDV_D2_A")
	)
	(segment
		(start 123.959112 -215.519)
		(end 123.574048 -215.133936)
		(width 0.1143)
		(layer "B.Cu")
		(net "REDV_D2_A")
	)
	(segment
		(start 121.012712 -228.8286)
		(end 121.012712 -222.913956)
		(width 0.1016)
		(layer "F.Cu")
		(net "SAS_HDD_CONN_TX7_N")
	)
	(segment
		(start 120.522238 -222.4405)
		(end 120.339612 -222.4405)
		(width 0.1016)
		(layer "F.Cu")
		(net "SAS_HDD_CONN_TX7_N")
	)
	(segment
		(start 118.179342 -232.66273)
		(end 120.305068 -230.537004)
		(width 0.1016)
		(layer "F.Cu")
		(net "SAS_HDD_CONN_TX7_N")
	)
	(segment
		(start 117.339872 -253.685548)
		(end 117.339872 -234.689396)
		(width 0.1016)
		(layer "F.Cu")
		(net "SAS_HDD_CONN_TX7_N")
	)
	(segment
		(start 116.999512 -256.25044)
		(end 116.999512 -254.507492)
		(width 0.1016)
		(layer "F.Cu")
		(net "SAS_HDD_CONN_TX7_N")
	)
	(arc
		(start 120.850914 -222.523304)
		(mid 120.691712 -222.461516)
		(end 120.522238 -222.4405)
		(width 0.1016)
		(layer "F.Cu")
		(net "SAS_HDD_CONN_TX7_N")
	)
	(arc
		(start 117.169692 -254.09652)
		(mid 117.295627 -253.90795)
		(end 117.339872 -253.685548)
		(width 0.1016)
		(layer "F.Cu")
		(net "SAS_HDD_CONN_TX7_N")
	)
	(arc
		(start 120.305068 -230.537004)
		(mid 120.828801 -229.753182)
		(end 121.012712 -228.8286)
		(width 0.1016)
		(layer "F.Cu")
		(net "SAS_HDD_CONN_TX7_N")
	)
	(arc
		(start 116.999512 -254.507492)
		(mid 117.043735 -254.285081)
		(end 117.169692 -254.09652)
		(width 0.1016)
		(layer "F.Cu")
		(net "SAS_HDD_CONN_TX7_N")
	)
	(arc
		(start 121.012712 -222.913956)
		(mid 120.970659 -222.702543)
		(end 120.850914 -222.523304)
		(width 0.1016)
		(layer "F.Cu")
		(net "SAS_HDD_CONN_TX7_N")
	)
	(arc
		(start 117.339872 -234.689396)
		(mid 117.558029 -233.592559)
		(end 118.179342 -232.66273)
		(width 0.1016)
		(layer "F.Cu")
		(net "SAS_HDD_CONN_TX7_N")
	)
	(via
		(at 122.905012 -213.1822)
		(size 0.7112)
		(drill 0.3556)
		(layers "F.Cu" "B.Cu")
		(net "REDV_I2C_SEL2A")
	)
	(segment
		(start 121.533412 -213.1822)
		(end 122.905012 -213.1822)
		(width 0.1143)
		(layer "B.Cu")
		(net "REDV_I2C_SEL2A")
	)
	(segment
		(start 123.565412 -213.36)
		(end 123.387612 -213.1822)
		(width 0.1143)
		(layer "B.Cu")
		(net "REDV_I2C_SEL2A")
	)
	(segment
		(start 123.387612 -213.1822)
		(end 122.905012 -213.1822)
		(width 0.1143)
		(layer "B.Cu")
		(net "REDV_I2C_SEL2A")
	)
	(segment
		(start 123.959112 -213.36)
		(end 123.565412 -213.36)
		(width 0.1143)
		(layer "B.Cu")
		(net "REDV_I2C_SEL2A")
	)
	(segment
		(start 120.161812 -214.133938)
		(end 120.581674 -214.133938)
		(width 0.1143)
		(layer "B.Cu")
		(net "REDV_I2C_SEL2A")
	)
	(segment
		(start 120.581674 -214.133938)
		(end 121.533412 -213.1822)
		(width 0.1143)
		(layer "B.Cu")
		(net "REDV_I2C_SEL2A")
	)
	(segment
		(start 116.64061 -217.24747)
		(end 116.64061 -216.662)
		(width 0.1016)
		(layer "B.Cu")
		(net "SAS_HDD_CONN_SER_RX7_N")
	)
	(segment
		(start 117.389148 -221.492064)
		(end 117.551454 -221.329758)
		(width 0.1016)
		(layer "B.Cu")
		(net "SAS_HDD_CONN_SER_RX7_N")
	)
	(segment
		(start 117.464332 -219.66428)
		(end 117.108224 -219.308172)
		(width 0.1016)
		(layer "B.Cu")
		(net "SAS_HDD_CONN_SER_RX7_N")
	)
	(segment
		(start 116.686838 -217.339164)
		(end 116.672868 -217.325194)
		(width 0.1016)
		(layer "B.Cu")
		(net "SAS_HDD_CONN_SER_RX7_N")
	)
	(segment
		(start 117.61089 -220.017594)
		(end 117.610636 -220.017848)
		(width 0.1016)
		(layer "B.Cu")
		(net "SAS_HDD_CONN_SER_RX7_N")
	)
	(segment
		(start 116.719096 -218.440254)
		(end 116.719096 -217.416888)
		(width 0.1016)
		(layer "B.Cu")
		(net "SAS_HDD_CONN_SER_RX7_N")
	)
	(segment
		(start 117.61089 -221.186248)
		(end 117.61089 -220.017594)
		(width 0.1016)
		(layer "B.Cu")
		(net "SAS_HDD_CONN_SER_RX7_N")
	)
	(segment
		(start 117.108224 -219.308172)
		(end 117.057424 -219.257118)
		(width 0.1016)
		(layer "B.Cu")
		(net "SAS_HDD_CONN_SER_RX7_N")
	)
	(segment
		(start 117.037612 -221.5515)
		(end 117.245638 -221.5515)
		(width 0.1016)
		(layer "B.Cu")
		(net "SAS_HDD_CONN_SER_RX7_N")
	)
	(arc
		(start 116.672868 -217.325194)
		(mid 116.648987 -217.289548)
		(end 116.64061 -217.24747)
		(width 0.1016)
		(layer "B.Cu")
		(net "SAS_HDD_CONN_SER_RX7_N")
	)
	(arc
		(start 116.719096 -217.416888)
		(mid 116.710709 -217.374814)
		(end 116.686838 -217.339164)
		(width 0.1016)
		(layer "B.Cu")
		(net "SAS_HDD_CONN_SER_RX7_N")
	)
	(arc
		(start 117.551454 -221.329758)
		(mid 117.595449 -221.263915)
		(end 117.61089 -221.186248)
		(width 0.1016)
		(layer "B.Cu")
		(net "SAS_HDD_CONN_SER_RX7_N")
	)
	(arc
		(start 117.245638 -221.5515)
		(mid 117.323302 -221.536052)
		(end 117.389148 -221.492064)
		(width 0.1016)
		(layer "B.Cu")
		(net "SAS_HDD_CONN_SER_RX7_N")
	)
	(arc
		(start 117.057424 -219.257118)
		(mid 116.807082 -218.88231)
		(end 116.719096 -218.440254)
		(width 0.1016)
		(layer "B.Cu")
		(net "SAS_HDD_CONN_SER_RX7_N")
	)
	(arc
		(start 117.610636 -220.017848)
		(mid 117.572668 -219.826502)
		(end 117.464332 -219.66428)
		(width 0.1016)
		(layer "B.Cu")
		(net "SAS_HDD_CONN_SER_RX7_N")
	)
	(via
		(at 109.549692 -211.50834)
		(size 0.7112)
		(drill 0.3556)
		(layers "F.Cu" "B.Cu")
		(net "REDV_D2_B")
	)
	(segment
		(start 112.140492 -212.39988)
		(end 111.379762 -211.63915)
		(width 0.1143)
		(layer "B.Cu")
		(net "REDV_D2_B")
	)
	(segment
		(start 109.470952 -211.582)
		(end 109.544612 -211.50834)
		(width 0.1143)
		(layer "B.Cu")
		(net "REDV_D2_B")
	)
	(segment
		(start 112.140492 -213.106)
		(end 112.140492 -212.39988)
		(width 0.1143)
		(layer "B.Cu")
		(net "REDV_D2_B")
	)
	(segment
		(start 111.379762 -211.63915)
		(end 109.680502 -211.63915)
		(width 0.1143)
		(layer "B.Cu")
		(net "REDV_D2_B")
	)
	(segment
		(start 109.680502 -211.63915)
		(end 109.549692 -211.50834)
		(width 0.1143)
		(layer "B.Cu")
		(net "REDV_D2_B")
	)
	(segment
		(start 108.465112 -211.582)
		(end 109.470952 -211.582)
		(width 0.1143)
		(layer "B.Cu")
		(net "REDV_D2_B")
	)
	(segment
		(start 109.544612 -211.50834)
		(end 109.549692 -211.50834)
		(width 0.1143)
		(layer "B.Cu")
		(net "REDV_D2_B")
	)
	(via
		(at 109.592364 -218.075002)
		(size 0.7112)
		(drill 0.3556)
		(layers "F.Cu" "B.Cu")
		(net "REDV_I2C_SEL2B")
	)
	(segment
		(start 108.465112 -217.297)
		(end 109.243114 -218.075002)
		(width 0.1143)
		(layer "B.Cu")
		(net "REDV_I2C_SEL2B")
	)
	(segment
		(start 109.243114 -218.075002)
		(end 109.592364 -218.075002)
		(width 0.1143)
		(layer "B.Cu")
		(net "REDV_I2C_SEL2B")
	)
	(segment
		(start 111.942372 -217.36812)
		(end 110.464092 -217.36812)
		(width 0.1143)
		(layer "B.Cu")
		(net "REDV_I2C_SEL2B")
	)
	(segment
		(start 110.464092 -217.36812)
		(end 109.75721 -218.075002)
		(width 0.1143)
		(layer "B.Cu")
		(net "REDV_I2C_SEL2B")
	)
	(segment
		(start 112.140492 -217.17)
		(end 111.942372 -217.36812)
		(width 0.1143)
		(layer "B.Cu")
		(net "REDV_I2C_SEL2B")
	)
	(segment
		(start 109.75721 -218.075002)
		(end 109.592364 -218.075002)
		(width 0.1143)
		(layer "B.Cu")
		(net "REDV_I2C_SEL2B")
	)
	(segment
		(start 112.140492 -216.662)
		(end 112.140492 -217.17)
		(width 0.1143)
		(layer "B.Cu")
		(net "REDV_I2C_SEL2B")
	)
	(segment
		(start 111.001556 -221.537022)
		(end 110.704376 -221.413832)
		(width 0.1016)
		(layer "B.Cu")
		(net "SAS_HDD_CONN_SER_RX8_P")
	)
	(segment
		(start 111.195612 -221.5515)
		(end 111.074962 -221.5515)
		(width 0.1016)
		(layer "B.Cu")
		(net "SAS_HDD_CONN_SER_RX8_P")
	)
	(segment
		(start 111.302292 -219.9259)
		(end 112.524286 -219.9259)
		(width 0.1016)
		(layer "B.Cu")
		(net "SAS_HDD_CONN_SER_RX8_P")
	)
	(segment
		(start 110.671102 -220.488764)
		(end 110.92815 -220.231462)
		(width 0.1016)
		(layer "B.Cu")
		(net "SAS_HDD_CONN_SER_RX8_P")
	)
	(segment
		(start 112.883696 -219.777056)
		(end 113.740184 -218.920568)
		(width 0.1016)
		(layer "B.Cu")
		(net "SAS_HDD_CONN_SER_RX8_P")
	)
	(segment
		(start 110.611412 -221.293436)
		(end 110.611412 -220.632528)
		(width 0.1016)
		(layer "B.Cu")
		(net "SAS_HDD_CONN_SER_RX8_P")
	)
	(segment
		(start 114.063272 -218.140534)
		(end 114.063272 -217.27033)
		(width 0.1016)
		(layer "B.Cu")
		(net "SAS_HDD_CONN_SER_RX8_P")
	)
	(segment
		(start 110.92815 -220.231462)
		(end 111.185198 -219.974414)
		(width 0.1016)
		(layer "B.Cu")
		(net "SAS_HDD_CONN_SER_RX8_P")
	)
	(segment
		(start 110.611412 -220.632528)
		(end 110.611666 -220.632274)
		(width 0.1016)
		(layer "B.Cu")
		(net "SAS_HDD_CONN_SER_RX8_P")
	)
	(segment
		(start 114.140488 -217.083894)
		(end 114.140488 -216.662)
		(width 0.1016)
		(layer "B.Cu")
		(net "SAS_HDD_CONN_SER_RX8_P")
	)
	(arc
		(start 111.074962 -221.5515)
		(mid 111.037549 -221.547866)
		(end 111.001556 -221.537022)
		(width 0.1016)
		(layer "B.Cu")
		(net "SAS_HDD_CONN_SER_RX8_P")
	)
	(arc
		(start 110.704376 -221.413832)
		(mid 110.658182 -221.384809)
		(end 110.624112 -221.342204)
		(width 0.1016)
		(layer "B.Cu")
		(net "SAS_HDD_CONN_SER_RX8_P")
	)
	(arc
		(start 111.185198 -219.974414)
		(mid 111.238921 -219.938517)
		(end 111.302292 -219.9259)
		(width 0.1016)
		(layer "B.Cu")
		(net "SAS_HDD_CONN_SER_RX8_P")
	)
	(arc
		(start 112.524286 -219.9259)
		(mid 112.718786 -219.887211)
		(end 112.883696 -219.777056)
		(width 0.1016)
		(layer "B.Cu")
		(net "SAS_HDD_CONN_SER_RX8_P")
	)
	(arc
		(start 110.611666 -220.632274)
		(mid 110.627114 -220.55461)
		(end 110.671102 -220.488764)
		(width 0.1016)
		(layer "B.Cu")
		(net "SAS_HDD_CONN_SER_RX8_P")
	)
	(arc
		(start 110.624112 -221.342204)
		(mid 110.614648 -221.318632)
		(end 110.611412 -221.293436)
		(width 0.1016)
		(layer "B.Cu")
		(net "SAS_HDD_CONN_SER_RX8_P")
	)
	(arc
		(start 113.740184 -218.920568)
		(mid 113.97926 -218.562671)
		(end 114.063272 -218.140534)
		(width 0.1016)
		(layer "B.Cu")
		(net "SAS_HDD_CONN_SER_RX8_P")
	)
	(arc
		(start 114.063272 -217.27033)
		(mid 114.073307 -217.219882)
		(end 114.10188 -217.177112)
		(width 0.1016)
		(layer "B.Cu")
		(net "SAS_HDD_CONN_SER_RX8_P")
	)
	(arc
		(start 114.10188 -217.177112)
		(mid 114.130457 -217.134343)
		(end 114.140488 -217.083894)
		(width 0.1016)
		(layer "B.Cu")
		(net "SAS_HDD_CONN_SER_RX8_P")
	)
	(segment
		(start 123.959112 -218.821)
		(end 122.727212 -218.821)
		(width 0.1143)
		(layer "B.Cu")
		(net "REDV_PD#")
	)
	(segment
		(start 119.958612 -218.821)
		(end 119.140732 -218.00312)
		(width 0.1143)
		(layer "B.Cu")
		(net "REDV_PD#")
	)
	(segment
		(start 119.140732 -218.00312)
		(end 119.140732 -216.662)
		(width 0.1143)
		(layer "B.Cu")
		(net "REDV_PD#")
	)
	(segment
		(start 122.727212 -218.821)
		(end 119.958612 -218.821)
		(width 0.1143)
		(layer "B.Cu")
		(net "REDV_PD#")
	)
	(segment
		(start 111.322612 -204.5335)
		(end 111.322612 -203.7334)
		(width 0.1016)
		(layer "F.Cu")
		(net "SAS_HDD_REDV_SER_TX8_N")
	)
	(via
		(at 111.322612 -203.7334)
		(size 0.5588)
		(drill 0.3048)
		(layers "F.Cu" "B.Cu")
		(net "SAS_HDD_REDV_SER_TX8_N")
	)
	(segment
		(start 111.882174 -207.1116)
		(end 111.882428 -207.1116)
		(width 0.1016)
		(layer "B.Cu")
		(net "SAS_HDD_REDV_SER_TX8_N")
	)
	(segment
		(start 111.882428 -207.1116)
		(end 111.882428 -204.19949)
		(width 0.1016)
		(layer "B.Cu")
		(net "SAS_HDD_REDV_SER_TX8_N")
	)
	(segment
		(start 114.670586 -210.611974)
		(end 113.402364 -209.344006)
		(width 0.1016)
		(layer "B.Cu")
		(net "SAS_HDD_REDV_SER_TX8_N")
	)
	(segment
		(start 112.833658 -208.7753)
		(end 112.385856 -208.327752)
		(width 0.1016)
		(layer "B.Cu")
		(net "SAS_HDD_REDV_SER_TX8_N")
	)
	(segment
		(start 114.7191 -212.351366)
		(end 114.7191 -210.728814)
		(width 0.1016)
		(layer "B.Cu")
		(net "SAS_HDD_REDV_SER_TX8_N")
	)
	(segment
		(start 111.416338 -203.7334)
		(end 111.322612 -203.7334)
		(width 0.1016)
		(layer "B.Cu")
		(net "SAS_HDD_REDV_SER_TX8_N")
	)
	(segment
		(start 114.640614 -213.106)
		(end 114.640614 -212.520784)
		(width 0.1016)
		(layer "B.Cu")
		(net "SAS_HDD_REDV_SER_TX8_N")
	)
	(segment
		(start 111.822992 -204.05598)
		(end 111.559848 -203.792836)
		(width 0.1016)
		(layer "B.Cu")
		(net "SAS_HDD_REDV_SER_TX8_N")
	)
	(segment
		(start 113.402364 -209.344006)
		(end 112.833658 -208.7753)
		(width 0.1016)
		(layer "B.Cu")
		(net "SAS_HDD_REDV_SER_TX8_N")
	)
	(segment
		(start 114.672872 -212.44306)
		(end 114.686842 -212.42909)
		(width 0.1016)
		(layer "B.Cu")
		(net "SAS_HDD_REDV_SER_TX8_N")
	)
	(arc
		(start 114.7191 -210.728814)
		(mid 114.70643 -210.665589)
		(end 114.670586 -210.611974)
		(width 0.1016)
		(layer "B.Cu")
		(net "SAS_HDD_REDV_SER_TX8_N")
	)
	(arc
		(start 111.882428 -204.19949)
		(mid 111.86698 -204.121826)
		(end 111.822992 -204.05598)
		(width 0.1016)
		(layer "B.Cu")
		(net "SAS_HDD_REDV_SER_TX8_N")
	)
	(arc
		(start 112.385856 -208.327752)
		(mid 112.013029 -207.769777)
		(end 111.882174 -207.1116)
		(width 0.1016)
		(layer "B.Cu")
		(net "SAS_HDD_REDV_SER_TX8_N")
	)
	(arc
		(start 114.686842 -212.42909)
		(mid 114.710723 -212.393444)
		(end 114.7191 -212.351366)
		(width 0.1016)
		(layer "B.Cu")
		(net "SAS_HDD_REDV_SER_TX8_N")
	)
	(arc
		(start 111.559848 -203.792836)
		(mid 111.494005 -203.748841)
		(end 111.416338 -203.7334)
		(width 0.1016)
		(layer "B.Cu")
		(net "SAS_HDD_REDV_SER_TX8_N")
	)
	(arc
		(start 114.640614 -212.520784)
		(mid 114.649001 -212.47871)
		(end 114.672872 -212.44306)
		(width 0.1016)
		(layer "B.Cu")
		(net "SAS_HDD_REDV_SER_TX8_N")
	)
	(segment
		(start 112.973612 -204.5335)
		(end 112.973612 -203.7334)
		(width 0.1016)
		(layer "F.Cu")
		(net "SAS_HDD_REDV_SER_TX8_P")
	)
	(via
		(at 112.973612 -203.7334)
		(size 0.5588)
		(drill 0.3048)
		(layers "F.Cu" "B.Cu")
		(net "SAS_HDD_REDV_SER_TX8_P")
	)
	(segment
		(start 112.284764 -204.346048)
		(end 112.843564 -203.787248)
		(width 0.1016)
		(layer "B.Cu")
		(net "SAS_HDD_REDV_SER_TX8_P")
	)
	(segment
		(start 115.140486 -213.106)
		(end 115.140486 -212.520784)
		(width 0.1016)
		(layer "B.Cu")
		(net "SAS_HDD_REDV_SER_TX8_P")
	)
	(segment
		(start 115.062 -212.351366)
		(end 115.062 -210.72856)
		(width 0.1016)
		(layer "B.Cu")
		(net "SAS_HDD_REDV_SER_TX8_P")
	)
	(segment
		(start 113.076228 -208.53273)
		(end 112.628426 -208.085182)
		(width 0.1016)
		(layer "B.Cu")
		(net "SAS_HDD_REDV_SER_TX8_P")
	)
	(segment
		(start 112.225328 -207.1116)
		(end 112.225328 -204.489558)
		(width 0.1016)
		(layer "B.Cu")
		(net "SAS_HDD_REDV_SER_TX8_P")
	)
	(segment
		(start 114.913156 -210.369404)
		(end 113.076482 -208.53273)
		(width 0.1016)
		(layer "B.Cu")
		(net "SAS_HDD_REDV_SER_TX8_P")
	)
	(segment
		(start 115.108228 -212.44306)
		(end 115.094258 -212.42909)
		(width 0.1016)
		(layer "B.Cu")
		(net "SAS_HDD_REDV_SER_TX8_P")
	)
	(segment
		(start 113.076482 -208.53273)
		(end 113.076228 -208.53273)
		(width 0.1016)
		(layer "B.Cu")
		(net "SAS_HDD_REDV_SER_TX8_P")
	)
	(arc
		(start 115.140486 -212.520784)
		(mid 115.132099 -212.47871)
		(end 115.108228 -212.44306)
		(width 0.1016)
		(layer "B.Cu")
		(net "SAS_HDD_REDV_SER_TX8_P")
	)
	(arc
		(start 112.628426 -208.085182)
		(mid 112.330045 -207.638484)
		(end 112.225328 -207.1116)
		(width 0.1016)
		(layer "B.Cu")
		(net "SAS_HDD_REDV_SER_TX8_P")
	)
	(arc
		(start 112.843564 -203.787248)
		(mid 112.903231 -203.74738)
		(end 112.973612 -203.7334)
		(width 0.1016)
		(layer "B.Cu")
		(net "SAS_HDD_REDV_SER_TX8_P")
	)
	(arc
		(start 115.062 -210.72856)
		(mid 115.023263 -210.534196)
		(end 114.913156 -210.369404)
		(width 0.1016)
		(layer "B.Cu")
		(net "SAS_HDD_REDV_SER_TX8_P")
	)
	(arc
		(start 115.094258 -212.42909)
		(mid 115.070377 -212.393444)
		(end 115.062 -212.351366)
		(width 0.1016)
		(layer "B.Cu")
		(net "SAS_HDD_REDV_SER_TX8_P")
	)
	(arc
		(start 112.225328 -204.489558)
		(mid 112.240776 -204.411894)
		(end 112.284764 -204.346048)
		(width 0.1016)
		(layer "B.Cu")
		(net "SAS_HDD_REDV_SER_TX8_P")
	)
	(segment
		(start 320.338958 -57.404)
		(end 319.338452 -57.404)
		(width 0.1143)
		(layer "F.Cu")
		(net "NCSI_10G_RCLK")
	)
	(segment
		(start 299.703236 -156.126688)
		(end 301.033688 -156.126688)
		(width 0.1143)
		(layer "F.Cu")
		(net "NCSI_10G_RCLK")
	)
	(segment
		(start 301.033688 -156.126688)
		(end 301.244 -156.337)
		(width 0.1143)
		(layer "F.Cu")
		(net "NCSI_10G_RCLK")
	)
	(segment
		(start 321.989958 -59.055)
		(end 320.338958 -57.404)
		(width 0.1143)
		(layer "F.Cu")
		(net "NCSI_10G_RCLK")
	)
	(via
		(at 303.419256 -134.857744)
		(size 0.5588)
		(drill 0.3048)
		(layers "F.Cu" "B.Cu")
		(net "NCSI_10G_RCLK")
	)
	(via
		(at 321.989958 -59.055)
		(size 0.5588)
		(drill 0.3048)
		(layers "F.Cu" "B.Cu")
		(net "NCSI_10G_RCLK")
	)
	(via
		(at 301.244 -156.337)
		(size 0.5588)
		(drill 0.3048)
		(layers "F.Cu" "B.Cu")
		(net "NCSI_10G_RCLK")
	)
	(via
		(at 320.338958 -57.404)
		(size 0.7112)
		(drill 0.3556)
		(layers "F.Cu" "B.Cu")
		(net "NCSI_10G_RCLK")
	)
	(segment
		(start 301.5107 -135.414766)
		(end 301.5107 -135.386318)
		(width 0.127)
		(layer "In2.Cu")
		(net "NCSI_10G_RCLK")
	)
	(segment
		(start 301.5107 -135.386318)
		(end 301.800768 -135.09625)
		(width 0.127)
		(layer "In2.Cu")
		(net "NCSI_10G_RCLK")
	)
	(segment
		(start 301.244 -156.337)
		(end 301.7647 -155.8163)
		(width 0.127)
		(layer "In2.Cu")
		(net "NCSI_10G_RCLK")
	)
	(segment
		(start 301.7647 -155.8163)
		(end 301.7647 -140.8557)
		(width 0.127)
		(layer "In2.Cu")
		(net "NCSI_10G_RCLK")
	)
	(segment
		(start 300.6217 -139.7127)
		(end 300.6217 -136.303766)
		(width 0.127)
		(layer "In2.Cu")
		(net "NCSI_10G_RCLK")
	)
	(segment
		(start 301.800768 -135.09625)
		(end 301.829216 -135.09625)
		(width 0.127)
		(layer "In2.Cu")
		(net "NCSI_10G_RCLK")
	)
	(segment
		(start 301.829216 -135.09625)
		(end 302.067722 -134.857744)
		(width 0.127)
		(layer "In2.Cu")
		(net "NCSI_10G_RCLK")
	)
	(segment
		(start 301.7647 -140.8557)
		(end 300.6217 -139.7127)
		(width 0.127)
		(layer "In2.Cu")
		(net "NCSI_10G_RCLK")
	)
	(segment
		(start 302.067722 -134.857744)
		(end 303.419256 -134.857744)
		(width 0.127)
		(layer "In2.Cu")
		(net "NCSI_10G_RCLK")
	)
	(segment
		(start 300.6217 -136.303766)
		(end 301.5107 -135.414766)
		(width 0.127)
		(layer "In2.Cu")
		(net "NCSI_10G_RCLK")
	)
	(segment
		(start 324.231 -61.296042)
		(end 324.231 -84.241132)
		(width 0.127)
		(layer "In5.Cu")
		(net "NCSI_10G_RCLK")
	)
	(segment
		(start 314.1091 -90.6145)
		(end 312.9153 -91.8083)
		(width 0.127)
		(layer "In5.Cu")
		(net "NCSI_10G_RCLK")
	)
	(segment
		(start 312.9153 -91.8083)
		(end 310.759602 -91.8083)
		(width 0.127)
		(layer "In5.Cu")
		(net "NCSI_10G_RCLK")
	)
	(segment
		(start 305.1683 -108.873798)
		(end 305.054 -108.988098)
		(width 0.127)
		(layer "In5.Cu")
		(net "NCSI_10G_RCLK")
	)
	(segment
		(start 319.024 -87.122)
		(end 315.5315 -90.6145)
		(width 0.127)
		(layer "In5.Cu")
		(net "NCSI_10G_RCLK")
	)
	(segment
		(start 305.054 -133.223)
		(end 303.419256 -134.857744)
		(width 0.127)
		(layer "In5.Cu")
		(net "NCSI_10G_RCLK")
	)
	(segment
		(start 315.5315 -90.6145)
		(end 314.1091 -90.6145)
		(width 0.127)
		(layer "In5.Cu")
		(net "NCSI_10G_RCLK")
	)
	(segment
		(start 321.350132 -87.122)
		(end 319.024 -87.122)
		(width 0.127)
		(layer "In5.Cu")
		(net "NCSI_10G_RCLK")
	)
	(segment
		(start 305.054 -108.988098)
		(end 305.054 -133.223)
		(width 0.127)
		(layer "In5.Cu")
		(net "NCSI_10G_RCLK")
	)
	(segment
		(start 310.759602 -91.8083)
		(end 305.1683 -97.399602)
		(width 0.127)
		(layer "In5.Cu")
		(net "NCSI_10G_RCLK")
	)
	(segment
		(start 321.989958 -59.055)
		(end 324.231 -61.296042)
		(width 0.127)
		(layer "In5.Cu")
		(net "NCSI_10G_RCLK")
	)
	(segment
		(start 305.1683 -97.399602)
		(end 305.1683 -108.873798)
		(width 0.127)
		(layer "In5.Cu")
		(net "NCSI_10G_RCLK")
	)
	(segment
		(start 324.231 -84.241132)
		(end 321.350132 -87.122)
		(width 0.127)
		(layer "In5.Cu")
		(net "NCSI_10G_RCLK")
	)
	(segment
		(start 308.675024 -62.00013)
		(end 306.7558 -62.00013)
		(width 0.1143)
		(layer "F.Cu")
		(net "NCSI_10G_RX_ER_R")
	)
	(segment
		(start 304.546 -62.865)
		(end 303.765458 -62.865)
		(width 0.1143)
		(layer "F.Cu")
		(net "NCSI_10G_RX_ER_R")
	)
	(segment
		(start 305.41087 -62.00013)
		(end 304.546 -62.865)
		(width 0.1143)
		(layer "F.Cu")
		(net "NCSI_10G_RX_ER_R")
	)
	(segment
		(start 306.7558 -62.00013)
		(end 305.41087 -62.00013)
		(width 0.1143)
		(layer "F.Cu")
		(net "NCSI_10G_RX_ER_R")
	)
	(via
		(at 306.7558 -62.00013)
		(size 0.7112)
		(drill 0.3556)
		(layers "F.Cu" "B.Cu")
		(net "NCSI_10G_RX_ER_R")
	)
	(segment
		(start 288.315908 -148.03755)
		(end 289.18535 -148.03755)
		(width 0.1143)
		(layer "F.Cu")
		(net "NCSI_10G_RX_ER")
	)
	(segment
		(start 302.876458 -62.865)
		(end 302.006 -62.865)
		(width 0.1143)
		(layer "F.Cu")
		(net "NCSI_10G_RX_ER")
	)
	(segment
		(start 296.034968 -169.040048)
		(end 296.034968 -169.0497)
		(width 0.1143)
		(layer "F.Cu")
		(net "NCSI_10G_RX_ER")
	)
	(segment
		(start 266.5095 -90.7415)
		(end 272.8722 -97.1042)
		(width 0.1143)
		(layer "F.Cu")
		(net "NCSI_10G_RX_ER")
	)
	(segment
		(start 266.5095 -86.038436)
		(end 266.5095 -90.7415)
		(width 0.1143)
		(layer "F.Cu")
		(net "NCSI_10G_RX_ER")
	)
	(segment
		(start 244.348 -63.881)
		(end 244.851682 -64.384682)
		(width 0.1143)
		(layer "F.Cu")
		(net "NCSI_10G_RX_ER")
	)
	(segment
		(start 272.8722 -119.888)
		(end 279.76195 -126.77775)
		(width 0.1143)
		(layer "F.Cu")
		(net "NCSI_10G_RX_ER")
	)
	(segment
		(start 244.855746 -64.384682)
		(end 266.5095 -86.038436)
		(width 0.1143)
		(layer "F.Cu")
		(net "NCSI_10G_RX_ER")
	)
	(segment
		(start 296.034968 -169.0497)
		(end 296.426636 -169.441368)
		(width 0.1143)
		(layer "F.Cu")
		(net "NCSI_10G_RX_ER")
	)
	(segment
		(start 302.006 -62.865)
		(end 301.752 -63.119)
		(width 0.1143)
		(layer "F.Cu")
		(net "NCSI_10G_RX_ER")
	)
	(segment
		(start 279.76195 -126.77775)
		(end 279.76195 -139.483592)
		(width 0.1143)
		(layer "F.Cu")
		(net "NCSI_10G_RX_ER")
	)
	(segment
		(start 244.851682 -64.384682)
		(end 244.855746 -64.384682)
		(width 0.1143)
		(layer "F.Cu")
		(net "NCSI_10G_RX_ER")
	)
	(segment
		(start 289.18535 -148.03755)
		(end 289.8394 -148.6916)
		(width 0.1143)
		(layer "F.Cu")
		(net "NCSI_10G_RX_ER")
	)
	(segment
		(start 272.8722 -97.1042)
		(end 272.8722 -119.888)
		(width 0.1143)
		(layer "F.Cu")
		(net "NCSI_10G_RX_ER")
	)
	(segment
		(start 279.76195 -139.483592)
		(end 288.315908 -148.03755)
		(width 0.1143)
		(layer "F.Cu")
		(net "NCSI_10G_RX_ER")
	)
	(via
		(at 296.426636 -169.441368)
		(size 0.508)
		(drill 0.254)
		(layers "F.Cu" "B.Cu")
		(net "NCSI_10G_RX_ER")
	)
	(via
		(at 297.63085 -160.02)
		(size 0.7112)
		(drill 0.3556)
		(layers "F.Cu" "B.Cu")
		(net "NCSI_10G_RX_ER")
	)
	(via
		(at 244.348 -63.881)
		(size 0.5588)
		(drill 0.3048)
		(layers "F.Cu" "B.Cu")
		(net "NCSI_10G_RX_ER")
	)
	(via
		(at 289.8394 -148.6916)
		(size 0.5588)
		(drill 0.3048)
		(layers "F.Cu" "B.Cu")
		(net "NCSI_10G_RX_ER")
	)
	(via
		(at 301.752 -63.119)
		(size 0.5588)
		(drill 0.3048)
		(layers "F.Cu" "B.Cu")
		(net "NCSI_10G_RX_ER")
	)
	(segment
		(start 296.426636 -169.426636)
		(end 296.426636 -169.441368)
		(width 0.0889)
		(layer "B.Cu")
		(net "NCSI_10G_RX_ER")
	)
	(segment
		(start 297.63085 -155.715208)
		(end 295.636188 -153.720546)
		(width 0.1143)
		(layer "B.Cu")
		(net "NCSI_10G_RX_ER")
	)
	(segment
		(start 295.636188 -153.720546)
		(end 294.868346 -153.720546)
		(width 0.1143)
		(layer "B.Cu")
		(net "NCSI_10G_RX_ER")
	)
	(segment
		(start 297.63085 -166.45509)
		(end 296.799 -167.28694)
		(width 0.1143)
		(layer "B.Cu")
		(net "NCSI_10G_RX_ER")
	)
	(segment
		(start 296.042842 -169.042842)
		(end 296.426636 -169.426636)
		(width 0.0889)
		(layer "B.Cu")
		(net "NCSI_10G_RX_ER")
	)
	(segment
		(start 294.868346 -153.720546)
		(end 289.8394 -148.6916)
		(width 0.1143)
		(layer "B.Cu")
		(net "NCSI_10G_RX_ER")
	)
	(segment
		(start 297.63085 -160.02)
		(end 297.63085 -155.715208)
		(width 0.1143)
		(layer "B.Cu")
		(net "NCSI_10G_RX_ER")
	)
	(segment
		(start 297.63085 -160.02)
		(end 297.63085 -166.45509)
		(width 0.1143)
		(layer "B.Cu")
		(net "NCSI_10G_RX_ER")
	)
	(segment
		(start 296.799 -167.28694)
		(end 296.799 -167.386)
		(width 0.1143)
		(layer "B.Cu")
		(net "NCSI_10G_RX_ER")
	)
	(segment
		(start 296.799 -167.716708)
		(end 296.042842 -168.472866)
		(width 0.0889)
		(layer "B.Cu")
		(net "NCSI_10G_RX_ER")
	)
	(segment
		(start 296.042842 -168.472866)
		(end 296.042842 -169.042842)
		(width 0.0889)
		(layer "B.Cu")
		(net "NCSI_10G_RX_ER")
	)
	(segment
		(start 296.799 -167.386)
		(end 296.799 -167.716708)
		(width 0.0889)
		(layer "B.Cu")
		(net "NCSI_10G_RX_ER")
	)
	(segment
		(start 276.987 -64.008)
		(end 283.083 -64.008)
		(width 0.127)
		(layer "In5.Cu")
		(net "NCSI_10G_RX_ER")
	)
	(segment
		(start 272.034 -59.055)
		(end 276.987 -64.008)
		(width 0.127)
		(layer "In5.Cu")
		(net "NCSI_10G_RX_ER")
	)
	(segment
		(start 298.069 -63.373)
		(end 301.498 -63.373)
		(width 0.127)
		(layer "In5.Cu")
		(net "NCSI_10G_RX_ER")
	)
	(segment
		(start 285.496 -64.135)
		(end 285.75 -63.881)
		(width 0.127)
		(layer "In5.Cu")
		(net "NCSI_10G_RX_ER")
	)
	(segment
		(start 293.116 -64.516)
		(end 296.926 -64.516)
		(width 0.127)
		(layer "In5.Cu")
		(net "NCSI_10G_RX_ER")
	)
	(segment
		(start 244.348 -63.881)
		(end 249.174 -59.055)
		(width 0.127)
		(layer "In5.Cu")
		(net "NCSI_10G_RX_ER")
	)
	(segment
		(start 285.75 -63.881)
		(end 292.481 -63.881)
		(width 0.127)
		(layer "In5.Cu")
		(net "NCSI_10G_RX_ER")
	)
	(segment
		(start 296.926 -64.516)
		(end 298.069 -63.373)
		(width 0.127)
		(layer "In5.Cu")
		(net "NCSI_10G_RX_ER")
	)
	(segment
		(start 283.083 -64.008)
		(end 283.21 -64.135)
		(width 0.127)
		(layer "In5.Cu")
		(net "NCSI_10G_RX_ER")
	)
	(segment
		(start 283.21 -64.135)
		(end 285.496 -64.135)
		(width 0.127)
		(layer "In5.Cu")
		(net "NCSI_10G_RX_ER")
	)
	(segment
		(start 249.174 -59.055)
		(end 272.034 -59.055)
		(width 0.127)
		(layer "In5.Cu")
		(net "NCSI_10G_RX_ER")
	)
	(segment
		(start 292.481 -63.881)
		(end 293.116 -64.516)
		(width 0.127)
		(layer "In5.Cu")
		(net "NCSI_10G_RX_ER")
	)
	(segment
		(start 301.498 -63.373)
		(end 301.752 -63.119)
		(width 0.127)
		(layer "In5.Cu")
		(net "NCSI_10G_RX_ER")
	)
	(segment
		(start 117.682772 -243.138452)
		(end 117.682772 -242.833652)
		(width 0.1016)
		(layer "F.Cu")
		(net "SAS_HDD_CONN_TX7_P")
	)
	(segment
		(start 117.682772 -241.573812)
		(end 117.682772 -241.269012)
		(width 0.1016)
		(layer "F.Cu")
		(net "SAS_HDD_CONN_TX7_P")
	)
	(segment
		(start 117.682772 -253.760224)
		(end 117.682772 -251.845572)
		(width 0.1016)
		(layer "F.Cu")
		(net "SAS_HDD_CONN_TX7_P")
	)
	(segment
		(start 117.921532 -240.791492)
		(end 117.921532 -240.486692)
		(width 0.1016)
		(layer "F.Cu")
		(net "SAS_HDD_CONN_TX7_P")
	)
	(segment
		(start 117.921532 -251.368052)
		(end 117.921532 -251.063252)
		(width 0.1016)
		(layer "F.Cu")
		(net "SAS_HDD_CONN_TX7_P")
	)
	(segment
		(start 117.921532 -237.84179)
		(end 117.921532 -237.53699)
		(width 0.1016)
		(layer "F.Cu")
		(net "SAS_HDD_CONN_TX7_P")
	)
	(segment
		(start 118.000272 -256.25044)
		(end 118.000272 -254.526796)
		(width 0.1016)
		(layer "F.Cu")
		(net "SAS_HDD_CONN_TX7_P")
	)
	(segment
		(start 117.921532 -243.920772)
		(end 117.921532 -243.615972)
		(width 0.1016)
		(layer "F.Cu")
		(net "SAS_HDD_CONN_TX7_P")
	)
	(segment
		(start 117.921532 -248.238772)
		(end 117.921532 -247.933972)
		(width 0.1016)
		(layer "F.Cu")
		(net "SAS_HDD_CONN_TX7_P")
	)
	(segment
		(start 121.772172 -222.4405)
		(end 121.990612 -222.4405)
		(width 0.1016)
		(layer "F.Cu")
		(net "SAS_HDD_CONN_TX7_P")
	)
	(segment
		(start 117.682772 -240.009172)
		(end 117.682772 -238.31931)
		(width 0.1016)
		(layer "F.Cu")
		(net "SAS_HDD_CONN_TX7_P")
	)
	(segment
		(start 117.921532 -249.803412)
		(end 117.921532 -249.498612)
		(width 0.1016)
		(layer "F.Cu")
		(net "SAS_HDD_CONN_TX7_P")
	)
	(segment
		(start 117.921532 -242.356132)
		(end 117.921532 -242.051332)
		(width 0.1016)
		(layer "F.Cu")
		(net "SAS_HDD_CONN_TX7_P")
	)
	(segment
		(start 117.682772 -250.585732)
		(end 117.682772 -250.280932)
		(width 0.1016)
		(layer "F.Cu")
		(net "SAS_HDD_CONN_TX7_P")
	)
	(segment
		(start 117.682772 -237.05947)
		(end 117.682772 -234.68965)
		(width 0.1016)
		(layer "F.Cu")
		(net "SAS_HDD_CONN_TX7_P")
	)
	(segment
		(start 117.682772 -249.021092)
		(end 117.682772 -248.716292)
		(width 0.1016)
		(layer "F.Cu")
		(net "SAS_HDD_CONN_TX7_P")
	)
	(segment
		(start 117.682772 -247.456452)
		(end 117.682772 -244.398292)
		(width 0.1016)
		(layer "F.Cu")
		(net "SAS_HDD_CONN_TX7_P")
	)
	(segment
		(start 118.421912 -232.9053)
		(end 120.547638 -230.779574)
		(width 0.1016)
		(layer "F.Cu")
		(net "SAS_HDD_CONN_TX7_P")
	)
	(segment
		(start 121.355612 -228.8286)
		(end 121.355612 -222.897954)
		(width 0.1016)
		(layer "F.Cu")
		(net "SAS_HDD_CONN_TX7_P")
	)
	(arc
		(start 117.802152 -247.695212)
		(mid 117.713358 -247.590398)
		(end 117.682772 -247.456452)
		(width 0.1016)
		(layer "F.Cu")
		(net "SAS_HDD_CONN_TX7_P")
	)
	(arc
		(start 117.921532 -237.53699)
		(mid 117.89104 -237.402997)
		(end 117.802152 -237.29823)
		(width 0.1016)
		(layer "F.Cu")
		(net "SAS_HDD_CONN_TX7_P")
	)
	(arc
		(start 117.802152 -240.247932)
		(mid 117.713358 -240.143118)
		(end 117.682772 -240.009172)
		(width 0.1016)
		(layer "F.Cu")
		(net "SAS_HDD_CONN_TX7_P")
	)
	(arc
		(start 117.921532 -240.486692)
		(mid 117.89104 -240.352699)
		(end 117.802152 -240.247932)
		(width 0.1016)
		(layer "F.Cu")
		(net "SAS_HDD_CONN_TX7_P")
	)
	(arc
		(start 117.841522 -254.14351)
		(mid 117.724021 -253.967657)
		(end 117.682772 -253.760224)
		(width 0.1016)
		(layer "F.Cu")
		(net "SAS_HDD_CONN_TX7_P")
	)
	(arc
		(start 120.547638 -230.779574)
		(mid 121.145651 -229.884444)
		(end 121.355612 -228.8286)
		(width 0.1016)
		(layer "F.Cu")
		(net "SAS_HDD_CONN_TX7_P")
	)
	(arc
		(start 117.921532 -242.051332)
		(mid 117.89104 -241.917339)
		(end 117.802152 -241.812572)
		(width 0.1016)
		(layer "F.Cu")
		(net "SAS_HDD_CONN_TX7_P")
	)
	(arc
		(start 117.802152 -250.824492)
		(mid 117.713358 -250.719678)
		(end 117.682772 -250.585732)
		(width 0.1016)
		(layer "F.Cu")
		(net "SAS_HDD_CONN_TX7_P")
	)
	(arc
		(start 117.921532 -243.615972)
		(mid 117.89104 -243.481979)
		(end 117.802152 -243.377212)
		(width 0.1016)
		(layer "F.Cu")
		(net "SAS_HDD_CONN_TX7_P")
	)
	(arc
		(start 117.921532 -249.498612)
		(mid 117.890946 -249.364694)
		(end 117.802152 -249.259852)
		(width 0.1016)
		(layer "F.Cu")
		(net "SAS_HDD_CONN_TX7_P")
	)
	(arc
		(start 117.802152 -249.259852)
		(mid 117.713358 -249.155038)
		(end 117.682772 -249.021092)
		(width 0.1016)
		(layer "F.Cu")
		(net "SAS_HDD_CONN_TX7_P")
	)
	(arc
		(start 117.682772 -251.845572)
		(mid 117.713358 -251.711654)
		(end 117.802152 -251.606812)
		(width 0.1016)
		(layer "F.Cu")
		(net "SAS_HDD_CONN_TX7_P")
	)
	(arc
		(start 117.802152 -250.042172)
		(mid 117.890946 -249.937358)
		(end 117.921532 -249.803412)
		(width 0.1016)
		(layer "F.Cu")
		(net "SAS_HDD_CONN_TX7_P")
	)
	(arc
		(start 117.682772 -244.398292)
		(mid 117.713264 -244.264299)
		(end 117.802152 -244.159532)
		(width 0.1016)
		(layer "F.Cu")
		(net "SAS_HDD_CONN_TX7_P")
	)
	(arc
		(start 117.921532 -247.933972)
		(mid 117.890946 -247.800054)
		(end 117.802152 -247.695212)
		(width 0.1016)
		(layer "F.Cu")
		(net "SAS_HDD_CONN_TX7_P")
	)
	(arc
		(start 117.802152 -237.29823)
		(mid 117.713358 -237.193416)
		(end 117.682772 -237.05947)
		(width 0.1016)
		(layer "F.Cu")
		(net "SAS_HDD_CONN_TX7_P")
	)
	(arc
		(start 118.000272 -254.526796)
		(mid 117.959012 -254.319368)
		(end 117.841522 -254.14351)
		(width 0.1016)
		(layer "F.Cu")
		(net "SAS_HDD_CONN_TX7_P")
	)
	(arc
		(start 117.802152 -251.606812)
		(mid 117.890946 -251.501998)
		(end 117.921532 -251.368052)
		(width 0.1016)
		(layer "F.Cu")
		(net "SAS_HDD_CONN_TX7_P")
	)
	(arc
		(start 121.355612 -222.897954)
		(mid 121.398187 -222.683916)
		(end 121.519442 -222.502476)
		(width 0.1016)
		(layer "F.Cu")
		(net "SAS_HDD_CONN_TX7_P")
	)
	(arc
		(start 117.682772 -242.833652)
		(mid 117.713264 -242.699659)
		(end 117.802152 -242.594892)
		(width 0.1016)
		(layer "F.Cu")
		(net "SAS_HDD_CONN_TX7_P")
	)
	(arc
		(start 117.682772 -250.280932)
		(mid 117.713358 -250.147014)
		(end 117.802152 -250.042172)
		(width 0.1016)
		(layer "F.Cu")
		(net "SAS_HDD_CONN_TX7_P")
	)
	(arc
		(start 117.921532 -251.063252)
		(mid 117.890946 -250.929334)
		(end 117.802152 -250.824492)
		(width 0.1016)
		(layer "F.Cu")
		(net "SAS_HDD_CONN_TX7_P")
	)
	(arc
		(start 117.802152 -244.159532)
		(mid 117.890946 -244.054718)
		(end 117.921532 -243.920772)
		(width 0.1016)
		(layer "F.Cu")
		(net "SAS_HDD_CONN_TX7_P")
	)
	(arc
		(start 117.682772 -238.31931)
		(mid 117.713264 -238.185317)
		(end 117.802152 -238.08055)
		(width 0.1016)
		(layer "F.Cu")
		(net "SAS_HDD_CONN_TX7_P")
	)
	(arc
		(start 117.682772 -241.269012)
		(mid 117.713264 -241.135019)
		(end 117.802152 -241.030252)
		(width 0.1016)
		(layer "F.Cu")
		(net "SAS_HDD_CONN_TX7_P")
	)
	(arc
		(start 117.682772 -234.68965)
		(mid 117.874861 -233.723952)
		(end 118.421912 -232.9053)
		(width 0.1016)
		(layer "F.Cu")
		(net "SAS_HDD_CONN_TX7_P")
	)
	(arc
		(start 121.519442 -222.502476)
		(mid 121.64206 -222.456219)
		(end 121.772172 -222.4405)
		(width 0.1016)
		(layer "F.Cu")
		(net "SAS_HDD_CONN_TX7_P")
	)
	(arc
		(start 117.802152 -242.594892)
		(mid 117.890946 -242.490078)
		(end 117.921532 -242.356132)
		(width 0.1016)
		(layer "F.Cu")
		(net "SAS_HDD_CONN_TX7_P")
	)
	(arc
		(start 117.802152 -248.477532)
		(mid 117.890946 -248.372718)
		(end 117.921532 -248.238772)
		(width 0.1016)
		(layer "F.Cu")
		(net "SAS_HDD_CONN_TX7_P")
	)
	(arc
		(start 117.802152 -241.030252)
		(mid 117.890946 -240.925438)
		(end 117.921532 -240.791492)
		(width 0.1016)
		(layer "F.Cu")
		(net "SAS_HDD_CONN_TX7_P")
	)
	(arc
		(start 117.802152 -241.812572)
		(mid 117.713358 -241.707758)
		(end 117.682772 -241.573812)
		(width 0.1016)
		(layer "F.Cu")
		(net "SAS_HDD_CONN_TX7_P")
	)
	(arc
		(start 117.802152 -243.377212)
		(mid 117.713358 -243.272398)
		(end 117.682772 -243.138452)
		(width 0.1016)
		(layer "F.Cu")
		(net "SAS_HDD_CONN_TX7_P")
	)
	(arc
		(start 117.802152 -238.08055)
		(mid 117.890946 -237.975736)
		(end 117.921532 -237.84179)
		(width 0.1016)
		(layer "F.Cu")
		(net "SAS_HDD_CONN_TX7_P")
	)
	(arc
		(start 117.682772 -248.716292)
		(mid 117.713358 -248.582374)
		(end 117.802152 -248.477532)
		(width 0.1016)
		(layer "F.Cu")
		(net "SAS_HDD_CONN_TX7_P")
	)
	(segment
		(start 308.675024 -64.400176)
		(end 304.411634 -64.400176)
		(width 0.1143)
		(layer "F.Cu")
		(net "NCSI_10G_TXD1_R")
	)
	(segment
		(start 304.411634 -64.400176)
		(end 303.765458 -64.135)
		(width 0.1143)
		(layer "F.Cu")
		(net "NCSI_10G_TXD1_R")
	)
	(segment
		(start 303.765458 -65.2145)
		(end 303.701958 -65.278)
		(width 0.1143)
		(layer "F.Cu")
		(net "NCSI_10G_TXD1_R")
	)
	(segment
		(start 303.765458 -64.135)
		(end 303.765458 -65.2145)
		(width 0.1143)
		(layer "F.Cu")
		(net "NCSI_10G_TXD1_R")
	)
	(via
		(at 303.701958 -65.278)
		(size 0.7112)
		(drill 0.3556)
		(layers "F.Cu" "B.Cu")
		(net "NCSI_10G_TXD1_R")
	)
	(via
		(at 121.685812 -212.344)
		(size 0.7112)
		(drill 0.3556)
		(layers "F.Cu" "B.Cu")
		(net "REDV_I2C_SEL1A")
	)
	(segment
		(start 120.339612 -213.106)
		(end 121.101612 -212.344)
		(width 0.1143)
		(layer "B.Cu")
		(net "REDV_I2C_SEL1A")
	)
	(segment
		(start 119.640604 -213.106)
		(end 120.339612 -213.106)
		(width 0.1143)
		(layer "B.Cu")
		(net "REDV_I2C_SEL1A")
	)
	(segment
		(start 121.101612 -212.344)
		(end 121.685812 -212.344)
		(width 0.1143)
		(layer "B.Cu")
		(net "REDV_I2C_SEL1A")
	)
	(segment
		(start 123.959112 -212.344)
		(end 121.685812 -212.344)
		(width 0.1143)
		(layer "B.Cu")
		(net "REDV_I2C_SEL1A")
	)
	(segment
		(start 308.675024 -63.600076)
		(end 307.29682 -63.600076)
		(width 0.1143)
		(layer "F.Cu")
		(net "NCSI_10G_TXD0_R")
	)
	(segment
		(start 301.1805 -63.627)
		(end 304.590958 -63.627)
		(width 0.1143)
		(layer "F.Cu")
		(net "NCSI_10G_TXD0_R")
	)
	(segment
		(start 307.29682 -63.600076)
		(end 307.142896 -63.754)
		(width 0.1143)
		(layer "F.Cu")
		(net "NCSI_10G_TXD0_R")
	)
	(segment
		(start 304.590958 -63.627)
		(end 304.717958 -63.754)
		(width 0.1143)
		(layer "F.Cu")
		(net "NCSI_10G_TXD0_R")
	)
	(segment
		(start 300.9265 -63.373)
		(end 301.1805 -63.627)
		(width 0.1143)
		(layer "F.Cu")
		(net "NCSI_10G_TXD0_R")
	)
	(segment
		(start 307.142896 -63.754)
		(end 304.717958 -63.754)
		(width 0.1143)
		(layer "F.Cu")
		(net "NCSI_10G_TXD0_R")
	)
	(segment
		(start 300.9265 -62.992)
		(end 300.9265 -63.373)
		(width 0.1143)
		(layer "F.Cu")
		(net "NCSI_10G_TXD0_R")
	)
	(via
		(at 304.717958 -63.754)
		(size 0.7112)
		(drill 0.3556)
		(layers "F.Cu" "B.Cu")
		(net "NCSI_10G_TXD0_R")
	)
	(via
		(at 109.506004 -215.480392)
		(size 0.7112)
		(drill 0.3556)
		(layers "F.Cu" "B.Cu")
		(net "REDV_I2C_A0")
	)
	(segment
		(start 108.465112 -215.011)
		(end 109.036612 -215.011)
		(width 0.1143)
		(layer "B.Cu")
		(net "REDV_I2C_A0")
	)
	(segment
		(start 109.036612 -215.011)
		(end 109.506004 -215.480392)
		(width 0.1143)
		(layer "B.Cu")
		(net "REDV_I2C_A0")
	)
	(segment
		(start 111.119412 -215.634062)
		(end 109.659674 -215.634062)
		(width 0.1143)
		(layer "B.Cu")
		(net "REDV_I2C_A0")
	)
	(segment
		(start 109.659674 -215.634062)
		(end 109.506004 -215.480392)
		(width 0.1143)
		(layer "B.Cu")
		(net "REDV_I2C_A0")
	)
	(segment
		(start 300.082458 -63.881)
		(end 299.593 -64.370458)
		(width 0.1143)
		(layer "F.Cu")
		(net "NCSI_10G_TXD0")
	)
	(segment
		(start 244.729 -65.024)
		(end 245.237 -65.532)
		(width 0.1143)
		(layer "F.Cu")
		(net "NCSI_10G_TXD0")
	)
	(segment
		(start 272.3769 -120.3579)
		(end 279.26665 -127.24765)
		(width 0.1143)
		(layer "F.Cu")
		(net "NCSI_10G_TXD0")
	)
	(segment
		(start 289.682174 -149.610826)
		(end 289.687 -149.606)
		(width 0.1143)
		(layer "F.Cu")
		(net "NCSI_10G_TXD0")
	)
	(segment
		(start 272.3769 -97.500186)
		(end 272.3769 -120.3579)
		(width 0.1143)
		(layer "F.Cu")
		(net "NCSI_10G_TXD0")
	)
	(segment
		(start 299.593 -64.370458)
		(end 299.593 -64.390524)
		(width 0.1143)
		(layer "F.Cu")
		(net "NCSI_10G_TXD0")
	)
	(segment
		(start 299.593 -64.390524)
		(end 299.55363 -64.429894)
		(width 0.1143)
		(layer "F.Cu")
		(net "NCSI_10G_TXD0")
	)
	(segment
		(start 279.26665 -127.24765)
		(end 279.26665 -139.688824)
		(width 0.1143)
		(layer "F.Cu")
		(net "NCSI_10G_TXD0")
	)
	(segment
		(start 245.237 -65.532)
		(end 245.302532 -65.532)
		(width 0.1143)
		(layer "F.Cu")
		(net "NCSI_10G_TXD0")
	)
	(segment
		(start 279.26665 -139.688824)
		(end 289.188652 -149.610826)
		(width 0.1143)
		(layer "F.Cu")
		(net "NCSI_10G_TXD0")
	)
	(segment
		(start 300.0375 -62.992)
		(end 300.082458 -63.881)
		(width 0.1143)
		(layer "F.Cu")
		(net "NCSI_10G_TXD0")
	)
	(segment
		(start 245.302532 -65.532)
		(end 266.0142 -86.243668)
		(width 0.1143)
		(layer "F.Cu")
		(net "NCSI_10G_TXD0")
	)
	(segment
		(start 266.0142 -86.243668)
		(end 266.0142 -91.137486)
		(width 0.1143)
		(layer "F.Cu")
		(net "NCSI_10G_TXD0")
	)
	(segment
		(start 294.434768 -167.440102)
		(end 294.829992 -167.044878)
		(width 0.1143)
		(layer "F.Cu")
		(net "NCSI_10G_TXD0")
	)
	(segment
		(start 289.188652 -149.610826)
		(end 289.682174 -149.610826)
		(width 0.1143)
		(layer "F.Cu")
		(net "NCSI_10G_TXD0")
	)
	(segment
		(start 266.0142 -91.137486)
		(end 272.3769 -97.500186)
		(width 0.1143)
		(layer "F.Cu")
		(net "NCSI_10G_TXD0")
	)
	(via
		(at 294.829992 -167.044878)
		(size 0.508)
		(drill 0.254)
		(layers "F.Cu" "B.Cu")
		(net "NCSI_10G_TXD0")
	)
	(via
		(at 289.687 -149.606)
		(size 0.5588)
		(drill 0.3048)
		(layers "F.Cu" "B.Cu")
		(net "NCSI_10G_TXD0")
	)
	(via
		(at 244.729 -65.024)
		(size 0.5588)
		(drill 0.3048)
		(layers "F.Cu" "B.Cu")
		(net "NCSI_10G_TXD0")
	)
	(via
		(at 300.082458 -63.881)
		(size 0.5588)
		(drill 0.3048)
		(layers "F.Cu" "B.Cu")
		(net "NCSI_10G_TXD0")
	)
	(via
		(at 299.55363 -64.429894)
		(size 0.7112)
		(drill 0.3556)
		(layers "F.Cu" "B.Cu")
		(net "NCSI_10G_TXD0")
	)
	(segment
		(start 290.1188 -150.0378)
		(end 290.1188 -150.203154)
		(width 0.127)
		(layer "In2.Cu")
		(net "NCSI_10G_TXD0")
	)
	(segment
		(start 290.1188 -150.203154)
		(end 290.482528 -150.566882)
		(width 0.127)
		(layer "In2.Cu")
		(net "NCSI_10G_TXD0")
	)
	(segment
		(start 296.291 -162.984434)
		(end 294.829992 -164.445442)
		(width 0.127)
		(layer "In2.Cu")
		(net "NCSI_10G_TXD0")
	)
	(segment
		(start 294.829992 -164.445442)
		(end 294.829992 -167.044878)
		(width 0.127)
		(layer "In2.Cu")
		(net "NCSI_10G_TXD0")
	)
	(segment
		(start 290.482528 -153.322528)
		(end 296.291 -159.131)
		(width 0.127)
		(layer "In2.Cu")
		(net "NCSI_10G_TXD0")
	)
	(segment
		(start 296.291 -159.131)
		(end 296.291 -162.984434)
		(width 0.127)
		(layer "In2.Cu")
		(net "NCSI_10G_TXD0")
	)
	(segment
		(start 290.482528 -150.566882)
		(end 290.482528 -153.322528)
		(width 0.127)
		(layer "In2.Cu")
		(net "NCSI_10G_TXD0")
	)
	(segment
		(start 289.687 -149.606)
		(end 290.1188 -150.0378)
		(width 0.127)
		(layer "In2.Cu")
		(net "NCSI_10G_TXD0")
	)
	(segment
		(start 276.86 -64.643)
		(end 285.75 -64.643)
		(width 0.127)
		(layer "In5.Cu")
		(net "NCSI_10G_TXD0")
	)
	(segment
		(start 286.004 -64.389)
		(end 292.227 -64.389)
		(width 0.127)
		(layer "In5.Cu")
		(net "NCSI_10G_TXD0")
	)
	(segment
		(start 244.729 -65.024)
		(end 250.19 -59.563)
		(width 0.127)
		(layer "In5.Cu")
		(net "NCSI_10G_TXD0")
	)
	(segment
		(start 292.862 -65.024)
		(end 297.18 -65.024)
		(width 0.127)
		(layer "In5.Cu")
		(net "NCSI_10G_TXD0")
	)
	(segment
		(start 297.18 -65.024)
		(end 298.323 -63.881)
		(width 0.127)
		(layer "In5.Cu")
		(net "NCSI_10G_TXD0")
	)
	(segment
		(start 298.323 -63.881)
		(end 300.082458 -63.881)
		(width 0.127)
		(layer "In5.Cu")
		(net "NCSI_10G_TXD0")
	)
	(segment
		(start 285.75 -64.643)
		(end 286.004 -64.389)
		(width 0.127)
		(layer "In5.Cu")
		(net "NCSI_10G_TXD0")
	)
	(segment
		(start 271.78 -59.563)
		(end 276.86 -64.643)
		(width 0.127)
		(layer "In5.Cu")
		(net "NCSI_10G_TXD0")
	)
	(segment
		(start 292.227 -64.389)
		(end 292.862 -65.024)
		(width 0.127)
		(layer "In5.Cu")
		(net "NCSI_10G_TXD0")
	)
	(segment
		(start 250.19 -59.563)
		(end 271.78 -59.563)
		(width 0.127)
		(layer "In5.Cu")
		(net "NCSI_10G_TXD0")
	)
	(segment
		(start 111.435134 -209.535522)
		(end 113.670588 -211.770976)
		(width 0.1016)
		(layer "B.Cu")
		(net "SAS_HDD_REDV_SER_RX8_N")
	)
	(segment
		(start 111.31804 -209.487262)
		(end 111.31804 -209.487008)
		(width 0.1016)
		(layer "B.Cu")
		(net "SAS_HDD_REDV_SER_RX8_N")
	)
	(segment
		(start 110.395258 -209.003646)
		(end 110.567724 -209.17662)
		(width 0.1016)
		(layer "B.Cu")
		(net "SAS_HDD_REDV_SER_RX8_N")
	)
	(segment
		(start 108.745782 -206.955644)
		(end 108.745782 -207.270096)
		(width 0.1016)
		(layer "B.Cu")
		(net "SAS_HDD_REDV_SER_RX8_N")
	)
	(segment
		(start 108.280962 -206.40675)
		(end 108.686346 -206.812134)
		(width 0.1016)
		(layer "B.Cu")
		(net "SAS_HDD_REDV_SER_RX8_N")
	)
	(segment
		(start 113.719102 -211.88807)
		(end 113.719102 -212.351366)
		(width 0.1016)
		(layer "B.Cu")
		(net "SAS_HDD_REDV_SER_RX8_N")
	)
	(segment
		(start 113.686844 -212.42909)
		(end 113.672874 -212.44306)
		(width 0.1016)
		(layer "B.Cu")
		(net "SAS_HDD_REDV_SER_RX8_N")
	)
	(segment
		(start 108.020612 -206.3115)
		(end 108.100876 -206.344774)
		(width 0.1016)
		(layer "B.Cu")
		(net "SAS_HDD_REDV_SER_RX8_N")
	)
	(segment
		(start 113.640616 -212.520784)
		(end 113.640616 -213.106)
		(width 0.1016)
		(layer "B.Cu")
		(net "SAS_HDD_REDV_SER_RX8_N")
	)
	(segment
		(start 108.805218 -207.413606)
		(end 110.395258 -209.003646)
		(width 0.1016)
		(layer "B.Cu")
		(net "SAS_HDD_REDV_SER_RX8_N")
	)
	(arc
		(start 113.670588 -211.770976)
		(mid 113.706485 -211.824699)
		(end 113.719102 -211.88807)
		(width 0.1016)
		(layer "B.Cu")
		(net "SAS_HDD_REDV_SER_RX8_N")
	)
	(arc
		(start 108.745782 -207.270096)
		(mid 108.76123 -207.34776)
		(end 108.805218 -207.413606)
		(width 0.1016)
		(layer "B.Cu")
		(net "SAS_HDD_REDV_SER_RX8_N")
	)
	(arc
		(start 108.686346 -206.812134)
		(mid 108.730341 -206.877977)
		(end 108.745782 -206.955644)
		(width 0.1016)
		(layer "B.Cu")
		(net "SAS_HDD_REDV_SER_RX8_N")
	)
	(arc
		(start 113.672874 -212.44306)
		(mid 113.648993 -212.478706)
		(end 113.640616 -212.520784)
		(width 0.1016)
		(layer "B.Cu")
		(net "SAS_HDD_REDV_SER_RX8_N")
	)
	(arc
		(start 111.31804 -209.487008)
		(mid 111.381415 -209.499614)
		(end 111.435134 -209.535522)
		(width 0.1016)
		(layer "B.Cu")
		(net "SAS_HDD_REDV_SER_RX8_N")
	)
	(arc
		(start 110.567724 -209.17662)
		(mid 110.911973 -209.40661)
		(end 111.31804 -209.487262)
		(width 0.1016)
		(layer "B.Cu")
		(net "SAS_HDD_REDV_SER_RX8_N")
	)
	(arc
		(start 108.15955 -206.356458)
		(mid 108.225258 -206.369528)
		(end 108.280962 -206.40675)
		(width 0.1016)
		(layer "B.Cu")
		(net "SAS_HDD_REDV_SER_RX8_N")
	)
	(arc
		(start 108.100876 -206.344774)
		(mid 108.129637 -206.353509)
		(end 108.15955 -206.356458)
		(width 0.1016)
		(layer "B.Cu")
		(net "SAS_HDD_REDV_SER_RX8_N")
	)
	(arc
		(start 113.719102 -212.351366)
		(mid 113.710715 -212.39344)
		(end 113.686844 -212.42909)
		(width 0.1016)
		(layer "B.Cu")
		(net "SAS_HDD_REDV_SER_RX8_N")
	)
	(segment
		(start 278.77135 -127.521462)
		(end 278.77135 -139.894564)
		(width 0.1143)
		(layer "F.Cu")
		(net "NCSI_10G_TXD1")
	)
	(segment
		(start 294.434768 -168.240202)
		(end 294.829992 -167.844978)
		(width 0.1143)
		(layer "F.Cu")
		(net "NCSI_10G_TXD1")
	)
	(segment
		(start 302.133 -64.135)
		(end 301.498 -64.77)
		(width 0.1143)
		(layer "F.Cu")
		(net "NCSI_10G_TXD1")
	)
	(segment
		(start 302.876458 -64.135)
		(end 302.133 -64.135)
		(width 0.1143)
		(layer "F.Cu")
		(net "NCSI_10G_TXD1")
	)
	(segment
		(start 299.891958 -65.151)
		(end 300.272958 -64.77)
		(width 0.1143)
		(layer "F.Cu")
		(net "NCSI_10G_TXD1")
	)
	(segment
		(start 289.466528 -150.589742)
		(end 289.466528 -150.988014)
		(width 0.1143)
		(layer "F.Cu")
		(net "NCSI_10G_TXD1")
	)
	(segment
		(start 265.5189 -86.4489)
		(end 265.5189 -91.342718)
		(width 0.1143)
		(layer "F.Cu")
		(net "NCSI_10G_TXD1")
	)
	(segment
		(start 265.5189 -91.342718)
		(end 271.8816 -97.705418)
		(width 0.1143)
		(layer "F.Cu")
		(net "NCSI_10G_TXD1")
	)
	(segment
		(start 245.237 -66.167)
		(end 265.5189 -86.4489)
		(width 0.1143)
		(layer "F.Cu")
		(net "NCSI_10G_TXD1")
	)
	(segment
		(start 300.272958 -64.77)
		(end 301.498 -64.77)
		(width 0.1143)
		(layer "F.Cu")
		(net "NCSI_10G_TXD1")
	)
	(segment
		(start 271.8816 -120.630696)
		(end 278.77135 -127.521462)
		(width 0.1143)
		(layer "F.Cu")
		(net "NCSI_10G_TXD1")
	)
	(segment
		(start 278.77135 -139.894564)
		(end 289.466528 -150.589742)
		(width 0.1143)
		(layer "F.Cu")
		(net "NCSI_10G_TXD1")
	)
	(segment
		(start 271.8816 -97.705418)
		(end 271.8816 -120.630696)
		(width 0.1143)
		(layer "F.Cu")
		(net "NCSI_10G_TXD1")
	)
	(via
		(at 289.466528 -150.988014)
		(size 0.5588)
		(drill 0.3048)
		(layers "F.Cu" "B.Cu")
		(net "NCSI_10G_TXD1")
	)
	(via
		(at 299.891958 -65.151)
		(size 0.5588)
		(drill 0.3048)
		(layers "F.Cu" "B.Cu")
		(net "NCSI_10G_TXD1")
	)
	(via
		(at 245.237 -66.167)
		(size 0.5588)
		(drill 0.3048)
		(layers "F.Cu" "B.Cu")
		(net "NCSI_10G_TXD1")
	)
	(via
		(at 294.829992 -167.844978)
		(size 0.508)
		(drill 0.254)
		(layers "F.Cu" "B.Cu")
		(net "NCSI_10G_TXD1")
	)
	(via
		(at 301.498 -64.77)
		(size 0.7112)
		(drill 0.3556)
		(layers "F.Cu" "B.Cu")
		(net "NCSI_10G_TXD1")
	)
	(segment
		(start 294.91305 -159.190182)
		(end 294.91305 -163.643818)
		(width 0.127)
		(layer "In2.Cu")
		(net "NCSI_10G_TXD1")
	)
	(segment
		(start 289.466528 -150.988014)
		(end 289.456368 -150.988014)
		(width 0.127)
		(layer "In2.Cu")
		(net "NCSI_10G_TXD1")
	)
	(segment
		(start 294.321992 -167.336978)
		(end 294.829992 -167.844978)
		(width 0.127)
		(layer "In2.Cu")
		(net "NCSI_10G_TXD1")
	)
	(segment
		(start 289.456368 -150.988014)
		(end 289.456368 -153.7335)
		(width 0.127)
		(layer "In2.Cu")
		(net "NCSI_10G_TXD1")
	)
	(segment
		(start 289.456368 -153.7335)
		(end 294.91305 -159.190182)
		(width 0.127)
		(layer "In2.Cu")
		(net "NCSI_10G_TXD1")
	)
	(segment
		(start 294.91305 -163.643818)
		(end 294.321992 -164.234876)
		(width 0.127)
		(layer "In2.Cu")
		(net "NCSI_10G_TXD1")
	)
	(segment
		(start 294.321992 -164.234876)
		(end 294.321992 -167.336978)
		(width 0.127)
		(layer "In2.Cu")
		(net "NCSI_10G_TXD1")
	)
	(segment
		(start 292.608 -65.532)
		(end 294.513 -65.532)
		(width 0.127)
		(layer "In5.Cu")
		(net "NCSI_10G_TXD1")
	)
	(segment
		(start 258.191 -64.516)
		(end 262.636 -60.071)
		(width 0.127)
		(layer "In5.Cu")
		(net "NCSI_10G_TXD1")
	)
	(segment
		(start 297.937428 -65.028572)
		(end 299.76953 -65.028572)
		(width 0.127)
		(layer "In5.Cu")
		(net "NCSI_10G_TXD1")
	)
	(segment
		(start 262.636 -60.071)
		(end 271.526 -60.071)
		(width 0.127)
		(layer "In5.Cu")
		(net "NCSI_10G_TXD1")
	)
	(segment
		(start 286.126428 -65.028572)
		(end 292.104572 -65.028572)
		(width 0.127)
		(layer "In5.Cu")
		(net "NCSI_10G_TXD1")
	)
	(segment
		(start 297.434 -65.532)
		(end 297.937428 -65.028572)
		(width 0.127)
		(layer "In5.Cu")
		(net "NCSI_10G_TXD1")
	)
	(segment
		(start 295.021 -66.04)
		(end 295.529 -66.04)
		(width 0.127)
		(layer "In5.Cu")
		(net "NCSI_10G_TXD1")
	)
	(segment
		(start 276.606 -65.151)
		(end 286.004 -65.151)
		(width 0.127)
		(layer "In5.Cu")
		(net "NCSI_10G_TXD1")
	)
	(segment
		(start 295.529 -66.04)
		(end 296.037 -65.532)
		(width 0.127)
		(layer "In5.Cu")
		(net "NCSI_10G_TXD1")
	)
	(segment
		(start 299.76953 -65.028572)
		(end 299.891958 -65.151)
		(width 0.127)
		(layer "In5.Cu")
		(net "NCSI_10G_TXD1")
	)
	(segment
		(start 286.004 -65.151)
		(end 286.126428 -65.028572)
		(width 0.127)
		(layer "In5.Cu")
		(net "NCSI_10G_TXD1")
	)
	(segment
		(start 292.104572 -65.028572)
		(end 292.608 -65.532)
		(width 0.127)
		(layer "In5.Cu")
		(net "NCSI_10G_TXD1")
	)
	(segment
		(start 245.237 -66.167)
		(end 246.888 -64.516)
		(width 0.127)
		(layer "In5.Cu")
		(net "NCSI_10G_TXD1")
	)
	(segment
		(start 296.037 -65.532)
		(end 297.434 -65.532)
		(width 0.127)
		(layer "In5.Cu")
		(net "NCSI_10G_TXD1")
	)
	(segment
		(start 294.513 -65.532)
		(end 295.021 -66.04)
		(width 0.127)
		(layer "In5.Cu")
		(net "NCSI_10G_TXD1")
	)
	(segment
		(start 271.526 -60.071)
		(end 276.606 -65.151)
		(width 0.127)
		(layer "In5.Cu")
		(net "NCSI_10G_TXD1")
	)
	(segment
		(start 246.888 -64.516)
		(end 258.191 -64.516)
		(width 0.127)
		(layer "In5.Cu")
		(net "NCSI_10G_TXD1")
	)
	(via
		(at 121.736612 -215.9)
		(size 0.7112)
		(drill 0.3556)
		(layers "F.Cu" "B.Cu")
		(net "REDV_I2C_SCL")
	)
	(segment
		(start 122.371612 -216.535)
		(end 121.736612 -215.9)
		(width 0.1143)
		(layer "B.Cu")
		(net "REDV_I2C_SCL")
	)
	(segment
		(start 120.161812 -215.634062)
		(end 121.470674 -215.634062)
		(width 0.1143)
		(layer "B.Cu")
		(net "REDV_I2C_SCL")
	)
	(segment
		(start 121.470674 -215.634062)
		(end 121.736612 -215.9)
		(width 0.1143)
		(layer "B.Cu")
		(net "REDV_I2C_SCL")
	)
	(segment
		(start 123.959112 -216.535)
		(end 122.371612 -216.535)
		(width 0.1143)
		(layer "B.Cu")
		(net "REDV_I2C_SCL")
	)
	(segment
		(start 316.846458 -65.913)
		(end 318.179958 -65.913)
		(width 0.1143)
		(layer "F.Cu")
		(net "NCSI_10G_RXD1")
	)
	(segment
		(start 296.025316 -170.640248)
		(end 295.634156 -171.031408)
		(width 0.1143)
		(layer "F.Cu")
		(net "NCSI_10G_RXD1")
	)
	(segment
		(start 296.034968 -170.640248)
		(end 296.025316 -170.640248)
		(width 0.1143)
		(layer "F.Cu")
		(net "NCSI_10G_RXD1")
	)
	(segment
		(start 319.405 -65.913)
		(end 318.179958 -65.913)
		(width 0.1143)
		(layer "F.Cu")
		(net "NCSI_10G_RXD1")
	)
	(segment
		(start 321.183 -66.04)
		(end 319.532 -66.04)
		(width 0.1143)
		(layer "F.Cu")
		(net "NCSI_10G_RXD1")
	)
	(segment
		(start 319.532 -66.04)
		(end 319.405 -65.913)
		(width 0.1143)
		(layer "F.Cu")
		(net "NCSI_10G_RXD1")
	)
	(via
		(at 304.927 -139.17295)
		(size 0.5588)
		(drill 0.3048)
		(layers "F.Cu" "B.Cu")
		(net "NCSI_10G_RXD1")
	)
	(via
		(at 321.183 -66.04)
		(size 0.5588)
		(drill 0.3048)
		(layers "F.Cu" "B.Cu")
		(net "NCSI_10G_RXD1")
	)
	(via
		(at 318.179958 -65.913)
		(size 0.7112)
		(drill 0.3556)
		(layers "F.Cu" "B.Cu")
		(net "NCSI_10G_RXD1")
	)
	(via
		(at 295.634156 -171.031408)
		(size 0.508)
		(drill 0.254)
		(layers "F.Cu" "B.Cu")
		(net "NCSI_10G_RXD1")
	)
	(segment
		(start 297.0022 -168.43248)
		(end 297.0022 -166.5478)
		(width 0.127)
		(layer "In2.Cu")
		(net "NCSI_10G_RXD1")
	)
	(segment
		(start 301.184056 -160.079944)
		(end 301.220124 -160.079944)
		(width 0.127)
		(layer "In2.Cu")
		(net "NCSI_10G_RXD1")
	)
	(segment
		(start 303.2887 -158.011368)
		(end 303.2887 -140.7033)
		(width 0.127)
		(layer "In2.Cu")
		(net "NCSI_10G_RXD1")
	)
	(segment
		(start 303.2887 -140.7033)
		(end 304.81905 -139.17295)
		(width 0.127)
		(layer "In2.Cu")
		(net "NCSI_10G_RXD1")
	)
	(segment
		(start 297.0022 -169.104056)
		(end 297.0022 -168.43248)
		(width 0.0889)
		(layer "In2.Cu")
		(net "NCSI_10G_RXD1")
	)
	(segment
		(start 297.0022 -166.5478)
		(end 300.101 -163.449)
		(width 0.127)
		(layer "In2.Cu")
		(net "NCSI_10G_RXD1")
	)
	(segment
		(start 296.375582 -169.841418)
		(end 296.592498 -169.841418)
		(width 0.0889)
		(layer "In2.Cu")
		(net "NCSI_10G_RXD1")
	)
	(segment
		(start 296.592498 -169.841418)
		(end 296.826686 -169.60723)
		(width 0.0889)
		(layer "In2.Cu")
		(net "NCSI_10G_RXD1")
	)
	(segment
		(start 296.034968 -170.415712)
		(end 296.034968 -170.182032)
		(width 0.0889)
		(layer "In2.Cu")
		(net "NCSI_10G_RXD1")
	)
	(segment
		(start 296.828718 -169.388282)
		(end 296.828718 -169.277538)
		(width 0.0889)
		(layer "In2.Cu")
		(net "NCSI_10G_RXD1")
	)
	(segment
		(start 295.634156 -170.816524)
		(end 296.034968 -170.415712)
		(width 0.0889)
		(layer "In2.Cu")
		(net "NCSI_10G_RXD1")
	)
	(segment
		(start 296.828718 -169.277538)
		(end 297.0022 -169.104056)
		(width 0.0889)
		(layer "In2.Cu")
		(net "NCSI_10G_RXD1")
	)
	(segment
		(start 296.826686 -169.60723)
		(end 296.826686 -169.390314)
		(width 0.0889)
		(layer "In2.Cu")
		(net "NCSI_10G_RXD1")
	)
	(segment
		(start 300.101 -161.163)
		(end 301.184056 -160.079944)
		(width 0.127)
		(layer "In2.Cu")
		(net "NCSI_10G_RXD1")
	)
	(segment
		(start 304.81905 -139.17295)
		(end 304.927 -139.17295)
		(width 0.127)
		(layer "In2.Cu")
		(net "NCSI_10G_RXD1")
	)
	(segment
		(start 295.634156 -171.031408)
		(end 295.634156 -170.816524)
		(width 0.0889)
		(layer "In2.Cu")
		(net "NCSI_10G_RXD1")
	)
	(segment
		(start 300.101 -163.449)
		(end 300.101 -161.163)
		(width 0.127)
		(layer "In2.Cu")
		(net "NCSI_10G_RXD1")
	)
	(segment
		(start 301.220124 -160.079944)
		(end 303.2887 -158.011368)
		(width 0.127)
		(layer "In2.Cu")
		(net "NCSI_10G_RXD1")
	)
	(segment
		(start 296.826686 -169.390314)
		(end 296.828718 -169.388282)
		(width 0.0889)
		(layer "In2.Cu")
		(net "NCSI_10G_RXD1")
	)
	(segment
		(start 296.034968 -170.182032)
		(end 296.375582 -169.841418)
		(width 0.0889)
		(layer "In2.Cu")
		(net "NCSI_10G_RXD1")
	)
	(segment
		(start 317.5 -85.598)
		(end 315.468 -87.63)
		(width 0.127)
		(layer "In5.Cu")
		(net "NCSI_10G_RXD1")
	)
	(segment
		(start 322.707 -83.479132)
		(end 320.588132 -85.598)
		(width 0.127)
		(layer "In5.Cu")
		(net "NCSI_10G_RXD1")
	)
	(segment
		(start 322.707 -67.564)
		(end 322.707 -83.479132)
		(width 0.127)
		(layer "In5.Cu")
		(net "NCSI_10G_RXD1")
	)
	(segment
		(start 304.81905 -139.065)
		(end 304.927 -139.17295)
		(width 0.127)
		(layer "In5.Cu")
		(net "NCSI_10G_RXD1")
	)
	(segment
		(start 312.283602 -90.2843)
		(end 309.2577 -90.2843)
		(width 0.127)
		(layer "In5.Cu")
		(net "NCSI_10G_RXD1")
	)
	(segment
		(start 300.8503 -103.583232)
		(end 300.609 -103.824532)
		(width 0.127)
		(layer "In5.Cu")
		(net "NCSI_10G_RXD1")
	)
	(segment
		(start 314.937902 -87.63)
		(end 312.283602 -90.2843)
		(width 0.127)
		(layer "In5.Cu")
		(net "NCSI_10G_RXD1")
	)
	(segment
		(start 300.609 -134.913116)
		(end 304.760884 -139.065)
		(width 0.127)
		(layer "In5.Cu")
		(net "NCSI_10G_RXD1")
	)
	(segment
		(start 304.760884 -139.065)
		(end 304.81905 -139.065)
		(width 0.127)
		(layer "In5.Cu")
		(net "NCSI_10G_RXD1")
	)
	(segment
		(start 300.8503 -98.6917)
		(end 300.8503 -103.583232)
		(width 0.127)
		(layer "In5.Cu")
		(net "NCSI_10G_RXD1")
	)
	(segment
		(start 309.2577 -90.2843)
		(end 300.8503 -98.6917)
		(width 0.127)
		(layer "In5.Cu")
		(net "NCSI_10G_RXD1")
	)
	(segment
		(start 321.183 -66.04)
		(end 322.707 -67.564)
		(width 0.127)
		(layer "In5.Cu")
		(net "NCSI_10G_RXD1")
	)
	(segment
		(start 300.609 -103.824532)
		(end 300.609 -134.913116)
		(width 0.127)
		(layer "In5.Cu")
		(net "NCSI_10G_RXD1")
	)
	(segment
		(start 315.468 -87.63)
		(end 314.937902 -87.63)
		(width 0.127)
		(layer "In5.Cu")
		(net "NCSI_10G_RXD1")
	)
	(segment
		(start 320.588132 -85.598)
		(end 317.5 -85.598)
		(width 0.127)
		(layer "In5.Cu")
		(net "NCSI_10G_RXD1")
	)
	(segment
		(start 295.740328 -163.929314)
		(end 295.740328 -166.718488)
		(width 0.1143)
		(layer "F.Cu")
		(net "NCSI_10G_RXD0")
	)
	(segment
		(start 320.675 -64.77)
		(end 320.689732 -64.755268)
		(width 0.1143)
		(layer "F.Cu")
		(net "NCSI_10G_RXD0")
	)
	(segment
		(start 295.234868 -167.223948)
		(end 295.234868 -167.440102)
		(width 0.1143)
		(layer "F.Cu")
		(net "NCSI_10G_RXD0")
	)
	(segment
		(start 321.5386 -64.7446)
		(end 320.7004 -64.7446)
		(width 0.1143)
		(layer "F.Cu")
		(net "NCSI_10G_RXD0")
	)
	(segment
		(start 320.7004 -64.7446)
		(end 320.689732 -64.755268)
		(width 0.1143)
		(layer "F.Cu")
		(net "NCSI_10G_RXD0")
	)
	(segment
		(start 300.157642 -159.512)
		(end 295.740328 -163.929314)
		(width 0.1143)
		(layer "F.Cu")
		(net "NCSI_10G_RXD0")
	)
	(segment
		(start 295.740328 -166.718488)
		(end 295.234868 -167.223948)
		(width 0.1143)
		(layer "F.Cu")
		(net "NCSI_10G_RXD0")
	)
	(segment
		(start 316.846458 -64.77)
		(end 320.675 -64.77)
		(width 0.1143)
		(layer "F.Cu")
		(net "NCSI_10G_RXD0")
	)
	(segment
		(start 300.482 -159.512)
		(end 300.157642 -159.512)
		(width 0.1143)
		(layer "F.Cu")
		(net "NCSI_10G_RXD0")
	)
	(via
		(at 321.5386 -64.7446)
		(size 0.7112)
		(drill 0.3556)
		(layers "F.Cu" "B.Cu")
		(net "NCSI_10G_RXD0")
	)
	(via
		(at 320.689732 -64.755268)
		(size 0.5588)
		(drill 0.3048)
		(layers "F.Cu" "B.Cu")
		(net "NCSI_10G_RXD0")
	)
	(via
		(at 302.006 -135.59155)
		(size 0.5588)
		(drill 0.3048)
		(layers "F.Cu" "B.Cu")
		(net "NCSI_10G_RXD0")
	)
	(via
		(at 300.482 -159.512)
		(size 0.5588)
		(drill 0.3048)
		(layers "F.Cu" "B.Cu")
		(net "NCSI_10G_RXD0")
	)
	(segment
		(start 301.069502 -159.512)
		(end 300.482 -159.512)
		(width 0.127)
		(layer "In2.Cu")
		(net "NCSI_10G_RXD0")
	)
	(segment
		(start 302.7807 -136.36625)
		(end 302.7807 -157.800802)
		(width 0.127)
		(layer "In2.Cu")
		(net "NCSI_10G_RXD0")
	)
	(segment
		(start 302.006 -135.59155)
		(end 302.7807 -136.36625)
		(width 0.127)
		(layer "In2.Cu")
		(net "NCSI_10G_RXD0")
	)
	(segment
		(start 302.7807 -157.800802)
		(end 301.069502 -159.512)
		(width 0.127)
		(layer "In2.Cu")
		(net "NCSI_10G_RXD0")
	)
	(segment
		(start 301.117 -105.602532)
		(end 302.1203 -104.599232)
		(width 0.127)
		(layer "In5.Cu")
		(net "NCSI_10G_RXD0")
	)
	(segment
		(start 323.215 -83.82)
		(end 323.215 -67.280536)
		(width 0.127)
		(layer "In5.Cu")
		(net "NCSI_10G_RXD0")
	)
	(segment
		(start 317.754 -86.106)
		(end 320.929 -86.106)
		(width 0.127)
		(layer "In5.Cu")
		(net "NCSI_10G_RXD0")
	)
	(segment
		(start 309.468266 -90.7923)
		(end 312.494168 -90.7923)
		(width 0.127)
		(layer "In5.Cu")
		(net "NCSI_10G_RXD0")
	)
	(segment
		(start 302.1203 -98.140266)
		(end 309.468266 -90.7923)
		(width 0.127)
		(layer "In5.Cu")
		(net "NCSI_10G_RXD0")
	)
	(segment
		(start 301.117 -134.70255)
		(end 301.117 -105.602532)
		(width 0.127)
		(layer "In5.Cu")
		(net "NCSI_10G_RXD0")
	)
	(segment
		(start 312.494168 -90.7923)
		(end 315.148468 -88.138)
		(width 0.127)
		(layer "In5.Cu")
		(net "NCSI_10G_RXD0")
	)
	(segment
		(start 323.215 -67.280536)
		(end 320.689732 -64.755268)
		(width 0.127)
		(layer "In5.Cu")
		(net "NCSI_10G_RXD0")
	)
	(segment
		(start 302.006 -135.59155)
		(end 301.117 -134.70255)
		(width 0.127)
		(layer "In5.Cu")
		(net "NCSI_10G_RXD0")
	)
	(segment
		(start 320.929 -86.106)
		(end 323.215 -83.82)
		(width 0.127)
		(layer "In5.Cu")
		(net "NCSI_10G_RXD0")
	)
	(segment
		(start 315.148468 -88.138)
		(end 315.722 -88.138)
		(width 0.127)
		(layer "In5.Cu")
		(net "NCSI_10G_RXD0")
	)
	(segment
		(start 315.722 -88.138)
		(end 317.754 -86.106)
		(width 0.127)
		(layer "In5.Cu")
		(net "NCSI_10G_RXD0")
	)
	(segment
		(start 302.1203 -104.599232)
		(end 302.1203 -98.140266)
		(width 0.127)
		(layer "In5.Cu")
		(net "NCSI_10G_RXD0")
	)
	(segment
		(start 117.706902 -219.42171)
		(end 117.351302 -219.06611)
		(width 0.1016)
		(layer "B.Cu")
		(net "SAS_HDD_CONN_SER_RX7_P")
	)
	(segment
		(start 118.688612 -221.5515)
		(end 118.582186 -221.5515)
		(width 0.1016)
		(layer "B.Cu")
		(net "SAS_HDD_CONN_SER_RX7_P")
	)
	(segment
		(start 117.351302 -219.06611)
		(end 117.300248 -219.014802)
		(width 0.1016)
		(layer "B.Cu")
		(net "SAS_HDD_CONN_SER_RX7_P")
	)
	(segment
		(start 117.140736 -217.246962)
		(end 117.140736 -216.662)
		(width 0.1016)
		(layer "B.Cu")
		(net "SAS_HDD_CONN_SER_RX7_P")
	)
	(segment
		(start 117.95379 -220.923104)
		(end 117.95379 -220.017848)
		(width 0.1016)
		(layer "B.Cu")
		(net "SAS_HDD_CONN_SER_RX7_P")
	)
	(segment
		(start 117.061996 -218.44)
		(end 117.061996 -217.417142)
		(width 0.1016)
		(layer "B.Cu")
		(net "SAS_HDD_CONN_SER_RX7_P")
	)
	(segment
		(start 117.094254 -217.339164)
		(end 117.108478 -217.32494)
		(width 0.1016)
		(layer "B.Cu")
		(net "SAS_HDD_CONN_SER_RX7_P")
	)
	(segment
		(start 118.438676 -221.492064)
		(end 118.013226 -221.066614)
		(width 0.1016)
		(layer "B.Cu")
		(net "SAS_HDD_CONN_SER_RX7_P")
	)
	(arc
		(start 117.95379 -220.017848)
		(mid 117.889618 -219.695236)
		(end 117.706902 -219.42171)
		(width 0.1016)
		(layer "B.Cu")
		(net "SAS_HDD_CONN_SER_RX7_P")
	)
	(arc
		(start 118.013226 -221.066614)
		(mid 117.969231 -221.000771)
		(end 117.95379 -220.923104)
		(width 0.1016)
		(layer "B.Cu")
		(net "SAS_HDD_CONN_SER_RX7_P")
	)
	(arc
		(start 118.582186 -221.5515)
		(mid 118.504522 -221.536052)
		(end 118.438676 -221.492064)
		(width 0.1016)
		(layer "B.Cu")
		(net "SAS_HDD_CONN_SER_RX7_P")
	)
	(arc
		(start 117.108478 -217.32494)
		(mid 117.13233 -217.289149)
		(end 117.140736 -217.246962)
		(width 0.1016)
		(layer "B.Cu")
		(net "SAS_HDD_CONN_SER_RX7_P")
	)
	(arc
		(start 117.300248 -219.014802)
		(mid 117.123952 -218.751096)
		(end 117.061996 -218.44)
		(width 0.1016)
		(layer "B.Cu")
		(net "SAS_HDD_CONN_SER_RX7_P")
	)
	(arc
		(start 117.061996 -217.417142)
		(mid 117.070372 -217.374942)
		(end 117.094254 -217.339164)
		(width 0.1016)
		(layer "B.Cu")
		(net "SAS_HDD_CONN_SER_RX7_P")
	)
	(segment
		(start 319.338452 -58.547)
		(end 320.338958 -58.547)
		(width 0.1143)
		(layer "F.Cu")
		(net "NCSI_10G_TXEN")
	)
	(segment
		(start 320.465958 -58.674)
		(end 321.100958 -59.309)
		(width 0.1143)
		(layer "F.Cu")
		(net "NCSI_10G_TXEN")
	)
	(segment
		(start 295.225216 -169.840148)
		(end 294.828214 -169.443146)
		(width 0.1143)
		(layer "F.Cu")
		(net "NCSI_10G_TXEN")
	)
	(segment
		(start 320.338958 -58.547)
		(end 320.465958 -58.674)
		(width 0.1143)
		(layer "F.Cu")
		(net "NCSI_10G_TXEN")
	)
	(segment
		(start 295.234868 -169.840148)
		(end 295.225216 -169.840148)
		(width 0.1143)
		(layer "F.Cu")
		(net "NCSI_10G_TXEN")
	)
	(via
		(at 321.100958 -59.309)
		(size 0.5588)
		(drill 0.3048)
		(layers "F.Cu" "B.Cu")
		(net "NCSI_10G_TXEN")
	)
	(via
		(at 320.465958 -58.674)
		(size 0.7112)
		(drill 0.3556)
		(layers "F.Cu" "B.Cu")
		(net "NCSI_10G_TXEN")
	)
	(via
		(at 302.514 -134.112)
		(size 0.5588)
		(drill 0.3048)
		(layers "F.Cu" "B.Cu")
		(net "NCSI_10G_TXEN")
	)
	(via
		(at 294.828214 -169.443146)
		(size 0.508)
		(drill 0.254)
		(layers "F.Cu" "B.Cu")
		(net "NCSI_10G_TXEN")
	)
	(segment
		(start 300.1137 -139.923266)
		(end 300.1137 -136.064752)
		(width 0.127)
		(layer "In2.Cu")
		(net "NCSI_10G_TXEN")
	)
	(segment
		(start 298.323 -155.759404)
		(end 301.2567 -152.825704)
		(width 0.127)
		(layer "In2.Cu")
		(net "NCSI_10G_TXEN")
	)
	(segment
		(start 301.2567 -152.825704)
		(end 301.2567 -141.066266)
		(width 0.127)
		(layer "In2.Cu")
		(net "NCSI_10G_TXEN")
	)
	(segment
		(start 301.2567 -141.066266)
		(end 300.1137 -139.923266)
		(width 0.127)
		(layer "In2.Cu")
		(net "NCSI_10G_TXEN")
	)
	(segment
		(start 294.828214 -169.217848)
		(end 295.235884 -168.810178)
		(width 0.1016)
		(layer "In2.Cu")
		(net "NCSI_10G_TXEN")
	)
	(segment
		(start 295.402 -164.719)
		(end 298.323 -161.798)
		(width 0.127)
		(layer "In2.Cu")
		(net "NCSI_10G_TXEN")
	)
	(segment
		(start 298.323 -161.798)
		(end 298.323 -155.759404)
		(width 0.127)
		(layer "In2.Cu")
		(net "NCSI_10G_TXEN")
	)
	(segment
		(start 294.828214 -169.443146)
		(end 294.828214 -169.217848)
		(width 0.1016)
		(layer "In2.Cu")
		(net "NCSI_10G_TXEN")
	)
	(segment
		(start 295.236392 -168.473374)
		(end 295.236392 -166.858442)
		(width 0.1016)
		(layer "In2.Cu")
		(net "NCSI_10G_TXEN")
	)
	(segment
		(start 295.235884 -168.473882)
		(end 295.236392 -168.473374)
		(width 0.1016)
		(layer "In2.Cu")
		(net "NCSI_10G_TXEN")
	)
	(segment
		(start 295.402 -166.692834)
		(end 295.402 -164.719)
		(width 0.127)
		(layer "In2.Cu")
		(net "NCSI_10G_TXEN")
	)
	(segment
		(start 300.1137 -136.064752)
		(end 302.066452 -134.112)
		(width 0.127)
		(layer "In2.Cu")
		(net "NCSI_10G_TXEN")
	)
	(segment
		(start 295.236392 -166.858442)
		(end 295.402 -166.692834)
		(width 0.127)
		(layer "In2.Cu")
		(net "NCSI_10G_TXEN")
	)
	(segment
		(start 295.235884 -168.810178)
		(end 295.235884 -168.473882)
		(width 0.1016)
		(layer "In2.Cu")
		(net "NCSI_10G_TXEN")
	)
	(segment
		(start 302.066452 -134.112)
		(end 302.514 -134.112)
		(width 0.127)
		(layer "In2.Cu")
		(net "NCSI_10G_TXEN")
	)
	(segment
		(start 314.911232 -90.1065)
		(end 318.403732 -86.614)
		(width 0.127)
		(layer "In5.Cu")
		(net "NCSI_10G_TXEN")
	)
	(segment
		(start 302.514 -134.112)
		(end 302.514 -128.016)
		(width 0.127)
		(layer "In5.Cu")
		(net "NCSI_10G_TXEN")
	)
	(segment
		(start 304.6603 -108.663232)
		(end 304.6603 -97.189036)
		(width 0.127)
		(layer "In5.Cu")
		(net "NCSI_10G_TXEN")
	)
	(segment
		(start 323.723 -84.030566)
		(end 323.723 -61.931042)
		(width 0.127)
		(layer "In5.Cu")
		(net "NCSI_10G_TXEN")
	)
	(segment
		(start 312.704734 -91.3003)
		(end 313.898534 -90.1065)
		(width 0.127)
		(layer "In5.Cu")
		(net "NCSI_10G_TXEN")
	)
	(segment
		(start 304.546 -108.777532)
		(end 304.6603 -108.663232)
		(width 0.127)
		(layer "In5.Cu")
		(net "NCSI_10G_TXEN")
	)
	(segment
		(start 302.514 -128.016)
		(end 304.546 -125.984)
		(width 0.127)
		(layer "In5.Cu")
		(net "NCSI_10G_TXEN")
	)
	(segment
		(start 304.546 -125.984)
		(end 304.546 -108.777532)
		(width 0.127)
		(layer "In5.Cu")
		(net "NCSI_10G_TXEN")
	)
	(segment
		(start 323.723 -61.931042)
		(end 321.100958 -59.309)
		(width 0.127)
		(layer "In5.Cu")
		(net "NCSI_10G_TXEN")
	)
	(segment
		(start 318.403732 -86.614)
		(end 321.139566 -86.614)
		(width 0.127)
		(layer "In5.Cu")
		(net "NCSI_10G_TXEN")
	)
	(segment
		(start 321.139566 -86.614)
		(end 323.723 -84.030566)
		(width 0.127)
		(layer "In5.Cu")
		(net "NCSI_10G_TXEN")
	)
	(segment
		(start 313.898534 -90.1065)
		(end 314.911232 -90.1065)
		(width 0.127)
		(layer "In5.Cu")
		(net "NCSI_10G_TXEN")
	)
	(segment
		(start 304.6603 -97.189036)
		(end 310.549036 -91.3003)
		(width 0.127)
		(layer "In5.Cu")
		(net "NCSI_10G_TXEN")
	)
	(segment
		(start 310.549036 -91.3003)
		(end 312.704734 -91.3003)
		(width 0.127)
		(layer "In5.Cu")
		(net "NCSI_10G_TXEN")
	)
	(segment
		(start 116.686838 -212.428836)
		(end 116.672868 -212.442806)
		(width 0.1016)
		(layer "B.Cu")
		(net "SAS_HDD_REDV_SER_RX7_N")
	)
	(segment
		(start 116.719096 -207.894428)
		(end 116.719096 -212.351112)
		(width 0.1016)
		(layer "B.Cu")
		(net "SAS_HDD_REDV_SER_RX7_N")
	)
	(segment
		(start 116.64061 -212.52053)
		(end 116.64061 -213.106)
		(width 0.1016)
		(layer "B.Cu")
		(net "SAS_HDD_REDV_SER_RX7_N")
	)
	(segment
		(start 116.5098 -206.5147)
		(end 116.5098 -207.389222)
		(width 0.1016)
		(layer "B.Cu")
		(net "SAS_HDD_REDV_SER_RX7_N")
	)
	(segment
		(start 115.894612 -206.3115)
		(end 116.3066 -206.3115)
		(width 0.1016)
		(layer "B.Cu")
		(net "SAS_HDD_REDV_SER_RX7_N")
	)
	(arc
		(start 116.672868 -212.442806)
		(mid 116.648987 -212.478452)
		(end 116.64061 -212.52053)
		(width 0.1016)
		(layer "B.Cu")
		(net "SAS_HDD_REDV_SER_RX7_N")
	)
	(arc
		(start 116.719096 -212.351112)
		(mid 116.710709 -212.393186)
		(end 116.686838 -212.428836)
		(width 0.1016)
		(layer "B.Cu")
		(net "SAS_HDD_REDV_SER_RX7_N")
	)
	(arc
		(start 116.6368 -207.6958)
		(mid 116.697692 -207.786931)
		(end 116.719096 -207.894428)
		(width 0.1016)
		(layer "B.Cu")
		(net "SAS_HDD_REDV_SER_RX7_N")
	)
	(arc
		(start 116.5098 -207.389222)
		(mid 116.542804 -207.555145)
		(end 116.6368 -207.6958)
		(width 0.1016)
		(layer "B.Cu")
		(net "SAS_HDD_REDV_SER_RX7_N")
	)
	(arc
		(start 116.3066 -206.3115)
		(mid 116.450284 -206.371016)
		(end 116.5098 -206.5147)
		(width 0.1016)
		(layer "B.Cu")
		(net "SAS_HDD_REDV_SER_RX7_N")
	)
	(segment
		(start 315.910214 -58.799984)
		(end 317.410846 -57.299352)
		(width 0.1143)
		(layer "F.Cu")
		(net "NCSI_10G_RCSDV_R")
	)
	(segment
		(start 318.449198 -56.261)
		(end 317.410846 -57.299352)
		(width 0.1143)
		(layer "F.Cu")
		(net "NCSI_10G_RCSDV_R")
	)
	(segment
		(start 313.125104 -58.799984)
		(end 315.910214 -58.799984)
		(width 0.1143)
		(layer "F.Cu")
		(net "NCSI_10G_RCSDV_R")
	)
	(segment
		(start 318.449452 -56.261)
		(end 318.449198 -56.261)
		(width 0.1143)
		(layer "F.Cu")
		(net "NCSI_10G_RCSDV_R")
	)
	(via
		(at 317.410846 -57.299352)
		(size 0.7112)
		(drill 0.3556)
		(layers "F.Cu" "B.Cu")
		(net "NCSI_10G_RCSDV_R")
	)
	(via
		(at 121.812812 -214.1728)
		(size 0.7112)
		(drill 0.3556)
		(layers "F.Cu" "B.Cu")
		(net "REDV_D1_A")
	)
	(segment
		(start 121.351548 -214.634064)
		(end 121.812812 -214.1728)
		(width 0.1143)
		(layer "B.Cu")
		(net "REDV_D1_A")
	)
	(segment
		(start 123.082812 -214.1728)
		(end 121.812812 -214.1728)
		(width 0.1143)
		(layer "B.Cu")
		(net "REDV_D1_A")
	)
	(segment
		(start 123.959112 -214.376)
		(end 123.286012 -214.376)
		(width 0.1143)
		(layer "B.Cu")
		(net "REDV_D1_A")
	)
	(segment
		(start 123.286012 -214.376)
		(end 123.082812 -214.1728)
		(width 0.1143)
		(layer "B.Cu")
		(net "REDV_D1_A")
	)
	(segment
		(start 120.161812 -214.634064)
		(end 121.351548 -214.634064)
		(width 0.1143)
		(layer "B.Cu")
		(net "REDV_D1_A")
	)
	(segment
		(start 316.86373 -58.547)
		(end 317.246 -58.547)
		(width 0.1143)
		(layer "F.Cu")
		(net "NCSI_10G_RCLK_R")
	)
	(segment
		(start 318.449452 -57.642506)
		(end 317.544958 -58.547)
		(width 0.1143)
		(layer "F.Cu")
		(net "NCSI_10G_RCLK_R")
	)
	(segment
		(start 314.287916 -59.600084)
		(end 314.592716 -59.295284)
		(width 0.1143)
		(layer "F.Cu")
		(net "NCSI_10G_RCLK_R")
	)
	(segment
		(start 318.449452 -57.404)
		(end 318.449452 -57.642506)
		(width 0.1143)
		(layer "F.Cu")
		(net "NCSI_10G_RCLK_R")
	)
	(segment
		(start 314.592716 -59.295284)
		(end 316.115446 -59.295284)
		(width 0.1143)
		(layer "F.Cu")
		(net "NCSI_10G_RCLK_R")
	)
	(segment
		(start 313.125104 -59.600084)
		(end 314.287916 -59.600084)
		(width 0.1143)
		(layer "F.Cu")
		(net "NCSI_10G_RCLK_R")
	)
	(segment
		(start 317.544958 -58.547)
		(end 317.246 -58.547)
		(width 0.1143)
		(layer "F.Cu")
		(net "NCSI_10G_RCLK_R")
	)
	(segment
		(start 316.115446 -59.295284)
		(end 316.86373 -58.547)
		(width 0.1143)
		(layer "F.Cu")
		(net "NCSI_10G_RCLK_R")
	)
	(via
		(at 317.246 -58.547)
		(size 0.7112)
		(drill 0.3556)
		(layers "F.Cu" "B.Cu")
		(net "NCSI_10G_RCLK_R")
	)
	(segment
		(start 318.449452 -58.547)
		(end 317.814452 -59.182)
		(width 0.1143)
		(layer "F.Cu")
		(net "NCSI_10G_TXEN_R")
	)
	(segment
		(start 314.630816 -60.400184)
		(end 315.170566 -59.860434)
		(width 0.1143)
		(layer "F.Cu")
		(net "NCSI_10G_TXEN_R")
	)
	(segment
		(start 316.320678 -59.790584)
		(end 315.28385 -59.790584)
		(width 0.1143)
		(layer "F.Cu")
		(net "NCSI_10G_TXEN_R")
	)
	(segment
		(start 315.28385 -59.790584)
		(end 315.214 -59.860434)
		(width 0.1143)
		(layer "F.Cu")
		(net "NCSI_10G_TXEN_R")
	)
	(segment
		(start 315.170566 -59.860434)
		(end 315.214 -59.860434)
		(width 0.1143)
		(layer "F.Cu")
		(net "NCSI_10G_TXEN_R")
	)
	(segment
		(start 317.814452 -59.182)
		(end 316.929262 -59.182)
		(width 0.1143)
		(layer "F.Cu")
		(net "NCSI_10G_TXEN_R")
	)
	(segment
		(start 316.929262 -59.182)
		(end 316.320678 -59.790584)
		(width 0.1143)
		(layer "F.Cu")
		(net "NCSI_10G_TXEN_R")
	)
	(segment
		(start 313.125104 -60.400184)
		(end 314.630816 -60.400184)
		(width 0.1143)
		(layer "F.Cu")
		(net "NCSI_10G_TXEN_R")
	)
	(via
		(at 315.214 -59.860434)
		(size 0.7112)
		(drill 0.3556)
		(layers "F.Cu" "B.Cu")
		(net "NCSI_10G_TXEN_R")
	)
	(segment
		(start 315.055758 -66.000122)
		(end 313.125104 -66.000122)
		(width 0.1143)
		(layer "F.Cu")
		(net "NCSI_10G_RXD1_R")
	)
	(segment
		(start 315.957458 -65.913)
		(end 315.174122 -65.913)
		(width 0.1143)
		(layer "F.Cu")
		(net "NCSI_10G_RXD1_R")
	)
	(segment
		(start 315.174122 -65.913)
		(end 315.087 -66.000122)
		(width 0.1143)
		(layer "F.Cu")
		(net "NCSI_10G_RXD1_R")
	)
	(segment
		(start 315.087 -66.000122)
		(end 315.055758 -66.000122)
		(width 0.1143)
		(layer "F.Cu")
		(net "NCSI_10G_RXD1_R")
	)
	(via
		(at 315.055758 -66.000122)
		(size 0.7112)
		(drill 0.3556)
		(layers "F.Cu" "B.Cu")
		(net "NCSI_10G_RXD1_R")
	)
	(segment
		(start 296.034968 -169.840148)
		(end 296.034968 -169.8498)
		(width 0.1143)
		(layer "F.Cu")
		(net "NCSI_10G_RCSDV")
	)
	(segment
		(start 296.034968 -169.8498)
		(end 295.634918 -170.24985)
		(width 0.1143)
		(layer "F.Cu")
		(net "NCSI_10G_RCSDV")
	)
	(segment
		(start 319.338452 -56.261)
		(end 321.056 -56.261)
		(width 0.1143)
		(layer "F.Cu")
		(net "NCSI_10G_RCSDV")
	)
	(segment
		(start 321.056 -56.261)
		(end 324.231 -59.436)
		(width 0.1143)
		(layer "F.Cu")
		(net "NCSI_10G_RCSDV")
	)
	(via
		(at 300.198536 -156.009594)
		(size 0.7112)
		(drill 0.3556)
		(layers "F.Cu" "B.Cu")
		(net "NCSI_10G_RCSDV")
	)
	(via
		(at 313.182 -140.843508)
		(size 0.5588)
		(drill 0.3048)
		(layers "F.Cu" "B.Cu")
		(net "NCSI_10G_RCSDV")
	)
	(via
		(at 324.231 -59.436)
		(size 0.5588)
		(drill 0.3048)
		(layers "F.Cu" "B.Cu")
		(net "NCSI_10G_RCSDV")
	)
	(via
		(at 295.634918 -170.24985)
		(size 0.508)
		(drill 0.254)
		(layers "F.Cu" "B.Cu")
		(net "NCSI_10G_RCSDV")
	)
	(segment
		(start 297.0911 -168.556432)
		(end 296.826686 -168.820846)
		(width 0.0889)
		(layer "B.Cu")
		(net "NCSI_10G_RCSDV")
	)
	(segment
		(start 298.1325 -161.70529)
		(end 298.1325 -165.671246)
		(width 0.1143)
		(layer "B.Cu")
		(net "NCSI_10G_RCSDV")
	)
	(segment
		(start 298.2595 -157.94863)
		(end 298.2595 -161.57829)
		(width 0.1143)
		(layer "B.Cu")
		(net "NCSI_10G_RCSDV")
	)
	(segment
		(start 300.198536 -156.009594)
		(end 301.14113 -155.067)
		(width 0.1143)
		(layer "B.Cu")
		(net "NCSI_10G_RCSDV")
	)
	(segment
		(start 313.309 -151.799544)
		(end 313.309 -140.970508)
		(width 0.1143)
		(layer "B.Cu")
		(net "NCSI_10G_RCSDV")
	)
	(segment
		(start 301.14113 -155.067)
		(end 310.041544 -155.067)
		(width 0.1143)
		(layer "B.Cu")
		(net "NCSI_10G_RCSDV")
	)
	(segment
		(start 296.592498 -169.841418)
		(end 296.04335 -169.841418)
		(width 0.0889)
		(layer "B.Cu")
		(net "NCSI_10G_RCSDV")
	)
	(segment
		(start 296.826686 -169.60723)
		(end 296.592498 -169.841418)
		(width 0.0889)
		(layer "B.Cu")
		(net "NCSI_10G_RCSDV")
	)
	(segment
		(start 296.826686 -168.820846)
		(end 296.826686 -169.60723)
		(width 0.0889)
		(layer "B.Cu")
		(net "NCSI_10G_RCSDV")
	)
	(segment
		(start 298.041314 -165.762432)
		(end 298.041314 -166.367968)
		(width 0.0889)
		(layer "B.Cu")
		(net "NCSI_10G_RCSDV")
	)
	(segment
		(start 298.2595 -161.57829)
		(end 298.1325 -161.70529)
		(width 0.1143)
		(layer "B.Cu")
		(net "NCSI_10G_RCSDV")
	)
	(segment
		(start 313.309 -140.970508)
		(end 313.182 -140.843508)
		(width 0.1143)
		(layer "B.Cu")
		(net "NCSI_10G_RCSDV")
	)
	(segment
		(start 298.041314 -166.367968)
		(end 297.0911 -167.318182)
		(width 0.0889)
		(layer "B.Cu")
		(net "NCSI_10G_RCSDV")
	)
	(segment
		(start 296.04335 -169.841418)
		(end 295.634918 -170.24985)
		(width 0.0889)
		(layer "B.Cu")
		(net "NCSI_10G_RCSDV")
	)
	(segment
		(start 300.198536 -156.009594)
		(end 298.2595 -157.94863)
		(width 0.1143)
		(layer "B.Cu")
		(net "NCSI_10G_RCSDV")
	)
	(segment
		(start 310.041544 -155.067)
		(end 313.309 -151.799544)
		(width 0.1143)
		(layer "B.Cu")
		(net "NCSI_10G_RCSDV")
	)
	(segment
		(start 297.0911 -167.318182)
		(end 297.0911 -168.556432)
		(width 0.0889)
		(layer "B.Cu")
		(net "NCSI_10G_RCSDV")
	)
	(segment
		(start 298.1325 -165.671246)
		(end 298.041314 -165.762432)
		(width 0.1143)
		(layer "B.Cu")
		(net "NCSI_10G_RCSDV")
	)
	(segment
		(start 325.247 -60.452)
		(end 324.231 -59.436)
		(width 0.127)
		(layer "In5.Cu")
		(net "NCSI_10G_RCSDV")
	)
	(segment
		(start 325.247 -84.662264)
		(end 325.247 -60.452)
		(width 0.127)
		(layer "In5.Cu")
		(net "NCSI_10G_RCSDV")
	)
	(segment
		(start 313.182 -140.843508)
		(end 309.307992 -136.9695)
		(width 0.127)
		(layer "In5.Cu")
		(net "NCSI_10G_RCSDV")
	)
	(segment
		(start 306.1843 -109.29493)
		(end 306.1843 -99.812602)
		(width 0.127)
		(layer "In5.Cu")
		(net "NCSI_10G_RCSDV")
	)
	(segment
		(start 309.307992 -136.9695)
		(end 308.881272 -136.9695)
		(width 0.127)
		(layer "In5.Cu")
		(net "NCSI_10G_RCSDV")
	)
	(segment
		(start 306.0827 -109.39653)
		(end 306.1843 -109.29493)
		(width 0.127)
		(layer "In5.Cu")
		(net "NCSI_10G_RCSDV")
	)
	(segment
		(start 306.1843 -99.812602)
		(end 313.159902 -92.837)
		(width 0.127)
		(layer "In5.Cu")
		(net "NCSI_10G_RCSDV")
	)
	(segment
		(start 306.0827 -134.170928)
		(end 306.0827 -109.39653)
		(width 0.127)
		(layer "In5.Cu")
		(net "NCSI_10G_RCSDV")
	)
	(segment
		(start 313.323732 -92.837)
		(end 314.212732 -91.948)
		(width 0.127)
		(layer "In5.Cu")
		(net "NCSI_10G_RCSDV")
	)
	(segment
		(start 313.159902 -92.837)
		(end 313.323732 -92.837)
		(width 0.127)
		(layer "In5.Cu")
		(net "NCSI_10G_RCSDV")
	)
	(segment
		(start 308.881272 -136.9695)
		(end 306.0827 -134.170928)
		(width 0.127)
		(layer "In5.Cu")
		(net "NCSI_10G_RCSDV")
	)
	(segment
		(start 317.961264 -91.948)
		(end 325.247 -84.662264)
		(width 0.127)
		(layer "In5.Cu")
		(net "NCSI_10G_RCSDV")
	)
	(segment
		(start 314.212732 -91.948)
		(end 317.961264 -91.948)
		(width 0.127)
		(layer "In5.Cu")
		(net "NCSI_10G_RCSDV")
	)
	(segment
		(start 315.957458 -64.77)
		(end 315.055758 -64.77)
		(width 0.1143)
		(layer "F.Cu")
		(net "NCSI_10G_RXD0_R")
	)
	(segment
		(start 314.625736 -65.200022)
		(end 315.055758 -64.77)
		(width 0.1143)
		(layer "F.Cu")
		(net "NCSI_10G_RXD0_R")
	)
	(segment
		(start 313.125104 -65.200022)
		(end 314.625736 -65.200022)
		(width 0.1143)
		(layer "F.Cu")
		(net "NCSI_10G_RXD0_R")
	)
	(via
		(at 315.055758 -64.77)
		(size 0.7112)
		(drill 0.3556)
		(layers "F.Cu" "B.Cu")
		(net "NCSI_10G_RXD0_R")
	)
	(segment
		(start 233.426 -14.0335)
		(end 231.521 -14.0335)
		(width 0.1778)
		(layer "F.Cu")
		(net "ENCLO_LED_RED_D")
	)
	(segment
		(start 231.521 -14.0335)
		(end 231.013 -13.5255)
		(width 0.1778)
		(layer "F.Cu")
		(net "ENCLO_LED_RED_D")
	)
	(segment
		(start 228.37775 -13.36675)
		(end 228.5365 -13.5255)
		(width 0.1778)
		(layer "F.Cu")
		(net "ENCLO_LED_RED_D")
	)
	(segment
		(start 228.5365 -13.5255)
		(end 231.013 -13.5255)
		(width 0.1778)
		(layer "F.Cu")
		(net "ENCLO_LED_RED_D")
	)
	(segment
		(start 226.8855 -13.36675)
		(end 228.37775 -13.36675)
		(width 0.1778)
		(layer "F.Cu")
		(net "ENCLO_LED_RED_D")
	)
	(via
		(at 228.5365 -13.5255)
		(size 0.7112)
		(drill 0.3556)
		(layers "F.Cu" "B.Cu")
		(net "ENCLO_LED_RED_D")
	)
	(segment
		(start 286.804354 -67.017646)
		(end 287.401 -66.421)
		(width 0.1143)
		(layer "F.Cu")
		(net "HSW_SCL1")
	)
	(segment
		(start 289.2425 -66.675)
		(end 288.29 -66.675)
		(width 0.1143)
		(layer "F.Cu")
		(net "HSW_SCL1")
	)
	(segment
		(start 286.160972 -67.017646)
		(end 286.804354 -67.017646)
		(width 0.1143)
		(layer "F.Cu")
		(net "HSW_SCL1")
	)
	(segment
		(start 289.2425 -65.659)
		(end 289.2425 -66.675)
		(width 0.1143)
		(layer "F.Cu")
		(net "HSW_SCL1")
	)
	(segment
		(start 288.29 -66.675)
		(end 288.036 -66.421)
		(width 0.1143)
		(layer "F.Cu")
		(net "HSW_SCL1")
	)
	(segment
		(start 287.401 -66.421)
		(end 288.036 -66.421)
		(width 0.1143)
		(layer "F.Cu")
		(net "HSW_SCL1")
	)
	(via
		(at 288.036 -66.421)
		(size 0.7112)
		(drill 0.3556)
		(layers "F.Cu" "B.Cu")
		(net "HSW_SCL1")
	)
	(segment
		(start 288.036 -67.691)
		(end 289.2425 -67.691)
		(width 0.1143)
		(layer "F.Cu")
		(net "HSW_SDA1")
	)
	(segment
		(start 286.160972 -67.516756)
		(end 287.734756 -67.516756)
		(width 0.1143)
		(layer "F.Cu")
		(net "HSW_SDA1")
	)
	(segment
		(start 287.909 -67.691)
		(end 288.036 -67.691)
		(width 0.1143)
		(layer "F.Cu")
		(net "HSW_SDA1")
	)
	(segment
		(start 289.2425 -67.691)
		(end 289.2425 -68.707)
		(width 0.1143)
		(layer "F.Cu")
		(net "HSW_SDA1")
	)
	(segment
		(start 287.734756 -67.516756)
		(end 287.909 -67.691)
		(width 0.1143)
		(layer "F.Cu")
		(net "HSW_SDA1")
	)
	(via
		(at 288.036 -67.691)
		(size 0.7112)
		(drill 0.3556)
		(layers "F.Cu" "B.Cu")
		(net "HSW_SDA1")
	)
	(via
		(at 109.900212 -210.1342)
		(size 0.7112)
		(drill 0.4064)
		(layers "F.Cu" "B.Cu")
		(net "1.2V_REDV")
	)
	(via
		(at 109.417612 -219.456)
		(size 0.7112)
		(drill 0.4064)
		(layers "F.Cu" "B.Cu")
		(net "1.2V_REDV")
	)
	(via
		(at 121.152412 -210.947)
		(size 0.7112)
		(drill 0.3556)
		(layers "F.Cu" "B.Cu")
		(net "1.2V_REDV")
	)
	(via
		(at 122.625612 -211.328)
		(size 0.7112)
		(drill 0.4064)
		(layers "F.Cu" "B.Cu")
		(net "1.2V_REDV")
	)
	(via
		(at 115.285012 -209.5246)
		(size 0.7112)
		(drill 0.4064)
		(layers "F.Cu" "B.Cu")
		(net "1.2V_REDV")
	)
	(via
		(at 115.894612 -220.091)
		(size 0.7112)
		(drill 0.4064)
		(layers "F.Cu" "B.Cu")
		(net "1.2V_REDV")
	)
	(via
		(at 122.498612 -220.345)
		(size 0.7112)
		(drill 0.4064)
		(layers "F.Cu" "B.Cu")
		(net "1.2V_REDV")
	)
	(via
		(at 115.894612 -210.693)
		(size 0.7112)
		(drill 0.3556)
		(layers "F.Cu" "B.Cu")
		(net "1.2V_REDV")
	)
	(segment
		(start 116.140738 -217.685874)
		(end 115.894612 -217.932)
		(width 0.3048)
		(layer "B.Cu")
		(net "1.2V_REDV")
	)
	(segment
		(start 118.640606 -212.392006)
		(end 120.085612 -210.947)
		(width 0.3048)
		(layer "B.Cu")
		(net "1.2V_REDV")
	)
	(segment
		(start 118.640606 -213.106)
		(end 118.640606 -212.392006)
		(width 0.3048)
		(layer "B.Cu")
		(net "1.2V_REDV")
	)
	(segment
		(start 108.782612 -209.423)
		(end 109.493812 -210.1342)
		(width 0.5588)
		(layer "B.Cu")
		(net "1.2V_REDV")
	)
	(segment
		(start 114.472212 -206.3115)
		(end 114.472212 -208.7118)
		(width 0.635)
		(layer "B.Cu")
		(net "1.2V_REDV")
	)
	(segment
		(start 116.140738 -213.106)
		(end 116.140738 -211.955126)
		(width 0.3048)
		(layer "B.Cu")
		(net "1.2V_REDV")
	)
	(segment
		(start 109.493812 -210.1342)
		(end 109.900212 -210.1342)
		(width 0.5588)
		(layer "B.Cu")
		(net "1.2V_REDV")
	)
	(segment
		(start 122.244612 -210.947)
		(end 122.625612 -211.328)
		(width 0.635)
		(layer "B.Cu")
		(net "1.2V_REDV")
	)
	(segment
		(start 122.625612 -211.328)
		(end 123.959112 -211.328)
		(width 0.635)
		(layer "B.Cu")
		(net "1.2V_REDV")
	)
	(segment
		(start 114.472212 -208.7118)
		(end 115.285012 -209.5246)
		(width 0.635)
		(layer "B.Cu")
		(net "1.2V_REDV")
	)
	(segment
		(start 115.640612 -216.662)
		(end 115.640612 -217.678)
		(width 0.3048)
		(layer "B.Cu")
		(net "1.2V_REDV")
	)
	(segment
		(start 110.624112 -219.0115)
		(end 110.179612 -219.456)
		(width 0.635)
		(layer "B.Cu")
		(net "1.2V_REDV")
	)
	(segment
		(start 118.640606 -216.662)
		(end 118.640606 -218.010994)
		(width 0.3048)
		(layer "B.Cu")
		(net "1.2V_REDV")
	)
	(segment
		(start 110.179612 -219.456)
		(end 109.417612 -219.456)
		(width 0.635)
		(layer "B.Cu")
		(net "1.2V_REDV")
	)
	(segment
		(start 108.465112 -209.423)
		(end 108.782612 -209.423)
		(width 0.5588)
		(layer "B.Cu")
		(net "1.2V_REDV")
	)
	(segment
		(start 113.14049 -218.019122)
		(end 112.148112 -219.0115)
		(width 0.3048)
		(layer "B.Cu")
		(net "1.2V_REDV")
	)
	(segment
		(start 113.14049 -212.05444)
		(end 111.817912 -210.731862)
		(width 0.3048)
		(layer "B.Cu")
		(net "1.2V_REDV")
	)
	(segment
		(start 115.640612 -217.678)
		(end 115.894612 -217.932)
		(width 0.3048)
		(layer "B.Cu")
		(net "1.2V_REDV")
	)
	(segment
		(start 113.14049 -213.106)
		(end 113.14049 -212.05444)
		(width 0.3048)
		(layer "B.Cu")
		(net "1.2V_REDV")
	)
	(segment
		(start 118.640606 -218.010994)
		(end 120.085612 -219.456)
		(width 0.3048)
		(layer "B.Cu")
		(net "1.2V_REDV")
	)
	(segment
		(start 120.720612 -219.456)
		(end 121.609612 -219.456)
		(width 0.635)
		(layer "B.Cu")
		(net "1.2V_REDV")
	)
	(segment
		(start 120.085612 -210.947)
		(end 120.974612 -210.947)
		(width 0.3048)
		(layer "B.Cu")
		(net "1.2V_REDV")
	)
	(segment
		(start 111.817912 -210.731862)
		(end 111.22025 -210.1342)
		(width 0.635)
		(layer "B.Cu")
		(net "1.2V_REDV")
	)
	(segment
		(start 115.767612 -220.218)
		(end 115.894612 -220.091)
		(width 0.635)
		(layer "B.Cu")
		(net "1.2V_REDV")
	)
	(segment
		(start 116.140738 -211.955126)
		(end 115.894612 -211.709)
		(width 0.3048)
		(layer "B.Cu")
		(net "1.2V_REDV")
	)
	(segment
		(start 115.767612 -221.5515)
		(end 115.767612 -220.218)
		(width 0.635)
		(layer "B.Cu")
		(net "1.2V_REDV")
	)
	(segment
		(start 122.498612 -220.345)
		(end 123.565412 -220.345)
		(width 0.635)
		(layer "B.Cu")
		(net "1.2V_REDV")
	)
	(segment
		(start 115.894612 -210.693)
		(end 115.894612 -210.0834)
		(width 0.635)
		(layer "B.Cu")
		(net "1.2V_REDV")
	)
	(segment
		(start 115.335812 -209.5246)
		(end 115.285012 -209.5246)
		(width 0.635)
		(layer "B.Cu")
		(net "1.2V_REDV")
	)
	(segment
		(start 115.640612 -211.963)
		(end 115.894612 -211.709)
		(width 0.3048)
		(layer "B.Cu")
		(net "1.2V_REDV")
	)
	(segment
		(start 120.974612 -210.947)
		(end 121.152412 -210.947)
		(width 0.635)
		(layer "B.Cu")
		(net "1.2V_REDV")
	)
	(segment
		(start 115.894612 -217.932)
		(end 115.894612 -220.091)
		(width 0.635)
		(layer "B.Cu")
		(net "1.2V_REDV")
	)
	(segment
		(start 116.140738 -216.662)
		(end 116.140738 -217.685874)
		(width 0.3048)
		(layer "B.Cu")
		(net "1.2V_REDV")
	)
	(segment
		(start 115.894612 -210.0834)
		(end 115.335812 -209.5246)
		(width 0.635)
		(layer "B.Cu")
		(net "1.2V_REDV")
	)
	(segment
		(start 112.148112 -219.0115)
		(end 110.624112 -219.0115)
		(width 0.635)
		(layer "B.Cu")
		(net "1.2V_REDV")
	)
	(segment
		(start 120.085612 -219.456)
		(end 120.720612 -219.456)
		(width 0.3048)
		(layer "B.Cu")
		(net "1.2V_REDV")
	)
	(segment
		(start 121.609612 -219.456)
		(end 122.498612 -220.345)
		(width 0.635)
		(layer "B.Cu")
		(net "1.2V_REDV")
	)
	(segment
		(start 111.22025 -210.1342)
		(end 109.900212 -210.1342)
		(width 0.635)
		(layer "B.Cu")
		(net "1.2V_REDV")
	)
	(segment
		(start 123.565412 -220.345)
		(end 123.565412 -222.377)
		(width 0.635)
		(layer "B.Cu")
		(net "1.2V_REDV")
	)
	(segment
		(start 108.439712 -219.456)
		(end 109.417612 -219.456)
		(width 0.635)
		(layer "B.Cu")
		(net "1.2V_REDV")
	)
	(segment
		(start 113.14049 -216.662)
		(end 113.14049 -218.019122)
		(width 0.3048)
		(layer "B.Cu")
		(net "1.2V_REDV")
	)
	(segment
		(start 115.640612 -213.106)
		(end 115.640612 -211.963)
		(width 0.3048)
		(layer "B.Cu")
		(net "1.2V_REDV")
	)
	(segment
		(start 115.894612 -211.709)
		(end 115.894612 -210.693)
		(width 0.635)
		(layer "B.Cu")
		(net "1.2V_REDV")
	)
	(segment
		(start 121.152412 -210.947)
		(end 122.244612 -210.947)
		(width 0.635)
		(layer "B.Cu")
		(net "1.2V_REDV")
	)
	(segment
		(start 299.225208 -182.640224)
		(end 298.830746 -183.034686)
		(width 0.1143)
		(layer "F.Cu")
		(net "BMC0_I2C_IO_EXP_RESET#")
	)
	(segment
		(start 299.23486 -182.640224)
		(end 299.225208 -182.640224)
		(width 0.1143)
		(layer "F.Cu")
		(net "BMC0_I2C_IO_EXP_RESET#")
	)
	(via
		(at 298.830746 -183.034686)
		(size 0.508)
		(drill 0.254)
		(layers "F.Cu" "B.Cu")
		(net "BMC0_I2C_IO_EXP_RESET#")
	)
	(via
		(at 303.421542 -184.80532)
		(size 0.7112)
		(drill 0.3556)
		(layers "F.Cu" "B.Cu")
		(net "BMC0_I2C_IO_EXP_RESET#")
	)
	(segment
		(start 299.339 -183.54294)
		(end 298.830746 -183.034686)
		(width 0.1143)
		(layer "B.Cu")
		(net "BMC0_I2C_IO_EXP_RESET#")
	)
	(segment
		(start 303.421542 -184.80532)
		(end 303.147222 -184.531)
		(width 0.1143)
		(layer "B.Cu")
		(net "BMC0_I2C_IO_EXP_RESET#")
	)
	(segment
		(start 310.30418 -184.80532)
		(end 303.421542 -184.80532)
		(width 0.1143)
		(layer "B.Cu")
		(net "BMC0_I2C_IO_EXP_RESET#")
	)
	(segment
		(start 303.147222 -184.531)
		(end 299.8724 -184.531)
		(width 0.1143)
		(layer "B.Cu")
		(net "BMC0_I2C_IO_EXP_RESET#")
	)
	(segment
		(start 299.8724 -184.531)
		(end 299.339 -183.9976)
		(width 0.1143)
		(layer "B.Cu")
		(net "BMC0_I2C_IO_EXP_RESET#")
	)
	(segment
		(start 299.339 -183.9976)
		(end 299.339 -183.54294)
		(width 0.1143)
		(layer "B.Cu")
		(net "BMC0_I2C_IO_EXP_RESET#")
	)
	(segment
		(start 310.4515 -184.658)
		(end 310.30418 -184.80532)
		(width 0.1143)
		(layer "B.Cu")
		(net "BMC0_I2C_IO_EXP_RESET#")
	)
	(segment
		(start 48.227996 -84.254086)
		(end 42.512996 -84.254086)
		(width 0.1016)
		(layer "F.Cu")
		(net "SAS_EXP2CONN_RX_P_22")
	)
	(segment
		(start 123.35002 -88.349836)
		(end 123.850146 -87.84971)
		(width 0.1016)
		(layer "F.Cu")
		(net "SAS_EXP2CONN_RX_P_22")
	)
	(segment
		(start 38.702996 -88.064086)
		(end 38.702996 -89.613486)
		(width 0.1016)
		(layer "F.Cu")
		(net "SAS_EXP2CONN_RX_P_22")
	)
	(segment
		(start 38.554406 -89.972134)
		(end 38.430454 -90.096086)
		(width 0.1016)
		(layer "F.Cu")
		(net "SAS_EXP2CONN_RX_P_22")
	)
	(segment
		(start 48.989996 -83.937094)
		(end 48.98771 -83.93938)
		(width 0.1016)
		(layer "F.Cu")
		(net "SAS_EXP2CONN_RX_P_22")
	)
	(via
		(at 123.850146 -87.84971)
		(size 0.508)
		(drill 0.254)
		(layers "F.Cu" "B.Cu")
		(net "SAS_EXP2CONN_RX_P_22")
	)
	(via
		(at 48.989996 -83.937094)
		(size 0.5588)
		(drill 0.3048)
		(layers "F.Cu" "B.Cu")
		(net "SAS_EXP2CONN_RX_P_22")
	)
	(via
		(at 38.430454 -90.096086)
		(size 0.5588)
		(drill 0.3048)
		(layers "F.Cu" "B.Cu")
		(net "SAS_EXP2CONN_RX_P_22")
	)
	(arc
		(start 48.98771 -83.93938)
		(mid 48.63915 -84.17228)
		(end 48.227996 -84.254086)
		(width 0.1016)
		(layer "F.Cu")
		(net "SAS_EXP2CONN_RX_P_22")
	)
	(arc
		(start 38.702996 -89.613486)
		(mid 38.664385 -89.807598)
		(end 38.554406 -89.972134)
		(width 0.1016)
		(layer "F.Cu")
		(net "SAS_EXP2CONN_RX_P_22")
	)
	(arc
		(start 42.512996 -84.254086)
		(mid 39.818919 -85.370009)
		(end 38.702996 -88.064086)
		(width 0.1016)
		(layer "F.Cu")
		(net "SAS_EXP2CONN_RX_P_22")
	)
	(segment
		(start 48.989996 -83.937094)
		(end 49.172114 -84.118958)
		(width 0.1016)
		(layer "B.Cu")
		(net "SAS_EXP2CONN_RX_P_22")
	)
	(segment
		(start 51.187096 -78.412086)
		(end 51.187096 -77.904086)
		(width 0.1016)
		(layer "B.Cu")
		(net "SAS_EXP2CONN_RX_P_22")
	)
	(segment
		(start 54.958996 -80.786986)
		(end 54.267862 -80.786986)
		(width 0.1016)
		(layer "B.Cu")
		(net "SAS_EXP2CONN_RX_P_22")
	)
	(segment
		(start 49.497996 -84.254086)
		(end 52.843684 -84.254086)
		(width 0.1016)
		(layer "B.Cu")
		(net "SAS_EXP2CONN_RX_P_22")
	)
	(segment
		(start 55.339996 -82.117438)
		(end 55.339996 -81.167986)
		(width 0.1016)
		(layer "B.Cu")
		(net "SAS_EXP2CONN_RX_P_22")
	)
	(segment
		(start 50.87493 -77.59192)
		(end 50.87493 -77.205586)
		(width 0.1016)
		(layer "B.Cu")
		(net "SAS_EXP2CONN_RX_P_22")
	)
	(segment
		(start 54.069996 -83.746086)
		(end 55.085996 -82.730086)
		(width 0.1016)
		(layer "B.Cu")
		(net "SAS_EXP2CONN_RX_P_22")
	)
	(segment
		(start 55.339742 -82.117184)
		(end 55.339996 -82.117438)
		(width 0.1016)
		(layer "B.Cu")
		(net "SAS_EXP2CONN_RX_P_22")
	)
	(segment
		(start 51.187096 -77.904086)
		(end 50.87493 -77.59192)
		(width 0.1016)
		(layer "B.Cu")
		(net "SAS_EXP2CONN_RX_P_22")
	)
	(arc
		(start 55.085996 -82.730086)
		(mid 55.273806 -82.448869)
		(end 55.339742 -82.117184)
		(width 0.1016)
		(layer "B.Cu")
		(net "SAS_EXP2CONN_RX_P_22")
	)
	(arc
		(start 49.172114 -84.118958)
		(mid 49.321615 -84.218944)
		(end 49.497996 -84.254086)
		(width 0.1016)
		(layer "B.Cu")
		(net "SAS_EXP2CONN_RX_P_22")
	)
	(arc
		(start 51.736498 -79.738728)
		(mid 51.329882 -79.130044)
		(end 51.187096 -78.412086)
		(width 0.1016)
		(layer "B.Cu")
		(net "SAS_EXP2CONN_RX_P_22")
	)
	(arc
		(start 54.267862 -80.786986)
		(mid 52.897907 -80.514654)
		(end 51.736498 -79.738728)
		(width 0.1016)
		(layer "B.Cu")
		(net "SAS_EXP2CONN_RX_P_22")
	)
	(arc
		(start 55.339996 -81.167986)
		(mid 55.228404 -80.898578)
		(end 54.958996 -80.786986)
		(width 0.1016)
		(layer "B.Cu")
		(net "SAS_EXP2CONN_RX_P_22")
	)
	(arc
		(start 52.843684 -84.254086)
		(mid 53.507376 -84.122069)
		(end 54.069996 -83.746086)
		(width 0.1016)
		(layer "B.Cu")
		(net "SAS_EXP2CONN_RX_P_22")
	)
	(segment
		(start 36.02482 -104.859074)
		(end 16.61922 -124.26442)
		(width 0.1016)
		(layer "In5.Cu")
		(net "SAS_EXP2CONN_RX_P_22")
	)
	(segment
		(start 38.6588 -94.045532)
		(end 38.658546 -94.045278)
		(width 0.1016)
		(layer "In5.Cu")
		(net "SAS_EXP2CONN_RX_P_22")
	)
	(segment
		(start 16.50492 -152.608026)
		(end 16.50492 -152.60828)
		(width 0.1016)
		(layer "In5.Cu")
		(net "SAS_EXP2CONN_RX_P_22")
	)
	(segment
		(start 123.477274 -166.215568)
		(end 143.893794 -145.799048)
		(width 0.1016)
		(layer "In5.Cu")
		(net "SAS_EXP2CONN_RX_P_22")
	)
	(segment
		(start 137.385552 -86.880446)
		(end 135.921496 -85.41639)
		(width 0.1016)
		(layer "In5.Cu")
		(net "SAS_EXP2CONN_RX_P_22")
	)
	(segment
		(start 36.7538 -98.644456)
		(end 36.7538 -103.099362)
		(width 0.1016)
		(layer "In5.Cu")
		(net "SAS_EXP2CONN_RX_P_22")
	)
	(segment
		(start 129.4765 -85.4075)
		(end 127.254 -87.63)
		(width 0.1016)
		(layer "In5.Cu")
		(net "SAS_EXP2CONN_RX_P_22")
	)
	(segment
		(start 16.61922 -124.26442)
		(end 16.452088 -124.431552)
		(width 0.1016)
		(layer "In5.Cu")
		(net "SAS_EXP2CONN_RX_P_22")
	)
	(segment
		(start 38.430454 -90.096086)
		(end 38.57879 -90.244422)
		(width 0.1016)
		(layer "In5.Cu")
		(net "SAS_EXP2CONN_RX_P_22")
	)
	(segment
		(start 134.826248 -84.963)
		(end 130.54965 -84.963)
		(width 0.1016)
		(layer "In5.Cu")
		(net "SAS_EXP2CONN_RX_P_22")
	)
	(segment
		(start 38.6588 -90.437716)
		(end 38.6588 -94.045532)
		(width 0.1016)
		(layer "In5.Cu")
		(net "SAS_EXP2CONN_RX_P_22")
	)
	(segment
		(start 138.485118 -121.006362)
		(end 138.485118 -89.535)
		(width 0.1016)
		(layer "In5.Cu")
		(net "SAS_EXP2CONN_RX_P_22")
	)
	(segment
		(start 143.891 -126.873)
		(end 138.811 -121.793)
		(width 0.1016)
		(layer "In5.Cu")
		(net "SAS_EXP2CONN_RX_P_22")
	)
	(segment
		(start 27.394154 -162.564318)
		(end 45.454316 -162.564318)
		(width 0.1016)
		(layer "In5.Cu")
		(net "SAS_EXP2CONN_RX_P_22")
	)
	(segment
		(start 126.539498 -87.92591)
		(end 124.034042 -87.92591)
		(width 0.1016)
		(layer "In5.Cu")
		(net "SAS_EXP2CONN_RX_P_22")
	)
	(segment
		(start 50.628042 -166.755318)
		(end 122.174 -166.755318)
		(width 0.1016)
		(layer "In5.Cu")
		(net "SAS_EXP2CONN_RX_P_22")
	)
	(segment
		(start 144.653 -143.966184)
		(end 144.653 -128.712722)
		(width 0.1016)
		(layer "In5.Cu")
		(net "SAS_EXP2CONN_RX_P_22")
	)
	(segment
		(start 15.7988 -126.009654)
		(end 15.7988 -150.903178)
		(width 0.1016)
		(layer "In5.Cu")
		(net "SAS_EXP2CONN_RX_P_22")
	)
	(segment
		(start 45.903388 -162.750246)
		(end 49.399698 -166.246556)
		(width 0.1016)
		(layer "In5.Cu")
		(net "SAS_EXP2CONN_RX_P_22")
	)
	(segment
		(start 25.80132 -161.90468)
		(end 25.801574 -161.90468)
		(width 0.1016)
		(layer "In5.Cu")
		(net "SAS_EXP2CONN_RX_P_22")
	)
	(segment
		(start 16.50492 -152.60828)
		(end 25.80132 -161.90468)
		(width 0.1016)
		(layer "In5.Cu")
		(net "SAS_EXP2CONN_RX_P_22")
	)
	(arc
		(start 138.485118 -89.535)
		(mid 138.199353 -88.09836)
		(end 137.385552 -86.880446)
		(width 0.1016)
		(layer "In5.Cu")
		(net "SAS_EXP2CONN_RX_P_22")
	)
	(arc
		(start 25.801574 -161.90468)
		(mid 26.532269 -162.392882)
		(end 27.394154 -162.564318)
		(width 0.1016)
		(layer "In5.Cu")
		(net "SAS_EXP2CONN_RX_P_22")
	)
	(arc
		(start 49.399698 -166.246556)
		(mid 49.96328 -166.623096)
		(end 50.628042 -166.755318)
		(width 0.1016)
		(layer "In5.Cu")
		(net "SAS_EXP2CONN_RX_P_22")
	)
	(arc
		(start 127.254 -87.63)
		(mid 126.926184 -87.84904)
		(end 126.539498 -87.92591)
		(width 0.1016)
		(layer "In5.Cu")
		(net "SAS_EXP2CONN_RX_P_22")
	)
	(arc
		(start 38.57879 -90.244422)
		(mid 38.637993 -90.33312)
		(end 38.6588 -90.437716)
		(width 0.1016)
		(layer "In5.Cu")
		(net "SAS_EXP2CONN_RX_P_22")
	)
	(arc
		(start 144.653 -128.712722)
		(mid 144.454903 -127.717111)
		(end 143.891 -126.873)
		(width 0.1016)
		(layer "In5.Cu")
		(net "SAS_EXP2CONN_RX_P_22")
	)
	(arc
		(start 122.174 -166.755318)
		(mid 122.879309 -166.615041)
		(end 123.477274 -166.215568)
		(width 0.1016)
		(layer "In5.Cu")
		(net "SAS_EXP2CONN_RX_P_22")
	)
	(arc
		(start 37.99332 -95.65132)
		(mid 37.075872 -97.024612)
		(end 36.7538 -98.644456)
		(width 0.1016)
		(layer "In5.Cu")
		(net "SAS_EXP2CONN_RX_P_22")
	)
	(arc
		(start 45.454316 -162.564318)
		(mid 45.69732 -162.612654)
		(end 45.903388 -162.750246)
		(width 0.1016)
		(layer "In5.Cu")
		(net "SAS_EXP2CONN_RX_P_22")
	)
	(arc
		(start 130.54965 -84.963)
		(mid 129.968896 -85.078577)
		(end 129.4765 -85.4075)
		(width 0.1016)
		(layer "In5.Cu")
		(net "SAS_EXP2CONN_RX_P_22")
	)
	(arc
		(start 38.658546 -94.045278)
		(mid 38.485656 -94.914455)
		(end 37.99332 -95.65132)
		(width 0.1016)
		(layer "In5.Cu")
		(net "SAS_EXP2CONN_RX_P_22")
	)
	(arc
		(start 138.811 -121.793)
		(mid 138.569846 -121.432087)
		(end 138.485118 -121.006362)
		(width 0.1016)
		(layer "In5.Cu")
		(net "SAS_EXP2CONN_RX_P_22")
	)
	(arc
		(start 124.034042 -87.92591)
		(mid 123.934508 -87.906111)
		(end 123.850146 -87.84971)
		(width 0.1016)
		(layer "In5.Cu")
		(net "SAS_EXP2CONN_RX_P_22")
	)
	(arc
		(start 15.7988 -150.903178)
		(mid 15.982377 -151.82579)
		(end 16.50492 -152.608026)
		(width 0.1016)
		(layer "In5.Cu")
		(net "SAS_EXP2CONN_RX_P_22")
	)
	(arc
		(start 36.7538 -103.099362)
		(mid 36.56433 -104.051715)
		(end 36.02482 -104.859074)
		(width 0.1016)
		(layer "In5.Cu")
		(net "SAS_EXP2CONN_RX_P_22")
	)
	(arc
		(start 135.921496 -85.41639)
		(mid 135.418977 -85.08071)
		(end 134.826248 -84.963)
		(width 0.1016)
		(layer "In5.Cu")
		(net "SAS_EXP2CONN_RX_P_22")
	)
	(arc
		(start 143.893794 -145.799048)
		(mid 144.455682 -144.958123)
		(end 144.653 -143.966184)
		(width 0.1016)
		(layer "In5.Cu")
		(net "SAS_EXP2CONN_RX_P_22")
	)
	(arc
		(start 16.452088 -124.431552)
		(mid 15.968466 -125.155621)
		(end 15.7988 -126.009654)
		(width 0.1016)
		(layer "In5.Cu")
		(net "SAS_EXP2CONN_RX_P_22")
	)
	(segment
		(start 279.899872 -207.374744)
		(end 279.905206 -207.483202)
		(width 0.1143)
		(layer "F.Cu")
		(net "RST_BMC_DDR3_R_N")
	)
	(segment
		(start 279.905206 -207.483202)
		(end 279.904444 -207.478376)
		(width 0.1143)
		(layer "F.Cu")
		(net "RST_BMC_DDR3_R_N")
	)
	(segment
		(start 278.900636 -205.748636)
		(end 279.899872 -205.748636)
		(width 0.1143)
		(layer "F.Cu")
		(net "RST_BMC_DDR3_R_N")
	)
	(segment
		(start 279.899872 -205.748636)
		(end 279.899872 -207.374744)
		(width 0.1143)
		(layer "F.Cu")
		(net "RST_BMC_DDR3_R_N")
	)
	(segment
		(start 278.892 -205.74)
		(end 278.900636 -205.748636)
		(width 0.1143)
		(layer "F.Cu")
		(net "RST_BMC_DDR3_R_N")
	)
	(via
		(at 278.892 -205.74)
		(size 0.7112)
		(drill 0.3556)
		(layers "F.Cu" "B.Cu")
		(net "RST_BMC_DDR3_R_N")
	)
	(segment
		(start 42.011346 -89.83599)
		(end 42.011346 -89.334086)
		(width 0.1016)
		(layer "F.Cu")
		(net "SAS_EXP2CONN_RX_N_23")
	)
	(segment
		(start 43.916346 -87.429086)
		(end 48.227996 -87.429086)
		(width 0.1016)
		(layer "F.Cu")
		(net "SAS_EXP2CONN_RX_N_23")
	)
	(segment
		(start 48.98771 -87.743792)
		(end 48.989996 -87.746078)
		(width 0.1016)
		(layer "F.Cu")
		(net "SAS_EXP2CONN_RX_N_23")
	)
	(segment
		(start 42.328338 -90.096086)
		(end 42.271442 -90.096086)
		(width 0.1016)
		(layer "F.Cu")
		(net "SAS_EXP2CONN_RX_N_23")
	)
	(segment
		(start 122.850148 -88.849708)
		(end 122.833892 -88.849708)
		(width 0.1016)
		(layer "F.Cu")
		(net "SAS_EXP2CONN_RX_N_23")
	)
	(segment
		(start 122.350022 -89.333578)
		(end 122.350022 -89.349834)
		(width 0.1016)
		(layer "F.Cu")
		(net "SAS_EXP2CONN_RX_N_23")
	)
	(segment
		(start 122.833892 -88.849708)
		(end 122.350022 -89.333578)
		(width 0.1016)
		(layer "F.Cu")
		(net "SAS_EXP2CONN_RX_N_23")
	)
	(via
		(at 48.989996 -87.746078)
		(size 0.5588)
		(drill 0.3048)
		(layers "F.Cu" "B.Cu")
		(net "SAS_EXP2CONN_RX_N_23")
	)
	(via
		(at 122.850148 -88.849708)
		(size 0.508)
		(drill 0.254)
		(layers "F.Cu" "B.Cu")
		(net "SAS_EXP2CONN_RX_N_23")
	)
	(via
		(at 42.328338 -90.096086)
		(size 0.5588)
		(drill 0.3048)
		(layers "F.Cu" "B.Cu")
		(net "SAS_EXP2CONN_RX_N_23")
	)
	(arc
		(start 48.227996 -87.429086)
		(mid 48.639159 -87.510871)
		(end 48.98771 -87.743792)
		(width 0.1016)
		(layer "F.Cu")
		(net "SAS_EXP2CONN_RX_N_23")
	)
	(arc
		(start 42.011346 -89.334086)
		(mid 42.569308 -87.987048)
		(end 43.916346 -87.429086)
		(width 0.1016)
		(layer "F.Cu")
		(net "SAS_EXP2CONN_RX_N_23")
	)
	(arc
		(start 42.087546 -90.019886)
		(mid 42.03117 -89.935514)
		(end 42.011346 -89.83599)
		(width 0.1016)
		(layer "F.Cu")
		(net "SAS_EXP2CONN_RX_N_23")
	)
	(arc
		(start 42.271442 -90.096086)
		(mid 42.171908 -90.076287)
		(end 42.087546 -90.019886)
		(width 0.1016)
		(layer "F.Cu")
		(net "SAS_EXP2CONN_RX_N_23")
	)
	(segment
		(start 57.47893 -79.78902)
		(end 57.47893 -82.222086)
		(width 0.1016)
		(layer "B.Cu")
		(net "SAS_EXP2CONN_RX_N_23")
	)
	(segment
		(start 53.96738 -77.853286)
		(end 53.96738 -78.412086)
		(width 0.1016)
		(layer "B.Cu")
		(net "SAS_EXP2CONN_RX_N_23")
	)
	(segment
		(start 54.20233 -77.751686)
		(end 54.06898 -77.751686)
		(width 0.1016)
		(layer "B.Cu")
		(net "SAS_EXP2CONN_RX_N_23")
	)
	(segment
		(start 56.390794 -84.849462)
		(end 54.770528 -86.469728)
		(width 0.1016)
		(layer "B.Cu")
		(net "SAS_EXP2CONN_RX_N_23")
	)
	(segment
		(start 54.22138 -78.666086)
		(end 56.355996 -78.666086)
		(width 0.1016)
		(layer "B.Cu")
		(net "SAS_EXP2CONN_RX_N_23")
	)
	(segment
		(start 54.30393 -77.205586)
		(end 54.30393 -77.650086)
		(width 0.1016)
		(layer "B.Cu")
		(net "SAS_EXP2CONN_RX_N_23")
	)
	(segment
		(start 52.545996 -87.390986)
		(end 49.847246 -87.390986)
		(width 0.1016)
		(layer "B.Cu")
		(net "SAS_EXP2CONN_RX_N_23")
	)
	(arc
		(start 56.355996 -78.666086)
		(mid 57.15003 -78.994986)
		(end 57.47893 -79.78902)
		(width 0.1016)
		(layer "B.Cu")
		(net "SAS_EXP2CONN_RX_N_23")
	)
	(arc
		(start 57.47893 -82.222086)
		(mid 57.196186 -83.644005)
		(end 56.390794 -84.849462)
		(width 0.1016)
		(layer "B.Cu")
		(net "SAS_EXP2CONN_RX_N_23")
	)
	(arc
		(start 54.30393 -77.650086)
		(mid 54.274172 -77.721928)
		(end 54.20233 -77.751686)
		(width 0.1016)
		(layer "B.Cu")
		(net "SAS_EXP2CONN_RX_N_23")
	)
	(arc
		(start 53.96738 -78.412086)
		(mid 54.041775 -78.591691)
		(end 54.22138 -78.666086)
		(width 0.1016)
		(layer "B.Cu")
		(net "SAS_EXP2CONN_RX_N_23")
	)
	(arc
		(start 54.06898 -77.751686)
		(mid 53.997138 -77.781444)
		(end 53.96738 -77.853286)
		(width 0.1016)
		(layer "B.Cu")
		(net "SAS_EXP2CONN_RX_N_23")
	)
	(arc
		(start 49.847246 -87.390986)
		(mid 49.383303 -87.48327)
		(end 48.989996 -87.746078)
		(width 0.1016)
		(layer "B.Cu")
		(net "SAS_EXP2CONN_RX_N_23")
	)
	(arc
		(start 54.770528 -86.469728)
		(mid 53.749875 -87.15155)
		(end 52.545996 -87.390986)
		(width 0.1016)
		(layer "B.Cu")
		(net "SAS_EXP2CONN_RX_N_23")
	)
	(segment
		(start 125.7046 -89.6874)
		(end 126.303532 -89.6874)
		(width 0.1016)
		(layer "In5.Cu")
		(net "SAS_EXP2CONN_RX_N_23")
	)
	(segment
		(start 127.662178 -89.12479)
		(end 128.522984 -88.263984)
		(width 0.1016)
		(layer "In5.Cu")
		(net "SAS_EXP2CONN_RX_N_23")
	)
	(segment
		(start 49.703736 -162.32759)
		(end 49.48809 -162.112198)
		(width 0.1016)
		(layer "In5.Cu")
		(net "SAS_EXP2CONN_RX_N_23")
	)
	(segment
		(start 136.398 -96.24568)
		(end 136.398 -121.946416)
		(width 0.1016)
		(layer "In5.Cu")
		(net "SAS_EXP2CONN_RX_N_23")
	)
	(segment
		(start 122.952256 -163.727892)
		(end 122.672602 -164.007038)
		(width 0.1016)
		(layer "In5.Cu")
		(net "SAS_EXP2CONN_RX_N_23")
	)
	(segment
		(start 137.159746 -89.02065)
		(end 137.16 -89.020396)
		(width 0.1016)
		(layer "In5.Cu")
		(net "SAS_EXP2CONN_RX_N_23")
	)
	(segment
		(start 137.16 -89.020396)
		(end 137.16 -94.406212)
		(width 0.1016)
		(layer "In5.Cu")
		(net "SAS_EXP2CONN_RX_N_23")
	)
	(segment
		(start 26.779982 -160.002982)
		(end 19.6723 -152.8953)
		(width 0.1016)
		(layer "In5.Cu")
		(net "SAS_EXP2CONN_RX_N_23")
	)
	(segment
		(start 41.935908 -90.488516)
		(end 42.328338 -90.096086)
		(width 0.1016)
		(layer "In5.Cu")
		(net "SAS_EXP2CONN_RX_N_23")
	)
	(segment
		(start 19.05 -151.39289)
		(end 19.05 -126.3904)
		(width 0.1016)
		(layer "In5.Cu")
		(net "SAS_EXP2CONN_RX_N_23")
	)
	(segment
		(start 19.786346 -124.612654)
		(end 39.2557 -105.1433)
		(width 0.1016)
		(layer "In5.Cu")
		(net "SAS_EXP2CONN_RX_N_23")
	)
	(segment
		(start 129.801874 -87.835232)
		(end 131.043426 -86.59368)
		(width 0.1016)
		(layer "In5.Cu")
		(net "SAS_EXP2CONN_RX_N_23")
	)
	(segment
		(start 135.201406 -86.433406)
		(end 136.7155 -87.9475)
		(width 0.1016)
		(layer "In5.Cu")
		(net "SAS_EXP2CONN_RX_N_23")
	)
	(segment
		(start 125.14072 -89.43848)
		(end 125.16739 -89.46515)
		(width 0.1016)
		(layer "In5.Cu")
		(net "SAS_EXP2CONN_RX_N_23")
	)
	(segment
		(start 132.03682 -86.1822)
		(end 134.594854 -86.1822)
		(width 0.1016)
		(layer "In5.Cu")
		(net "SAS_EXP2CONN_RX_N_23")
	)
	(segment
		(start 49.008538 -161.952178)
		(end 48.165766 -161.109406)
		(width 0.1016)
		(layer "In5.Cu")
		(net "SAS_EXP2CONN_RX_N_23")
	)
	(segment
		(start 120.9548 -164.719)
		(end 52.428648 -164.719)
		(width 0.1016)
		(layer "In5.Cu")
		(net "SAS_EXP2CONN_RX_N_23")
	)
	(segment
		(start 142.06982 -144.610074)
		(end 122.952256 -163.727892)
		(width 0.1016)
		(layer "In5.Cu")
		(net "SAS_EXP2CONN_RX_N_23")
	)
	(segment
		(start 50.079148 -163.022788)
		(end 49.863502 -162.807142)
		(width 0.1016)
		(layer "In5.Cu")
		(net "SAS_EXP2CONN_RX_N_23")
	)
	(segment
		(start 40.005 -103.334312)
		(end 40.005 -98.29419)
		(width 0.1016)
		(layer "In5.Cu")
		(net "SAS_EXP2CONN_RX_N_23")
	)
	(segment
		(start 142.358872 -144.318736)
		(end 142.065756 -144.611852)
		(width 0.1016)
		(layer "In5.Cu")
		(net "SAS_EXP2CONN_RX_N_23")
	)
	(segment
		(start 124.136658 -89.3826)
		(end 125.006608 -89.3826)
		(width 0.1016)
		(layer "In5.Cu")
		(net "SAS_EXP2CONN_RX_N_23")
	)
	(segment
		(start 46.761146 -160.528)
		(end 28.046934 -160.528)
		(width 0.1016)
		(layer "In5.Cu")
		(net "SAS_EXP2CONN_RX_N_23")
	)
	(segment
		(start 51.31308 -164.25672)
		(end 50.934112 -163.877752)
		(width 0.1016)
		(layer "In5.Cu")
		(net "SAS_EXP2CONN_RX_N_23")
	)
	(segment
		(start 142.544546 -129.644648)
		(end 142.5448 -129.644394)
		(width 0.1016)
		(layer "In5.Cu")
		(net "SAS_EXP2CONN_RX_N_23")
	)
	(segment
		(start 142.065756 -144.611852)
		(end 142.066772 -144.612868)
		(width 0.1016)
		(layer "In5.Cu")
		(net "SAS_EXP2CONN_RX_N_23")
	)
	(segment
		(start 50.774092 -163.3982)
		(end 50.5587 -163.182554)
		(width 0.1016)
		(layer "In5.Cu")
		(net "SAS_EXP2CONN_RX_N_23")
	)
	(segment
		(start 142.5448 -129.644394)
		(end 142.5448 -143.869664)
		(width 0.1016)
		(layer "In5.Cu")
		(net "SAS_EXP2CONN_RX_N_23")
	)
	(segment
		(start 142.066772 -144.612868)
		(end 142.06982 -144.610074)
		(width 0.1016)
		(layer "In5.Cu")
		(net "SAS_EXP2CONN_RX_N_23")
	)
	(segment
		(start 128.88849 -88.1126)
		(end 129.132076 -88.1126)
		(width 0.1016)
		(layer "In5.Cu")
		(net "SAS_EXP2CONN_RX_N_23")
	)
	(segment
		(start 136.799066 -122.915172)
		(end 141.857984 -127.973836)
		(width 0.1016)
		(layer "In5.Cu")
		(net "SAS_EXP2CONN_RX_N_23")
	)
	(segment
		(start 41.91 -93.695266)
		(end 41.91 -90.551)
		(width 0.1016)
		(layer "In5.Cu")
		(net "SAS_EXP2CONN_RX_N_23")
	)
	(arc
		(start 50.854102 -163.637976)
		(mid 50.843052 -163.508431)
		(end 50.774092 -163.3982)
		(width 0.1016)
		(layer "In5.Cu")
		(net "SAS_EXP2CONN_RX_N_23")
	)
	(arc
		(start 129.132076 -88.1126)
		(mid 129.494555 -88.040516)
		(end 129.801874 -87.835232)
		(width 0.1016)
		(layer "In5.Cu")
		(net "SAS_EXP2CONN_RX_N_23")
	)
	(arc
		(start 19.6723 -152.8953)
		(mid 19.211717 -152.205988)
		(end 19.05 -151.39289)
		(width 0.1016)
		(layer "In5.Cu")
		(net "SAS_EXP2CONN_RX_N_23")
	)
	(arc
		(start 134.594854 -86.1822)
		(mid 134.923104 -86.247493)
		(end 135.201406 -86.433406)
		(width 0.1016)
		(layer "In5.Cu")
		(net "SAS_EXP2CONN_RX_N_23")
	)
	(arc
		(start 125.16739 -89.46515)
		(mid 125.413879 -89.629756)
		(end 125.7046 -89.6874)
		(width 0.1016)
		(layer "In5.Cu")
		(net "SAS_EXP2CONN_RX_N_23")
	)
	(arc
		(start 122.672602 -164.007038)
		(mid 121.884512 -164.533872)
		(end 120.9548 -164.719)
		(width 0.1016)
		(layer "In5.Cu")
		(net "SAS_EXP2CONN_RX_N_23")
	)
	(arc
		(start 136.87552 -95.09252)
		(mid 136.522111 -95.621623)
		(end 136.398 -96.24568)
		(width 0.1016)
		(layer "In5.Cu")
		(net "SAS_EXP2CONN_RX_N_23")
	)
	(arc
		(start 122.850148 -88.849708)
		(mid 123.440404 -89.244104)
		(end 124.136658 -89.3826)
		(width 0.1016)
		(layer "In5.Cu")
		(net "SAS_EXP2CONN_RX_N_23")
	)
	(arc
		(start 19.05 -126.3904)
		(mid 19.241374 -125.428299)
		(end 19.786346 -124.612654)
		(width 0.1016)
		(layer "In5.Cu")
		(net "SAS_EXP2CONN_RX_N_23")
	)
	(arc
		(start 48.165766 -161.109406)
		(mid 47.521291 -160.678967)
		(end 46.761146 -160.528)
		(width 0.1016)
		(layer "In5.Cu")
		(net "SAS_EXP2CONN_RX_N_23")
	)
	(arc
		(start 131.043426 -86.59368)
		(mid 131.499199 -86.289142)
		(end 132.03682 -86.1822)
		(width 0.1016)
		(layer "In5.Cu")
		(net "SAS_EXP2CONN_RX_N_23")
	)
	(arc
		(start 28.046934 -160.528)
		(mid 27.361245 -160.391496)
		(end 26.779982 -160.002982)
		(width 0.1016)
		(layer "In5.Cu")
		(net "SAS_EXP2CONN_RX_N_23")
	)
	(arc
		(start 50.318924 -163.102544)
		(mid 50.189402 -163.091627)
		(end 50.079148 -163.022788)
		(width 0.1016)
		(layer "In5.Cu")
		(net "SAS_EXP2CONN_RX_N_23")
	)
	(arc
		(start 49.148492 -162.02914)
		(mid 49.072828 -162.000993)
		(end 49.008538 -161.952178)
		(width 0.1016)
		(layer "In5.Cu")
		(net "SAS_EXP2CONN_RX_N_23")
	)
	(arc
		(start 126.303532 -89.6874)
		(mid 127.038793 -89.541183)
		(end 127.662178 -89.12479)
		(width 0.1016)
		(layer "In5.Cu")
		(net "SAS_EXP2CONN_RX_N_23")
	)
	(arc
		(start 39.2557 -105.1433)
		(mid 39.810269 -104.313329)
		(end 40.005 -103.334312)
		(width 0.1016)
		(layer "In5.Cu")
		(net "SAS_EXP2CONN_RX_N_23")
	)
	(arc
		(start 136.398 -121.946416)
		(mid 136.502189 -122.470678)
		(end 136.799066 -122.915172)
		(width 0.1016)
		(layer "In5.Cu")
		(net "SAS_EXP2CONN_RX_N_23")
	)
	(arc
		(start 50.934112 -163.877752)
		(mid 50.865115 -163.767533)
		(end 50.854102 -163.637976)
		(width 0.1016)
		(layer "In5.Cu")
		(net "SAS_EXP2CONN_RX_N_23")
	)
	(arc
		(start 49.248314 -162.032188)
		(mid 49.198263 -162.035214)
		(end 49.148492 -162.02914)
		(width 0.1016)
		(layer "In5.Cu")
		(net "SAS_EXP2CONN_RX_N_23")
	)
	(arc
		(start 137.16 -94.406212)
		(mid 137.086073 -94.777688)
		(end 136.87552 -95.09252)
		(width 0.1016)
		(layer "In5.Cu")
		(net "SAS_EXP2CONN_RX_N_23")
	)
	(arc
		(start 49.48809 -162.112198)
		(mid 49.377871 -162.043201)
		(end 49.248314 -162.032188)
		(width 0.1016)
		(layer "In5.Cu")
		(net "SAS_EXP2CONN_RX_N_23")
	)
	(arc
		(start 50.5587 -163.182554)
		(mid 50.44847 -163.11362)
		(end 50.318924 -163.102544)
		(width 0.1016)
		(layer "In5.Cu")
		(net "SAS_EXP2CONN_RX_N_23")
	)
	(arc
		(start 49.863502 -162.807142)
		(mid 49.794568 -162.696912)
		(end 49.783492 -162.567366)
		(width 0.1016)
		(layer "In5.Cu")
		(net "SAS_EXP2CONN_RX_N_23")
	)
	(arc
		(start 125.006608 -89.3826)
		(mid 125.079207 -89.397228)
		(end 125.14072 -89.43848)
		(width 0.1016)
		(layer "In5.Cu")
		(net "SAS_EXP2CONN_RX_N_23")
	)
	(arc
		(start 40.561006 -95.953834)
		(mid 40.991526 -95.245752)
		(end 41.529 -94.615)
		(width 0.1016)
		(layer "In5.Cu")
		(net "SAS_EXP2CONN_RX_N_23")
	)
	(arc
		(start 142.5448 -143.869664)
		(mid 142.496464 -144.112668)
		(end 142.358872 -144.318736)
		(width 0.1016)
		(layer "In5.Cu")
		(net "SAS_EXP2CONN_RX_N_23")
	)
	(arc
		(start 128.522984 -88.263984)
		(mid 128.69068 -88.151933)
		(end 128.88849 -88.1126)
		(width 0.1016)
		(layer "In5.Cu")
		(net "SAS_EXP2CONN_RX_N_23")
	)
	(arc
		(start 41.91 -90.551)
		(mid 41.916728 -90.517174)
		(end 41.935908 -90.488516)
		(width 0.1016)
		(layer "In5.Cu")
		(net "SAS_EXP2CONN_RX_N_23")
	)
	(arc
		(start 52.428648 -164.719)
		(mid 51.82486 -164.598863)
		(end 51.31308 -164.25672)
		(width 0.1016)
		(layer "In5.Cu")
		(net "SAS_EXP2CONN_RX_N_23")
	)
	(arc
		(start 49.783492 -162.567366)
		(mid 49.772575 -162.437844)
		(end 49.703736 -162.32759)
		(width 0.1016)
		(layer "In5.Cu")
		(net "SAS_EXP2CONN_RX_N_23")
	)
	(arc
		(start 141.857984 -127.973836)
		(mid 142.366215 -128.741455)
		(end 142.544546 -129.644648)
		(width 0.1016)
		(layer "In5.Cu")
		(net "SAS_EXP2CONN_RX_N_23")
	)
	(arc
		(start 40.005 -98.29419)
		(mid 40.145918 -97.091447)
		(end 40.561006 -95.953834)
		(width 0.1016)
		(layer "In5.Cu")
		(net "SAS_EXP2CONN_RX_N_23")
	)
	(arc
		(start 136.7155 -87.9475)
		(mid 137.044298 -88.439909)
		(end 137.159746 -89.02065)
		(width 0.1016)
		(layer "In5.Cu")
		(net "SAS_EXP2CONN_RX_N_23")
	)
	(arc
		(start 41.529 -94.615)
		(mid 41.810956 -94.193022)
		(end 41.91 -93.695266)
		(width 0.1016)
		(layer "In5.Cu")
		(net "SAS_EXP2CONN_RX_N_23")
	)
	(segment
		(start 43.916346 -87.086186)
		(end 48.227996 -87.086186)
		(width 0.1016)
		(layer "F.Cu")
		(net "SAS_EXP2CONN_RX_P_23")
	)
	(segment
		(start 41.668446 -89.671398)
		(end 41.668446 -89.334086)
		(width 0.1016)
		(layer "F.Cu")
		(net "SAS_EXP2CONN_RX_P_23")
	)
	(segment
		(start 41.351454 -90.096086)
		(end 41.592246 -89.855294)
		(width 0.1016)
		(layer "F.Cu")
		(net "SAS_EXP2CONN_RX_P_23")
	)
	(segment
		(start 48.98771 -86.77148)
		(end 48.989996 -86.769194)
		(width 0.1016)
		(layer "F.Cu")
		(net "SAS_EXP2CONN_RX_P_23")
	)
	(segment
		(start 123.35002 -89.349834)
		(end 123.850146 -88.849708)
		(width 0.1016)
		(layer "F.Cu")
		(net "SAS_EXP2CONN_RX_P_23")
	)
	(via
		(at 48.989996 -86.769194)
		(size 0.5588)
		(drill 0.3048)
		(layers "F.Cu" "B.Cu")
		(net "SAS_EXP2CONN_RX_P_23")
	)
	(via
		(at 41.351454 -90.096086)
		(size 0.5588)
		(drill 0.3048)
		(layers "F.Cu" "B.Cu")
		(net "SAS_EXP2CONN_RX_P_23")
	)
	(via
		(at 123.850146 -88.849708)
		(size 0.508)
		(drill 0.254)
		(layers "F.Cu" "B.Cu")
		(net "SAS_EXP2CONN_RX_P_23")
	)
	(arc
		(start 41.668446 -89.334086)
		(mid 42.326841 -87.744581)
		(end 43.916346 -87.086186)
		(width 0.1016)
		(layer "F.Cu")
		(net "SAS_EXP2CONN_RX_P_23")
	)
	(arc
		(start 48.227996 -87.086186)
		(mid 48.639159 -87.004401)
		(end 48.98771 -86.77148)
		(width 0.1016)
		(layer "F.Cu")
		(net "SAS_EXP2CONN_RX_P_23")
	)
	(arc
		(start 41.592246 -89.855294)
		(mid 41.648622 -89.770922)
		(end 41.668446 -89.671398)
		(width 0.1016)
		(layer "F.Cu")
		(net "SAS_EXP2CONN_RX_P_23")
	)
	(segment
		(start 53.28793 -77.205586)
		(end 53.28793 -77.650086)
		(width 0.1016)
		(layer "B.Cu")
		(net "SAS_EXP2CONN_RX_P_23")
	)
	(segment
		(start 57.13603 -79.78902)
		(end 57.13603 -82.222086)
		(width 0.1016)
		(layer "B.Cu")
		(net "SAS_EXP2CONN_RX_P_23")
	)
	(segment
		(start 53.62448 -77.853286)
		(end 53.62448 -78.412086)
		(width 0.1016)
		(layer "B.Cu")
		(net "SAS_EXP2CONN_RX_P_23")
	)
	(segment
		(start 52.545996 -87.048086)
		(end 49.66335 -87.048086)
		(width 0.1016)
		(layer "B.Cu")
		(net "SAS_EXP2CONN_RX_P_23")
	)
	(segment
		(start 54.22138 -79.008986)
		(end 56.355996 -79.008986)
		(width 0.1016)
		(layer "B.Cu")
		(net "SAS_EXP2CONN_RX_P_23")
	)
	(segment
		(start 53.38953 -77.751686)
		(end 53.52288 -77.751686)
		(width 0.1016)
		(layer "B.Cu")
		(net "SAS_EXP2CONN_RX_P_23")
	)
	(segment
		(start 56.148224 -84.606892)
		(end 54.527958 -86.227158)
		(width 0.1016)
		(layer "B.Cu")
		(net "SAS_EXP2CONN_RX_P_23")
	)
	(arc
		(start 54.527958 -86.227158)
		(mid 53.618626 -86.834754)
		(end 52.545996 -87.048086)
		(width 0.1016)
		(layer "B.Cu")
		(net "SAS_EXP2CONN_RX_P_23")
	)
	(arc
		(start 57.13603 -82.222086)
		(mid 56.879305 -83.512729)
		(end 56.148224 -84.606892)
		(width 0.1016)
		(layer "B.Cu")
		(net "SAS_EXP2CONN_RX_P_23")
	)
	(arc
		(start 53.62448 -78.412086)
		(mid 53.799308 -78.834158)
		(end 54.22138 -79.008986)
		(width 0.1016)
		(layer "B.Cu")
		(net "SAS_EXP2CONN_RX_P_23")
	)
	(arc
		(start 56.355996 -79.008986)
		(mid 56.907563 -79.237453)
		(end 57.13603 -79.78902)
		(width 0.1016)
		(layer "B.Cu")
		(net "SAS_EXP2CONN_RX_P_23")
	)
	(arc
		(start 53.28793 -77.650086)
		(mid 53.317688 -77.721928)
		(end 53.38953 -77.751686)
		(width 0.1016)
		(layer "B.Cu")
		(net "SAS_EXP2CONN_RX_P_23")
	)
	(arc
		(start 49.66335 -87.048086)
		(mid 49.298941 -86.975601)
		(end 48.989996 -86.769194)
		(width 0.1016)
		(layer "B.Cu")
		(net "SAS_EXP2CONN_RX_P_23")
	)
	(arc
		(start 53.52288 -77.751686)
		(mid 53.594722 -77.781444)
		(end 53.62448 -77.853286)
		(width 0.1016)
		(layer "B.Cu")
		(net "SAS_EXP2CONN_RX_P_23")
	)
	(segment
		(start 39.674546 -98.29419)
		(end 39.674546 -99.586542)
		(width 0.1016)
		(layer "In5.Cu")
		(net "SAS_EXP2CONN_RX_P_23")
	)
	(segment
		(start 127.851154 -88.468454)
		(end 127.428498 -88.89111)
		(width 0.1016)
		(layer "In5.Cu")
		(net "SAS_EXP2CONN_RX_P_23")
	)
	(segment
		(start 136.728454 -121.946416)
		(end 136.7282 -121.94667)
		(width 0.1016)
		(layer "In5.Cu")
		(net "SAS_EXP2CONN_RX_P_23")
	)
	(segment
		(start 126.303278 -89.3572)
		(end 125.7046 -89.3572)
		(width 0.1016)
		(layer "In5.Cu")
		(net "SAS_EXP2CONN_RX_P_23")
	)
	(segment
		(start 134.5946 -85.852)
		(end 132.036566 -85.852)
		(width 0.1016)
		(layer "In5.Cu")
		(net "SAS_EXP2CONN_RX_P_23")
	)
	(segment
		(start 142.08252 -127.731012)
		(end 141.9479 -127.596646)
		(width 0.1016)
		(layer "In5.Cu")
		(net "SAS_EXP2CONN_RX_P_23")
	)
	(segment
		(start 47.932086 -161.343086)
		(end 51.0794 -164.4904)
		(width 0.1016)
		(layer "In5.Cu")
		(net "SAS_EXP2CONN_RX_P_23")
	)
	(segment
		(start 39.674546 -99.586542)
		(end 39.6748 -99.586796)
		(width 0.1016)
		(layer "In5.Cu")
		(net "SAS_EXP2CONN_RX_P_23")
	)
	(segment
		(start 141.9479 -127.596646)
		(end 137.032746 -122.681492)
		(width 0.1016)
		(layer "In5.Cu")
		(net "SAS_EXP2CONN_RX_P_23")
	)
	(segment
		(start 39.6748 -99.586796)
		(end 39.6748 -103.334312)
		(width 0.1016)
		(layer "In5.Cu")
		(net "SAS_EXP2CONN_RX_P_23")
	)
	(segment
		(start 19.43862 -153.12898)
		(end 26.546302 -160.236662)
		(width 0.1016)
		(layer "In5.Cu")
		(net "SAS_EXP2CONN_RX_P_23")
	)
	(segment
		(start 39.022274 -104.90962)
		(end 19.552666 -124.378974)
		(width 0.1016)
		(layer "In5.Cu")
		(net "SAS_EXP2CONN_RX_P_23")
	)
	(segment
		(start 128.289304 -88.030558)
		(end 127.851154 -88.468454)
		(width 0.1016)
		(layer "In5.Cu")
		(net "SAS_EXP2CONN_RX_P_23")
	)
	(segment
		(start 130.81 -86.36)
		(end 129.568194 -87.601552)
		(width 0.1016)
		(layer "In5.Cu")
		(net "SAS_EXP2CONN_RX_P_23")
	)
	(segment
		(start 125.40107 -89.23147)
		(end 125.3744 -89.2048)
		(width 0.1016)
		(layer "In5.Cu")
		(net "SAS_EXP2CONN_RX_P_23")
	)
	(segment
		(start 41.5798 -90.437716)
		(end 41.5798 -93.695012)
		(width 0.1016)
		(layer "In5.Cu")
		(net "SAS_EXP2CONN_RX_P_23")
	)
	(segment
		(start 129.131822 -87.7824)
		(end 128.88849 -87.7824)
		(width 0.1016)
		(layer "In5.Cu")
		(net "SAS_EXP2CONN_RX_P_23")
	)
	(segment
		(start 123.3424 -163.804854)
		(end 142.592298 -144.554956)
		(width 0.1016)
		(layer "In5.Cu")
		(net "SAS_EXP2CONN_RX_P_23")
	)
	(segment
		(start 137.4902 -94.406466)
		(end 137.4902 -89.02065)
		(width 0.1016)
		(layer "In5.Cu")
		(net "SAS_EXP2CONN_RX_P_23")
	)
	(segment
		(start 18.7198 -126.390654)
		(end 18.7198 -151.392636)
		(width 0.1016)
		(layer "In5.Cu")
		(net "SAS_EXP2CONN_RX_P_23")
	)
	(segment
		(start 125.006354 -89.0524)
		(end 124.339604 -89.0524)
		(width 0.1016)
		(layer "In5.Cu")
		(net "SAS_EXP2CONN_RX_P_23")
	)
	(segment
		(start 28.046934 -160.8582)
		(end 46.7614 -160.8582)
		(width 0.1016)
		(layer "In5.Cu")
		(net "SAS_EXP2CONN_RX_P_23")
	)
	(segment
		(start 41.351454 -90.096086)
		(end 41.49979 -90.244422)
		(width 0.1016)
		(layer "In5.Cu")
		(net "SAS_EXP2CONN_RX_P_23")
	)
	(segment
		(start 52.428394 -165.0492)
		(end 120.9548 -165.0492)
		(width 0.1016)
		(layer "In5.Cu")
		(net "SAS_EXP2CONN_RX_P_23")
	)
	(segment
		(start 19.438874 -153.12898)
		(end 19.43862 -153.12898)
		(width 0.1016)
		(layer "In5.Cu")
		(net "SAS_EXP2CONN_RX_P_23")
	)
	(segment
		(start 122.906282 -164.240718)
		(end 123.3424 -163.804854)
		(width 0.1016)
		(layer "In5.Cu")
		(net "SAS_EXP2CONN_RX_P_23")
	)
	(segment
		(start 142.875 -143.872458)
		(end 142.875 -129.644648)
		(width 0.1016)
		(layer "In5.Cu")
		(net "SAS_EXP2CONN_RX_P_23")
	)
	(segment
		(start 136.948926 -87.71382)
		(end 135.434832 -86.199726)
		(width 0.1016)
		(layer "In5.Cu")
		(net "SAS_EXP2CONN_RX_P_23")
	)
	(segment
		(start 136.7282 -121.94667)
		(end 136.7282 -96.245934)
		(width 0.1016)
		(layer "In5.Cu")
		(net "SAS_EXP2CONN_RX_P_23")
	)
	(arc
		(start 18.7198 -151.392636)
		(mid 18.906572 -152.332363)
		(end 19.438874 -153.12898)
		(width 0.1016)
		(layer "In5.Cu")
		(net "SAS_EXP2CONN_RX_P_23")
	)
	(arc
		(start 120.9548 -165.0492)
		(mid 122.010939 -164.839027)
		(end 122.906282 -164.240718)
		(width 0.1016)
		(layer "In5.Cu")
		(net "SAS_EXP2CONN_RX_P_23")
	)
	(arc
		(start 132.036566 -85.852)
		(mid 131.372802 -85.984089)
		(end 130.81 -86.36)
		(width 0.1016)
		(layer "In5.Cu")
		(net "SAS_EXP2CONN_RX_P_23")
	)
	(arc
		(start 40.265858 -95.805244)
		(mid 39.824384 -97.015076)
		(end 39.674546 -98.29419)
		(width 0.1016)
		(layer "In5.Cu")
		(net "SAS_EXP2CONN_RX_P_23")
	)
	(arc
		(start 41.49979 -90.244422)
		(mid 41.558993 -90.33312)
		(end 41.5798 -90.437716)
		(width 0.1016)
		(layer "In5.Cu")
		(net "SAS_EXP2CONN_RX_P_23")
	)
	(arc
		(start 135.434832 -86.199726)
		(mid 135.0493 -85.942308)
		(end 134.5946 -85.852)
		(width 0.1016)
		(layer "In5.Cu")
		(net "SAS_EXP2CONN_RX_P_23")
	)
	(arc
		(start 51.0794 -164.4904)
		(mid 51.698324 -164.903952)
		(end 52.428394 -165.0492)
		(width 0.1016)
		(layer "In5.Cu")
		(net "SAS_EXP2CONN_RX_P_23")
	)
	(arc
		(start 39.6748 -103.334312)
		(mid 39.505231 -104.186881)
		(end 39.022274 -104.90962)
		(width 0.1016)
		(layer "In5.Cu")
		(net "SAS_EXP2CONN_RX_P_23")
	)
	(arc
		(start 142.59433 -144.55267)
		(mid 142.802031 -144.24036)
		(end 142.875 -143.872458)
		(width 0.1016)
		(layer "In5.Cu")
		(net "SAS_EXP2CONN_RX_P_23")
	)
	(arc
		(start 26.546302 -160.236662)
		(mid 27.234798 -160.6967)
		(end 28.046934 -160.8582)
		(width 0.1016)
		(layer "In5.Cu")
		(net "SAS_EXP2CONN_RX_P_23")
	)
	(arc
		(start 125.7046 -89.3572)
		(mid 125.540329 -89.324525)
		(end 125.40107 -89.23147)
		(width 0.1016)
		(layer "In5.Cu")
		(net "SAS_EXP2CONN_RX_P_23")
	)
	(arc
		(start 142.875 -129.644648)
		(mid 142.669092 -128.609009)
		(end 142.08252 -127.731012)
		(width 0.1016)
		(layer "In5.Cu")
		(net "SAS_EXP2CONN_RX_P_23")
	)
	(arc
		(start 127.428498 -88.89111)
		(mid 126.912243 -89.236061)
		(end 126.303278 -89.3572)
		(width 0.1016)
		(layer "In5.Cu")
		(net "SAS_EXP2CONN_RX_P_23")
	)
	(arc
		(start 41.5798 -93.695012)
		(mid 41.505873 -94.066488)
		(end 41.29532 -94.38132)
		(width 0.1016)
		(layer "In5.Cu")
		(net "SAS_EXP2CONN_RX_P_23")
	)
	(arc
		(start 136.7282 -96.245934)
		(mid 136.827212 -95.748165)
		(end 137.1092 -95.3262)
		(width 0.1016)
		(layer "In5.Cu")
		(net "SAS_EXP2CONN_RX_P_23")
	)
	(arc
		(start 128.88849 -87.7824)
		(mid 128.564186 -87.846832)
		(end 128.289304 -88.030558)
		(width 0.1016)
		(layer "In5.Cu")
		(net "SAS_EXP2CONN_RX_P_23")
	)
	(arc
		(start 137.4902 -89.02065)
		(mid 137.349521 -88.313411)
		(end 136.948926 -87.71382)
		(width 0.1016)
		(layer "In5.Cu")
		(net "SAS_EXP2CONN_RX_P_23")
	)
	(arc
		(start 46.7614 -160.8582)
		(mid 47.39496 -160.984223)
		(end 47.932086 -161.343086)
		(width 0.1016)
		(layer "In5.Cu")
		(net "SAS_EXP2CONN_RX_P_23")
	)
	(arc
		(start 19.552666 -124.378974)
		(mid 18.936125 -125.301971)
		(end 18.7198 -126.390654)
		(width 0.1016)
		(layer "In5.Cu")
		(net "SAS_EXP2CONN_RX_P_23")
	)
	(arc
		(start 125.3744 -89.2048)
		(mid 125.205539 -89.091971)
		(end 125.006354 -89.0524)
		(width 0.1016)
		(layer "In5.Cu")
		(net "SAS_EXP2CONN_RX_P_23")
	)
	(arc
		(start 142.592298 -144.554956)
		(mid 142.593315 -144.553814)
		(end 142.59433 -144.55267)
		(width 0.1016)
		(layer "In5.Cu")
		(net "SAS_EXP2CONN_RX_P_23")
	)
	(arc
		(start 137.032746 -122.681492)
		(mid 136.807536 -122.344207)
		(end 136.728454 -121.946416)
		(width 0.1016)
		(layer "In5.Cu")
		(net "SAS_EXP2CONN_RX_P_23")
	)
	(arc
		(start 137.1092 -95.3262)
		(mid 137.391156 -94.904222)
		(end 137.4902 -94.406466)
		(width 0.1016)
		(layer "In5.Cu")
		(net "SAS_EXP2CONN_RX_P_23")
	)
	(arc
		(start 41.29532 -94.38132)
		(mid 40.723727 -95.05217)
		(end 40.265858 -95.805244)
		(width 0.1016)
		(layer "In5.Cu")
		(net "SAS_EXP2CONN_RX_P_23")
	)
	(arc
		(start 124.339604 -89.0524)
		(mid 124.07473 -88.999713)
		(end 123.850146 -88.849708)
		(width 0.1016)
		(layer "In5.Cu")
		(net "SAS_EXP2CONN_RX_P_23")
	)
	(arc
		(start 129.568194 -87.601552)
		(mid 129.367999 -87.735381)
		(end 129.131822 -87.7824)
		(width 0.1016)
		(layer "In5.Cu")
		(net "SAS_EXP2CONN_RX_P_23")
	)
	(segment
		(start 39.115746 -90.026236)
		(end 39.086028 -89.996518)
		(width 0.1016)
		(layer "F.Cu")
		(net "SAS_EXP2CONN_RX_N_22")
	)
	(segment
		(start 39.407338 -90.096086)
		(end 39.284402 -90.096086)
		(width 0.1016)
		(layer "F.Cu")
		(net "SAS_EXP2CONN_RX_N_22")
	)
	(segment
		(start 42.512996 -84.596986)
		(end 48.227996 -84.596986)
		(width 0.1016)
		(layer "F.Cu")
		(net "SAS_EXP2CONN_RX_N_22")
	)
	(segment
		(start 122.350022 -88.349836)
		(end 122.850148 -87.84971)
		(width 0.1016)
		(layer "F.Cu")
		(net "SAS_EXP2CONN_RX_N_22")
	)
	(segment
		(start 39.045896 -89.899744)
		(end 39.045896 -88.064086)
		(width 0.1016)
		(layer "F.Cu")
		(net "SAS_EXP2CONN_RX_N_22")
	)
	(segment
		(start 48.98771 -84.911692)
		(end 48.989996 -84.913978)
		(width 0.1016)
		(layer "F.Cu")
		(net "SAS_EXP2CONN_RX_N_22")
	)
	(via
		(at 48.989996 -84.913978)
		(size 0.5588)
		(drill 0.3048)
		(layers "F.Cu" "B.Cu")
		(net "SAS_EXP2CONN_RX_N_22")
	)
	(via
		(at 122.850148 -87.84971)
		(size 0.508)
		(drill 0.254)
		(layers "F.Cu" "B.Cu")
		(net "SAS_EXP2CONN_RX_N_22")
	)
	(via
		(at 39.407338 -90.096086)
		(size 0.5588)
		(drill 0.3048)
		(layers "F.Cu" "B.Cu")
		(net "SAS_EXP2CONN_RX_N_22")
	)
	(arc
		(start 39.284402 -90.096086)
		(mid 39.19313 -90.077931)
		(end 39.115746 -90.026236)
		(width 0.1016)
		(layer "F.Cu")
		(net "SAS_EXP2CONN_RX_N_22")
	)
	(arc
		(start 48.227996 -84.596986)
		(mid 48.639159 -84.678771)
		(end 48.98771 -84.911692)
		(width 0.1016)
		(layer "F.Cu")
		(net "SAS_EXP2CONN_RX_N_22")
	)
	(arc
		(start 39.086028 -89.996518)
		(mid 39.056307 -89.952132)
		(end 39.045896 -89.899744)
		(width 0.1016)
		(layer "F.Cu")
		(net "SAS_EXP2CONN_RX_N_22")
	)
	(arc
		(start 39.045896 -88.064086)
		(mid 40.061386 -85.612476)
		(end 42.512996 -84.596986)
		(width 0.1016)
		(layer "F.Cu")
		(net "SAS_EXP2CONN_RX_N_22")
	)
	(segment
		(start 51.76393 -77.205586)
		(end 51.76393 -77.670152)
		(width 0.1016)
		(layer "B.Cu")
		(net "SAS_EXP2CONN_RX_N_22")
	)
	(segment
		(start 55.328566 -82.972656)
		(end 54.312566 -83.988656)
		(width 0.1016)
		(layer "B.Cu")
		(net "SAS_EXP2CONN_RX_N_22")
	)
	(segment
		(start 49.172114 -84.732114)
		(end 48.989996 -84.913978)
		(width 0.1016)
		(layer "B.Cu")
		(net "SAS_EXP2CONN_RX_N_22")
	)
	(segment
		(start 51.529996 -77.904086)
		(end 51.529996 -78.412086)
		(width 0.1016)
		(layer "B.Cu")
		(net "SAS_EXP2CONN_RX_N_22")
	)
	(segment
		(start 54.267608 -80.444086)
		(end 54.958996 -80.444086)
		(width 0.1016)
		(layer "B.Cu")
		(net "SAS_EXP2CONN_RX_N_22")
	)
	(segment
		(start 51.76393 -77.670152)
		(end 51.529996 -77.904086)
		(width 0.1016)
		(layer "B.Cu")
		(net "SAS_EXP2CONN_RX_N_22")
	)
	(segment
		(start 52.843938 -84.596986)
		(end 49.497996 -84.596986)
		(width 0.1016)
		(layer "B.Cu")
		(net "SAS_EXP2CONN_RX_N_22")
	)
	(segment
		(start 55.682896 -81.167986)
		(end 55.682896 -82.117184)
		(width 0.1016)
		(layer "B.Cu")
		(net "SAS_EXP2CONN_RX_N_22")
	)
	(arc
		(start 55.682896 -82.117184)
		(mid 55.590805 -82.580155)
		(end 55.328566 -82.972656)
		(width 0.1016)
		(layer "B.Cu")
		(net "SAS_EXP2CONN_RX_N_22")
	)
	(arc
		(start 54.958996 -80.444086)
		(mid 55.470871 -80.656111)
		(end 55.682896 -81.167986)
		(width 0.1016)
		(layer "B.Cu")
		(net "SAS_EXP2CONN_RX_N_22")
	)
	(arc
		(start 54.312566 -83.988656)
		(mid 53.638755 -84.438912)
		(end 52.843938 -84.596986)
		(width 0.1016)
		(layer "B.Cu")
		(net "SAS_EXP2CONN_RX_N_22")
	)
	(arc
		(start 51.529996 -78.412086)
		(mid 51.6467 -78.998795)
		(end 51.979068 -79.496158)
		(width 0.1016)
		(layer "B.Cu")
		(net "SAS_EXP2CONN_RX_N_22")
	)
	(arc
		(start 49.497996 -84.596986)
		(mid 49.321629 -84.632161)
		(end 49.172114 -84.732114)
		(width 0.1016)
		(layer "B.Cu")
		(net "SAS_EXP2CONN_RX_N_22")
	)
	(arc
		(start 51.979068 -79.496158)
		(mid 53.029059 -80.19774)
		(end 54.267608 -80.444086)
		(width 0.1016)
		(layer "B.Cu")
		(net "SAS_EXP2CONN_RX_N_22")
	)
	(segment
		(start 49.317402 -165.377368)
		(end 49.101756 -165.161976)
		(width 0.1016)
		(layer "In5.Cu")
		(net "SAS_EXP2CONN_RX_N_22")
	)
	(segment
		(start 143.660114 -145.565622)
		(end 143.65986 -145.565368)
		(width 0.1016)
		(layer "In5.Cu")
		(net "SAS_EXP2CONN_RX_N_22")
	)
	(segment
		(start 130.549904 -85.2932)
		(end 134.826502 -85.2932)
		(width 0.1016)
		(layer "In5.Cu")
		(net "SAS_EXP2CONN_RX_N_22")
	)
	(segment
		(start 135.68807 -85.65007)
		(end 136.905746 -86.867746)
		(width 0.1016)
		(layer "In5.Cu")
		(net "SAS_EXP2CONN_RX_N_22")
	)
	(segment
		(start 136.905746 -86.868)
		(end 137.151872 -87.114126)
		(width 0.1016)
		(layer "In5.Cu")
		(net "SAS_EXP2CONN_RX_N_22")
	)
	(segment
		(start 123.47702 -88.25611)
		(end 126.539498 -88.25611)
		(width 0.1016)
		(layer "In5.Cu")
		(net "SAS_EXP2CONN_RX_N_22")
	)
	(segment
		(start 49.633124 -166.012876)
		(end 49.477168 -165.85692)
		(width 0.1016)
		(layer "In5.Cu")
		(net "SAS_EXP2CONN_RX_N_22")
	)
	(segment
		(start 127.48768 -87.863426)
		(end 129.709926 -85.64118)
		(width 0.1016)
		(layer "In5.Cu")
		(net "SAS_EXP2CONN_RX_N_22")
	)
	(segment
		(start 16.129 -150.902924)
		(end 16.129 -126.0094)
		(width 0.1016)
		(layer "In5.Cu")
		(net "SAS_EXP2CONN_RX_N_22")
	)
	(segment
		(start 144.3228 -128.712976)
		(end 144.3228 -143.96593)
		(width 0.1016)
		(layer "In5.Cu")
		(net "SAS_EXP2CONN_RX_N_22")
	)
	(segment
		(start 136.905746 -86.867746)
		(end 136.905746 -86.868)
		(width 0.1016)
		(layer "In5.Cu")
		(net "SAS_EXP2CONN_RX_N_22")
	)
	(segment
		(start 48.622204 -165.001956)
		(end 48.406812 -164.786564)
		(width 0.1016)
		(layer "In5.Cu")
		(net "SAS_EXP2CONN_RX_N_22")
	)
	(segment
		(start 138.57732 -122.026426)
		(end 143.65732 -127.106426)
		(width 0.1016)
		(layer "In5.Cu")
		(net "SAS_EXP2CONN_RX_N_22")
	)
	(segment
		(start 123.594114 -165.631368)
		(end 123.243594 -165.981888)
		(width 0.1016)
		(layer "In5.Cu")
		(net "SAS_EXP2CONN_RX_N_22")
	)
	(segment
		(start 122.850148 -87.84971)
		(end 123.100592 -88.100154)
		(width 0.1016)
		(layer "In5.Cu")
		(net "SAS_EXP2CONN_RX_N_22")
	)
	(segment
		(start 16.685768 -124.665232)
		(end 36.2585 -105.0925)
		(width 0.1016)
		(layer "In5.Cu")
		(net "SAS_EXP2CONN_RX_N_22")
	)
	(segment
		(start 38.989 -94.045278)
		(end 38.989 -90.551)
		(width 0.1016)
		(layer "In5.Cu")
		(net "SAS_EXP2CONN_RX_N_22")
	)
	(segment
		(start 37.084 -103.099616)
		(end 37.084 -98.644456)
		(width 0.1016)
		(layer "In5.Cu")
		(net "SAS_EXP2CONN_RX_N_22")
	)
	(segment
		(start 26.035 -161.671)
		(end 16.7386 -152.3746)
		(width 0.1016)
		(layer "In5.Cu")
		(net "SAS_EXP2CONN_RX_N_22")
	)
	(segment
		(start 138.154918 -89.535254)
		(end 138.154918 -121.006616)
		(width 0.1016)
		(layer "In5.Cu")
		(net "SAS_EXP2CONN_RX_N_22")
	)
	(segment
		(start 143.65986 -145.565368)
		(end 123.594114 -165.631368)
		(width 0.1016)
		(layer "In5.Cu")
		(net "SAS_EXP2CONN_RX_N_22")
	)
	(segment
		(start 45.45457 -162.234118)
		(end 27.394408 -162.234118)
		(width 0.1016)
		(layer "In5.Cu")
		(net "SAS_EXP2CONN_RX_N_22")
	)
	(segment
		(start 47.551848 -163.9316)
		(end 46.137068 -162.51682)
		(width 0.1016)
		(layer "In5.Cu")
		(net "SAS_EXP2CONN_RX_N_22")
	)
	(segment
		(start 39.014908 -90.488516)
		(end 39.407338 -90.096086)
		(width 0.1016)
		(layer "In5.Cu")
		(net "SAS_EXP2CONN_RX_N_22")
	)
	(segment
		(start 122.174254 -166.425118)
		(end 50.628296 -166.425118)
		(width 0.1016)
		(layer "In5.Cu")
		(net "SAS_EXP2CONN_RX_N_22")
	)
	(segment
		(start 48.246792 -164.307012)
		(end 48.0314 -164.091366)
		(width 0.1016)
		(layer "In5.Cu")
		(net "SAS_EXP2CONN_RX_N_22")
	)
	(arc
		(start 46.137068 -162.51682)
		(mid 45.823935 -162.307591)
		(end 45.45457 -162.234118)
		(width 0.1016)
		(layer "In5.Cu")
		(net "SAS_EXP2CONN_RX_N_22")
	)
	(arc
		(start 37.084 -98.644456)
		(mid 37.381057 -97.151051)
		(end 38.227 -95.885)
		(width 0.1016)
		(layer "In5.Cu")
		(net "SAS_EXP2CONN_RX_N_22")
	)
	(arc
		(start 123.243594 -165.981888)
		(mid 122.752992 -166.30982)
		(end 122.174254 -166.425118)
		(width 0.1016)
		(layer "In5.Cu")
		(net "SAS_EXP2CONN_RX_N_22")
	)
	(arc
		(start 49.397158 -165.617144)
		(mid 49.386241 -165.487622)
		(end 49.317402 -165.377368)
		(width 0.1016)
		(layer "In5.Cu")
		(net "SAS_EXP2CONN_RX_N_22")
	)
	(arc
		(start 36.2585 -105.0925)
		(mid 36.869444 -104.178157)
		(end 37.084 -103.099616)
		(width 0.1016)
		(layer "In5.Cu")
		(net "SAS_EXP2CONN_RX_N_22")
	)
	(arc
		(start 48.326802 -164.546788)
		(mid 48.315752 -164.417243)
		(end 48.246792 -164.307012)
		(width 0.1016)
		(layer "In5.Cu")
		(net "SAS_EXP2CONN_RX_N_22")
	)
	(arc
		(start 144.3228 -143.96593)
		(mid 144.150557 -144.831676)
		(end 143.660114 -145.565622)
		(width 0.1016)
		(layer "In5.Cu")
		(net "SAS_EXP2CONN_RX_N_22")
	)
	(arc
		(start 123.100592 -88.100154)
		(mid 123.273299 -88.215553)
		(end 123.47702 -88.25611)
		(width 0.1016)
		(layer "In5.Cu")
		(net "SAS_EXP2CONN_RX_N_22")
	)
	(arc
		(start 134.826502 -85.2932)
		(mid 135.292778 -85.385948)
		(end 135.68807 -85.65007)
		(width 0.1016)
		(layer "In5.Cu")
		(net "SAS_EXP2CONN_RX_N_22")
	)
	(arc
		(start 49.477168 -165.85692)
		(mid 49.408234 -165.74669)
		(end 49.397158 -165.617144)
		(width 0.1016)
		(layer "In5.Cu")
		(net "SAS_EXP2CONN_RX_N_22")
	)
	(arc
		(start 27.394408 -162.234118)
		(mid 26.658689 -162.087774)
		(end 26.035 -161.671)
		(width 0.1016)
		(layer "In5.Cu")
		(net "SAS_EXP2CONN_RX_N_22")
	)
	(arc
		(start 38.989 -90.551)
		(mid 38.995728 -90.517174)
		(end 39.014908 -90.488516)
		(width 0.1016)
		(layer "In5.Cu")
		(net "SAS_EXP2CONN_RX_N_22")
	)
	(arc
		(start 47.791624 -164.01161)
		(mid 47.662067 -164.000567)
		(end 47.551848 -163.9316)
		(width 0.1016)
		(layer "In5.Cu")
		(net "SAS_EXP2CONN_RX_N_22")
	)
	(arc
		(start 48.86198 -165.081966)
		(mid 48.732435 -165.070916)
		(end 48.622204 -165.001956)
		(width 0.1016)
		(layer "In5.Cu")
		(net "SAS_EXP2CONN_RX_N_22")
	)
	(arc
		(start 48.0314 -164.091366)
		(mid 47.921145 -164.02253)
		(end 47.791624 -164.01161)
		(width 0.1016)
		(layer "In5.Cu")
		(net "SAS_EXP2CONN_RX_N_22")
	)
	(arc
		(start 50.628296 -166.425118)
		(mid 50.089702 -166.317985)
		(end 49.633124 -166.012876)
		(width 0.1016)
		(layer "In5.Cu")
		(net "SAS_EXP2CONN_RX_N_22")
	)
	(arc
		(start 16.7386 -152.3746)
		(mid 16.287439 -151.699389)
		(end 16.129 -150.902924)
		(width 0.1016)
		(layer "In5.Cu")
		(net "SAS_EXP2CONN_RX_N_22")
	)
	(arc
		(start 138.154918 -121.006616)
		(mid 138.264753 -121.558501)
		(end 138.57732 -122.026426)
		(width 0.1016)
		(layer "In5.Cu")
		(net "SAS_EXP2CONN_RX_N_22")
	)
	(arc
		(start 129.709926 -85.64118)
		(mid 130.095311 -85.383674)
		(end 130.549904 -85.2932)
		(width 0.1016)
		(layer "In5.Cu")
		(net "SAS_EXP2CONN_RX_N_22")
	)
	(arc
		(start 49.101756 -165.161976)
		(mid 48.991537 -165.092979)
		(end 48.86198 -165.081966)
		(width 0.1016)
		(layer "In5.Cu")
		(net "SAS_EXP2CONN_RX_N_22")
	)
	(arc
		(start 126.539498 -88.25611)
		(mid 127.052665 -88.154111)
		(end 127.48768 -87.863426)
		(width 0.1016)
		(layer "In5.Cu")
		(net "SAS_EXP2CONN_RX_N_22")
	)
	(arc
		(start 143.65732 -127.106426)
		(mid 144.149829 -127.843517)
		(end 144.3228 -128.712976)
		(width 0.1016)
		(layer "In5.Cu")
		(net "SAS_EXP2CONN_RX_N_22")
	)
	(arc
		(start 16.129 -126.0094)
		(mid 16.2737 -125.281943)
		(end 16.685768 -124.665232)
		(width 0.1016)
		(layer "In5.Cu")
		(net "SAS_EXP2CONN_RX_N_22")
	)
	(arc
		(start 38.227 -95.885)
		(mid 38.790991 -95.040928)
		(end 38.989 -94.045278)
		(width 0.1016)
		(layer "In5.Cu")
		(net "SAS_EXP2CONN_RX_N_22")
	)
	(arc
		(start 48.406812 -164.786564)
		(mid 48.337815 -164.676345)
		(end 48.326802 -164.546788)
		(width 0.1016)
		(layer "In5.Cu")
		(net "SAS_EXP2CONN_RX_N_22")
	)
	(arc
		(start 137.151872 -87.114126)
		(mid 137.894208 -88.22492)
		(end 138.154918 -89.535254)
		(width 0.1016)
		(layer "In5.Cu")
		(net "SAS_EXP2CONN_RX_N_22")
	)
	(segment
		(start 299.4406 -165.8874)
		(end 299.339 -165.8874)
		(width 0.1143)
		(layer "F.Cu")
		(net "EXP_ID_BMC")
	)
	(segment
		(start 300.4566 -164.8714)
		(end 299.4406 -165.8874)
		(width 0.1143)
		(layer "F.Cu")
		(net "EXP_ID_BMC")
	)
	(segment
		(start 297.634914 -170.640248)
		(end 298.015406 -170.259756)
		(width 0.1143)
		(layer "F.Cu")
		(net "EXP_ID_BMC")
	)
	(segment
		(start 298.015406 -170.259756)
		(end 298.024804 -170.259756)
		(width 0.1143)
		(layer "F.Cu")
		(net "EXP_ID_BMC")
	)
	(segment
		(start 298.024804 -170.259756)
		(end 298.044362 -170.240198)
		(width 0.1143)
		(layer "F.Cu")
		(net "EXP_ID_BMC")
	)
	(via
		(at 300.4566 -164.8714)
		(size 0.7112)
		(drill 0.3556)
		(layers "F.Cu" "B.Cu")
		(net "EXP_ID_BMC")
	)
	(via
		(at 298.044362 -170.240198)
		(size 0.508)
		(drill 0.254)
		(layers "F.Cu" "B.Cu")
		(net "EXP_ID_BMC")
	)
	(via
		(at 299.339 -165.8874)
		(size 0.5588)
		(drill 0.3048)
		(layers "F.Cu" "B.Cu")
		(net "EXP_ID_BMC")
	)
	(segment
		(start 298.356274 -166.7383)
		(end 297.785028 -167.309546)
		(width 0.1143)
		(layer "B.Cu")
		(net "EXP_ID_BMC")
	)
	(segment
		(start 297.785028 -167.822372)
		(end 297.613578 -167.993822)
		(width 0.1143)
		(layer "B.Cu")
		(net "EXP_ID_BMC")
	)
	(segment
		(start 299.339 -165.8874)
		(end 299.339 -166.2684)
		(width 0.1143)
		(layer "B.Cu")
		(net "EXP_ID_BMC")
	)
	(segment
		(start 297.613578 -167.993822)
		(end 297.613578 -169.02176)
		(width 0.1143)
		(layer "B.Cu")
		(net "EXP_ID_BMC")
	)
	(segment
		(start 297.628818 -169.037)
		(end 297.628818 -169.739818)
		(width 0.0889)
		(layer "B.Cu")
		(net "EXP_ID_BMC")
	)
	(segment
		(start 298.8691 -166.7383)
		(end 298.356274 -166.7383)
		(width 0.1143)
		(layer "B.Cu")
		(net "EXP_ID_BMC")
	)
	(segment
		(start 297.613578 -169.02176)
		(end 297.628818 -169.037)
		(width 0.1143)
		(layer "B.Cu")
		(net "EXP_ID_BMC")
	)
	(segment
		(start 297.785028 -167.309546)
		(end 297.785028 -167.822372)
		(width 0.1143)
		(layer "B.Cu")
		(net "EXP_ID_BMC")
	)
	(segment
		(start 298.044362 -170.155362)
		(end 298.044362 -170.240198)
		(width 0.0889)
		(layer "B.Cu")
		(net "EXP_ID_BMC")
	)
	(segment
		(start 299.339 -164.5285)
		(end 299.339 -165.8874)
		(width 0.1143)
		(layer "B.Cu")
		(net "EXP_ID_BMC")
	)
	(segment
		(start 299.339 -166.2684)
		(end 298.8691 -166.7383)
		(width 0.1143)
		(layer "B.Cu")
		(net "EXP_ID_BMC")
	)
	(segment
		(start 297.628818 -169.739818)
		(end 298.044362 -170.155362)
		(width 0.0889)
		(layer "B.Cu")
		(net "EXP_ID_BMC")
	)
	(segment
		(start 23.564088 -182.309516)
		(end 23.564088 -183.308752)
		(width 0.1143)
		(layer "F.Cu")
		(net "PRE_SDA")
	)
	(segment
		(start 23.710138 -183.454802)
		(end 23.710138 -185.409586)
		(width 0.1143)
		(layer "F.Cu")
		(net "PRE_SDA")
	)
	(segment
		(start 23.564088 -183.308752)
		(end 23.710138 -183.454802)
		(width 0.1143)
		(layer "F.Cu")
		(net "PRE_SDA")
	)
	(via
		(at 23.710138 -183.454802)
		(size 0.7112)
		(drill 0.3556)
		(layers "F.Cu" "B.Cu")
		(net "PRE_SDA")
	)
	(segment
		(start 38.95725 -82.387186)
		(end 39.275004 -82.387186)
		(width 0.1016)
		(layer "F.Cu")
		(net "SAS_EXP2CONN_RX_P_21")
	)
	(segment
		(start 37.063426 -83.630516)
		(end 37.84727 -82.846672)
		(width 0.1016)
		(layer "F.Cu")
		(net "SAS_EXP2CONN_RX_P_21")
	)
	(segment
		(start 123.850146 -86.849712)
		(end 123.767088 -86.849712)
		(width 0.1016)
		(layer "F.Cu")
		(net "SAS_EXP2CONN_RX_P_21")
	)
	(segment
		(start 39.275004 -82.387186)
		(end 39.591996 -82.070194)
		(width 0.1016)
		(layer "F.Cu")
		(net "SAS_EXP2CONN_RX_P_21")
	)
	(segment
		(start 123.35002 -87.26678)
		(end 123.35002 -87.349838)
		(width 0.1016)
		(layer "F.Cu")
		(net "SAS_EXP2CONN_RX_P_21")
	)
	(segment
		(start 35.693096 -89.537286)
		(end 35.693096 -86.938866)
		(width 0.1016)
		(layer "F.Cu")
		(net "SAS_EXP2CONN_RX_P_21")
	)
	(segment
		(start 123.767088 -86.849712)
		(end 123.35002 -87.26678)
		(width 0.1016)
		(layer "F.Cu")
		(net "SAS_EXP2CONN_RX_P_21")
	)
	(segment
		(start 35.382454 -90.096086)
		(end 35.517582 -89.960958)
		(width 0.1016)
		(layer "F.Cu")
		(net "SAS_EXP2CONN_RX_P_21")
	)
	(via
		(at 35.382454 -90.096086)
		(size 0.5588)
		(drill 0.3048)
		(layers "F.Cu" "B.Cu")
		(net "SAS_EXP2CONN_RX_P_21")
	)
	(via
		(at 39.591996 -82.070194)
		(size 0.5588)
		(drill 0.3048)
		(layers "F.Cu" "B.Cu")
		(net "SAS_EXP2CONN_RX_P_21")
	)
	(via
		(at 123.850146 -86.849712)
		(size 0.508)
		(drill 0.254)
		(layers "F.Cu" "B.Cu")
		(net "SAS_EXP2CONN_RX_P_21")
	)
	(arc
		(start 37.84727 -82.846672)
		(mid 38.356549 -82.506505)
		(end 38.95725 -82.387186)
		(width 0.1016)
		(layer "F.Cu")
		(net "SAS_EXP2CONN_RX_P_21")
	)
	(arc
		(start 35.693096 -86.938866)
		(mid 36.049224 -85.148398)
		(end 37.063426 -83.630516)
		(width 0.1016)
		(layer "F.Cu")
		(net "SAS_EXP2CONN_RX_P_21")
	)
	(arc
		(start 35.517582 -89.960958)
		(mid 35.647464 -89.766576)
		(end 35.693096 -89.537286)
		(width 0.1016)
		(layer "F.Cu")
		(net "SAS_EXP2CONN_RX_P_21")
	)
	(segment
		(start 44.798996 -80.444086)
		(end 44.798996 -78.686152)
		(width 0.1016)
		(layer "B.Cu")
		(net "SAS_EXP2CONN_RX_P_21")
	)
	(segment
		(start 39.591996 -82.070194)
		(end 39.908988 -82.387186)
		(width 0.1016)
		(layer "B.Cu")
		(net "SAS_EXP2CONN_RX_P_21")
	)
	(segment
		(start 44.798996 -78.686152)
		(end 44.52493 -78.412086)
		(width 0.1016)
		(layer "B.Cu")
		(net "SAS_EXP2CONN_RX_P_21")
	)
	(segment
		(start 44.52493 -78.412086)
		(end 44.52493 -78.094586)
		(width 0.1016)
		(layer "B.Cu")
		(net "SAS_EXP2CONN_RX_P_21")
	)
	(segment
		(start 39.908988 -82.387186)
		(end 42.855896 -82.387186)
		(width 0.1016)
		(layer "B.Cu")
		(net "SAS_EXP2CONN_RX_P_21")
	)
	(arc
		(start 42.855896 -82.387186)
		(mid 44.229875 -81.818065)
		(end 44.798996 -80.444086)
		(width 0.1016)
		(layer "B.Cu")
		(net "SAS_EXP2CONN_RX_P_21")
	)
	(segment
		(start 28.328874 -108.298234)
		(end 28.54452 -108.082588)
		(width 0.1016)
		(layer "In5.Cu")
		(net "SAS_EXP2CONN_RX_P_21")
	)
	(segment
		(start 15.493746 -121.133108)
		(end 15.709392 -120.917716)
		(width 0.1016)
		(layer "In5.Cu")
		(net "SAS_EXP2CONN_RX_P_21")
	)
	(segment
		(start 22.185122 -114.441986)
		(end 22.400514 -114.22634)
		(width 0.1016)
		(layer "In5.Cu")
		(net "SAS_EXP2CONN_RX_P_21")
	)
	(segment
		(start 13.584936 -123.361704)
		(end 15.33398 -121.61266)
		(width 0.1016)
		(layer "In5.Cu")
		(net "SAS_EXP2CONN_RX_P_21")
	)
	(segment
		(start 130.279902 -83.9978)
		(end 135.975598 -83.9978)
		(width 0.1016)
		(layer "In5.Cu")
		(net "SAS_EXP2CONN_RX_P_21")
	)
	(segment
		(start 35.342068 -95.635572)
		(end 35.45332 -95.52432)
		(width 0.1016)
		(layer "In5.Cu")
		(net "SAS_EXP2CONN_RX_P_21")
	)
	(segment
		(start 126.81331 -86.968076)
		(end 126.82982 -86.95182)
		(width 0.1016)
		(layer "In5.Cu")
		(net "SAS_EXP2CONN_RX_P_21")
	)
	(segment
		(start 122.428 -168.656)
		(end 49.828958 -168.656)
		(width 0.1016)
		(layer "In5.Cu")
		(net "SAS_EXP2CONN_RX_P_21")
	)
	(segment
		(start 43.9166 -164.465)
		(end 24.79929 -164.465)
		(width 0.1016)
		(layer "In5.Cu")
		(net "SAS_EXP2CONN_RX_P_21")
	)
	(segment
		(start 124.594366 -87.311738)
		(end 125.984 -87.311738)
		(width 0.1016)
		(layer "In5.Cu")
		(net "SAS_EXP2CONN_RX_P_21")
	)
	(segment
		(start 16.188944 -120.757696)
		(end 16.404336 -120.542304)
		(width 0.1016)
		(layer "In5.Cu")
		(net "SAS_EXP2CONN_RX_P_21")
	)
	(segment
		(start 140.208 -90.188542)
		(end 140.208 -120.269)
		(width 0.1016)
		(layer "In5.Cu")
		(net "SAS_EXP2CONN_RX_P_21")
	)
	(segment
		(start 23.787354 -164.0459)
		(end 23.7871 -164.0459)
		(width 0.1016)
		(layer "In5.Cu")
		(net "SAS_EXP2CONN_RX_P_21")
	)
	(segment
		(start 123.923044 -86.879938)
		(end 124.185426 -87.14232)
		(width 0.1016)
		(layer "In5.Cu")
		(net "SAS_EXP2CONN_RX_P_21")
	)
	(segment
		(start 29.399484 -107.227878)
		(end 29.614876 -107.012232)
		(width 0.1016)
		(layer "In5.Cu")
		(net "SAS_EXP2CONN_RX_P_21")
	)
	(segment
		(start 22.880066 -114.066574)
		(end 23.095712 -113.851182)
		(width 0.1016)
		(layer "In5.Cu")
		(net "SAS_EXP2CONN_RX_P_21")
	)
	(segment
		(start 18.329656 -118.616984)
		(end 22.025102 -114.921538)
		(width 0.1016)
		(layer "In5.Cu")
		(net "SAS_EXP2CONN_RX_P_21")
	)
	(segment
		(start 16.564102 -120.062752)
		(end 16.779748 -119.847106)
		(width 0.1016)
		(layer "In5.Cu")
		(net "SAS_EXP2CONN_RX_P_21")
	)
	(segment
		(start 35.7378 -94.838012)
		(end 35.7378 -90.564716)
		(width 0.1016)
		(layer "In5.Cu")
		(net "SAS_EXP2CONN_RX_P_21")
	)
	(segment
		(start 140.567156 -121.136156)
		(end 145.669 -126.238)
		(width 0.1016)
		(layer "In5.Cu")
		(net "SAS_EXP2CONN_RX_P_21")
	)
	(segment
		(start 24.326088 -112.30102)
		(end 24.54148 -112.085628)
		(width 0.1016)
		(layer "In5.Cu")
		(net "SAS_EXP2CONN_RX_P_21")
	)
	(segment
		(start 17.634712 -118.992396)
		(end 17.850104 -118.77675)
		(width 0.1016)
		(layer "In5.Cu")
		(net "SAS_EXP2CONN_RX_P_21")
	)
	(segment
		(start 35.65779 -90.371422)
		(end 35.382454 -90.096086)
		(width 0.1016)
		(layer "In5.Cu")
		(net "SAS_EXP2CONN_RX_P_21")
	)
	(segment
		(start 17.2593 -119.68734)
		(end 17.474692 -119.471948)
		(width 0.1016)
		(layer "In5.Cu")
		(net "SAS_EXP2CONN_RX_P_21")
	)
	(segment
		(start 27.953716 -108.993178)
		(end 28.169108 -108.777786)
		(width 0.1016)
		(layer "In5.Cu")
		(net "SAS_EXP2CONN_RX_P_21")
	)
	(segment
		(start 145.923 -146.177)
		(end 124.162312 -167.937688)
		(width 0.1016)
		(layer "In5.Cu")
		(net "SAS_EXP2CONN_RX_P_21")
	)
	(segment
		(start 138.31697 -85.817456)
		(end 138.454384 -85.95487)
		(width 0.1016)
		(layer "In5.Cu")
		(net "SAS_EXP2CONN_RX_P_21")
	)
	(segment
		(start 12.8778 -152.069546)
		(end 12.8778 -125.069854)
		(width 0.1016)
		(layer "In5.Cu")
		(net "SAS_EXP2CONN_RX_P_21")
	)
	(segment
		(start 23.255478 -113.37163)
		(end 23.471124 -113.155984)
		(width 0.1016)
		(layer "In5.Cu")
		(net "SAS_EXP2CONN_RX_P_21")
	)
	(segment
		(start 23.950676 -112.996218)
		(end 24.166068 -112.780572)
		(width 0.1016)
		(layer "In5.Cu")
		(net "SAS_EXP2CONN_RX_P_21")
	)
	(segment
		(start 29.024072 -107.922822)
		(end 29.239464 -107.70743)
		(width 0.1016)
		(layer "In5.Cu")
		(net "SAS_EXP2CONN_RX_P_21")
	)
	(segment
		(start 27.258518 -109.36859)
		(end 27.474164 -109.153198)
		(width 0.1016)
		(layer "In5.Cu")
		(net "SAS_EXP2CONN_RX_P_21")
	)
	(segment
		(start 48.2346 -167.9956)
		(end 45.260768 -165.021768)
		(width 0.1016)
		(layer "In5.Cu")
		(net "SAS_EXP2CONN_RX_P_21")
	)
	(segment
		(start 25.021032 -111.925862)
		(end 27.098752 -109.848142)
		(width 0.1016)
		(layer "In5.Cu")
		(net "SAS_EXP2CONN_RX_P_21")
	)
	(segment
		(start 136.86663 -84.366862)
		(end 138.31697 -85.817202)
		(width 0.1016)
		(layer "In5.Cu")
		(net "SAS_EXP2CONN_RX_P_21")
	)
	(segment
		(start 126.82982 -86.95182)
		(end 128.76657 -85.01507)
		(width 0.1016)
		(layer "In5.Cu")
		(net "SAS_EXP2CONN_RX_P_21")
	)
	(segment
		(start 33.7058 -102.569772)
		(end 33.7058 -99.586542)
		(width 0.1016)
		(layer "In5.Cu")
		(net "SAS_EXP2CONN_RX_P_21")
	)
	(segment
		(start 128.76657 -85.01507)
		(end 129.433574 -84.34832)
		(width 0.1016)
		(layer "In5.Cu")
		(net "SAS_EXP2CONN_RX_P_21")
	)
	(segment
		(start 30.094428 -106.852466)
		(end 33.231074 -103.71582)
		(width 0.1016)
		(layer "In5.Cu")
		(net "SAS_EXP2CONN_RX_P_21")
	)
	(segment
		(start 146.431 -128.077722)
		(end 146.431 -144.950688)
		(width 0.1016)
		(layer "In5.Cu")
		(net "SAS_EXP2CONN_RX_P_21")
	)
	(segment
		(start 13.639546 -153.898346)
		(end 13.639546 -153.8986)
		(width 0.1016)
		(layer "In5.Cu")
		(net "SAS_EXP2CONN_RX_P_21")
	)
	(segment
		(start 23.7871 -164.0459)
		(end 13.639546 -153.898346)
		(width 0.1016)
		(layer "In5.Cu")
		(net "SAS_EXP2CONN_RX_P_21")
	)
	(segment
		(start 138.31697 -85.817202)
		(end 138.31697 -85.817456)
		(width 0.1016)
		(layer "In5.Cu")
		(net "SAS_EXP2CONN_RX_P_21")
	)
	(segment
		(start 13.639546 -153.8986)
		(end 13.631672 -153.890726)
		(width 0.1016)
		(layer "In5.Cu")
		(net "SAS_EXP2CONN_RX_P_21")
	)
	(arc
		(start 16.779748 -119.847106)
		(mid 16.890003 -119.77827)
		(end 17.019524 -119.76735)
		(width 0.1016)
		(layer "In5.Cu")
		(net "SAS_EXP2CONN_RX_P_21")
	)
	(arc
		(start 12.8778 -125.069854)
		(mid 13.061487 -124.145457)
		(end 13.584936 -123.361704)
		(width 0.1016)
		(layer "In5.Cu")
		(net "SAS_EXP2CONN_RX_P_21")
	)
	(arc
		(start 124.185426 -87.14232)
		(mid 124.373049 -87.267686)
		(end 124.594366 -87.311738)
		(width 0.1016)
		(layer "In5.Cu")
		(net "SAS_EXP2CONN_RX_P_21")
	)
	(arc
		(start 24.166068 -112.780572)
		(mid 24.235065 -112.670353)
		(end 24.246078 -112.540796)
		(width 0.1016)
		(layer "In5.Cu")
		(net "SAS_EXP2CONN_RX_P_21")
	)
	(arc
		(start 145.669 -126.238)
		(mid 146.232966 -127.082085)
		(end 146.431 -128.077722)
		(width 0.1016)
		(layer "In5.Cu")
		(net "SAS_EXP2CONN_RX_P_21")
	)
	(arc
		(start 135.975598 -83.9978)
		(mid 136.45779 -84.093772)
		(end 136.86663 -84.366862)
		(width 0.1016)
		(layer "In5.Cu")
		(net "SAS_EXP2CONN_RX_P_21")
	)
	(arc
		(start 23.471124 -113.155984)
		(mid 23.581379 -113.087148)
		(end 23.7109 -113.076228)
		(width 0.1016)
		(layer "In5.Cu")
		(net "SAS_EXP2CONN_RX_P_21")
	)
	(arc
		(start 35.45332 -95.52432)
		(mid 35.663824 -95.209468)
		(end 35.7378 -94.838012)
		(width 0.1016)
		(layer "In5.Cu")
		(net "SAS_EXP2CONN_RX_P_21")
	)
	(arc
		(start 29.614876 -107.012232)
		(mid 29.725106 -106.943298)
		(end 29.854652 -106.932222)
		(width 0.1016)
		(layer "In5.Cu")
		(net "SAS_EXP2CONN_RX_P_21")
	)
	(arc
		(start 35.7378 -90.564716)
		(mid 35.717011 -90.460113)
		(end 35.65779 -90.371422)
		(width 0.1016)
		(layer "In5.Cu")
		(net "SAS_EXP2CONN_RX_P_21")
	)
	(arc
		(start 123.850146 -86.849712)
		(mid 123.88961 -86.857562)
		(end 123.923044 -86.879938)
		(width 0.1016)
		(layer "In5.Cu")
		(net "SAS_EXP2CONN_RX_P_21")
	)
	(arc
		(start 23.175722 -113.611406)
		(mid 23.186639 -113.481884)
		(end 23.255478 -113.37163)
		(width 0.1016)
		(layer "In5.Cu")
		(net "SAS_EXP2CONN_RX_P_21")
	)
	(arc
		(start 24.79929 -164.465)
		(mid 24.251681 -164.356016)
		(end 23.787354 -164.0459)
		(width 0.1016)
		(layer "In5.Cu")
		(net "SAS_EXP2CONN_RX_P_21")
	)
	(arc
		(start 29.319474 -107.467654)
		(mid 29.330524 -107.338109)
		(end 29.399484 -107.227878)
		(width 0.1016)
		(layer "In5.Cu")
		(net "SAS_EXP2CONN_RX_P_21")
	)
	(arc
		(start 16.484346 -120.302528)
		(mid 16.495263 -120.173006)
		(end 16.564102 -120.062752)
		(width 0.1016)
		(layer "In5.Cu")
		(net "SAS_EXP2CONN_RX_P_21")
	)
	(arc
		(start 17.554702 -119.232172)
		(mid 17.565752 -119.102627)
		(end 17.634712 -118.992396)
		(width 0.1016)
		(layer "In5.Cu")
		(net "SAS_EXP2CONN_RX_P_21")
	)
	(arc
		(start 17.850104 -118.77675)
		(mid 17.960334 -118.707816)
		(end 18.08988 -118.69674)
		(width 0.1016)
		(layer "In5.Cu")
		(net "SAS_EXP2CONN_RX_P_21")
	)
	(arc
		(start 18.08988 -118.69674)
		(mid 18.219402 -118.685823)
		(end 18.329656 -118.616984)
		(width 0.1016)
		(layer "In5.Cu")
		(net "SAS_EXP2CONN_RX_P_21")
	)
	(arc
		(start 33.7058 -99.586542)
		(mid 34.131005 -97.448331)
		(end 35.342068 -95.635572)
		(width 0.1016)
		(layer "In5.Cu")
		(net "SAS_EXP2CONN_RX_P_21")
	)
	(arc
		(start 23.7109 -113.076228)
		(mid 23.840457 -113.065185)
		(end 23.950676 -112.996218)
		(width 0.1016)
		(layer "In5.Cu")
		(net "SAS_EXP2CONN_RX_P_21")
	)
	(arc
		(start 15.949168 -120.837706)
		(mid 16.078713 -120.826656)
		(end 16.188944 -120.757696)
		(width 0.1016)
		(layer "In5.Cu")
		(net "SAS_EXP2CONN_RX_P_21")
	)
	(arc
		(start 124.162312 -167.937688)
		(mid 123.366589 -168.46931)
		(end 122.428 -168.656)
		(width 0.1016)
		(layer "In5.Cu")
		(net "SAS_EXP2CONN_RX_P_21")
	)
	(arc
		(start 15.33398 -121.61266)
		(mid 15.402816 -121.502405)
		(end 15.413736 -121.372884)
		(width 0.1016)
		(layer "In5.Cu")
		(net "SAS_EXP2CONN_RX_P_21")
	)
	(arc
		(start 29.854652 -106.932222)
		(mid 29.984174 -106.921305)
		(end 30.094428 -106.852466)
		(width 0.1016)
		(layer "In5.Cu")
		(net "SAS_EXP2CONN_RX_P_21")
	)
	(arc
		(start 24.54148 -112.085628)
		(mid 24.65171 -112.016694)
		(end 24.781256 -112.005618)
		(width 0.1016)
		(layer "In5.Cu")
		(net "SAS_EXP2CONN_RX_P_21")
	)
	(arc
		(start 28.784296 -108.002832)
		(mid 28.913853 -107.991789)
		(end 29.024072 -107.922822)
		(width 0.1016)
		(layer "In5.Cu")
		(net "SAS_EXP2CONN_RX_P_21")
	)
	(arc
		(start 27.098752 -109.848142)
		(mid 27.167588 -109.737887)
		(end 27.178508 -109.608366)
		(width 0.1016)
		(layer "In5.Cu")
		(net "SAS_EXP2CONN_RX_P_21")
	)
	(arc
		(start 129.433574 -84.34832)
		(mid 129.821886 -84.088892)
		(end 130.279902 -83.9978)
		(width 0.1016)
		(layer "In5.Cu")
		(net "SAS_EXP2CONN_RX_P_21")
	)
	(arc
		(start 24.246078 -112.540796)
		(mid 24.257128 -112.411251)
		(end 24.326088 -112.30102)
		(width 0.1016)
		(layer "In5.Cu")
		(net "SAS_EXP2CONN_RX_P_21")
	)
	(arc
		(start 13.631672 -153.890726)
		(mid 13.073615 -153.055116)
		(end 12.8778 -152.069546)
		(width 0.1016)
		(layer "In5.Cu")
		(net "SAS_EXP2CONN_RX_P_21")
	)
	(arc
		(start 27.474164 -109.153198)
		(mid 27.584383 -109.084201)
		(end 27.71394 -109.073188)
		(width 0.1016)
		(layer "In5.Cu")
		(net "SAS_EXP2CONN_RX_P_21")
	)
	(arc
		(start 23.095712 -113.851182)
		(mid 23.164646 -113.740952)
		(end 23.175722 -113.611406)
		(width 0.1016)
		(layer "In5.Cu")
		(net "SAS_EXP2CONN_RX_P_21")
	)
	(arc
		(start 27.71394 -109.073188)
		(mid 27.843485 -109.062138)
		(end 27.953716 -108.993178)
		(width 0.1016)
		(layer "In5.Cu")
		(net "SAS_EXP2CONN_RX_P_21")
	)
	(arc
		(start 24.781256 -112.005618)
		(mid 24.910778 -111.994701)
		(end 25.021032 -111.925862)
		(width 0.1016)
		(layer "In5.Cu")
		(net "SAS_EXP2CONN_RX_P_21")
	)
	(arc
		(start 146.431 -144.950688)
		(mid 146.298983 -145.61438)
		(end 145.923 -146.177)
		(width 0.1016)
		(layer "In5.Cu")
		(net "SAS_EXP2CONN_RX_P_21")
	)
	(arc
		(start 16.404336 -120.542304)
		(mid 16.47327 -120.432074)
		(end 16.484346 -120.302528)
		(width 0.1016)
		(layer "In5.Cu")
		(net "SAS_EXP2CONN_RX_P_21")
	)
	(arc
		(start 15.413736 -121.372884)
		(mid 15.424779 -121.243327)
		(end 15.493746 -121.133108)
		(width 0.1016)
		(layer "In5.Cu")
		(net "SAS_EXP2CONN_RX_P_21")
	)
	(arc
		(start 22.105112 -114.681762)
		(mid 22.116162 -114.552217)
		(end 22.185122 -114.441986)
		(width 0.1016)
		(layer "In5.Cu")
		(net "SAS_EXP2CONN_RX_P_21")
	)
	(arc
		(start 138.454384 -85.95487)
		(mid 139.752247 -87.897309)
		(end 140.208 -90.188542)
		(width 0.1016)
		(layer "In5.Cu")
		(net "SAS_EXP2CONN_RX_P_21")
	)
	(arc
		(start 33.231074 -103.71582)
		(mid 33.582356 -103.189994)
		(end 33.7058 -102.569772)
		(width 0.1016)
		(layer "In5.Cu")
		(net "SAS_EXP2CONN_RX_P_21")
	)
	(arc
		(start 140.208 -120.269)
		(mid 140.301347 -120.738289)
		(end 140.567156 -121.136156)
		(width 0.1016)
		(layer "In5.Cu")
		(net "SAS_EXP2CONN_RX_P_21")
	)
	(arc
		(start 125.984 -87.311738)
		(mid 126.432823 -87.222368)
		(end 126.81331 -86.968076)
		(width 0.1016)
		(layer "In5.Cu")
		(net "SAS_EXP2CONN_RX_P_21")
	)
	(arc
		(start 22.400514 -114.22634)
		(mid 22.510769 -114.157504)
		(end 22.64029 -114.146584)
		(width 0.1016)
		(layer "In5.Cu")
		(net "SAS_EXP2CONN_RX_P_21")
	)
	(arc
		(start 22.025102 -114.921538)
		(mid 22.094099 -114.811319)
		(end 22.105112 -114.681762)
		(width 0.1016)
		(layer "In5.Cu")
		(net "SAS_EXP2CONN_RX_P_21")
	)
	(arc
		(start 28.54452 -108.082588)
		(mid 28.654775 -108.013752)
		(end 28.784296 -108.002832)
		(width 0.1016)
		(layer "In5.Cu")
		(net "SAS_EXP2CONN_RX_P_21")
	)
	(arc
		(start 15.709392 -120.917716)
		(mid 15.819611 -120.848719)
		(end 15.949168 -120.837706)
		(width 0.1016)
		(layer "In5.Cu")
		(net "SAS_EXP2CONN_RX_P_21")
	)
	(arc
		(start 49.828958 -168.656)
		(mid 48.966099 -168.484367)
		(end 48.2346 -167.9956)
		(width 0.1016)
		(layer "In5.Cu")
		(net "SAS_EXP2CONN_RX_P_21")
	)
	(arc
		(start 17.019524 -119.76735)
		(mid 17.149081 -119.756307)
		(end 17.2593 -119.68734)
		(width 0.1016)
		(layer "In5.Cu")
		(net "SAS_EXP2CONN_RX_P_21")
	)
	(arc
		(start 29.239464 -107.70743)
		(mid 29.308461 -107.597211)
		(end 29.319474 -107.467654)
		(width 0.1016)
		(layer "In5.Cu")
		(net "SAS_EXP2CONN_RX_P_21")
	)
	(arc
		(start 28.249118 -108.53801)
		(mid 28.260035 -108.408488)
		(end 28.328874 -108.298234)
		(width 0.1016)
		(layer "In5.Cu")
		(net "SAS_EXP2CONN_RX_P_21")
	)
	(arc
		(start 17.474692 -119.471948)
		(mid 17.543689 -119.361729)
		(end 17.554702 -119.232172)
		(width 0.1016)
		(layer "In5.Cu")
		(net "SAS_EXP2CONN_RX_P_21")
	)
	(arc
		(start 28.169108 -108.777786)
		(mid 28.238042 -108.667556)
		(end 28.249118 -108.53801)
		(width 0.1016)
		(layer "In5.Cu")
		(net "SAS_EXP2CONN_RX_P_21")
	)
	(arc
		(start 22.64029 -114.146584)
		(mid 22.769835 -114.135534)
		(end 22.880066 -114.066574)
		(width 0.1016)
		(layer "In5.Cu")
		(net "SAS_EXP2CONN_RX_P_21")
	)
	(arc
		(start 27.178508 -109.608366)
		(mid 27.189551 -109.478809)
		(end 27.258518 -109.36859)
		(width 0.1016)
		(layer "In5.Cu")
		(net "SAS_EXP2CONN_RX_P_21")
	)
	(arc
		(start 45.260768 -165.021768)
		(mid 44.644058 -164.609696)
		(end 43.9166 -164.465)
		(width 0.1016)
		(layer "In5.Cu")
		(net "SAS_EXP2CONN_RX_P_21")
	)
	(segment
		(start 24.969216 -182.698644)
		(end 24.969216 -183.31688)
		(width 0.1143)
		(layer "F.Cu")
		(net "PRE_SCL")
	)
	(segment
		(start 24.360378 -184.20588)
		(end 24.969216 -183.597042)
		(width 0.1143)
		(layer "F.Cu")
		(net "PRE_SCL")
	)
	(segment
		(start 24.360378 -185.409586)
		(end 24.360378 -184.20588)
		(width 0.1143)
		(layer "F.Cu")
		(net "PRE_SCL")
	)
	(segment
		(start 24.580088 -182.309516)
		(end 24.969216 -182.698644)
		(width 0.1143)
		(layer "F.Cu")
		(net "PRE_SCL")
	)
	(segment
		(start 24.969216 -183.597042)
		(end 24.969216 -183.31688)
		(width 0.1143)
		(layer "F.Cu")
		(net "PRE_SCL")
	)
	(via
		(at 24.969216 -183.31688)
		(size 0.7112)
		(drill 0.3556)
		(layers "F.Cu" "B.Cu")
		(net "PRE_SCL")
	)
	(segment
		(start 36.359338 -90.096086)
		(end 36.202366 -89.939368)
		(width 0.1016)
		(layer "F.Cu")
		(net "SAS_EXP2CONN_RX_N_21")
	)
	(segment
		(start 36.035996 -89.537286)
		(end 36.035996 -86.93912)
		(width 0.1016)
		(layer "F.Cu")
		(net "SAS_EXP2CONN_RX_N_21")
	)
	(segment
		(start 122.850148 -86.849712)
		(end 122.850148 -86.876382)
		(width 0.1016)
		(layer "F.Cu")
		(net "SAS_EXP2CONN_RX_N_21")
	)
	(segment
		(start 37.305996 -83.873086)
		(end 38.08984 -83.089242)
		(width 0.1016)
		(layer "F.Cu")
		(net "SAS_EXP2CONN_RX_N_21")
	)
	(segment
		(start 122.831352 -86.921848)
		(end 122.440954 -87.312246)
		(width 0.1016)
		(layer "F.Cu")
		(net "SAS_EXP2CONN_RX_N_21")
	)
	(segment
		(start 38.956996 -82.730086)
		(end 39.275004 -82.730086)
		(width 0.1016)
		(layer "F.Cu")
		(net "SAS_EXP2CONN_RX_N_21")
	)
	(segment
		(start 39.275004 -82.730086)
		(end 39.591996 -83.047078)
		(width 0.1016)
		(layer "F.Cu")
		(net "SAS_EXP2CONN_RX_N_21")
	)
	(via
		(at 122.850148 -86.849712)
		(size 0.508)
		(drill 0.254)
		(layers "F.Cu" "B.Cu")
		(net "SAS_EXP2CONN_RX_N_21")
	)
	(via
		(at 36.359338 -90.096086)
		(size 0.5588)
		(drill 0.3048)
		(layers "F.Cu" "B.Cu")
		(net "SAS_EXP2CONN_RX_N_21")
	)
	(via
		(at 39.591996 -83.047078)
		(size 0.5588)
		(drill 0.3048)
		(layers "F.Cu" "B.Cu")
		(net "SAS_EXP2CONN_RX_N_21")
	)
	(arc
		(start 36.035996 -86.93912)
		(mid 36.366057 -85.279792)
		(end 37.305996 -83.873086)
		(width 0.1016)
		(layer "F.Cu")
		(net "SAS_EXP2CONN_RX_N_21")
	)
	(arc
		(start 36.202366 -89.939368)
		(mid 36.079186 -89.754876)
		(end 36.035996 -89.537286)
		(width 0.1016)
		(layer "F.Cu")
		(net "SAS_EXP2CONN_RX_N_21")
	)
	(arc
		(start 122.440954 -87.312246)
		(mid 122.39922 -87.340069)
		(end 122.350022 -87.349838)
		(width 0.1016)
		(layer "F.Cu")
		(net "SAS_EXP2CONN_RX_N_21")
	)
	(arc
		(start 38.08984 -83.089242)
		(mid 38.487695 -82.823404)
		(end 38.956996 -82.730086)
		(width 0.1016)
		(layer "F.Cu")
		(net "SAS_EXP2CONN_RX_N_21")
	)
	(arc
		(start 122.850148 -86.876382)
		(mid 122.845256 -86.900974)
		(end 122.831352 -86.921848)
		(width 0.1016)
		(layer "F.Cu")
		(net "SAS_EXP2CONN_RX_N_21")
	)
	(segment
		(start 45.54093 -78.305152)
		(end 45.54093 -78.094586)
		(width 0.1016)
		(layer "B.Cu")
		(net "SAS_EXP2CONN_RX_N_21")
	)
	(segment
		(start 45.141896 -80.444086)
		(end 45.141896 -78.704186)
		(width 0.1016)
		(layer "B.Cu")
		(net "SAS_EXP2CONN_RX_N_21")
	)
	(segment
		(start 45.141896 -78.704186)
		(end 45.54093 -78.305152)
		(width 0.1016)
		(layer "B.Cu")
		(net "SAS_EXP2CONN_RX_N_21")
	)
	(segment
		(start 39.908988 -82.730086)
		(end 42.855896 -82.730086)
		(width 0.1016)
		(layer "B.Cu")
		(net "SAS_EXP2CONN_RX_N_21")
	)
	(segment
		(start 39.591996 -83.047078)
		(end 39.908988 -82.730086)
		(width 0.1016)
		(layer "B.Cu")
		(net "SAS_EXP2CONN_RX_N_21")
	)
	(arc
		(start 42.855896 -82.730086)
		(mid 44.472342 -82.060532)
		(end 45.141896 -80.444086)
		(width 0.1016)
		(layer "B.Cu")
		(net "SAS_EXP2CONN_RX_N_21")
	)
	(segment
		(start 34.036 -99.586542)
		(end 34.036 -102.569772)
		(width 0.1016)
		(layer "In5.Cu")
		(net "SAS_EXP2CONN_RX_N_21")
	)
	(segment
		(start 17.17167 -156.643324)
		(end 17.387316 -156.85897)
		(width 0.1016)
		(layer "In5.Cu")
		(net "SAS_EXP2CONN_RX_N_21")
	)
	(segment
		(start 36.359338 -90.096086)
		(end 36.326826 -90.096086)
		(width 0.1016)
		(layer "In5.Cu")
		(net "SAS_EXP2CONN_RX_N_21")
	)
	(segment
		(start 129.667 -84.582)
		(end 128.9812 -85.2678)
		(width 0.1016)
		(layer "In5.Cu")
		(net "SAS_EXP2CONN_RX_N_21")
	)
	(segment
		(start 17.547082 -157.338522)
		(end 17.762474 -157.553914)
		(width 0.1016)
		(layer "In5.Cu")
		(net "SAS_EXP2CONN_RX_N_21")
	)
	(segment
		(start 13.43406 -137.716768)
		(end 13.43406 -138.021568)
		(width 0.1016)
		(layer "In5.Cu")
		(net "SAS_EXP2CONN_RX_N_21")
	)
	(segment
		(start 36.2712 -90.1192)
		(end 36.181284 -90.20937)
		(width 0.1016)
		(layer "In5.Cu")
		(net "SAS_EXP2CONN_RX_N_21")
	)
	(segment
		(start 145.68932 -145.94332)
		(end 145.68932 -145.943574)
		(width 0.1016)
		(layer "In5.Cu")
		(net "SAS_EXP2CONN_RX_N_21")
	)
	(segment
		(start 33.4645 -103.9495)
		(end 13.818616 -123.595384)
		(width 0.1016)
		(layer "In5.Cu")
		(net "SAS_EXP2CONN_RX_N_21")
	)
	(segment
		(start 123.951746 -87.376)
		(end 123.914408 -87.338662)
		(width 0.1016)
		(layer "In5.Cu")
		(net "SAS_EXP2CONN_RX_N_21")
	)
	(segment
		(start 128.980946 -85.2678)
		(end 127.061722 -87.187024)
		(width 0.1016)
		(layer "In5.Cu")
		(net "SAS_EXP2CONN_RX_N_21")
	)
	(segment
		(start 137.98677 -85.954362)
		(end 137.98677 -85.954108)
		(width 0.1016)
		(layer "In5.Cu")
		(net "SAS_EXP2CONN_RX_N_21")
	)
	(segment
		(start 45.494448 -164.788088)
		(end 48.46828 -167.76192)
		(width 0.1016)
		(layer "In5.Cu")
		(net "SAS_EXP2CONN_RX_N_21")
	)
	(segment
		(start 13.43406 -148.360384)
		(end 13.43406 -148.665184)
		(width 0.1016)
		(layer "In5.Cu")
		(net "SAS_EXP2CONN_RX_N_21")
	)
	(segment
		(start 22.15642 -161.628074)
		(end 22.371812 -161.843466)
		(width 0.1016)
		(layer "In5.Cu")
		(net "SAS_EXP2CONN_RX_N_21")
	)
	(segment
		(start 125.984254 -87.641938)
		(end 124.594112 -87.641938)
		(width 0.1016)
		(layer "In5.Cu")
		(net "SAS_EXP2CONN_RX_N_21")
	)
	(segment
		(start 139.8778 -120.268746)
		(end 139.8778 -90.188796)
		(width 0.1016)
		(layer "In5.Cu")
		(net "SAS_EXP2CONN_RX_N_21")
	)
	(segment
		(start 36.068 -90.48242)
		(end 36.068 -94.838266)
		(width 0.1016)
		(layer "In5.Cu")
		(net "SAS_EXP2CONN_RX_N_21")
	)
	(segment
		(start 137.98677 -85.954108)
		(end 136.633204 -84.600542)
		(width 0.1016)
		(layer "In5.Cu")
		(net "SAS_EXP2CONN_RX_N_21")
	)
	(segment
		(start 13.43406 -142.984474)
		(end 13.43406 -143.289274)
		(width 0.1016)
		(layer "In5.Cu")
		(net "SAS_EXP2CONN_RX_N_21")
	)
	(segment
		(start 13.865352 -153.657046)
		(end 16.691864 -156.483558)
		(width 0.1016)
		(layer "In5.Cu")
		(net "SAS_EXP2CONN_RX_N_21")
	)
	(segment
		(start 13.208 -135.446008)
		(end 13.208 -135.750808)
		(width 0.1016)
		(layer "In5.Cu")
		(net "SAS_EXP2CONN_RX_N_21")
	)
	(segment
		(start 24.799544 -164.1348)
		(end 43.916346 -164.1348)
		(width 0.1016)
		(layer "In5.Cu")
		(net "SAS_EXP2CONN_RX_N_21")
	)
	(segment
		(start 13.208 -138.473688)
		(end 13.208 -141.018514)
		(width 0.1016)
		(layer "In5.Cu")
		(net "SAS_EXP2CONN_RX_N_21")
	)
	(segment
		(start 13.208 -136.959848)
		(end 13.208 -137.264648)
		(width 0.1016)
		(layer "In5.Cu")
		(net "SAS_EXP2CONN_RX_N_21")
	)
	(segment
		(start 35.687 -95.758)
		(end 35.575748 -95.869252)
		(width 0.1016)
		(layer "In5.Cu")
		(net "SAS_EXP2CONN_RX_N_21")
	)
	(segment
		(start 23.226776 -162.69843)
		(end 23.442168 -162.914076)
		(width 0.1016)
		(layer "In5.Cu")
		(net "SAS_EXP2CONN_RX_N_21")
	)
	(segment
		(start 123.928632 -167.704008)
		(end 145.68932 -145.94332)
		(width 0.1016)
		(layer "In5.Cu")
		(net "SAS_EXP2CONN_RX_N_21")
	)
	(segment
		(start 13.208 -142.227554)
		(end 13.208 -142.532354)
		(width 0.1016)
		(layer "In5.Cu")
		(net "SAS_EXP2CONN_RX_N_21")
	)
	(segment
		(start 146.1008 -144.950434)
		(end 146.1008 -128.077976)
		(width 0.1016)
		(layer "In5.Cu")
		(net "SAS_EXP2CONN_RX_N_21")
	)
	(segment
		(start 49.828958 -168.3258)
		(end 122.427746 -168.3258)
		(width 0.1016)
		(layer "In5.Cu")
		(net "SAS_EXP2CONN_RX_N_21")
	)
	(segment
		(start 13.43406 -146.846544)
		(end 13.43406 -147.151344)
		(width 0.1016)
		(layer "In5.Cu")
		(net "SAS_EXP2CONN_RX_N_21")
	)
	(segment
		(start 13.43406 -136.202928)
		(end 13.43406 -136.507728)
		(width 0.1016)
		(layer "In5.Cu")
		(net "SAS_EXP2CONN_RX_N_21")
	)
	(segment
		(start 13.208 -147.603464)
		(end 13.208 -147.908264)
		(width 0.1016)
		(layer "In5.Cu")
		(net "SAS_EXP2CONN_RX_N_21")
	)
	(segment
		(start 122.93219 -86.931754)
		(end 122.850148 -86.849712)
		(width 0.1016)
		(layer "In5.Cu")
		(net "SAS_EXP2CONN_RX_N_21")
	)
	(segment
		(start 16.691864 -156.483558)
		(end 16.692118 -156.483558)
		(width 0.1016)
		(layer "In5.Cu")
		(net "SAS_EXP2CONN_RX_N_21")
	)
	(segment
		(start 13.43406 -141.470634)
		(end 13.43406 -141.775434)
		(width 0.1016)
		(layer "In5.Cu")
		(net "SAS_EXP2CONN_RX_N_21")
	)
	(segment
		(start 21.08581 -160.557718)
		(end 21.301456 -160.77311)
		(width 0.1016)
		(layer "In5.Cu")
		(net "SAS_EXP2CONN_RX_N_21")
	)
	(segment
		(start 138.220704 -86.188296)
		(end 137.98677 -85.954362)
		(width 0.1016)
		(layer "In5.Cu")
		(net "SAS_EXP2CONN_RX_N_21")
	)
	(segment
		(start 135.975344 -84.328)
		(end 130.280156 -84.328)
		(width 0.1016)
		(layer "In5.Cu")
		(net "SAS_EXP2CONN_RX_N_21")
	)
	(segment
		(start 21.461222 -161.252662)
		(end 21.676868 -161.468308)
		(width 0.1016)
		(layer "In5.Cu")
		(net "SAS_EXP2CONN_RX_N_21")
	)
	(segment
		(start 18.242026 -157.713934)
		(end 18.457672 -157.929326)
		(width 0.1016)
		(layer "In5.Cu")
		(net "SAS_EXP2CONN_RX_N_21")
	)
	(segment
		(start 22.531578 -162.323018)
		(end 22.747224 -162.538664)
		(width 0.1016)
		(layer "In5.Cu")
		(net "SAS_EXP2CONN_RX_N_21")
	)
	(segment
		(start 23.602188 -163.393628)
		(end 24.02078 -163.81222)
		(width 0.1016)
		(layer "In5.Cu")
		(net "SAS_EXP2CONN_RX_N_21")
	)
	(segment
		(start 13.208 -143.741394)
		(end 13.208 -146.394424)
		(width 0.1016)
		(layer "In5.Cu")
		(net "SAS_EXP2CONN_RX_N_21")
	)
	(segment
		(start 18.617438 -158.408878)
		(end 20.606258 -160.397698)
		(width 0.1016)
		(layer "In5.Cu")
		(net "SAS_EXP2CONN_RX_N_21")
	)
	(segment
		(start 13.208 -125.0696)
		(end 13.208 -134.236968)
		(width 0.1016)
		(layer "In5.Cu")
		(net "SAS_EXP2CONN_RX_N_21")
	)
	(segment
		(start 13.208 -149.117304)
		(end 13.208 -152.0698)
		(width 0.1016)
		(layer "In5.Cu")
		(net "SAS_EXP2CONN_RX_N_21")
	)
	(segment
		(start 13.43406 -134.689088)
		(end 13.43406 -134.993888)
		(width 0.1016)
		(layer "In5.Cu")
		(net "SAS_EXP2CONN_RX_N_21")
	)
	(segment
		(start 145.43532 -126.471426)
		(end 140.333984 -121.37009)
		(width 0.1016)
		(layer "In5.Cu")
		(net "SAS_EXP2CONN_RX_N_21")
	)
	(segment
		(start 127.061722 -87.187024)
		(end 127.045974 -87.202518)
		(width 0.1016)
		(layer "In5.Cu")
		(net "SAS_EXP2CONN_RX_N_21")
	)
	(segment
		(start 128.9812 -85.2678)
		(end 128.980946 -85.2678)
		(width 0.1016)
		(layer "In5.Cu")
		(net "SAS_EXP2CONN_RX_N_21")
	)
	(arc
		(start 24.02078 -163.81222)
		(mid 24.37808 -164.05096)
		(end 24.799544 -164.1348)
		(width 0.1016)
		(layer "In5.Cu")
		(net "SAS_EXP2CONN_RX_N_21")
	)
	(arc
		(start 13.43406 -134.993888)
		(mid 13.404821 -135.120549)
		(end 13.32103 -135.219948)
		(width 0.1016)
		(layer "In5.Cu")
		(net "SAS_EXP2CONN_RX_N_21")
	)
	(arc
		(start 127.045974 -87.202518)
		(mid 126.558754 -87.527656)
		(end 125.984254 -87.641938)
		(width 0.1016)
		(layer "In5.Cu")
		(net "SAS_EXP2CONN_RX_N_21")
	)
	(arc
		(start 145.68932 -145.943574)
		(mid 145.993887 -145.487946)
		(end 146.1008 -144.950434)
		(width 0.1016)
		(layer "In5.Cu")
		(net "SAS_EXP2CONN_RX_N_21")
	)
	(arc
		(start 13.32103 -143.515334)
		(mid 13.237193 -143.61471)
		(end 13.208 -143.741394)
		(width 0.1016)
		(layer "In5.Cu")
		(net "SAS_EXP2CONN_RX_N_21")
	)
	(arc
		(start 13.32103 -147.377404)
		(mid 13.237193 -147.47678)
		(end 13.208 -147.603464)
		(width 0.1016)
		(layer "In5.Cu")
		(net "SAS_EXP2CONN_RX_N_21")
	)
	(arc
		(start 124.594112 -87.641938)
		(mid 124.246491 -87.572828)
		(end 123.951746 -87.376)
		(width 0.1016)
		(layer "In5.Cu")
		(net "SAS_EXP2CONN_RX_N_21")
	)
	(arc
		(start 13.32103 -148.891244)
		(mid 13.237193 -148.99062)
		(end 13.208 -149.117304)
		(width 0.1016)
		(layer "In5.Cu")
		(net "SAS_EXP2CONN_RX_N_21")
	)
	(arc
		(start 43.916346 -164.1348)
		(mid 44.770369 -164.304489)
		(end 45.494448 -164.788088)
		(width 0.1016)
		(layer "In5.Cu")
		(net "SAS_EXP2CONN_RX_N_21")
	)
	(arc
		(start 13.32103 -142.758414)
		(mid 13.404867 -142.85779)
		(end 13.43406 -142.984474)
		(width 0.1016)
		(layer "In5.Cu")
		(net "SAS_EXP2CONN_RX_N_21")
	)
	(arc
		(start 13.208 -146.394424)
		(mid 13.237239 -146.521085)
		(end 13.32103 -146.620484)
		(width 0.1016)
		(layer "In5.Cu")
		(net "SAS_EXP2CONN_RX_N_21")
	)
	(arc
		(start 13.32103 -137.490708)
		(mid 13.404867 -137.590084)
		(end 13.43406 -137.716768)
		(width 0.1016)
		(layer "In5.Cu")
		(net "SAS_EXP2CONN_RX_N_21")
	)
	(arc
		(start 36.181284 -90.20937)
		(mid 36.097494 -90.334631)
		(end 36.068 -90.48242)
		(width 0.1016)
		(layer "In5.Cu")
		(net "SAS_EXP2CONN_RX_N_21")
	)
	(arc
		(start 22.371812 -161.843466)
		(mid 22.440746 -161.953696)
		(end 22.451822 -162.083242)
		(width 0.1016)
		(layer "In5.Cu")
		(net "SAS_EXP2CONN_RX_N_21")
	)
	(arc
		(start 18.537682 -158.169102)
		(mid 18.548599 -158.298624)
		(end 18.617438 -158.408878)
		(width 0.1016)
		(layer "In5.Cu")
		(net "SAS_EXP2CONN_RX_N_21")
	)
	(arc
		(start 13.32103 -142.001494)
		(mid 13.237193 -142.10087)
		(end 13.208 -142.227554)
		(width 0.1016)
		(layer "In5.Cu")
		(net "SAS_EXP2CONN_RX_N_21")
	)
	(arc
		(start 136.633204 -84.600542)
		(mid 136.331375 -84.398866)
		(end 135.975344 -84.328)
		(width 0.1016)
		(layer "In5.Cu")
		(net "SAS_EXP2CONN_RX_N_21")
	)
	(arc
		(start 13.43406 -147.151344)
		(mid 13.404821 -147.278005)
		(end 13.32103 -147.377404)
		(width 0.1016)
		(layer "In5.Cu")
		(net "SAS_EXP2CONN_RX_N_21")
	)
	(arc
		(start 17.467072 -157.098746)
		(mid 17.478115 -157.228303)
		(end 17.547082 -157.338522)
		(width 0.1016)
		(layer "In5.Cu")
		(net "SAS_EXP2CONN_RX_N_21")
	)
	(arc
		(start 23.442168 -162.914076)
		(mid 23.511165 -163.024295)
		(end 23.522178 -163.153852)
		(width 0.1016)
		(layer "In5.Cu")
		(net "SAS_EXP2CONN_RX_N_21")
	)
	(arc
		(start 16.931894 -156.563568)
		(mid 17.061416 -156.574485)
		(end 17.17167 -156.643324)
		(width 0.1016)
		(layer "In5.Cu")
		(net "SAS_EXP2CONN_RX_N_21")
	)
	(arc
		(start 123.914408 -87.338662)
		(mid 123.815119 -87.272319)
		(end 123.698 -87.249)
		(width 0.1016)
		(layer "In5.Cu")
		(net "SAS_EXP2CONN_RX_N_21")
	)
	(arc
		(start 13.208 -142.532354)
		(mid 13.237239 -142.659015)
		(end 13.32103 -142.758414)
		(width 0.1016)
		(layer "In5.Cu")
		(net "SAS_EXP2CONN_RX_N_21")
	)
	(arc
		(start 13.32103 -135.976868)
		(mid 13.404867 -136.076244)
		(end 13.43406 -136.202928)
		(width 0.1016)
		(layer "In5.Cu")
		(net "SAS_EXP2CONN_RX_N_21")
	)
	(arc
		(start 13.32103 -134.463028)
		(mid 13.404867 -134.562404)
		(end 13.43406 -134.689088)
		(width 0.1016)
		(layer "In5.Cu")
		(net "SAS_EXP2CONN_RX_N_21")
	)
	(arc
		(start 13.43406 -143.289274)
		(mid 13.404821 -143.415935)
		(end 13.32103 -143.515334)
		(width 0.1016)
		(layer "In5.Cu")
		(net "SAS_EXP2CONN_RX_N_21")
	)
	(arc
		(start 13.208 -135.750808)
		(mid 13.237239 -135.877469)
		(end 13.32103 -135.976868)
		(width 0.1016)
		(layer "In5.Cu")
		(net "SAS_EXP2CONN_RX_N_21")
	)
	(arc
		(start 130.280156 -84.328)
		(mid 129.94831 -84.394008)
		(end 129.667 -84.582)
		(width 0.1016)
		(layer "In5.Cu")
		(net "SAS_EXP2CONN_RX_N_21")
	)
	(arc
		(start 13.43406 -148.665184)
		(mid 13.404821 -148.791845)
		(end 13.32103 -148.891244)
		(width 0.1016)
		(layer "In5.Cu")
		(net "SAS_EXP2CONN_RX_N_21")
	)
	(arc
		(start 13.32103 -135.219948)
		(mid 13.237193 -135.319324)
		(end 13.208 -135.446008)
		(width 0.1016)
		(layer "In5.Cu")
		(net "SAS_EXP2CONN_RX_N_21")
	)
	(arc
		(start 13.43406 -141.775434)
		(mid 13.404821 -141.902095)
		(end 13.32103 -142.001494)
		(width 0.1016)
		(layer "In5.Cu")
		(net "SAS_EXP2CONN_RX_N_21")
	)
	(arc
		(start 13.818616 -123.595384)
		(mid 13.366676 -124.27176)
		(end 13.208 -125.0696)
		(width 0.1016)
		(layer "In5.Cu")
		(net "SAS_EXP2CONN_RX_N_21")
	)
	(arc
		(start 13.32103 -136.733788)
		(mid 13.237193 -136.833164)
		(end 13.208 -136.959848)
		(width 0.1016)
		(layer "In5.Cu")
		(net "SAS_EXP2CONN_RX_N_21")
	)
	(arc
		(start 17.762474 -157.553914)
		(mid 17.872693 -157.622911)
		(end 18.00225 -157.633924)
		(width 0.1016)
		(layer "In5.Cu")
		(net "SAS_EXP2CONN_RX_N_21")
	)
	(arc
		(start 18.00225 -157.633924)
		(mid 18.131795 -157.644974)
		(end 18.242026 -157.713934)
		(width 0.1016)
		(layer "In5.Cu")
		(net "SAS_EXP2CONN_RX_N_21")
	)
	(arc
		(start 21.916644 -161.548064)
		(mid 22.046201 -161.559107)
		(end 22.15642 -161.628074)
		(width 0.1016)
		(layer "In5.Cu")
		(net "SAS_EXP2CONN_RX_N_21")
	)
	(arc
		(start 16.692118 -156.483558)
		(mid 16.802348 -156.552492)
		(end 16.931894 -156.563568)
		(width 0.1016)
		(layer "In5.Cu")
		(net "SAS_EXP2CONN_RX_N_21")
	)
	(arc
		(start 22.747224 -162.538664)
		(mid 22.857454 -162.607598)
		(end 22.987 -162.618674)
		(width 0.1016)
		(layer "In5.Cu")
		(net "SAS_EXP2CONN_RX_N_21")
	)
	(arc
		(start 13.208 -147.908264)
		(mid 13.237239 -148.034925)
		(end 13.32103 -148.134324)
		(width 0.1016)
		(layer "In5.Cu")
		(net "SAS_EXP2CONN_RX_N_21")
	)
	(arc
		(start 36.068 -94.838266)
		(mid 35.968988 -95.336035)
		(end 35.687 -95.758)
		(width 0.1016)
		(layer "In5.Cu")
		(net "SAS_EXP2CONN_RX_N_21")
	)
	(arc
		(start 22.451822 -162.083242)
		(mid 22.462739 -162.212764)
		(end 22.531578 -162.323018)
		(width 0.1016)
		(layer "In5.Cu")
		(net "SAS_EXP2CONN_RX_N_21")
	)
	(arc
		(start 35.575748 -95.869252)
		(mid 34.436165 -97.574759)
		(end 34.036 -99.586542)
		(width 0.1016)
		(layer "In5.Cu")
		(net "SAS_EXP2CONN_RX_N_21")
	)
	(arc
		(start 13.32103 -148.134324)
		(mid 13.404867 -148.2337)
		(end 13.43406 -148.360384)
		(width 0.1016)
		(layer "In5.Cu")
		(net "SAS_EXP2CONN_RX_N_21")
	)
	(arc
		(start 13.208 -134.236968)
		(mid 13.237239 -134.363629)
		(end 13.32103 -134.463028)
		(width 0.1016)
		(layer "In5.Cu")
		(net "SAS_EXP2CONN_RX_N_21")
	)
	(arc
		(start 13.32103 -146.620484)
		(mid 13.404867 -146.71986)
		(end 13.43406 -146.846544)
		(width 0.1016)
		(layer "In5.Cu")
		(net "SAS_EXP2CONN_RX_N_21")
	)
	(arc
		(start 21.676868 -161.468308)
		(mid 21.787123 -161.537144)
		(end 21.916644 -161.548064)
		(width 0.1016)
		(layer "In5.Cu")
		(net "SAS_EXP2CONN_RX_N_21")
	)
	(arc
		(start 13.208 -152.0698)
		(mid 13.378845 -152.928785)
		(end 13.865352 -153.657046)
		(width 0.1016)
		(layer "In5.Cu")
		(net "SAS_EXP2CONN_RX_N_21")
	)
	(arc
		(start 34.036 -102.569772)
		(mid 33.887472 -103.316475)
		(end 33.4645 -103.9495)
		(width 0.1016)
		(layer "In5.Cu")
		(net "SAS_EXP2CONN_RX_N_21")
	)
	(arc
		(start 22.987 -162.618674)
		(mid 23.116522 -162.629591)
		(end 23.226776 -162.69843)
		(width 0.1016)
		(layer "In5.Cu")
		(net "SAS_EXP2CONN_RX_N_21")
	)
	(arc
		(start 13.32103 -138.247628)
		(mid 13.237193 -138.347004)
		(end 13.208 -138.473688)
		(width 0.1016)
		(layer "In5.Cu")
		(net "SAS_EXP2CONN_RX_N_21")
	)
	(arc
		(start 21.381212 -161.012886)
		(mid 21.392255 -161.142443)
		(end 21.461222 -161.252662)
		(width 0.1016)
		(layer "In5.Cu")
		(net "SAS_EXP2CONN_RX_N_21")
	)
	(arc
		(start 13.43406 -138.021568)
		(mid 13.404821 -138.148229)
		(end 13.32103 -138.247628)
		(width 0.1016)
		(layer "In5.Cu")
		(net "SAS_EXP2CONN_RX_N_21")
	)
	(arc
		(start 146.1008 -128.077976)
		(mid 145.927852 -127.208508)
		(end 145.43532 -126.471426)
		(width 0.1016)
		(layer "In5.Cu")
		(net "SAS_EXP2CONN_RX_N_21")
	)
	(arc
		(start 13.208 -137.264648)
		(mid 13.237239 -137.391309)
		(end 13.32103 -137.490708)
		(width 0.1016)
		(layer "In5.Cu")
		(net "SAS_EXP2CONN_RX_N_21")
	)
	(arc
		(start 18.457672 -157.929326)
		(mid 18.526606 -158.039556)
		(end 18.537682 -158.169102)
		(width 0.1016)
		(layer "In5.Cu")
		(net "SAS_EXP2CONN_RX_N_21")
	)
	(arc
		(start 139.8778 -90.188796)
		(mid 139.447141 -88.023728)
		(end 138.220704 -86.188296)
		(width 0.1016)
		(layer "In5.Cu")
		(net "SAS_EXP2CONN_RX_N_21")
	)
	(arc
		(start 23.522178 -163.153852)
		(mid 23.533228 -163.283397)
		(end 23.602188 -163.393628)
		(width 0.1016)
		(layer "In5.Cu")
		(net "SAS_EXP2CONN_RX_N_21")
	)
	(arc
		(start 20.846034 -160.477708)
		(mid 20.975579 -160.488758)
		(end 21.08581 -160.557718)
		(width 0.1016)
		(layer "In5.Cu")
		(net "SAS_EXP2CONN_RX_N_21")
	)
	(arc
		(start 140.333984 -121.37009)
		(mid 139.996353 -120.864789)
		(end 139.8778 -120.268746)
		(width 0.1016)
		(layer "In5.Cu")
		(net "SAS_EXP2CONN_RX_N_21")
	)
	(arc
		(start 17.387316 -156.85897)
		(mid 17.456152 -156.969225)
		(end 17.467072 -157.098746)
		(width 0.1016)
		(layer "In5.Cu")
		(net "SAS_EXP2CONN_RX_N_21")
	)
	(arc
		(start 13.43406 -136.507728)
		(mid 13.404821 -136.634389)
		(end 13.32103 -136.733788)
		(width 0.1016)
		(layer "In5.Cu")
		(net "SAS_EXP2CONN_RX_N_21")
	)
	(arc
		(start 13.208 -141.018514)
		(mid 13.237239 -141.145175)
		(end 13.32103 -141.244574)
		(width 0.1016)
		(layer "In5.Cu")
		(net "SAS_EXP2CONN_RX_N_21")
	)
	(arc
		(start 21.301456 -160.77311)
		(mid 21.370292 -160.883365)
		(end 21.381212 -161.012886)
		(width 0.1016)
		(layer "In5.Cu")
		(net "SAS_EXP2CONN_RX_N_21")
	)
	(arc
		(start 20.606258 -160.397698)
		(mid 20.716477 -160.466695)
		(end 20.846034 -160.477708)
		(width 0.1016)
		(layer "In5.Cu")
		(net "SAS_EXP2CONN_RX_N_21")
	)
	(arc
		(start 36.326826 -90.096086)
		(mid 36.296708 -90.102095)
		(end 36.2712 -90.1192)
		(width 0.1016)
		(layer "In5.Cu")
		(net "SAS_EXP2CONN_RX_N_21")
	)
	(arc
		(start 48.46828 -167.76192)
		(mid 49.092535 -168.17919)
		(end 49.828958 -168.3258)
		(width 0.1016)
		(layer "In5.Cu")
		(net "SAS_EXP2CONN_RX_N_21")
	)
	(arc
		(start 13.32103 -141.244574)
		(mid 13.404867 -141.34395)
		(end 13.43406 -141.470634)
		(width 0.1016)
		(layer "In5.Cu")
		(net "SAS_EXP2CONN_RX_N_21")
	)
	(arc
		(start 123.698 -87.249)
		(mid 123.283532 -87.166557)
		(end 122.93219 -86.931754)
		(width 0.1016)
		(layer "In5.Cu")
		(net "SAS_EXP2CONN_RX_N_21")
	)
	(arc
		(start 122.427746 -168.3258)
		(mid 123.240045 -168.164206)
		(end 123.928632 -167.704008)
		(width 0.1016)
		(layer "In5.Cu")
		(net "SAS_EXP2CONN_RX_N_21")
	)
	(segment
		(start 99.549966 -54.99989)
		(end 99.55022 -54.99989)
		(width 0.254)
		(layer "F.Cu")
		(net "P1V8_C_PG")
	)
	(segment
		(start 222.25 -111.379)
		(end 222.504 -111.125)
		(width 0.254)
		(layer "F.Cu")
		(net "P1V8_C_PG")
	)
	(segment
		(start 221.361 -111.9505)
		(end 222.25 -111.9505)
		(width 0.254)
		(layer "F.Cu")
		(net "P1V8_C_PG")
	)
	(segment
		(start 222.25 -111.9505)
		(end 222.25 -111.379)
		(width 0.254)
		(layer "F.Cu")
		(net "P1V8_C_PG")
	)
	(segment
		(start 220.218 -110.8075)
		(end 221.361 -111.9505)
		(width 0.254)
		(layer "F.Cu")
		(net "P1V8_C_PG")
	)
	(segment
		(start 222.504 -111.125)
		(end 222.504 -110.617)
		(width 0.254)
		(layer "F.Cu")
		(net "P1V8_C_PG")
	)
	(segment
		(start 99.55022 -54.99989)
		(end 99.950016 -55.399686)
		(width 0.254)
		(layer "F.Cu")
		(net "P1V8_C_PG")
	)
	(via
		(at 222.504 -110.617)
		(size 0.5588)
		(drill 0.3048)
		(layers "F.Cu" "B.Cu")
		(net "P1V8_C_PG")
	)
	(via
		(at 224.663 -82.169)
		(size 0.508)
		(drill 0.254)
		(layers "F.Cu" "B.Cu")
		(net "P1V8_C_PG")
	)
	(via
		(at 223.39554 -90.27414)
		(size 0.5588)
		(drill 0.3048)
		(layers "F.Cu" "B.Cu")
		(net "P1V8_C_PG")
	)
	(via
		(at 99.950016 -55.399686)
		(size 0.508)
		(drill 0.254)
		(layers "F.Cu" "B.Cu")
		(net "P1V8_C_PG")
	)
	(via
		(at 224.155 -86.233)
		(size 0.7112)
		(drill 0.3556)
		(layers "F.Cu" "B.Cu")
		(net "P1V8_C_PG")
	)
	(segment
		(start 223.393 -90.2716)
		(end 223.393 -88.340438)
		(width 0.254)
		(layer "B.Cu")
		(net "P1V8_C_PG")
	)
	(segment
		(start 223.39808 -88.335358)
		(end 223.39808 -87.872062)
		(width 0.254)
		(layer "B.Cu")
		(net "P1V8_C_PG")
	)
	(segment
		(start 224.155 -86.233)
		(end 224.663 -85.725)
		(width 0.254)
		(layer "B.Cu")
		(net "P1V8_C_PG")
	)
	(segment
		(start 223.39554 -90.27414)
		(end 223.393 -90.2716)
		(width 0.254)
		(layer "B.Cu")
		(net "P1V8_C_PG")
	)
	(segment
		(start 223.39808 -87.872062)
		(end 223.393 -87.866982)
		(width 0.254)
		(layer "B.Cu")
		(net "P1V8_C_PG")
	)
	(segment
		(start 223.393 -86.995)
		(end 224.155 -86.233)
		(width 0.254)
		(layer "B.Cu")
		(net "P1V8_C_PG")
	)
	(segment
		(start 224.663 -85.725)
		(end 224.663 -82.169)
		(width 0.254)
		(layer "B.Cu")
		(net "P1V8_C_PG")
	)
	(segment
		(start 223.393 -87.866982)
		(end 223.393 -86.995)
		(width 0.254)
		(layer "B.Cu")
		(net "P1V8_C_PG")
	)
	(segment
		(start 223.393 -88.340438)
		(end 223.39808 -88.335358)
		(width 0.254)
		(layer "B.Cu")
		(net "P1V8_C_PG")
	)
	(segment
		(start 143.72463 -67.8815)
		(end 133.2357 -67.8815)
		(width 0.254)
		(layer "In2.Cu")
		(net "P1V8_C_PG")
	)
	(segment
		(start 223.39554 -94.23146)
		(end 223.39554 -90.27414)
		(width 0.254)
		(layer "In2.Cu")
		(net "P1V8_C_PG")
	)
	(segment
		(start 112.247172 -62.767972)
		(end 111.252 -61.7728)
		(width 0.254)
		(layer "In2.Cu")
		(net "P1V8_C_PG")
	)
	(segment
		(start 225.2218 -67.607434)
		(end 220.542866 -62.9285)
		(width 0.254)
		(layer "In2.Cu")
		(net "P1V8_C_PG")
	)
	(segment
		(start 99.949 -60.408566)
		(end 99.949 -59.69)
		(width 0.254)
		(layer "In2.Cu")
		(net "P1V8_C_PG")
	)
	(segment
		(start 99.950016 -56.78805)
		(end 99.950016 -55.399686)
		(width 0.254)
		(layer "In2.Cu")
		(net "P1V8_C_PG")
	)
	(segment
		(start 128.122172 -62.767972)
		(end 112.247172 -62.767972)
		(width 0.254)
		(layer "In2.Cu")
		(net "P1V8_C_PG")
	)
	(segment
		(start 100.438966 -59.200034)
		(end 100.438966 -57.277)
		(width 0.254)
		(layer "In2.Cu")
		(net "P1V8_C_PG")
	)
	(segment
		(start 133.2357 -67.8815)
		(end 128.122172 -62.767972)
		(width 0.254)
		(layer "In2.Cu")
		(net "P1V8_C_PG")
	)
	(segment
		(start 100.438966 -57.277)
		(end 99.950016 -56.78805)
		(width 0.254)
		(layer "In2.Cu")
		(net "P1V8_C_PG")
	)
	(segment
		(start 222.1992 -110.3122)
		(end 222.1992 -95.4278)
		(width 0.254)
		(layer "In2.Cu")
		(net "P1V8_C_PG")
	)
	(segment
		(start 111.252 -61.7728)
		(end 101.313234 -61.7728)
		(width 0.254)
		(layer "In2.Cu")
		(net "P1V8_C_PG")
	)
	(segment
		(start 148.67763 -62.9285)
		(end 143.72463 -67.8815)
		(width 0.254)
		(layer "In2.Cu")
		(net "P1V8_C_PG")
	)
	(segment
		(start 101.313234 -61.7728)
		(end 99.949 -60.408566)
		(width 0.254)
		(layer "In2.Cu")
		(net "P1V8_C_PG")
	)
	(segment
		(start 220.542866 -62.9285)
		(end 148.67763 -62.9285)
		(width 0.254)
		(layer "In2.Cu")
		(net "P1V8_C_PG")
	)
	(segment
		(start 224.663 -82.169)
		(end 225.2218 -81.6102)
		(width 0.254)
		(layer "In2.Cu")
		(net "P1V8_C_PG")
	)
	(segment
		(start 225.2218 -81.6102)
		(end 225.2218 -67.607434)
		(width 0.254)
		(layer "In2.Cu")
		(net "P1V8_C_PG")
	)
	(segment
		(start 99.949 -59.69)
		(end 100.438966 -59.200034)
		(width 0.254)
		(layer "In2.Cu")
		(net "P1V8_C_PG")
	)
	(segment
		(start 222.504 -110.617)
		(end 222.1992 -110.3122)
		(width 0.254)
		(layer "In2.Cu")
		(net "P1V8_C_PG")
	)
	(segment
		(start 222.1992 -95.4278)
		(end 223.39554 -94.23146)
		(width 0.254)
		(layer "In2.Cu")
		(net "P1V8_C_PG")
	)
	(segment
		(start 36.162996 -82.222086)
		(end 37.402008 -80.98282)
		(width 0.1016)
		(layer "F.Cu")
		(net "SAS_EXP2CONN_RX_N_20")
	)
	(segment
		(start 35.295078 -83.090004)
		(end 36.162996 -82.222086)
		(width 0.1016)
		(layer "F.Cu")
		(net "SAS_EXP2CONN_RX_N_20")
	)
	(segment
		(start 38.702996 -80.444086)
		(end 39.210996 -80.444086)
		(width 0.1016)
		(layer "F.Cu")
		(net "SAS_EXP2CONN_RX_N_20")
	)
	(segment
		(start 39.385494 -80.516222)
		(end 39.591996 -80.722978)
		(width 0.1016)
		(layer "F.Cu")
		(net "SAS_EXP2CONN_RX_N_20")
	)
	(segment
		(start 122.350022 -86.34984)
		(end 122.850148 -85.849714)
		(width 0.1016)
		(layer "F.Cu")
		(net "SAS_EXP2CONN_RX_N_20")
	)
	(segment
		(start 33.076896 -89.588086)
		(end 33.076896 -88.445086)
		(width 0.1016)
		(layer "F.Cu")
		(net "SAS_EXP2CONN_RX_N_20")
	)
	(segment
		(start 33.311338 -90.096086)
		(end 33.270444 -90.054938)
		(width 0.1016)
		(layer "F.Cu")
		(net "SAS_EXP2CONN_RX_N_20")
	)
	(via
		(at 122.850148 -85.849714)
		(size 0.508)
		(drill 0.254)
		(layers "F.Cu" "B.Cu")
		(net "SAS_EXP2CONN_RX_N_20")
	)
	(via
		(at 33.311338 -90.096086)
		(size 0.5588)
		(drill 0.3048)
		(layers "F.Cu" "B.Cu")
		(net "SAS_EXP2CONN_RX_N_20")
	)
	(via
		(at 39.591996 -80.722978)
		(size 0.5588)
		(drill 0.3048)
		(layers "F.Cu" "B.Cu")
		(net "SAS_EXP2CONN_RX_N_20")
	)
	(arc
		(start 37.402008 -80.98282)
		(mid 37.998921 -80.584068)
		(end 38.702996 -80.444086)
		(width 0.1016)
		(layer "F.Cu")
		(net "SAS_EXP2CONN_RX_N_20")
	)
	(arc
		(start 39.210996 -80.444086)
		(mid 39.305432 -80.462777)
		(end 39.385494 -80.516222)
		(width 0.1016)
		(layer "F.Cu")
		(net "SAS_EXP2CONN_RX_N_20")
	)
	(arc
		(start 33.076896 -88.445086)
		(mid 33.653376 -85.546923)
		(end 35.295078 -83.090004)
		(width 0.1016)
		(layer "F.Cu")
		(net "SAS_EXP2CONN_RX_N_20")
	)
	(arc
		(start 33.270444 -90.054938)
		(mid 33.127242 -89.84076)
		(end 33.076896 -89.588086)
		(width 0.1016)
		(layer "F.Cu")
		(net "SAS_EXP2CONN_RX_N_20")
	)
	(segment
		(start 42.79138 -79.111602)
		(end 42.79138 -78.742286)
		(width 0.1016)
		(layer "B.Cu")
		(net "SAS_EXP2CONN_RX_N_20")
	)
	(segment
		(start 42.89298 -78.640686)
		(end 43.02633 -78.640686)
		(width 0.1016)
		(layer "B.Cu")
		(net "SAS_EXP2CONN_RX_N_20")
	)
	(segment
		(start 39.908988 -80.405986)
		(end 41.496996 -80.405986)
		(width 0.1016)
		(layer "B.Cu")
		(net "SAS_EXP2CONN_RX_N_20")
	)
	(segment
		(start 43.12793 -78.539086)
		(end 43.12793 -78.094586)
		(width 0.1016)
		(layer "B.Cu")
		(net "SAS_EXP2CONN_RX_N_20")
	)
	(segment
		(start 39.591996 -80.722978)
		(end 39.908988 -80.405986)
		(width 0.1016)
		(layer "B.Cu")
		(net "SAS_EXP2CONN_RX_N_20")
	)
	(arc
		(start 41.496996 -80.405986)
		(mid 42.412264 -80.02687)
		(end 42.79138 -79.111602)
		(width 0.1016)
		(layer "B.Cu")
		(net "SAS_EXP2CONN_RX_N_20")
	)
	(arc
		(start 43.02633 -78.640686)
		(mid 43.098172 -78.610928)
		(end 43.12793 -78.539086)
		(width 0.1016)
		(layer "B.Cu")
		(net "SAS_EXP2CONN_RX_N_20")
	)
	(arc
		(start 42.79138 -78.742286)
		(mid 42.821138 -78.670444)
		(end 42.89298 -78.640686)
		(width 0.1016)
		(layer "B.Cu")
		(net "SAS_EXP2CONN_RX_N_20")
	)
	(segment
		(start 124.671074 -169.50182)
		(end 124.67082 -169.50182)
		(width 0.1016)
		(layer "In5.Cu")
		(net "SAS_EXP2CONN_RX_N_20")
	)
	(segment
		(start 124.817632 -86.179914)
		(end 124.295408 -86.179914)
		(width 0.1016)
		(layer "In5.Cu")
		(net "SAS_EXP2CONN_RX_N_20")
	)
	(segment
		(start 29.5148 -104.8512)
		(end 11.200384 -123.165616)
		(width 0.1016)
		(layer "In5.Cu")
		(net "SAS_EXP2CONN_RX_N_20")
	)
	(segment
		(start 33.02 -90.477086)
		(end 33.02 -92.7227)
		(width 0.1016)
		(layer "In5.Cu")
		(net "SAS_EXP2CONN_RX_N_20")
	)
	(segment
		(start 18.914872 -161.993326)
		(end 19.130264 -162.208718)
		(width 0.1016)
		(layer "In5.Cu")
		(net "SAS_EXP2CONN_RX_N_20")
	)
	(segment
		(start 33.311338 -90.096086)
		(end 33.27908 -90.096086)
		(width 0.1016)
		(layer "In5.Cu")
		(net "SAS_EXP2CONN_RX_N_20")
	)
	(segment
		(start 19.985228 -163.063682)
		(end 20.20062 -163.279328)
		(width 0.1016)
		(layer "In5.Cu")
		(net "SAS_EXP2CONN_RX_N_20")
	)
	(segment
		(start 33.093914 -90.219784)
		(end 33.049972 -90.325956)
		(width 0.1016)
		(layer "In5.Cu")
		(net "SAS_EXP2CONN_RX_N_20")
	)
	(segment
		(start 140.424408 -86.382352)
		(end 138.154918 -84.112862)
		(width 0.1016)
		(layer "In5.Cu")
		(net "SAS_EXP2CONN_RX_N_20")
	)
	(segment
		(start 123.5202 -86.233)
		(end 123.33986 -86.052406)
		(width 0.1016)
		(layer "In5.Cu")
		(net "SAS_EXP2CONN_RX_N_20")
	)
	(segment
		(start 19.29003 -162.68827)
		(end 19.505676 -162.903916)
		(width 0.1016)
		(layer "In5.Cu")
		(net "SAS_EXP2CONN_RX_N_20")
	)
	(segment
		(start 30.988 -97.628456)
		(end 30.988 -101.294438)
		(width 0.1016)
		(layer "In5.Cu")
		(net "SAS_EXP2CONN_RX_N_20")
	)
	(segment
		(start 142.13332 -120.629426)
		(end 142.13332 -120.62968)
		(width 0.1016)
		(layer "In5.Cu")
		(net "SAS_EXP2CONN_RX_N_20")
	)
	(segment
		(start 124.04471 -86.2838)
		(end 123.642882 -86.2838)
		(width 0.1016)
		(layer "In5.Cu")
		(net "SAS_EXP2CONN_RX_N_20")
	)
	(segment
		(start 147.8788 -145.668746)
		(end 147.8788 -127.495554)
		(width 0.1016)
		(layer "In5.Cu")
		(net "SAS_EXP2CONN_RX_N_20")
	)
	(segment
		(start 10.99058 -154.38882)
		(end 18.43532 -161.83356)
		(width 0.1016)
		(layer "In5.Cu")
		(net "SAS_EXP2CONN_RX_N_20")
	)
	(segment
		(start 124.67082 -169.50182)
		(end 147.436586 -146.736054)
		(width 0.1016)
		(layer "In5.Cu")
		(net "SAS_EXP2CONN_RX_N_20")
	)
	(segment
		(start 10.033 -125.984)
		(end 10.033 -152.076912)
		(width 0.1016)
		(layer "In5.Cu")
		(net "SAS_EXP2CONN_RX_N_20")
	)
	(segment
		(start 141.7828 -119.887746)
		(end 141.7828 -89.662)
		(width 0.1016)
		(layer "In5.Cu")
		(net "SAS_EXP2CONN_RX_N_20")
	)
	(segment
		(start 49.302924 -170.053)
		(end 123.340622 -170.053)
		(width 0.1016)
		(layer "In5.Cu")
		(net "SAS_EXP2CONN_RX_N_20")
	)
	(segment
		(start 147.08632 -125.582426)
		(end 142.13332 -120.629426)
		(width 0.1016)
		(layer "In5.Cu")
		(net "SAS_EXP2CONN_RX_N_20")
	)
	(segment
		(start 128.217168 -83.872832)
		(end 126.6825 -85.4075)
		(width 0.1016)
		(layer "In5.Cu")
		(net "SAS_EXP2CONN_RX_N_20")
	)
	(segment
		(start 23.73503 -166.1922)
		(end 44.010072 -166.1922)
		(width 0.1016)
		(layer "In5.Cu")
		(net "SAS_EXP2CONN_RX_N_20")
	)
	(segment
		(start 21.430996 -164.829236)
		(end 22.12848 -165.52672)
		(width 0.1016)
		(layer "In5.Cu")
		(net "SAS_EXP2CONN_RX_N_20")
	)
	(segment
		(start 20.36064 -163.75888)
		(end 20.576032 -163.974272)
		(width 0.1016)
		(layer "In5.Cu")
		(net "SAS_EXP2CONN_RX_N_20")
	)
	(segment
		(start 137.018522 -83.6422)
		(end 128.773936 -83.6422)
		(width 0.1016)
		(layer "In5.Cu")
		(net "SAS_EXP2CONN_RX_N_20")
	)
	(segment
		(start 142.13332 -120.62968)
		(end 142.058898 -120.555258)
		(width 0.1016)
		(layer "In5.Cu")
		(net "SAS_EXP2CONN_RX_N_20")
	)
	(segment
		(start 21.055584 -164.134292)
		(end 21.27123 -164.349684)
		(width 0.1016)
		(layer "In5.Cu")
		(net "SAS_EXP2CONN_RX_N_20")
	)
	(segment
		(start 44.69257 -166.474902)
		(end 47.539402 -169.322496)
		(width 0.1016)
		(layer "In5.Cu")
		(net "SAS_EXP2CONN_RX_N_20")
	)
	(arc
		(start 123.340622 -170.053)
		(mid 124.060663 -169.909739)
		(end 124.671074 -169.50182)
		(width 0.1016)
		(layer "In5.Cu")
		(net "SAS_EXP2CONN_RX_N_20")
	)
	(arc
		(start 19.130264 -162.208718)
		(mid 19.199198 -162.318948)
		(end 19.210274 -162.448494)
		(width 0.1016)
		(layer "In5.Cu")
		(net "SAS_EXP2CONN_RX_N_20")
	)
	(arc
		(start 33.02 -92.7227)
		(mid 32.788952 -93.884259)
		(end 32.131 -94.869)
		(width 0.1016)
		(layer "In5.Cu")
		(net "SAS_EXP2CONN_RX_N_20")
	)
	(arc
		(start 142.058898 -120.555258)
		(mid 141.85443 -120.248971)
		(end 141.7828 -119.887746)
		(width 0.1016)
		(layer "In5.Cu")
		(net "SAS_EXP2CONN_RX_N_20")
	)
	(arc
		(start 30.988 -101.294438)
		(mid 30.605185 -103.219361)
		(end 29.5148 -104.8512)
		(width 0.1016)
		(layer "In5.Cu")
		(net "SAS_EXP2CONN_RX_N_20")
	)
	(arc
		(start 123.33986 -86.052406)
		(mid 123.115163 -85.902361)
		(end 122.850148 -85.849714)
		(width 0.1016)
		(layer "In5.Cu")
		(net "SAS_EXP2CONN_RX_N_20")
	)
	(arc
		(start 20.20062 -163.279328)
		(mid 20.269617 -163.389547)
		(end 20.28063 -163.519104)
		(width 0.1016)
		(layer "In5.Cu")
		(net "SAS_EXP2CONN_RX_N_20")
	)
	(arc
		(start 22.12848 -165.52672)
		(mid 22.865571 -166.019229)
		(end 23.73503 -166.1922)
		(width 0.1016)
		(layer "In5.Cu")
		(net "SAS_EXP2CONN_RX_N_20")
	)
	(arc
		(start 19.745452 -162.983926)
		(mid 19.874974 -162.994843)
		(end 19.985228 -163.063682)
		(width 0.1016)
		(layer "In5.Cu")
		(net "SAS_EXP2CONN_RX_N_20")
	)
	(arc
		(start 126.6825 -85.4075)
		(mid 125.826891 -85.979199)
		(end 124.817632 -86.179914)
		(width 0.1016)
		(layer "In5.Cu")
		(net "SAS_EXP2CONN_RX_N_20")
	)
	(arc
		(start 33.27908 -90.096086)
		(mid 33.167744 -90.129858)
		(end 33.093914 -90.219784)
		(width 0.1016)
		(layer "In5.Cu")
		(net "SAS_EXP2CONN_RX_N_20")
	)
	(arc
		(start 20.815808 -164.054282)
		(mid 20.945353 -164.065332)
		(end 21.055584 -164.134292)
		(width 0.1016)
		(layer "In5.Cu")
		(net "SAS_EXP2CONN_RX_N_20")
	)
	(arc
		(start 19.505676 -162.903916)
		(mid 19.615906 -162.97285)
		(end 19.745452 -162.983926)
		(width 0.1016)
		(layer "In5.Cu")
		(net "SAS_EXP2CONN_RX_N_20")
	)
	(arc
		(start 18.43532 -161.83356)
		(mid 18.545575 -161.902396)
		(end 18.675096 -161.913316)
		(width 0.1016)
		(layer "In5.Cu")
		(net "SAS_EXP2CONN_RX_N_20")
	)
	(arc
		(start 21.27123 -164.349684)
		(mid 21.340164 -164.459914)
		(end 21.35124 -164.58946)
		(width 0.1016)
		(layer "In5.Cu")
		(net "SAS_EXP2CONN_RX_N_20")
	)
	(arc
		(start 19.210274 -162.448494)
		(mid 19.221191 -162.578016)
		(end 19.29003 -162.68827)
		(width 0.1016)
		(layer "In5.Cu")
		(net "SAS_EXP2CONN_RX_N_20")
	)
	(arc
		(start 33.049972 -90.325956)
		(mid 33.027568 -90.400048)
		(end 33.02 -90.477086)
		(width 0.1016)
		(layer "In5.Cu")
		(net "SAS_EXP2CONN_RX_N_20")
	)
	(arc
		(start 20.28063 -163.519104)
		(mid 20.291673 -163.648661)
		(end 20.36064 -163.75888)
		(width 0.1016)
		(layer "In5.Cu")
		(net "SAS_EXP2CONN_RX_N_20")
	)
	(arc
		(start 20.576032 -163.974272)
		(mid 20.686251 -164.043269)
		(end 20.815808 -164.054282)
		(width 0.1016)
		(layer "In5.Cu")
		(net "SAS_EXP2CONN_RX_N_20")
	)
	(arc
		(start 21.35124 -164.58946)
		(mid 21.362157 -164.718982)
		(end 21.430996 -164.829236)
		(width 0.1016)
		(layer "In5.Cu")
		(net "SAS_EXP2CONN_RX_N_20")
	)
	(arc
		(start 128.773936 -83.6422)
		(mid 128.472611 -83.702137)
		(end 128.217168 -83.872832)
		(width 0.1016)
		(layer "In5.Cu")
		(net "SAS_EXP2CONN_RX_N_20")
	)
	(arc
		(start 44.010072 -166.1922)
		(mid 44.379438 -166.265671)
		(end 44.69257 -166.474902)
		(width 0.1016)
		(layer "In5.Cu")
		(net "SAS_EXP2CONN_RX_N_20")
	)
	(arc
		(start 18.675096 -161.913316)
		(mid 18.804653 -161.924359)
		(end 18.914872 -161.993326)
		(width 0.1016)
		(layer "In5.Cu")
		(net "SAS_EXP2CONN_RX_N_20")
	)
	(arc
		(start 147.436586 -146.736054)
		(mid 147.763837 -146.246383)
		(end 147.8788 -145.668746)
		(width 0.1016)
		(layer "In5.Cu")
		(net "SAS_EXP2CONN_RX_N_20")
	)
	(arc
		(start 147.8788 -127.495554)
		(mid 147.672848 -126.460163)
		(end 147.08632 -125.582426)
		(width 0.1016)
		(layer "In5.Cu")
		(net "SAS_EXP2CONN_RX_N_20")
	)
	(arc
		(start 11.200384 -123.165616)
		(mid 10.336372 -124.458702)
		(end 10.033 -125.984)
		(width 0.1016)
		(layer "In5.Cu")
		(net "SAS_EXP2CONN_RX_N_20")
	)
	(arc
		(start 141.7828 -89.662)
		(mid 141.429765 -87.887085)
		(end 140.424408 -86.382352)
		(width 0.1016)
		(layer "In5.Cu")
		(net "SAS_EXP2CONN_RX_N_20")
	)
	(arc
		(start 138.154918 -84.112862)
		(mid 137.633535 -83.764485)
		(end 137.018522 -83.6422)
		(width 0.1016)
		(layer "In5.Cu")
		(net "SAS_EXP2CONN_RX_N_20")
	)
	(arc
		(start 47.539402 -169.322496)
		(mid 48.348513 -169.863127)
		(end 49.302924 -170.053)
		(width 0.1016)
		(layer "In5.Cu")
		(net "SAS_EXP2CONN_RX_N_20")
	)
	(arc
		(start 124.295408 -86.179914)
		(mid 124.180387 -86.256769)
		(end 124.04471 -86.2838)
		(width 0.1016)
		(layer "In5.Cu")
		(net "SAS_EXP2CONN_RX_N_20")
	)
	(arc
		(start 10.033 -152.076912)
		(mid 10.281875 -153.328091)
		(end 10.99058 -154.38882)
		(width 0.1016)
		(layer "In5.Cu")
		(net "SAS_EXP2CONN_RX_N_20")
	)
	(arc
		(start 123.642882 -86.2838)
		(mid 123.576493 -86.270594)
		(end 123.5202 -86.233)
		(width 0.1016)
		(layer "In5.Cu")
		(net "SAS_EXP2CONN_RX_N_20")
	)
	(arc
		(start 32.131 -94.869)
		(mid 31.285053 -96.135049)
		(end 30.988 -97.628456)
		(width 0.1016)
		(layer "In5.Cu")
		(net "SAS_EXP2CONN_RX_N_20")
	)
	(segment
		(start 32.334454 -90.096086)
		(end 32.657288 -89.773252)
		(width 0.1016)
		(layer "F.Cu")
		(net "SAS_EXP2CONN_RX_P_20")
	)
	(segment
		(start 39.236904 -80.101186)
		(end 39.591996 -79.746094)
		(width 0.1016)
		(layer "F.Cu")
		(net "SAS_EXP2CONN_RX_P_20")
	)
	(segment
		(start 38.70325 -80.101186)
		(end 39.236904 -80.101186)
		(width 0.1016)
		(layer "F.Cu")
		(net "SAS_EXP2CONN_RX_P_20")
	)
	(segment
		(start 35.920426 -81.979516)
		(end 37.159438 -80.74025)
		(width 0.1016)
		(layer "F.Cu")
		(net "SAS_EXP2CONN_RX_P_20")
	)
	(segment
		(start 32.733996 -89.588086)
		(end 32.733996 -88.445086)
		(width 0.1016)
		(layer "F.Cu")
		(net "SAS_EXP2CONN_RX_P_20")
	)
	(segment
		(start 123.35002 -86.34984)
		(end 123.850146 -85.849714)
		(width 0.1016)
		(layer "F.Cu")
		(net "SAS_EXP2CONN_RX_P_20")
	)
	(segment
		(start 35.052508 -82.847434)
		(end 35.920426 -81.979516)
		(width 0.1016)
		(layer "F.Cu")
		(net "SAS_EXP2CONN_RX_P_20")
	)
	(via
		(at 32.334454 -90.096086)
		(size 0.5588)
		(drill 0.3048)
		(layers "F.Cu" "B.Cu")
		(net "SAS_EXP2CONN_RX_P_20")
	)
	(via
		(at 39.591996 -79.746094)
		(size 0.5588)
		(drill 0.3048)
		(layers "F.Cu" "B.Cu")
		(net "SAS_EXP2CONN_RX_P_20")
	)
	(via
		(at 123.850146 -85.849714)
		(size 0.508)
		(drill 0.254)
		(layers "F.Cu" "B.Cu")
		(net "SAS_EXP2CONN_RX_P_20")
	)
	(arc
		(start 37.159438 -80.74025)
		(mid 37.867761 -80.267087)
		(end 38.70325 -80.101186)
		(width 0.1016)
		(layer "F.Cu")
		(net "SAS_EXP2CONN_RX_P_20")
	)
	(arc
		(start 32.657288 -89.773252)
		(mid 32.714053 -89.688297)
		(end 32.733996 -89.588086)
		(width 0.1016)
		(layer "F.Cu")
		(net "SAS_EXP2CONN_RX_P_20")
	)
	(arc
		(start 32.733996 -88.445086)
		(mid 33.336495 -85.415647)
		(end 35.052508 -82.847434)
		(width 0.1016)
		(layer "F.Cu")
		(net "SAS_EXP2CONN_RX_P_20")
	)
	(segment
		(start 42.34688 -78.640686)
		(end 42.21353 -78.640686)
		(width 0.1016)
		(layer "B.Cu")
		(net "SAS_EXP2CONN_RX_P_20")
	)
	(segment
		(start 39.908988 -80.063086)
		(end 41.496996 -80.063086)
		(width 0.1016)
		(layer "B.Cu")
		(net "SAS_EXP2CONN_RX_P_20")
	)
	(segment
		(start 42.11193 -78.539086)
		(end 42.11193 -78.094586)
		(width 0.1016)
		(layer "B.Cu")
		(net "SAS_EXP2CONN_RX_P_20")
	)
	(segment
		(start 39.591996 -79.746094)
		(end 39.908988 -80.063086)
		(width 0.1016)
		(layer "B.Cu")
		(net "SAS_EXP2CONN_RX_P_20")
	)
	(segment
		(start 42.44848 -79.111602)
		(end 42.44848 -78.742286)
		(width 0.1016)
		(layer "B.Cu")
		(net "SAS_EXP2CONN_RX_P_20")
	)
	(arc
		(start 41.496996 -80.063086)
		(mid 42.169797 -79.784403)
		(end 42.44848 -79.111602)
		(width 0.1016)
		(layer "B.Cu")
		(net "SAS_EXP2CONN_RX_P_20")
	)
	(arc
		(start 42.21353 -78.640686)
		(mid 42.141688 -78.610928)
		(end 42.11193 -78.539086)
		(width 0.1016)
		(layer "B.Cu")
		(net "SAS_EXP2CONN_RX_P_20")
	)
	(arc
		(start 42.44848 -78.742286)
		(mid 42.418722 -78.670444)
		(end 42.34688 -78.640686)
		(width 0.1016)
		(layer "B.Cu")
		(net "SAS_EXP2CONN_RX_P_20")
	)
	(segment
		(start 140.475208 -85.965792)
		(end 140.658088 -86.148672)
		(width 0.1016)
		(layer "In5.Cu")
		(net "SAS_EXP2CONN_RX_P_20")
	)
	(segment
		(start 12.08532 -121.81332)
		(end 29.281374 -104.61752)
		(width 0.1016)
		(layer "In5.Cu")
		(net "SAS_EXP2CONN_RX_P_20")
	)
	(segment
		(start 126.44882 -85.174074)
		(end 127.983742 -83.639152)
		(width 0.1016)
		(layer "In5.Cu")
		(net "SAS_EXP2CONN_RX_P_20")
	)
	(segment
		(start 21.895054 -165.7604)
		(end 21.8948 -165.7604)
		(width 0.1016)
		(layer "In5.Cu")
		(net "SAS_EXP2CONN_RX_P_20")
	)
	(segment
		(start 47.305976 -169.556176)
		(end 44.458128 -166.708328)
		(width 0.1016)
		(layer "In5.Cu")
		(net "SAS_EXP2CONN_RX_P_20")
	)
	(segment
		(start 30.6578 -101.294438)
		(end 30.6578 -97.628456)
		(width 0.1016)
		(layer "In5.Cu")
		(net "SAS_EXP2CONN_RX_P_20")
	)
	(segment
		(start 128.773682 -83.312)
		(end 137.018776 -83.312)
		(width 0.1016)
		(layer "In5.Cu")
		(net "SAS_EXP2CONN_RX_P_20")
	)
	(segment
		(start 140.474954 -85.965792)
		(end 140.475208 -85.965792)
		(width 0.1016)
		(layer "In5.Cu")
		(net "SAS_EXP2CONN_RX_P_20")
	)
	(segment
		(start 44.009056 -166.5224)
		(end 23.734776 -166.5224)
		(width 0.1016)
		(layer "In5.Cu")
		(net "SAS_EXP2CONN_RX_P_20")
	)
	(segment
		(start 142.113 -89.662254)
		(end 142.113 -119.888)
		(width 0.1016)
		(layer "In5.Cu")
		(net "SAS_EXP2CONN_RX_P_20")
	)
	(segment
		(start 32.349948 -90.11158)
		(end 32.334454 -90.096086)
		(width 0.1016)
		(layer "In5.Cu")
		(net "SAS_EXP2CONN_RX_P_20")
	)
	(segment
		(start 21.8948 -165.7604)
		(end 18.20164 -162.06724)
		(width 0.1016)
		(layer "In5.Cu")
		(net "SAS_EXP2CONN_RX_P_20")
	)
	(segment
		(start 148.209 -127.4953)
		(end 148.209 -145.669)
		(width 0.1016)
		(layer "In5.Cu")
		(net "SAS_EXP2CONN_RX_P_20")
	)
	(segment
		(start 9.7028 -152.076658)
		(end 9.7028 -125.984254)
		(width 0.1016)
		(layer "In5.Cu")
		(net "SAS_EXP2CONN_RX_P_20")
	)
	(segment
		(start 142.292578 -120.321578)
		(end 147.32 -125.349)
		(width 0.1016)
		(layer "In5.Cu")
		(net "SAS_EXP2CONN_RX_P_20")
	)
	(segment
		(start 18.20164 -162.06724)
		(end 18.20164 -162.066986)
		(width 0.1016)
		(layer "In5.Cu")
		(net "SAS_EXP2CONN_RX_P_20")
	)
	(segment
		(start 123.340876 -170.3832)
		(end 49.30267 -170.3832)
		(width 0.1016)
		(layer "In5.Cu")
		(net "SAS_EXP2CONN_RX_P_20")
	)
	(segment
		(start 123.850146 -85.849714)
		(end 124.817632 -85.849714)
		(width 0.1016)
		(layer "In5.Cu")
		(net "SAS_EXP2CONN_RX_P_20")
	)
	(segment
		(start 32.689546 -92.7227)
		(end 32.6898 -90.932)
		(width 0.1016)
		(layer "In5.Cu")
		(net "SAS_EXP2CONN_RX_P_20")
	)
	(segment
		(start 18.20164 -162.066986)
		(end 10.7569 -154.622246)
		(width 0.1016)
		(layer "In5.Cu")
		(net "SAS_EXP2CONN_RX_P_20")
	)
	(segment
		(start 138.388598 -83.879436)
		(end 140.474954 -85.965792)
		(width 0.1016)
		(layer "In5.Cu")
		(net "SAS_EXP2CONN_RX_P_20")
	)
	(segment
		(start 147.670266 -146.969734)
		(end 124.9045 -169.7355)
		(width 0.1016)
		(layer "In5.Cu")
		(net "SAS_EXP2CONN_RX_P_20")
	)
	(segment
		(start 10.966704 -122.931936)
		(end 12.08532 -121.81332)
		(width 0.1016)
		(layer "In5.Cu")
		(net "SAS_EXP2CONN_RX_P_20")
	)
	(arc
		(start 137.018776 -83.312)
		(mid 137.760133 -83.459465)
		(end 138.388598 -83.879436)
		(width 0.1016)
		(layer "In5.Cu")
		(net "SAS_EXP2CONN_RX_P_20")
	)
	(arc
		(start 127.983742 -83.639152)
		(mid 128.346183 -83.39701)
		(end 128.773682 -83.312)
		(width 0.1016)
		(layer "In5.Cu")
		(net "SAS_EXP2CONN_RX_P_20")
	)
	(arc
		(start 148.209 -145.669)
		(mid 148.068994 -146.372948)
		(end 147.670266 -146.969734)
		(width 0.1016)
		(layer "In5.Cu")
		(net "SAS_EXP2CONN_RX_P_20")
	)
	(arc
		(start 9.7028 -125.984254)
		(mid 10.031187 -124.3324)
		(end 10.966704 -122.931936)
		(width 0.1016)
		(layer "In5.Cu")
		(net "SAS_EXP2CONN_RX_P_20")
	)
	(arc
		(start 147.32 -125.349)
		(mid 147.977952 -126.333744)
		(end 148.209 -127.4953)
		(width 0.1016)
		(layer "In5.Cu")
		(net "SAS_EXP2CONN_RX_P_20")
	)
	(arc
		(start 31.89732 -94.63532)
		(mid 32.483658 -93.757802)
		(end 32.689546 -92.7227)
		(width 0.1016)
		(layer "In5.Cu")
		(net "SAS_EXP2CONN_RX_P_20")
	)
	(arc
		(start 32.6898 -90.932)
		(mid 32.60148 -90.487983)
		(end 32.349948 -90.11158)
		(width 0.1016)
		(layer "In5.Cu")
		(net "SAS_EXP2CONN_RX_P_20")
	)
	(arc
		(start 23.734776 -166.5224)
		(mid 22.739165 -166.324303)
		(end 21.895054 -165.7604)
		(width 0.1016)
		(layer "In5.Cu")
		(net "SAS_EXP2CONN_RX_P_20")
	)
	(arc
		(start 142.113 -119.888)
		(mid 142.159674 -120.122645)
		(end 142.292578 -120.321578)
		(width 0.1016)
		(layer "In5.Cu")
		(net "SAS_EXP2CONN_RX_P_20")
	)
	(arc
		(start 30.6578 -97.628456)
		(mid 30.979894 -96.008621)
		(end 31.89732 -94.63532)
		(width 0.1016)
		(layer "In5.Cu")
		(net "SAS_EXP2CONN_RX_P_20")
	)
	(arc
		(start 10.7569 -154.622246)
		(mid 9.976683 -153.45429)
		(end 9.7028 -152.076658)
		(width 0.1016)
		(layer "In5.Cu")
		(net "SAS_EXP2CONN_RX_P_20")
	)
	(arc
		(start 29.281374 -104.61752)
		(mid 30.300108 -103.092877)
		(end 30.6578 -101.294438)
		(width 0.1016)
		(layer "In5.Cu")
		(net "SAS_EXP2CONN_RX_P_20")
	)
	(arc
		(start 44.458128 -166.708328)
		(mid 44.252092 -166.570659)
		(end 44.009056 -166.5224)
		(width 0.1016)
		(layer "In5.Cu")
		(net "SAS_EXP2CONN_RX_P_20")
	)
	(arc
		(start 49.30267 -170.3832)
		(mid 48.222105 -170.168204)
		(end 47.305976 -169.556176)
		(width 0.1016)
		(layer "In5.Cu")
		(net "SAS_EXP2CONN_RX_P_20")
	)
	(arc
		(start 124.9045 -169.7355)
		(mid 124.187103 -170.214849)
		(end 123.340876 -170.3832)
		(width 0.1016)
		(layer "In5.Cu")
		(net "SAS_EXP2CONN_RX_P_20")
	)
	(arc
		(start 124.817632 -85.849714)
		(mid 125.700417 -85.674117)
		(end 126.44882 -85.174074)
		(width 0.1016)
		(layer "In5.Cu")
		(net "SAS_EXP2CONN_RX_P_20")
	)
	(arc
		(start 140.658088 -86.148672)
		(mid 141.735002 -87.760761)
		(end 142.113 -89.662254)
		(width 0.1016)
		(layer "In5.Cu")
		(net "SAS_EXP2CONN_RX_P_20")
	)
	(segment
		(start 301.532544 -167.8305)
		(end 301.244 -168.119044)
		(width 0.1143)
		(layer "F.Cu")
		(net "PU_BMC0_SDA12")
	)
	(segment
		(start 300.224952 -169.040048)
		(end 300.03496 -169.040048)
		(width 0.1143)
		(layer "F.Cu")
		(net "PU_BMC0_SDA12")
	)
	(segment
		(start 312.293 -167.005)
		(end 305.562 -167.005)
		(width 0.1143)
		(layer "F.Cu")
		(net "PU_BMC0_SDA12")
	)
	(segment
		(start 305.09845 -167.46855)
		(end 302.17745 -167.46855)
		(width 0.1143)
		(layer "F.Cu")
		(net "PU_BMC0_SDA12")
	)
	(segment
		(start 301.8155 -167.8305)
		(end 301.532544 -167.8305)
		(width 0.1143)
		(layer "F.Cu")
		(net "PU_BMC0_SDA12")
	)
	(segment
		(start 300.931072 -168.656)
		(end 300.609 -168.656)
		(width 0.1143)
		(layer "F.Cu")
		(net "PU_BMC0_SDA12")
	)
	(segment
		(start 315.6966 -164.338)
		(end 314.96 -164.338)
		(width 0.1143)
		(layer "F.Cu")
		(net "PU_BMC0_SDA12")
	)
	(segment
		(start 301.244 -168.119044)
		(end 301.244 -168.343072)
		(width 0.1143)
		(layer "F.Cu")
		(net "PU_BMC0_SDA12")
	)
	(segment
		(start 301.244 -168.343072)
		(end 300.931072 -168.656)
		(width 0.1143)
		(layer "F.Cu")
		(net "PU_BMC0_SDA12")
	)
	(segment
		(start 314.96 -164.338)
		(end 312.293 -167.005)
		(width 0.1143)
		(layer "F.Cu")
		(net "PU_BMC0_SDA12")
	)
	(segment
		(start 300.609 -168.656)
		(end 300.224952 -169.040048)
		(width 0.1143)
		(layer "F.Cu")
		(net "PU_BMC0_SDA12")
	)
	(segment
		(start 317.5635 -164.338)
		(end 315.6966 -164.338)
		(width 0.1143)
		(layer "F.Cu")
		(net "PU_BMC0_SDA12")
	)
	(segment
		(start 305.562 -167.005)
		(end 305.09845 -167.46855)
		(width 0.1143)
		(layer "F.Cu")
		(net "PU_BMC0_SDA12")
	)
	(segment
		(start 302.17745 -167.46855)
		(end 301.8155 -167.8305)
		(width 0.1143)
		(layer "F.Cu")
		(net "PU_BMC0_SDA12")
	)
	(via
		(at 315.6966 -164.338)
		(size 0.7112)
		(drill 0.3556)
		(layers "F.Cu" "B.Cu")
		(net "PU_BMC0_SDA12")
	)
	(segment
		(start 299.23486 -169.840148)
		(end 298.837604 -169.442892)
		(width 0.1143)
		(layer "F.Cu")
		(net "PU_BMC0_SCL12")
	)
	(segment
		(start 314.8965 -163.322)
		(end 317.5635 -163.322)
		(width 0.1143)
		(layer "F.Cu")
		(net "PU_BMC0_SCL12")
	)
	(segment
		(start 298.837604 -169.442892)
		(end 298.837604 -169.441368)
		(width 0.1143)
		(layer "F.Cu")
		(net "PU_BMC0_SCL12")
	)
	(segment
		(start 311.7215 -166.497)
		(end 314.8965 -163.322)
		(width 0.1143)
		(layer "F.Cu")
		(net "PU_BMC0_SCL12")
	)
	(segment
		(start 305.3588 -166.497)
		(end 311.7215 -166.497)
		(width 0.1143)
		(layer "F.Cu")
		(net "PU_BMC0_SCL12")
	)
	(segment
		(start 303.226216 -166.92245)
		(end 304.93335 -166.92245)
		(width 0.1143)
		(layer "F.Cu")
		(net "PU_BMC0_SCL12")
	)
	(segment
		(start 304.93335 -166.92245)
		(end 305.3588 -166.497)
		(width 0.1143)
		(layer "F.Cu")
		(net "PU_BMC0_SCL12")
	)
	(via
		(at 303.226216 -166.92245)
		(size 0.5588)
		(drill 0.3048)
		(layers "F.Cu" "B.Cu")
		(net "PU_BMC0_SCL12")
	)
	(via
		(at 300.355 -168.783)
		(size 0.7112)
		(drill 0.3556)
		(layers "F.Cu" "B.Cu")
		(net "PU_BMC0_SCL12")
	)
	(via
		(at 298.837604 -169.441368)
		(size 0.508)
		(drill 0.254)
		(layers "F.Cu" "B.Cu")
		(net "PU_BMC0_SCL12")
	)
	(segment
		(start 300.355 -168.783)
		(end 299.696632 -169.441368)
		(width 0.1143)
		(layer "B.Cu")
		(net "PU_BMC0_SCL12")
	)
	(segment
		(start 299.696632 -169.441368)
		(end 298.837604 -169.441368)
		(width 0.1143)
		(layer "B.Cu")
		(net "PU_BMC0_SCL12")
	)
	(segment
		(start 302.20158 -166.93642)
		(end 300.355 -168.783)
		(width 0.1143)
		(layer "B.Cu")
		(net "PU_BMC0_SCL12")
	)
	(segment
		(start 303.212246 -166.93642)
		(end 302.20158 -166.93642)
		(width 0.1143)
		(layer "B.Cu")
		(net "PU_BMC0_SCL12")
	)
	(segment
		(start 303.226216 -166.92245)
		(end 303.212246 -166.93642)
		(width 0.1143)
		(layer "B.Cu")
		(net "PU_BMC0_SCL12")
	)
	(segment
		(start 44.19981 -79.590138)
		(end 44.19981 -80.618838)
		(width 0.1016)
		(layer "F.Cu")
		(net "SAS_EXP2CONN_TX_P_21")
	)
	(segment
		(start 131.5974 -88.519)
		(end 131.861814 -88.519)
		(width 0.1016)
		(layer "F.Cu")
		(net "SAS_EXP2CONN_TX_P_21")
	)
	(segment
		(start 44.30141 -80.720438)
		(end 44.32681 -80.720438)
		(width 0.1016)
		(layer "F.Cu")
		(net "SAS_EXP2CONN_TX_P_21")
	)
	(segment
		(start 44.964096 -82.625692)
		(end 44.964096 -82.984086)
		(width 0.1016)
		(layer "F.Cu")
		(net "SAS_EXP2CONN_TX_P_21")
	)
	(segment
		(start 44.821856 -83.327494)
		(end 44.647104 -83.502246)
		(width 0.1016)
		(layer "F.Cu")
		(net "SAS_EXP2CONN_TX_P_21")
	)
	(segment
		(start 44.42841 -80.822038)
		(end 44.42841 -81.33334)
		(width 0.1016)
		(layer "F.Cu")
		(net "SAS_EXP2CONN_TX_P_21")
	)
	(via
		(at 44.647104 -83.502246)
		(size 0.5588)
		(drill 0.3048)
		(layers "F.Cu" "B.Cu")
		(net "SAS_EXP2CONN_TX_P_21")
	)
	(via
		(at 132.207 -88.375998)
		(size 0.5588)
		(drill 0.3048)
		(layers "F.Cu" "B.Cu")
		(net "SAS_EXP2CONN_TX_P_21")
	)
	(arc
		(start 44.42841 -81.33334)
		(mid 44.519486 -81.790828)
		(end 44.778676 -82.178652)
		(width 0.1016)
		(layer "F.Cu")
		(net "SAS_EXP2CONN_TX_P_21")
	)
	(arc
		(start 44.778676 -82.178652)
		(mid 44.915834 -82.38374)
		(end 44.964096 -82.625692)
		(width 0.1016)
		(layer "F.Cu")
		(net "SAS_EXP2CONN_TX_P_21")
	)
	(arc
		(start 44.19981 -80.618838)
		(mid 44.229568 -80.69068)
		(end 44.30141 -80.720438)
		(width 0.1016)
		(layer "F.Cu")
		(net "SAS_EXP2CONN_TX_P_21")
	)
	(arc
		(start 44.32681 -80.720438)
		(mid 44.398652 -80.750196)
		(end 44.42841 -80.822038)
		(width 0.1016)
		(layer "F.Cu")
		(net "SAS_EXP2CONN_TX_P_21")
	)
	(arc
		(start 131.861814 -88.519)
		(mid 132.048635 -88.481839)
		(end 132.207 -88.375998)
		(width 0.1016)
		(layer "F.Cu")
		(net "SAS_EXP2CONN_TX_P_21")
	)
	(arc
		(start 44.964096 -82.984086)
		(mid 44.927128 -83.169935)
		(end 44.821856 -83.327494)
		(width 0.1016)
		(layer "F.Cu")
		(net "SAS_EXP2CONN_TX_P_21")
	)
	(segment
		(start 46.4058 -92.6592)
		(end 46.405546 -93.292422)
		(width 0.1016)
		(layer "In5.Cu")
		(net "SAS_EXP2CONN_TX_P_21")
	)
	(segment
		(start 29.21 -157.28569)
		(end 29.21 -157.285436)
		(width 0.1016)
		(layer "In5.Cu")
		(net "SAS_EXP2CONN_TX_P_21")
	)
	(segment
		(start 24.963374 -153.82748)
		(end 24.96312 -153.82748)
		(width 0.1016)
		(layer "In5.Cu")
		(net "SAS_EXP2CONN_TX_P_21")
	)
	(segment
		(start 139.192 -142.156434)
		(end 139.192 -130.692144)
		(width 0.1016)
		(layer "In5.Cu")
		(net "SAS_EXP2CONN_TX_P_21")
	)
	(segment
		(start 135.509 -93.494606)
		(end 135.509 -89.840816)
		(width 0.1016)
		(layer "In5.Cu")
		(net "SAS_EXP2CONN_TX_P_21")
	)
	(segment
		(start 134.304024 -88.6714)
		(end 132.6896 -88.6714)
		(width 0.1016)
		(layer "In5.Cu")
		(net "SAS_EXP2CONN_TX_P_21")
	)
	(segment
		(start 43.321478 -106.324908)
		(end 24.992584 -124.654056)
		(width 0.1016)
		(layer "In5.Cu")
		(net "SAS_EXP2CONN_TX_P_21")
	)
	(segment
		(start 135.292846 -89.318846)
		(end 134.8867 -88.9127)
		(width 0.1016)
		(layer "In5.Cu")
		(net "SAS_EXP2CONN_TX_P_21")
	)
	(segment
		(start 44.958 -83.981798)
		(end 44.958 -84.826856)
		(width 0.1016)
		(layer "In5.Cu")
		(net "SAS_EXP2CONN_TX_P_21")
	)
	(segment
		(start 44.970446 -83.969352)
		(end 44.958 -83.981798)
		(width 0.1016)
		(layer "In5.Cu")
		(net "SAS_EXP2CONN_TX_P_21")
	)
	(segment
		(start 29.21 -157.285436)
		(end 50.6222 -157.285436)
		(width 0.1016)
		(layer "In5.Cu")
		(net "SAS_EXP2CONN_TX_P_21")
	)
	(segment
		(start 121.031254 -161.036)
		(end 121.098056 -160.968944)
		(width 0.1016)
		(layer "In5.Cu")
		(net "SAS_EXP2CONN_TX_P_21")
	)
	(segment
		(start 44.069 -98.933)
		(end 44.069 -104.521)
		(width 0.1016)
		(layer "In5.Cu")
		(net "SAS_EXP2CONN_TX_P_21")
	)
	(segment
		(start 27.769566 -156.633672)
		(end 27.863546 -156.727906)
		(width 0.1016)
		(layer "In5.Cu")
		(net "SAS_EXP2CONN_TX_P_21")
	)
	(segment
		(start 24.2316 -126.491746)
		(end 24.2316 -152.060402)
		(width 0.1016)
		(layer "In5.Cu")
		(net "SAS_EXP2CONN_TX_P_21")
	)
	(segment
		(start 133.6421 -95.8469)
		(end 135.165846 -94.323154)
		(width 0.1016)
		(layer "In5.Cu")
		(net "SAS_EXP2CONN_TX_P_21")
	)
	(segment
		(start 133.282436 -123.429776)
		(end 133.282436 -96.6978)
		(width 0.1016)
		(layer "In5.Cu")
		(net "SAS_EXP2CONN_TX_P_21")
	)
	(segment
		(start 50.940462 -157.417262)
		(end 54.843934 -161.320734)
		(width 0.1016)
		(layer "In5.Cu")
		(net "SAS_EXP2CONN_TX_P_21")
	)
	(segment
		(start 132.370068 -88.539066)
		(end 132.207 -88.375998)
		(width 0.1016)
		(layer "In5.Cu")
		(net "SAS_EXP2CONN_TX_P_21")
	)
	(segment
		(start 138.557 -129.159)
		(end 133.604 -124.206)
		(width 0.1016)
		(layer "In5.Cu")
		(net "SAS_EXP2CONN_TX_P_21")
	)
	(segment
		(start 121.098056 -160.968944)
		(end 138.684 -143.383)
		(width 0.1016)
		(layer "In5.Cu")
		(net "SAS_EXP2CONN_TX_P_21")
	)
	(segment
		(start 27.769312 -156.633672)
		(end 27.769566 -156.633672)
		(width 0.1016)
		(layer "In5.Cu")
		(net "SAS_EXP2CONN_TX_P_21")
	)
	(segment
		(start 44.647104 -83.502246)
		(end 44.940728 -83.79587)
		(width 0.1016)
		(layer "In5.Cu")
		(net "SAS_EXP2CONN_TX_P_21")
	)
	(segment
		(start 44.970446 -83.867752)
		(end 44.970446 -83.969352)
		(width 0.1016)
		(layer "In5.Cu")
		(net "SAS_EXP2CONN_TX_P_21")
	)
	(segment
		(start 24.96312 -153.82748)
		(end 27.769312 -156.633672)
		(width 0.1016)
		(layer "In5.Cu")
		(net "SAS_EXP2CONN_TX_P_21")
	)
	(segment
		(start 133.629908 -95.859346)
		(end 133.6421 -95.8469)
		(width 0.1016)
		(layer "In5.Cu")
		(net "SAS_EXP2CONN_TX_P_21")
	)
	(segment
		(start 55.526432 -161.603436)
		(end 119.660924 -161.603436)
		(width 0.1016)
		(layer "In5.Cu")
		(net "SAS_EXP2CONN_TX_P_21")
	)
	(segment
		(start 46.4058 -88.32215)
		(end 46.4058 -92.6592)
		(width 0.1016)
		(layer "In5.Cu")
		(net "SAS_EXP2CONN_TX_P_21")
	)
	(arc
		(start 45.593 -86.36)
		(mid 46.194523 -87.260242)
		(end 46.4058 -88.32215)
		(width 0.1016)
		(layer "In5.Cu")
		(net "SAS_EXP2CONN_TX_P_21")
	)
	(arc
		(start 44.069 -104.521)
		(mid 43.874671 -105.497308)
		(end 43.321478 -106.324908)
		(width 0.1016)
		(layer "In5.Cu")
		(net "SAS_EXP2CONN_TX_P_21")
	)
	(arc
		(start 24.992584 -124.654056)
		(mid 24.429324 -125.497224)
		(end 24.2316 -126.491746)
		(width 0.1016)
		(layer "In5.Cu")
		(net "SAS_EXP2CONN_TX_P_21")
	)
	(arc
		(start 45.3263 -95.897954)
		(mid 44.395784 -97.29043)
		(end 44.069 -98.933)
		(width 0.1016)
		(layer "In5.Cu")
		(net "SAS_EXP2CONN_TX_P_21")
	)
	(arc
		(start 27.863546 -156.727906)
		(mid 28.48129 -157.140733)
		(end 29.21 -157.28569)
		(width 0.1016)
		(layer "In5.Cu")
		(net "SAS_EXP2CONN_TX_P_21")
	)
	(arc
		(start 135.509 -89.840816)
		(mid 135.452882 -89.558309)
		(end 135.292846 -89.318846)
		(width 0.1016)
		(layer "In5.Cu")
		(net "SAS_EXP2CONN_TX_P_21")
	)
	(arc
		(start 138.684 -143.383)
		(mid 139.059995 -142.820233)
		(end 139.192 -142.156434)
		(width 0.1016)
		(layer "In5.Cu")
		(net "SAS_EXP2CONN_TX_P_21")
	)
	(arc
		(start 135.165846 -94.323154)
		(mid 135.419819 -93.943012)
		(end 135.509 -93.494606)
		(width 0.1016)
		(layer "In5.Cu")
		(net "SAS_EXP2CONN_TX_P_21")
	)
	(arc
		(start 119.660924 -161.603436)
		(mid 120.402554 -161.456068)
		(end 121.031254 -161.036)
		(width 0.1016)
		(layer "In5.Cu")
		(net "SAS_EXP2CONN_TX_P_21")
	)
	(arc
		(start 132.6896 -88.6714)
		(mid 132.516678 -88.637004)
		(end 132.370068 -88.539066)
		(width 0.1016)
		(layer "In5.Cu")
		(net "SAS_EXP2CONN_TX_P_21")
	)
	(arc
		(start 46.405546 -93.292422)
		(mid 46.125059 -94.702525)
		(end 45.3263 -95.897954)
		(width 0.1016)
		(layer "In5.Cu")
		(net "SAS_EXP2CONN_TX_P_21")
	)
	(arc
		(start 133.604 -124.206)
		(mid 133.366038 -123.849865)
		(end 133.282436 -123.429776)
		(width 0.1016)
		(layer "In5.Cu")
		(net "SAS_EXP2CONN_TX_P_21")
	)
	(arc
		(start 134.8867 -88.9127)
		(mid 134.619365 -88.734102)
		(end 134.304024 -88.6714)
		(width 0.1016)
		(layer "In5.Cu")
		(net "SAS_EXP2CONN_TX_P_21")
	)
	(arc
		(start 44.940728 -83.79587)
		(mid 44.962711 -83.828864)
		(end 44.970446 -83.867752)
		(width 0.1016)
		(layer "In5.Cu")
		(net "SAS_EXP2CONN_TX_P_21")
	)
	(arc
		(start 24.2316 -152.060402)
		(mid 24.421678 -153.01675)
		(end 24.963374 -153.82748)
		(width 0.1016)
		(layer "In5.Cu")
		(net "SAS_EXP2CONN_TX_P_21")
	)
	(arc
		(start 133.282436 -96.6978)
		(mid 133.372792 -96.244019)
		(end 133.629908 -95.859346)
		(width 0.1016)
		(layer "In5.Cu")
		(net "SAS_EXP2CONN_TX_P_21")
	)
	(arc
		(start 44.958 -84.826856)
		(mid 45.12304 -85.656569)
		(end 45.593 -86.36)
		(width 0.1016)
		(layer "In5.Cu")
		(net "SAS_EXP2CONN_TX_P_21")
	)
	(arc
		(start 139.192 -130.692144)
		(mid 139.026907 -129.862456)
		(end 138.557 -129.159)
		(width 0.1016)
		(layer "In5.Cu")
		(net "SAS_EXP2CONN_TX_P_21")
	)
	(arc
		(start 50.6222 -157.285436)
		(mid 50.794441 -157.319697)
		(end 50.940462 -157.417262)
		(width 0.1016)
		(layer "In5.Cu")
		(net "SAS_EXP2CONN_TX_P_21")
	)
	(arc
		(start 54.843934 -161.320734)
		(mid 55.157067 -161.529963)
		(end 55.526432 -161.603436)
		(width 0.1016)
		(layer "In5.Cu")
		(net "SAS_EXP2CONN_TX_P_21")
	)
	(segment
		(start 45.449236 -83.327494)
		(end 45.623988 -83.502246)
		(width 0.1016)
		(layer "F.Cu")
		(net "SAS_EXP2CONN_TX_N_21")
	)
	(segment
		(start 44.77131 -80.822038)
		(end 44.77131 -81.333086)
		(width 0.1016)
		(layer "F.Cu")
		(net "SAS_EXP2CONN_TX_N_21")
	)
	(segment
		(start 44.99991 -79.590138)
		(end 44.99991 -80.618838)
		(width 0.1016)
		(layer "F.Cu")
		(net "SAS_EXP2CONN_TX_N_21")
	)
	(segment
		(start 45.306996 -82.625946)
		(end 45.306996 -82.984086)
		(width 0.1016)
		(layer "F.Cu")
		(net "SAS_EXP2CONN_TX_N_21")
	)
	(segment
		(start 44.89831 -80.720438)
		(end 44.87291 -80.720438)
		(width 0.1016)
		(layer "F.Cu")
		(net "SAS_EXP2CONN_TX_N_21")
	)
	(segment
		(start 131.5974 -89.154)
		(end 131.900422 -89.154)
		(width 0.1016)
		(layer "F.Cu")
		(net "SAS_EXP2CONN_TX_N_21")
	)
	(via
		(at 45.623988 -83.502246)
		(size 0.5588)
		(drill 0.3048)
		(layers "F.Cu" "B.Cu")
		(net "SAS_EXP2CONN_TX_N_21")
	)
	(via
		(at 132.207 -89.281)
		(size 0.5588)
		(drill 0.3048)
		(layers "F.Cu" "B.Cu")
		(net "SAS_EXP2CONN_TX_N_21")
	)
	(arc
		(start 45.021246 -81.936082)
		(mid 45.232733 -82.252594)
		(end 45.306996 -82.625946)
		(width 0.1016)
		(layer "F.Cu")
		(net "SAS_EXP2CONN_TX_N_21")
	)
	(arc
		(start 44.87291 -80.720438)
		(mid 44.801068 -80.750196)
		(end 44.77131 -80.822038)
		(width 0.1016)
		(layer "F.Cu")
		(net "SAS_EXP2CONN_TX_N_21")
	)
	(arc
		(start 44.99991 -80.618838)
		(mid 44.970152 -80.69068)
		(end 44.89831 -80.720438)
		(width 0.1016)
		(layer "F.Cu")
		(net "SAS_EXP2CONN_TX_N_21")
	)
	(arc
		(start 44.77131 -81.333086)
		(mid 44.836319 -81.659435)
		(end 45.021246 -81.936082)
		(width 0.1016)
		(layer "F.Cu")
		(net "SAS_EXP2CONN_TX_N_21")
	)
	(arc
		(start 45.306996 -82.984086)
		(mid 45.343964 -83.169935)
		(end 45.449236 -83.327494)
		(width 0.1016)
		(layer "F.Cu")
		(net "SAS_EXP2CONN_TX_N_21")
	)
	(arc
		(start 131.900422 -89.154)
		(mid 132.066345 -89.187004)
		(end 132.207 -89.281)
		(width 0.1016)
		(layer "F.Cu")
		(net "SAS_EXP2CONN_TX_N_21")
	)
	(segment
		(start 24.5618 -139.422886)
		(end 24.5618 -139.727686)
		(width 0.1016)
		(layer "In5.Cu")
		(net "SAS_EXP2CONN_TX_N_21")
	)
	(segment
		(start 55.52694 -161.273236)
		(end 119.660924 -161.273236)
		(width 0.1016)
		(layer "In5.Cu")
		(net "SAS_EXP2CONN_TX_N_21")
	)
	(segment
		(start 138.32332 -129.392426)
		(end 135.84682 -126.91618)
		(width 0.1016)
		(layer "In5.Cu")
		(net "SAS_EXP2CONN_TX_N_21")
	)
	(segment
		(start 24.78786 -140.179806)
		(end 24.78786 -140.484606)
		(width 0.1016)
		(layer "In5.Cu")
		(net "SAS_EXP2CONN_TX_N_21")
	)
	(segment
		(start 51.174142 -157.183582)
		(end 55.077868 -161.087308)
		(width 0.1016)
		(layer "In5.Cu")
		(net "SAS_EXP2CONN_TX_N_21")
	)
	(segment
		(start 135.84682 -126.91618)
		(end 133.37032 -124.43968)
		(width 0.1016)
		(layer "In5.Cu")
		(net "SAS_EXP2CONN_TX_N_21")
	)
	(segment
		(start 135.1788 -93.494606)
		(end 135.1788 -89.840816)
		(width 0.1016)
		(layer "In5.Cu")
		(net "SAS_EXP2CONN_TX_N_21")
	)
	(segment
		(start 132.34289 -89.145364)
		(end 132.207 -89.281)
		(width 0.1016)
		(layer "In5.Cu")
		(net "SAS_EXP2CONN_TX_N_21")
	)
	(segment
		(start 24.5618 -126.492)
		(end 24.5618 -136.700006)
		(width 0.1016)
		(layer "In5.Cu")
		(net "SAS_EXP2CONN_TX_N_21")
	)
	(segment
		(start 120.797574 -160.80232)
		(end 120.79732 -160.80232)
		(width 0.1016)
		(layer "In5.Cu")
		(net "SAS_EXP2CONN_TX_N_21")
	)
	(segment
		(start 45.2882 -84.82711)
		(end 45.288454 -84.826856)
		(width 0.1016)
		(layer "In5.Cu")
		(net "SAS_EXP2CONN_TX_N_21")
	)
	(segment
		(start 29.21 -156.955236)
		(end 50.621946 -156.955236)
		(width 0.1016)
		(layer "In5.Cu")
		(net "SAS_EXP2CONN_TX_N_21")
	)
	(segment
		(start 138.8618 -142.15618)
		(end 138.8618 -130.692398)
		(width 0.1016)
		(layer "In5.Cu")
		(net "SAS_EXP2CONN_TX_N_21")
	)
	(segment
		(start 45.300646 -84.106258)
		(end 45.2882 -84.118704)
		(width 0.1016)
		(layer "In5.Cu")
		(net "SAS_EXP2CONN_TX_N_21")
	)
	(segment
		(start 120.79732 -160.80232)
		(end 127.65532 -153.94432)
		(width 0.1016)
		(layer "In5.Cu")
		(net "SAS_EXP2CONN_TX_N_21")
	)
	(segment
		(start 44.3992 -98.933254)
		(end 44.3992 -104.521254)
		(width 0.1016)
		(layer "In5.Cu")
		(net "SAS_EXP2CONN_TX_N_21")
	)
	(segment
		(start 128.4732 -153.126694)
		(end 138.45032 -143.149574)
		(width 0.1016)
		(layer "In5.Cu")
		(net "SAS_EXP2CONN_TX_N_21")
	)
	(segment
		(start 46.736 -88.321896)
		(end 46.736 -93.292422)
		(width 0.1016)
		(layer "In5.Cu")
		(net "SAS_EXP2CONN_TX_N_21")
	)
	(segment
		(start 134.304024 -89.0016)
		(end 132.6896 -89.0016)
		(width 0.1016)
		(layer "In5.Cu")
		(net "SAS_EXP2CONN_TX_N_21")
	)
	(segment
		(start 45.300646 -83.867752)
		(end 45.300646 -84.106258)
		(width 0.1016)
		(layer "In5.Cu")
		(net "SAS_EXP2CONN_TX_N_21")
	)
	(segment
		(start 43.555158 -106.558588)
		(end 25.226264 -124.887736)
		(width 0.1016)
		(layer "In5.Cu")
		(net "SAS_EXP2CONN_TX_N_21")
	)
	(segment
		(start 24.78786 -137.152126)
		(end 24.78786 -137.456926)
		(width 0.1016)
		(layer "In5.Cu")
		(net "SAS_EXP2CONN_TX_N_21")
	)
	(segment
		(start 127.65532 -153.94432)
		(end 128.4732 -153.126694)
		(width 0.1016)
		(layer "In5.Cu")
		(net "SAS_EXP2CONN_TX_N_21")
	)
	(segment
		(start 28.0035 -156.4005)
		(end 28.097226 -156.49448)
		(width 0.1016)
		(layer "In5.Cu")
		(net "SAS_EXP2CONN_TX_N_21")
	)
	(segment
		(start 25.1968 -153.5938)
		(end 28.0035 -156.4005)
		(width 0.1016)
		(layer "In5.Cu")
		(net "SAS_EXP2CONN_TX_N_21")
	)
	(segment
		(start 45.2882 -84.118704)
		(end 45.2882 -84.82711)
		(width 0.1016)
		(layer "In5.Cu")
		(net "SAS_EXP2CONN_TX_N_21")
	)
	(segment
		(start 132.952236 -123.43003)
		(end 132.952236 -96.697546)
		(width 0.1016)
		(layer "In5.Cu")
		(net "SAS_EXP2CONN_TX_N_21")
	)
	(segment
		(start 24.5618 -140.936726)
		(end 24.5618 -152.060656)
		(width 0.1016)
		(layer "In5.Cu")
		(net "SAS_EXP2CONN_TX_N_21")
	)
	(segment
		(start 133.394958 -95.626936)
		(end 134.93242 -94.089474)
		(width 0.1016)
		(layer "In5.Cu")
		(net "SAS_EXP2CONN_TX_N_21")
	)
	(segment
		(start 45.623988 -83.502246)
		(end 45.330364 -83.79587)
		(width 0.1016)
		(layer "In5.Cu")
		(net "SAS_EXP2CONN_TX_N_21")
	)
	(segment
		(start 135.05942 -89.552526)
		(end 134.65302 -89.146126)
		(width 0.1016)
		(layer "In5.Cu")
		(net "SAS_EXP2CONN_TX_N_21")
	)
	(segment
		(start 24.78786 -138.665966)
		(end 24.78786 -138.970766)
		(width 0.1016)
		(layer "In5.Cu")
		(net "SAS_EXP2CONN_TX_N_21")
	)
	(segment
		(start 24.5618 -137.909046)
		(end 24.5618 -138.213846)
		(width 0.1016)
		(layer "In5.Cu")
		(net "SAS_EXP2CONN_TX_N_21")
	)
	(arc
		(start 25.226264 -124.887736)
		(mid 24.73451 -125.623793)
		(end 24.5618 -126.492)
		(width 0.1016)
		(layer "In5.Cu")
		(net "SAS_EXP2CONN_TX_N_21")
	)
	(arc
		(start 55.077868 -161.087308)
		(mid 55.283904 -161.224977)
		(end 55.52694 -161.273236)
		(width 0.1016)
		(layer "In5.Cu")
		(net "SAS_EXP2CONN_TX_N_21")
	)
	(arc
		(start 24.5618 -152.060656)
		(mid 24.72684 -152.890369)
		(end 25.1968 -153.5938)
		(width 0.1016)
		(layer "In5.Cu")
		(net "SAS_EXP2CONN_TX_N_21")
	)
	(arc
		(start 24.67483 -139.953746)
		(mid 24.758667 -140.053122)
		(end 24.78786 -140.179806)
		(width 0.1016)
		(layer "In5.Cu")
		(net "SAS_EXP2CONN_TX_N_21")
	)
	(arc
		(start 24.67483 -139.196826)
		(mid 24.590993 -139.296202)
		(end 24.5618 -139.422886)
		(width 0.1016)
		(layer "In5.Cu")
		(net "SAS_EXP2CONN_TX_N_21")
	)
	(arc
		(start 24.5618 -138.213846)
		(mid 24.591039 -138.340507)
		(end 24.67483 -138.439906)
		(width 0.1016)
		(layer "In5.Cu")
		(net "SAS_EXP2CONN_TX_N_21")
	)
	(arc
		(start 24.78786 -140.484606)
		(mid 24.758621 -140.611267)
		(end 24.67483 -140.710666)
		(width 0.1016)
		(layer "In5.Cu")
		(net "SAS_EXP2CONN_TX_N_21")
	)
	(arc
		(start 24.5618 -139.727686)
		(mid 24.591039 -139.854347)
		(end 24.67483 -139.953746)
		(width 0.1016)
		(layer "In5.Cu")
		(net "SAS_EXP2CONN_TX_N_21")
	)
	(arc
		(start 132.6896 -89.0016)
		(mid 132.501957 -89.039018)
		(end 132.34289 -89.145364)
		(width 0.1016)
		(layer "In5.Cu")
		(net "SAS_EXP2CONN_TX_N_21")
	)
	(arc
		(start 132.952236 -96.697546)
		(mid 133.067349 -96.118316)
		(end 133.394958 -95.626936)
		(width 0.1016)
		(layer "In5.Cu")
		(net "SAS_EXP2CONN_TX_N_21")
	)
	(arc
		(start 133.37032 -124.43968)
		(mid 133.060906 -123.97642)
		(end 132.952236 -123.43003)
		(width 0.1016)
		(layer "In5.Cu")
		(net "SAS_EXP2CONN_TX_N_21")
	)
	(arc
		(start 44.3992 -104.521254)
		(mid 44.179785 -105.623855)
		(end 43.555158 -106.558588)
		(width 0.1016)
		(layer "In5.Cu")
		(net "SAS_EXP2CONN_TX_N_21")
	)
	(arc
		(start 45.55998 -96.131634)
		(mid 44.700917 -97.416985)
		(end 44.3992 -98.933254)
		(width 0.1016)
		(layer "In5.Cu")
		(net "SAS_EXP2CONN_TX_N_21")
	)
	(arc
		(start 134.65302 -89.146126)
		(mid 134.492899 -89.039137)
		(end 134.304024 -89.0016)
		(width 0.1016)
		(layer "In5.Cu")
		(net "SAS_EXP2CONN_TX_N_21")
	)
	(arc
		(start 45.82668 -86.12632)
		(mid 46.499655 -87.133687)
		(end 46.736 -88.321896)
		(width 0.1016)
		(layer "In5.Cu")
		(net "SAS_EXP2CONN_TX_N_21")
	)
	(arc
		(start 24.5618 -136.700006)
		(mid 24.591039 -136.826667)
		(end 24.67483 -136.926066)
		(width 0.1016)
		(layer "In5.Cu")
		(net "SAS_EXP2CONN_TX_N_21")
	)
	(arc
		(start 24.67483 -140.710666)
		(mid 24.590993 -140.810042)
		(end 24.5618 -140.936726)
		(width 0.1016)
		(layer "In5.Cu")
		(net "SAS_EXP2CONN_TX_N_21")
	)
	(arc
		(start 24.67483 -138.439906)
		(mid 24.758667 -138.539282)
		(end 24.78786 -138.665966)
		(width 0.1016)
		(layer "In5.Cu")
		(net "SAS_EXP2CONN_TX_N_21")
	)
	(arc
		(start 28.097226 -156.49448)
		(mid 28.607786 -156.835532)
		(end 29.21 -156.955236)
		(width 0.1016)
		(layer "In5.Cu")
		(net "SAS_EXP2CONN_TX_N_21")
	)
	(arc
		(start 24.78786 -137.456926)
		(mid 24.758621 -137.583587)
		(end 24.67483 -137.682986)
		(width 0.1016)
		(layer "In5.Cu")
		(net "SAS_EXP2CONN_TX_N_21")
	)
	(arc
		(start 138.8618 -130.692398)
		(mid 138.721856 -129.988853)
		(end 138.32332 -129.392426)
		(width 0.1016)
		(layer "In5.Cu")
		(net "SAS_EXP2CONN_TX_N_21")
	)
	(arc
		(start 119.660924 -161.273236)
		(mid 120.276084 -161.150837)
		(end 120.797574 -160.80232)
		(width 0.1016)
		(layer "In5.Cu")
		(net "SAS_EXP2CONN_TX_N_21")
	)
	(arc
		(start 24.67483 -136.926066)
		(mid 24.758667 -137.025442)
		(end 24.78786 -137.152126)
		(width 0.1016)
		(layer "In5.Cu")
		(net "SAS_EXP2CONN_TX_N_21")
	)
	(arc
		(start 138.45032 -143.149574)
		(mid 138.754858 -142.693801)
		(end 138.8618 -142.15618)
		(width 0.1016)
		(layer "In5.Cu")
		(net "SAS_EXP2CONN_TX_N_21")
	)
	(arc
		(start 45.288454 -84.826856)
		(mid 45.42834 -85.53011)
		(end 45.82668 -86.12632)
		(width 0.1016)
		(layer "In5.Cu")
		(net "SAS_EXP2CONN_TX_N_21")
	)
	(arc
		(start 46.736 -93.292422)
		(mid 46.430359 -94.828985)
		(end 45.55998 -96.131634)
		(width 0.1016)
		(layer "In5.Cu")
		(net "SAS_EXP2CONN_TX_N_21")
	)
	(arc
		(start 135.1788 -89.840816)
		(mid 135.147768 -89.684807)
		(end 135.05942 -89.552526)
		(width 0.1016)
		(layer "In5.Cu")
		(net "SAS_EXP2CONN_TX_N_21")
	)
	(arc
		(start 45.330364 -83.79587)
		(mid 45.308381 -83.828864)
		(end 45.300646 -83.867752)
		(width 0.1016)
		(layer "In5.Cu")
		(net "SAS_EXP2CONN_TX_N_21")
	)
	(arc
		(start 24.67483 -137.682986)
		(mid 24.590993 -137.782362)
		(end 24.5618 -137.909046)
		(width 0.1016)
		(layer "In5.Cu")
		(net "SAS_EXP2CONN_TX_N_21")
	)
	(arc
		(start 50.621946 -156.955236)
		(mid 50.920754 -157.014485)
		(end 51.174142 -157.183582)
		(width 0.1016)
		(layer "In5.Cu")
		(net "SAS_EXP2CONN_TX_N_21")
	)
	(arc
		(start 24.78786 -138.970766)
		(mid 24.758621 -139.097427)
		(end 24.67483 -139.196826)
		(width 0.1016)
		(layer "In5.Cu")
		(net "SAS_EXP2CONN_TX_N_21")
	)
	(arc
		(start 134.93242 -94.089474)
		(mid 135.114784 -93.816546)
		(end 135.1788 -93.494606)
		(width 0.1016)
		(layer "In5.Cu")
		(net "SAS_EXP2CONN_TX_N_21")
	)
	(segment
		(start 132.111496 -89.93505)
		(end 133.407912 -89.93505)
		(width 0.1016)
		(layer "F.Cu")
		(net "SAS_EXP2CONN_TX_P_22")
	)
	(segment
		(start 50.701448 -80.720438)
		(end 50.726848 -80.720438)
		(width 0.1016)
		(layer "F.Cu")
		(net "SAS_EXP2CONN_TX_P_22")
	)
	(segment
		(start 50.79873 -81.830164)
		(end 50.511456 -82.117438)
		(width 0.1016)
		(layer "F.Cu")
		(net "SAS_EXP2CONN_TX_P_22")
	)
	(segment
		(start 50.828448 -80.822038)
		(end 50.828448 -81.758282)
		(width 0.1016)
		(layer "F.Cu")
		(net "SAS_EXP2CONN_TX_P_22")
	)
	(segment
		(start 131.953 -89.818718)
		(end 132.039614 -89.905332)
		(width 0.1016)
		(layer "F.Cu")
		(net "SAS_EXP2CONN_TX_P_22")
	)
	(segment
		(start 50.599848 -79.590138)
		(end 50.599848 -80.618838)
		(width 0.1016)
		(layer "F.Cu")
		(net "SAS_EXP2CONN_TX_P_22")
	)
	(segment
		(start 133.479794 -89.905332)
		(end 133.731 -89.654126)
		(width 0.1016)
		(layer "F.Cu")
		(net "SAS_EXP2CONN_TX_P_22")
	)
	(segment
		(start 131.5974 -89.789)
		(end 131.881118 -89.789)
		(width 0.1016)
		(layer "F.Cu")
		(net "SAS_EXP2CONN_TX_P_22")
	)
	(via
		(at 50.511456 -82.117438)
		(size 0.5588)
		(drill 0.3048)
		(layers "F.Cu" "B.Cu")
		(net "SAS_EXP2CONN_TX_P_22")
	)
	(via
		(at 133.731 -89.654126)
		(size 0.5588)
		(drill 0.3048)
		(layers "F.Cu" "B.Cu")
		(net "SAS_EXP2CONN_TX_P_22")
	)
	(arc
		(start 131.881118 -89.789)
		(mid 131.920013 -89.796719)
		(end 131.953 -89.818718)
		(width 0.1016)
		(layer "F.Cu")
		(net "SAS_EXP2CONN_TX_P_22")
	)
	(arc
		(start 133.407912 -89.93505)
		(mid 133.446807 -89.927331)
		(end 133.479794 -89.905332)
		(width 0.1016)
		(layer "F.Cu")
		(net "SAS_EXP2CONN_TX_P_22")
	)
	(arc
		(start 50.828448 -81.758282)
		(mid 50.820729 -81.797177)
		(end 50.79873 -81.830164)
		(width 0.1016)
		(layer "F.Cu")
		(net "SAS_EXP2CONN_TX_P_22")
	)
	(arc
		(start 50.599848 -80.618838)
		(mid 50.629606 -80.69068)
		(end 50.701448 -80.720438)
		(width 0.1016)
		(layer "F.Cu")
		(net "SAS_EXP2CONN_TX_P_22")
	)
	(arc
		(start 50.726848 -80.720438)
		(mid 50.79869 -80.750196)
		(end 50.828448 -80.822038)
		(width 0.1016)
		(layer "F.Cu")
		(net "SAS_EXP2CONN_TX_P_22")
	)
	(arc
		(start 132.039614 -89.905332)
		(mid 132.072608 -89.927315)
		(end 132.111496 -89.93505)
		(width 0.1016)
		(layer "F.Cu")
		(net "SAS_EXP2CONN_TX_P_22")
	)
	(segment
		(start 53.6702 -156.2608)
		(end 56.619902 -159.210502)
		(width 0.1016)
		(layer "In5.Cu")
		(net "SAS_EXP2CONN_TX_P_22")
	)
	(segment
		(start 27.049984 -153.501344)
		(end 28.65882 -155.11018)
		(width 0.1016)
		(layer "In5.Cu")
		(net "SAS_EXP2CONN_TX_P_22")
	)
	(segment
		(start 136.779 -142.875254)
		(end 136.779 -142.875)
		(width 0.1016)
		(layer "In5.Cu")
		(net "SAS_EXP2CONN_TX_P_22")
	)
	(segment
		(start 49.629314 -94.134686)
		(end 46.99 -96.774)
		(width 0.1016)
		(layer "In5.Cu")
		(net "SAS_EXP2CONN_TX_P_22")
	)
	(segment
		(start 136.51611 -129.530602)
		(end 136.460992 -129.475992)
		(width 0.1016)
		(layer "In5.Cu")
		(net "SAS_EXP2CONN_TX_P_22")
	)
	(segment
		(start 132.390896 -125.405896)
		(end 132.110734 -125.125988)
		(width 0.1016)
		(layer "In5.Cu")
		(net "SAS_EXP2CONN_TX_P_22")
	)
	(segment
		(start 50.511456 -82.117438)
		(end 50.695098 -82.30108)
		(width 0.1016)
		(layer "In5.Cu")
		(net "SAS_EXP2CONN_TX_P_22")
	)
	(segment
		(start 131.572 -123.825)
		(end 131.572 -97.3074)
		(width 0.1016)
		(layer "In5.Cu")
		(net "SAS_EXP2CONN_TX_P_22")
	)
	(segment
		(start 29.782008 -155.575)
		(end 52.014628 -155.575)
		(width 0.1016)
		(layer "In5.Cu")
		(net "SAS_EXP2CONN_TX_P_22")
	)
	(segment
		(start 45.847 -99.533456)
		(end 45.847 -104.795574)
		(width 0.1016)
		(layer "In5.Cu")
		(net "SAS_EXP2CONN_TX_P_22")
	)
	(segment
		(start 120.3325 -159.321754)
		(end 136.779 -142.875254)
		(width 0.1016)
		(layer "In5.Cu")
		(net "SAS_EXP2CONN_TX_P_22")
	)
	(segment
		(start 137.414 -141.341856)
		(end 137.414 -131.699)
		(width 0.1016)
		(layer "In5.Cu")
		(net "SAS_EXP2CONN_TX_P_22")
	)
	(segment
		(start 134.4041 -90.207846)
		(end 134.400544 -90.20429)
		(width 0.1016)
		(layer "In5.Cu")
		(net "SAS_EXP2CONN_TX_P_22")
	)
	(segment
		(start 136.460992 -129.475992)
		(end 132.390896 -125.405896)
		(width 0.1016)
		(layer "In5.Cu")
		(net "SAS_EXP2CONN_TX_P_22")
	)
	(segment
		(start 134.62 -93.024198)
		(end 134.62 -90.621612)
		(width 0.1016)
		(layer "In5.Cu")
		(net "SAS_EXP2CONN_TX_P_22")
	)
	(segment
		(start 132.038852 -96.180148)
		(end 134.2136 -94.0054)
		(width 0.1016)
		(layer "In5.Cu")
		(net "SAS_EXP2CONN_TX_P_22")
	)
	(segment
		(start 50.8508 -82.677)
		(end 50.8508 -91.186)
		(width 0.1016)
		(layer "In5.Cu")
		(net "SAS_EXP2CONN_TX_P_22")
	)
	(segment
		(start 26.289 -126.898654)
		(end 26.289 -151.663654)
		(width 0.1016)
		(layer "In5.Cu")
		(net "SAS_EXP2CONN_TX_P_22")
	)
	(segment
		(start 58.2676 -159.893)
		(end 118.953026 -159.893)
		(width 0.1016)
		(layer "In5.Cu")
		(net "SAS_EXP2CONN_TX_P_22")
	)
	(segment
		(start 134.480046 -90.284046)
		(end 134.403846 -90.207846)
		(width 0.1016)
		(layer "In5.Cu")
		(net "SAS_EXP2CONN_TX_P_22")
	)
	(segment
		(start 44.755054 -107.43184)
		(end 26.996136 -125.190504)
		(width 0.1016)
		(layer "In5.Cu")
		(net "SAS_EXP2CONN_TX_P_22")
	)
	(segment
		(start 137.414 -131.699)
		(end 137.414254 -131.699)
		(width 0.1016)
		(layer "In5.Cu")
		(net "SAS_EXP2CONN_TX_P_22")
	)
	(segment
		(start 134.403846 -90.207846)
		(end 134.4041 -90.207846)
		(width 0.1016)
		(layer "In5.Cu")
		(net "SAS_EXP2CONN_TX_P_22")
	)
	(arc
		(start 134.400544 -90.20429)
		(mid 134.267458 -90.103636)
		(end 134.112 -90.043)
		(width 0.1016)
		(layer "In5.Cu")
		(net "SAS_EXP2CONN_TX_P_22")
	)
	(arc
		(start 134.62 -90.621612)
		(mid 134.583568 -90.438927)
		(end 134.480046 -90.284046)
		(width 0.1016)
		(layer "In5.Cu")
		(net "SAS_EXP2CONN_TX_P_22")
	)
	(arc
		(start 45.847 -104.795574)
		(mid 45.563207 -106.222299)
		(end 44.755054 -107.43184)
		(width 0.1016)
		(layer "In5.Cu")
		(net "SAS_EXP2CONN_TX_P_22")
	)
	(arc
		(start 136.779 -142.875)
		(mid 137.248981 -142.171574)
		(end 137.414 -141.341856)
		(width 0.1016)
		(layer "In5.Cu")
		(net "SAS_EXP2CONN_TX_P_22")
	)
	(arc
		(start 134.2136 -94.0054)
		(mid 134.514376 -93.555207)
		(end 134.62 -93.024198)
		(width 0.1016)
		(layer "In5.Cu")
		(net "SAS_EXP2CONN_TX_P_22")
	)
	(arc
		(start 118.953026 -159.893)
		(mid 119.699563 -159.74454)
		(end 120.3325 -159.321754)
		(width 0.1016)
		(layer "In5.Cu")
		(net "SAS_EXP2CONN_TX_P_22")
	)
	(arc
		(start 50.695098 -82.30108)
		(mid 50.810341 -82.473554)
		(end 50.8508 -82.677)
		(width 0.1016)
		(layer "In5.Cu")
		(net "SAS_EXP2CONN_TX_P_22")
	)
	(arc
		(start 131.572 -97.3074)
		(mid 131.693329 -96.697349)
		(end 132.038852 -96.180148)
		(width 0.1016)
		(layer "In5.Cu")
		(net "SAS_EXP2CONN_TX_P_22")
	)
	(arc
		(start 137.414254 -131.699)
		(mid 137.18088 -130.52546)
		(end 136.51611 -129.530602)
		(width 0.1016)
		(layer "In5.Cu")
		(net "SAS_EXP2CONN_TX_P_22")
	)
	(arc
		(start 132.110734 -125.125988)
		(mid 131.711982 -124.529075)
		(end 131.572 -123.825)
		(width 0.1016)
		(layer "In5.Cu")
		(net "SAS_EXP2CONN_TX_P_22")
	)
	(arc
		(start 26.996136 -125.190504)
		(mid 26.472676 -125.974241)
		(end 26.289 -126.898654)
		(width 0.1016)
		(layer "In5.Cu")
		(net "SAS_EXP2CONN_TX_P_22")
	)
	(arc
		(start 50.8508 -91.186)
		(mid 50.53335 -92.781841)
		(end 49.629314 -94.134686)
		(width 0.1016)
		(layer "In5.Cu")
		(net "SAS_EXP2CONN_TX_P_22")
	)
	(arc
		(start 134.112 -90.043)
		(mid 133.865386 -89.903536)
		(end 133.731 -89.654126)
		(width 0.1016)
		(layer "In5.Cu")
		(net "SAS_EXP2CONN_TX_P_22")
	)
	(arc
		(start 46.99 -96.774)
		(mid 46.144053 -98.040049)
		(end 45.847 -99.533456)
		(width 0.1016)
		(layer "In5.Cu")
		(net "SAS_EXP2CONN_TX_P_22")
	)
	(arc
		(start 52.014628 -155.575)
		(mid 52.910632 -155.753226)
		(end 53.6702 -156.2608)
		(width 0.1016)
		(layer "In5.Cu")
		(net "SAS_EXP2CONN_TX_P_22")
	)
	(arc
		(start 26.289 -151.663654)
		(mid 26.486767 -152.658166)
		(end 27.049984 -153.501344)
		(width 0.1016)
		(layer "In5.Cu")
		(net "SAS_EXP2CONN_TX_P_22")
	)
	(arc
		(start 28.65882 -155.11018)
		(mid 29.174188 -155.454259)
		(end 29.782008 -155.575)
		(width 0.1016)
		(layer "In5.Cu")
		(net "SAS_EXP2CONN_TX_P_22")
	)
	(arc
		(start 56.619902 -159.210502)
		(mid 57.375872 -159.715625)
		(end 58.2676 -159.893)
		(width 0.1016)
		(layer "In5.Cu")
		(net "SAS_EXP2CONN_TX_P_22")
	)
	(segment
		(start 131.5974 -91.948)
		(end 131.900422 -91.948)
		(width 0.1016)
		(layer "F.Cu")
		(net "SAS_EXP2CONN_TX_N_23")
	)
	(segment
		(start 53.571394 -80.822038)
		(end 53.571394 -81.764632)
		(width 0.1016)
		(layer "F.Cu")
		(net "SAS_EXP2CONN_TX_N_23")
	)
	(segment
		(start 53.698394 -80.720438)
		(end 53.672994 -80.720438)
		(width 0.1016)
		(layer "F.Cu")
		(net "SAS_EXP2CONN_TX_N_23")
	)
	(segment
		(start 53.799994 -79.590138)
		(end 53.799994 -80.618838)
		(width 0.1016)
		(layer "F.Cu")
		(net "SAS_EXP2CONN_TX_N_23")
	)
	(segment
		(start 53.601112 -81.836514)
		(end 53.882036 -82.117438)
		(width 0.1016)
		(layer "F.Cu")
		(net "SAS_EXP2CONN_TX_N_23")
	)
	(via
		(at 53.882036 -82.117438)
		(size 0.5588)
		(drill 0.3048)
		(layers "F.Cu" "B.Cu")
		(net "SAS_EXP2CONN_TX_N_23")
	)
	(via
		(at 132.207 -92.075)
		(size 0.5588)
		(drill 0.3048)
		(layers "F.Cu" "B.Cu")
		(net "SAS_EXP2CONN_TX_N_23")
	)
	(arc
		(start 53.799994 -80.618838)
		(mid 53.770236 -80.69068)
		(end 53.698394 -80.720438)
		(width 0.1016)
		(layer "F.Cu")
		(net "SAS_EXP2CONN_TX_N_23")
	)
	(arc
		(start 53.672994 -80.720438)
		(mid 53.601152 -80.750196)
		(end 53.571394 -80.822038)
		(width 0.1016)
		(layer "F.Cu")
		(net "SAS_EXP2CONN_TX_N_23")
	)
	(arc
		(start 131.900422 -91.948)
		(mid 132.066345 -91.981004)
		(end 132.207 -92.075)
		(width 0.1016)
		(layer "F.Cu")
		(net "SAS_EXP2CONN_TX_N_23")
	)
	(arc
		(start 53.571394 -81.764632)
		(mid 53.579113 -81.803527)
		(end 53.601112 -81.836514)
		(width 0.1016)
		(layer "F.Cu")
		(net "SAS_EXP2CONN_TX_N_23")
	)
	(segment
		(start 135.3058 -140.58265)
		(end 135.3058 -132.343398)
		(width 0.1016)
		(layer "In5.Cu")
		(net "SAS_EXP2CONN_TX_N_23")
	)
	(segment
		(start 134.76732 -131.043426)
		(end 132.51307 -128.78943)
		(width 0.1016)
		(layer "In5.Cu")
		(net "SAS_EXP2CONN_TX_N_23")
	)
	(segment
		(start 53.793898 -82.15249)
		(end 53.76799 -82.177382)
		(width 0.1016)
		(layer "In5.Cu")
		(net "SAS_EXP2CONN_TX_N_23")
	)
	(segment
		(start 30.743144 -153.4668)
		(end 54.280054 -153.4668)
		(width 0.1016)
		(layer "In5.Cu")
		(net "SAS_EXP2CONN_TX_N_23")
	)
	(segment
		(start 45.719492 -109.601254)
		(end 29.2735 -126.0475)
		(width 0.1016)
		(layer "In5.Cu")
		(net "SAS_EXP2CONN_TX_N_23")
	)
	(segment
		(start 59.531504 -157.7848)
		(end 117.924326 -157.7848)
		(width 0.1016)
		(layer "In5.Cu")
		(net "SAS_EXP2CONN_TX_N_23")
	)
	(segment
		(start 132.960364 -91.795346)
		(end 132.6642 -91.795346)
		(width 0.1016)
		(layer "In5.Cu")
		(net "SAS_EXP2CONN_TX_N_23")
	)
	(segment
		(start 119.43842 -157.157674)
		(end 134.80542 -141.790674)
		(width 0.1016)
		(layer "In5.Cu")
		(net "SAS_EXP2CONN_TX_N_23")
	)
	(segment
		(start 53.82006 -84.71027)
		(end 53.82006 -85.01507)
		(width 0.1016)
		(layer "In5.Cu")
		(net "SAS_EXP2CONN_TX_N_23")
	)
	(segment
		(start 129.4638 -124.615448)
		(end 129.4638 -97.561146)
		(width 0.1016)
		(layer "In5.Cu")
		(net "SAS_EXP2CONN_TX_N_23")
	)
	(segment
		(start 53.594 -82.58683)
		(end 53.594 -84.25815)
		(width 0.1016)
		(layer "In5.Cu")
		(net "SAS_EXP2CONN_TX_N_23")
	)
	(segment
		(start 53.82006 -86.22411)
		(end 53.82006 -86.52891)
		(width 0.1016)
		(layer "In5.Cu")
		(net "SAS_EXP2CONN_TX_N_23")
	)
	(segment
		(start 132.360924 -91.920822)
		(end 132.207 -92.075)
		(width 0.1016)
		(layer "In5.Cu")
		(net "SAS_EXP2CONN_TX_N_23")
	)
	(segment
		(start 53.594 -85.46719)
		(end 53.594 -85.77199)
		(width 0.1016)
		(layer "In5.Cu")
		(net "SAS_EXP2CONN_TX_N_23")
	)
	(segment
		(start 28.5242 -127.856488)
		(end 28.5242 -150.709376)
		(width 0.1016)
		(layer "In5.Cu")
		(net "SAS_EXP2CONN_TX_N_23")
	)
	(segment
		(start 53.594 -86.98103)
		(end 53.594 -92.94622)
		(width 0.1016)
		(layer "In5.Cu")
		(net "SAS_EXP2CONN_TX_N_23")
	)
	(segment
		(start 48.006 -101.267768)
		(end 48.006 -104.521)
		(width 0.1016)
		(layer "In5.Cu")
		(net "SAS_EXP2CONN_TX_N_23")
	)
	(segment
		(start 46.030642 -109.290104)
		(end 45.719492 -109.601254)
		(width 0.1016)
		(layer "In5.Cu")
		(net "SAS_EXP2CONN_TX_N_23")
	)
	(segment
		(start 129.93751 -96.41713)
		(end 133.26872 -93.086174)
		(width 0.1016)
		(layer "In5.Cu")
		(net "SAS_EXP2CONN_TX_N_23")
	)
	(segment
		(start 53.311298 -93.628718)
		(end 49.595024 -97.344992)
		(width 0.1016)
		(layer "In5.Cu")
		(net "SAS_EXP2CONN_TX_N_23")
	)
	(segment
		(start 132.51307 -128.78943)
		(end 130.25882 -126.53518)
		(width 0.1016)
		(layer "In5.Cu")
		(net "SAS_EXP2CONN_TX_N_23")
	)
	(segment
		(start 55.42407 -153.94051)
		(end 59.082432 -157.598872)
		(width 0.1016)
		(layer "In5.Cu")
		(net "SAS_EXP2CONN_TX_N_23")
	)
	(segment
		(start 53.882036 -82.117438)
		(end 53.880766 -82.117438)
		(width 0.1016)
		(layer "In5.Cu")
		(net "SAS_EXP2CONN_TX_N_23")
	)
	(segment
		(start 133.29412 -91.978226)
		(end 133.21792 -91.902026)
		(width 0.1016)
		(layer "In5.Cu")
		(net "SAS_EXP2CONN_TX_N_23")
	)
	(segment
		(start 133.4008 -92.767404)
		(end 133.4008 -92.235782)
		(width 0.1016)
		(layer "In5.Cu")
		(net "SAS_EXP2CONN_TX_N_23")
	)
	(arc
		(start 59.082432 -157.598872)
		(mid 59.288468 -157.736541)
		(end 59.531504 -157.7848)
		(width 0.1016)
		(layer "In5.Cu")
		(net "SAS_EXP2CONN_TX_N_23")
	)
	(arc
		(start 53.70703 -84.48421)
		(mid 53.790867 -84.583586)
		(end 53.82006 -84.71027)
		(width 0.1016)
		(layer "In5.Cu")
		(net "SAS_EXP2CONN_TX_N_23")
	)
	(arc
		(start 48.006 -104.521)
		(mid 47.492623 -107.102008)
		(end 46.030642 -109.290104)
		(width 0.1016)
		(layer "In5.Cu")
		(net "SAS_EXP2CONN_TX_N_23")
	)
	(arc
		(start 54.280054 -153.4668)
		(mid 54.899159 -153.589912)
		(end 55.42407 -153.94051)
		(width 0.1016)
		(layer "In5.Cu")
		(net "SAS_EXP2CONN_TX_N_23")
	)
	(arc
		(start 117.924326 -157.7848)
		(mid 118.743735 -157.621809)
		(end 119.43842 -157.157674)
		(width 0.1016)
		(layer "In5.Cu")
		(net "SAS_EXP2CONN_TX_N_23")
	)
	(arc
		(start 133.26872 -93.086174)
		(mid 133.366443 -92.939921)
		(end 133.4008 -92.767404)
		(width 0.1016)
		(layer "In5.Cu")
		(net "SAS_EXP2CONN_TX_N_23")
	)
	(arc
		(start 135.3058 -132.343398)
		(mid 135.165856 -131.639853)
		(end 134.76732 -131.043426)
		(width 0.1016)
		(layer "In5.Cu")
		(net "SAS_EXP2CONN_TX_N_23")
	)
	(arc
		(start 132.6642 -91.795346)
		(mid 132.50007 -91.8279)
		(end 132.360924 -91.920822)
		(width 0.1016)
		(layer "In5.Cu")
		(net "SAS_EXP2CONN_TX_N_23")
	)
	(arc
		(start 53.70703 -86.75497)
		(mid 53.623193 -86.854346)
		(end 53.594 -86.98103)
		(width 0.1016)
		(layer "In5.Cu")
		(net "SAS_EXP2CONN_TX_N_23")
	)
	(arc
		(start 29.44368 -152.92832)
		(mid 30.03985 -153.326824)
		(end 30.743144 -153.4668)
		(width 0.1016)
		(layer "In5.Cu")
		(net "SAS_EXP2CONN_TX_N_23")
	)
	(arc
		(start 129.4638 -97.561146)
		(mid 129.586912 -96.942041)
		(end 129.93751 -96.41713)
		(width 0.1016)
		(layer "In5.Cu")
		(net "SAS_EXP2CONN_TX_N_23")
	)
	(arc
		(start 53.880766 -82.117438)
		(mid 53.833926 -82.126528)
		(end 53.793898 -82.15249)
		(width 0.1016)
		(layer "In5.Cu")
		(net "SAS_EXP2CONN_TX_N_23")
	)
	(arc
		(start 28.5242 -150.709376)
		(mid 28.763264 -151.910291)
		(end 29.44368 -152.92832)
		(width 0.1016)
		(layer "In5.Cu")
		(net "SAS_EXP2CONN_TX_N_23")
	)
	(arc
		(start 130.25882 -126.53518)
		(mid 129.670409 -125.654371)
		(end 129.4638 -124.615448)
		(width 0.1016)
		(layer "In5.Cu")
		(net "SAS_EXP2CONN_TX_N_23")
	)
	(arc
		(start 134.80542 -141.790674)
		(mid 135.175755 -141.236428)
		(end 135.3058 -140.58265)
		(width 0.1016)
		(layer "In5.Cu")
		(net "SAS_EXP2CONN_TX_N_23")
	)
	(arc
		(start 53.594 -84.25815)
		(mid 53.623239 -84.384811)
		(end 53.70703 -84.48421)
		(width 0.1016)
		(layer "In5.Cu")
		(net "SAS_EXP2CONN_TX_N_23")
	)
	(arc
		(start 133.21792 -91.902026)
		(mid 133.099752 -91.823069)
		(end 132.960364 -91.795346)
		(width 0.1016)
		(layer "In5.Cu")
		(net "SAS_EXP2CONN_TX_N_23")
	)
	(arc
		(start 53.70703 -85.24113)
		(mid 53.623193 -85.340506)
		(end 53.594 -85.46719)
		(width 0.1016)
		(layer "In5.Cu")
		(net "SAS_EXP2CONN_TX_N_23")
	)
	(arc
		(start 53.76799 -82.177382)
		(mid 53.639316 -82.364385)
		(end 53.594 -82.58683)
		(width 0.1016)
		(layer "In5.Cu")
		(net "SAS_EXP2CONN_TX_N_23")
	)
	(arc
		(start 29.2735 -126.0475)
		(mid 28.718931 -126.877471)
		(end 28.5242 -127.856488)
		(width 0.1016)
		(layer "In5.Cu")
		(net "SAS_EXP2CONN_TX_N_23")
	)
	(arc
		(start 53.82006 -85.01507)
		(mid 53.790821 -85.141731)
		(end 53.70703 -85.24113)
		(width 0.1016)
		(layer "In5.Cu")
		(net "SAS_EXP2CONN_TX_N_23")
	)
	(arc
		(start 133.4008 -92.235782)
		(mid 133.373074 -92.096395)
		(end 133.29412 -91.978226)
		(width 0.1016)
		(layer "In5.Cu")
		(net "SAS_EXP2CONN_TX_N_23")
	)
	(arc
		(start 49.595024 -97.344992)
		(mid 48.418386 -99.151583)
		(end 48.006 -101.267768)
		(width 0.1016)
		(layer "In5.Cu")
		(net "SAS_EXP2CONN_TX_N_23")
	)
	(arc
		(start 53.594 -85.77199)
		(mid 53.623239 -85.898651)
		(end 53.70703 -85.99805)
		(width 0.1016)
		(layer "In5.Cu")
		(net "SAS_EXP2CONN_TX_N_23")
	)
	(arc
		(start 53.70703 -85.99805)
		(mid 53.790867 -86.097426)
		(end 53.82006 -86.22411)
		(width 0.1016)
		(layer "In5.Cu")
		(net "SAS_EXP2CONN_TX_N_23")
	)
	(arc
		(start 53.82006 -86.52891)
		(mid 53.790821 -86.655571)
		(end 53.70703 -86.75497)
		(width 0.1016)
		(layer "In5.Cu")
		(net "SAS_EXP2CONN_TX_N_23")
	)
	(arc
		(start 53.594 -92.94622)
		(mid 53.520529 -93.315586)
		(end 53.311298 -93.628718)
		(width 0.1016)
		(layer "In5.Cu")
		(net "SAS_EXP2CONN_TX_N_23")
	)
	(segment
		(start 131.5974 -90.424)
		(end 131.881118 -90.424)
		(width 0.1016)
		(layer "F.Cu")
		(net "SAS_EXP2CONN_TX_N_22")
	)
	(segment
		(start 51.298348 -80.720438)
		(end 51.272948 -80.720438)
		(width 0.1016)
		(layer "F.Cu")
		(net "SAS_EXP2CONN_TX_N_22")
	)
	(segment
		(start 132.111496 -90.27795)
		(end 133.407658 -90.27795)
		(width 0.1016)
		(layer "F.Cu")
		(net "SAS_EXP2CONN_TX_N_22")
	)
	(segment
		(start 51.399948 -79.590138)
		(end 51.399948 -80.618838)
		(width 0.1016)
		(layer "F.Cu")
		(net "SAS_EXP2CONN_TX_N_22")
	)
	(segment
		(start 51.171348 -80.822038)
		(end 51.171348 -81.758282)
		(width 0.1016)
		(layer "F.Cu")
		(net "SAS_EXP2CONN_TX_N_22")
	)
	(segment
		(start 131.953 -90.394282)
		(end 132.039614 -90.307668)
		(width 0.1016)
		(layer "F.Cu")
		(net "SAS_EXP2CONN_TX_N_22")
	)
	(segment
		(start 133.47954 -90.307668)
		(end 133.731 -90.559128)
		(width 0.1016)
		(layer "F.Cu")
		(net "SAS_EXP2CONN_TX_N_22")
	)
	(segment
		(start 51.201066 -81.830164)
		(end 51.48834 -82.117438)
		(width 0.1016)
		(layer "F.Cu")
		(net "SAS_EXP2CONN_TX_N_22")
	)
	(via
		(at 51.48834 -82.117438)
		(size 0.5588)
		(drill 0.3048)
		(layers "F.Cu" "B.Cu")
		(net "SAS_EXP2CONN_TX_N_22")
	)
	(via
		(at 133.731 -90.559128)
		(size 0.5588)
		(drill 0.3048)
		(layers "F.Cu" "B.Cu")
		(net "SAS_EXP2CONN_TX_N_22")
	)
	(arc
		(start 132.039614 -90.307668)
		(mid 132.072608 -90.285685)
		(end 132.111496 -90.27795)
		(width 0.1016)
		(layer "F.Cu")
		(net "SAS_EXP2CONN_TX_N_22")
	)
	(arc
		(start 51.171348 -81.758282)
		(mid 51.179067 -81.797177)
		(end 51.201066 -81.830164)
		(width 0.1016)
		(layer "F.Cu")
		(net "SAS_EXP2CONN_TX_N_22")
	)
	(arc
		(start 131.881118 -90.424)
		(mid 131.920013 -90.416281)
		(end 131.953 -90.394282)
		(width 0.1016)
		(layer "F.Cu")
		(net "SAS_EXP2CONN_TX_N_22")
	)
	(arc
		(start 51.399948 -80.618838)
		(mid 51.37019 -80.69068)
		(end 51.298348 -80.720438)
		(width 0.1016)
		(layer "F.Cu")
		(net "SAS_EXP2CONN_TX_N_22")
	)
	(arc
		(start 133.407658 -90.27795)
		(mid 133.446553 -90.285669)
		(end 133.47954 -90.307668)
		(width 0.1016)
		(layer "F.Cu")
		(net "SAS_EXP2CONN_TX_N_22")
	)
	(arc
		(start 51.272948 -80.720438)
		(mid 51.201106 -80.750196)
		(end 51.171348 -80.822038)
		(width 0.1016)
		(layer "F.Cu")
		(net "SAS_EXP2CONN_TX_N_22")
	)
	(segment
		(start 29.781754 -155.2448)
		(end 52.014882 -155.2448)
		(width 0.1016)
		(layer "In5.Cu")
		(net "SAS_EXP2CONN_TX_N_22")
	)
	(segment
		(start 131.805172 -95.946468)
		(end 131.96062 -95.79102)
		(width 0.1016)
		(layer "In5.Cu")
		(net "SAS_EXP2CONN_TX_N_22")
	)
	(segment
		(start 132.017008 -125.499622)
		(end 131.877054 -125.359668)
		(width 0.1016)
		(layer "In5.Cu")
		(net "SAS_EXP2CONN_TX_N_22")
	)
	(segment
		(start 51.40706 -89.019634)
		(end 51.40706 -89.324434)
		(width 0.1016)
		(layer "In5.Cu")
		(net "SAS_EXP2CONN_TX_N_22")
	)
	(segment
		(start 134.24662 -90.517726)
		(end 134.166864 -90.43797)
		(width 0.1016)
		(layer "In5.Cu")
		(net "SAS_EXP2CONN_TX_N_22")
	)
	(segment
		(start 136.282684 -129.764536)
		(end 136.22782 -129.709926)
		(width 0.1016)
		(layer "In5.Cu")
		(net "SAS_EXP2CONN_TX_N_22")
	)
	(segment
		(start 131.2418 -123.824746)
		(end 131.2418 -97.307146)
		(width 0.1016)
		(layer "In5.Cu")
		(net "SAS_EXP2CONN_TX_N_22")
	)
	(segment
		(start 49.862994 -94.368366)
		(end 47.22368 -97.00768)
		(width 0.1016)
		(layer "In5.Cu")
		(net "SAS_EXP2CONN_TX_N_22")
	)
	(segment
		(start 133.850888 -90.43924)
		(end 133.731 -90.559128)
		(width 0.1016)
		(layer "In5.Cu")
		(net "SAS_EXP2CONN_TX_N_22")
	)
	(segment
		(start 131.96062 -95.79102)
		(end 133.97992 -93.771974)
		(width 0.1016)
		(layer "In5.Cu")
		(net "SAS_EXP2CONN_TX_N_22")
	)
	(segment
		(start 51.181 -86.101428)
		(end 51.181 -86.406228)
		(width 0.1016)
		(layer "In5.Cu")
		(net "SAS_EXP2CONN_TX_N_22")
	)
	(segment
		(start 51.40706 -86.858348)
		(end 51.40706 -87.163148)
		(width 0.1016)
		(layer "In5.Cu")
		(net "SAS_EXP2CONN_TX_N_22")
	)
	(segment
		(start 53.90388 -156.02712)
		(end 56.853582 -158.976822)
		(width 0.1016)
		(layer "In5.Cu")
		(net "SAS_EXP2CONN_TX_N_22")
	)
	(segment
		(start 120.09882 -159.088074)
		(end 136.54532 -142.641574)
		(width 0.1016)
		(layer "In5.Cu")
		(net "SAS_EXP2CONN_TX_N_22")
	)
	(segment
		(start 132.15747 -125.639576)
		(end 132.017008 -125.499622)
		(width 0.1016)
		(layer "In5.Cu")
		(net "SAS_EXP2CONN_TX_N_22")
	)
	(segment
		(start 136.22782 -129.709926)
		(end 132.15747 -125.639576)
		(width 0.1016)
		(layer "In5.Cu")
		(net "SAS_EXP2CONN_TX_N_22")
	)
	(segment
		(start 51.181 -84.587588)
		(end 51.181 -84.892388)
		(width 0.1016)
		(layer "In5.Cu")
		(net "SAS_EXP2CONN_TX_N_22")
	)
	(segment
		(start 51.40706 -85.344508)
		(end 51.40706 -85.649308)
		(width 0.1016)
		(layer "In5.Cu")
		(net "SAS_EXP2CONN_TX_N_22")
	)
	(segment
		(start 46.1772 -99.533456)
		(end 46.177454 -104.013)
		(width 0.1016)
		(layer "In5.Cu")
		(net "SAS_EXP2CONN_TX_N_22")
	)
	(segment
		(start 51.48834 -82.117438)
		(end 51.359308 -82.24647)
		(width 0.1016)
		(layer "In5.Cu")
		(net "SAS_EXP2CONN_TX_N_22")
	)
	(segment
		(start 137.0838 -141.341602)
		(end 137.0838 -131.699)
		(width 0.1016)
		(layer "In5.Cu")
		(net "SAS_EXP2CONN_TX_N_22")
	)
	(segment
		(start 51.181 -87.615268)
		(end 51.181 -88.567514)
		(width 0.1016)
		(layer "In5.Cu")
		(net "SAS_EXP2CONN_TX_N_22")
	)
	(segment
		(start 44.988734 -107.66552)
		(end 27.229816 -125.424184)
		(width 0.1016)
		(layer "In5.Cu")
		(net "SAS_EXP2CONN_TX_N_22")
	)
	(segment
		(start 134.2898 -93.023944)
		(end 134.2898 -90.621866)
		(width 0.1016)
		(layer "In5.Cu")
		(net "SAS_EXP2CONN_TX_N_22")
	)
	(segment
		(start 58.267346 -159.5628)
		(end 118.953026 -159.5628)
		(width 0.1016)
		(layer "In5.Cu")
		(net "SAS_EXP2CONN_TX_N_22")
	)
	(segment
		(start 51.181 -89.776554)
		(end 51.181 -91.186254)
		(width 0.1016)
		(layer "In5.Cu")
		(net "SAS_EXP2CONN_TX_N_22")
	)
	(segment
		(start 51.181 -82.677)
		(end 51.181 -83.378548)
		(width 0.1016)
		(layer "In5.Cu")
		(net "SAS_EXP2CONN_TX_N_22")
	)
	(segment
		(start 26.6192 -126.8984)
		(end 26.6192 -151.6634)
		(width 0.1016)
		(layer "In5.Cu")
		(net "SAS_EXP2CONN_TX_N_22")
	)
	(segment
		(start 46.177454 -104.013)
		(end 46.1772 -104.013)
		(width 0.1016)
		(layer "In5.Cu")
		(net "SAS_EXP2CONN_TX_N_22")
	)
	(segment
		(start 27.283664 -153.267664)
		(end 28.8925 -154.8765)
		(width 0.1016)
		(layer "In5.Cu")
		(net "SAS_EXP2CONN_TX_N_22")
	)
	(segment
		(start 51.40706 -83.830668)
		(end 51.40706 -84.135468)
		(width 0.1016)
		(layer "In5.Cu")
		(net "SAS_EXP2CONN_TX_N_22")
	)
	(segment
		(start 46.1772 -104.013)
		(end 46.1772 -104.79532)
		(width 0.1016)
		(layer "In5.Cu")
		(net "SAS_EXP2CONN_TX_N_22")
	)
	(arc
		(start 51.29403 -89.550494)
		(mid 51.210193 -89.64987)
		(end 51.181 -89.776554)
		(width 0.1016)
		(layer "In5.Cu")
		(net "SAS_EXP2CONN_TX_N_22")
	)
	(arc
		(start 28.8925 -154.8765)
		(mid 29.300493 -155.149112)
		(end 29.781754 -155.2448)
		(width 0.1016)
		(layer "In5.Cu")
		(net "SAS_EXP2CONN_TX_N_22")
	)
	(arc
		(start 118.953026 -159.5628)
		(mid 119.573133 -159.439377)
		(end 120.09882 -159.088074)
		(width 0.1016)
		(layer "In5.Cu")
		(net "SAS_EXP2CONN_TX_N_22")
	)
	(arc
		(start 51.181 -88.567514)
		(mid 51.210239 -88.694175)
		(end 51.29403 -88.793574)
		(width 0.1016)
		(layer "In5.Cu")
		(net "SAS_EXP2CONN_TX_N_22")
	)
	(arc
		(start 51.181 -86.406228)
		(mid 51.210239 -86.532889)
		(end 51.29403 -86.632288)
		(width 0.1016)
		(layer "In5.Cu")
		(net "SAS_EXP2CONN_TX_N_22")
	)
	(arc
		(start 51.40706 -87.163148)
		(mid 51.377821 -87.289809)
		(end 51.29403 -87.389208)
		(width 0.1016)
		(layer "In5.Cu")
		(net "SAS_EXP2CONN_TX_N_22")
	)
	(arc
		(start 136.54532 -142.641574)
		(mid 136.943843 -142.045142)
		(end 137.0838 -141.341602)
		(width 0.1016)
		(layer "In5.Cu")
		(net "SAS_EXP2CONN_TX_N_22")
	)
	(arc
		(start 52.014882 -155.2448)
		(mid 53.03718 -155.448112)
		(end 53.90388 -156.02712)
		(width 0.1016)
		(layer "In5.Cu")
		(net "SAS_EXP2CONN_TX_N_22")
	)
	(arc
		(start 134.166864 -90.43797)
		(mid 134.095063 -90.390058)
		(end 134.0104 -90.3732)
		(width 0.1016)
		(layer "In5.Cu")
		(net "SAS_EXP2CONN_TX_N_22")
	)
	(arc
		(start 51.40706 -89.324434)
		(mid 51.377821 -89.451095)
		(end 51.29403 -89.550494)
		(width 0.1016)
		(layer "In5.Cu")
		(net "SAS_EXP2CONN_TX_N_22")
	)
	(arc
		(start 51.181 -84.892388)
		(mid 51.210239 -85.019049)
		(end 51.29403 -85.118448)
		(width 0.1016)
		(layer "In5.Cu")
		(net "SAS_EXP2CONN_TX_N_22")
	)
	(arc
		(start 26.6192 -151.6634)
		(mid 26.791882 -152.531619)
		(end 27.283664 -153.267664)
		(width 0.1016)
		(layer "In5.Cu")
		(net "SAS_EXP2CONN_TX_N_22")
	)
	(arc
		(start 51.40706 -85.649308)
		(mid 51.377821 -85.775969)
		(end 51.29403 -85.875368)
		(width 0.1016)
		(layer "In5.Cu")
		(net "SAS_EXP2CONN_TX_N_22")
	)
	(arc
		(start 51.29403 -84.361528)
		(mid 51.210193 -84.460904)
		(end 51.181 -84.587588)
		(width 0.1016)
		(layer "In5.Cu")
		(net "SAS_EXP2CONN_TX_N_22")
	)
	(arc
		(start 133.97992 -93.771974)
		(mid 134.209238 -93.428775)
		(end 134.2898 -93.023944)
		(width 0.1016)
		(layer "In5.Cu")
		(net "SAS_EXP2CONN_TX_N_22")
	)
	(arc
		(start 47.22368 -97.00768)
		(mid 46.449234 -98.166487)
		(end 46.1772 -99.533456)
		(width 0.1016)
		(layer "In5.Cu")
		(net "SAS_EXP2CONN_TX_N_22")
	)
	(arc
		(start 131.2418 -97.307146)
		(mid 131.388215 -96.570801)
		(end 131.805172 -95.946468)
		(width 0.1016)
		(layer "In5.Cu")
		(net "SAS_EXP2CONN_TX_N_22")
	)
	(arc
		(start 27.229816 -125.424184)
		(mid 26.777876 -126.10056)
		(end 26.6192 -126.8984)
		(width 0.1016)
		(layer "In5.Cu")
		(net "SAS_EXP2CONN_TX_N_22")
	)
	(arc
		(start 51.181 -83.378548)
		(mid 51.210239 -83.505209)
		(end 51.29403 -83.604608)
		(width 0.1016)
		(layer "In5.Cu")
		(net "SAS_EXP2CONN_TX_N_22")
	)
	(arc
		(start 46.1772 -104.79532)
		(mid 45.868418 -106.348612)
		(end 44.988734 -107.66552)
		(width 0.1016)
		(layer "In5.Cu")
		(net "SAS_EXP2CONN_TX_N_22")
	)
	(arc
		(start 51.29403 -86.632288)
		(mid 51.377867 -86.731664)
		(end 51.40706 -86.858348)
		(width 0.1016)
		(layer "In5.Cu")
		(net "SAS_EXP2CONN_TX_N_22")
	)
	(arc
		(start 51.181 -91.186254)
		(mid 50.838464 -92.908389)
		(end 49.862994 -94.368366)
		(width 0.1016)
		(layer "In5.Cu")
		(net "SAS_EXP2CONN_TX_N_22")
	)
	(arc
		(start 51.29403 -85.875368)
		(mid 51.210193 -85.974744)
		(end 51.181 -86.101428)
		(width 0.1016)
		(layer "In5.Cu")
		(net "SAS_EXP2CONN_TX_N_22")
	)
	(arc
		(start 56.853582 -158.976822)
		(mid 57.502192 -159.410396)
		(end 58.267346 -159.5628)
		(width 0.1016)
		(layer "In5.Cu")
		(net "SAS_EXP2CONN_TX_N_22")
	)
	(arc
		(start 51.40706 -84.135468)
		(mid 51.377821 -84.262129)
		(end 51.29403 -84.361528)
		(width 0.1016)
		(layer "In5.Cu")
		(net "SAS_EXP2CONN_TX_N_22")
	)
	(arc
		(start 131.877054 -125.359668)
		(mid 131.406753 -124.655395)
		(end 131.2418 -123.824746)
		(width 0.1016)
		(layer "In5.Cu")
		(net "SAS_EXP2CONN_TX_N_22")
	)
	(arc
		(start 51.29403 -85.118448)
		(mid 51.377867 -85.217824)
		(end 51.40706 -85.344508)
		(width 0.1016)
		(layer "In5.Cu")
		(net "SAS_EXP2CONN_TX_N_22")
	)
	(arc
		(start 137.0838 -131.699)
		(mid 136.875649 -130.652085)
		(end 136.282684 -129.764536)
		(width 0.1016)
		(layer "In5.Cu")
		(net "SAS_EXP2CONN_TX_N_22")
	)
	(arc
		(start 51.29403 -87.389208)
		(mid 51.210193 -87.488584)
		(end 51.181 -87.615268)
		(width 0.1016)
		(layer "In5.Cu")
		(net "SAS_EXP2CONN_TX_N_22")
	)
	(arc
		(start 134.2898 -90.621866)
		(mid 134.278586 -90.565489)
		(end 134.24662 -90.517726)
		(width 0.1016)
		(layer "In5.Cu")
		(net "SAS_EXP2CONN_TX_N_22")
	)
	(arc
		(start 51.29403 -88.793574)
		(mid 51.377867 -88.89295)
		(end 51.40706 -89.019634)
		(width 0.1016)
		(layer "In5.Cu")
		(net "SAS_EXP2CONN_TX_N_22")
	)
	(arc
		(start 51.359308 -82.24647)
		(mid 51.227323 -82.443999)
		(end 51.181 -82.677)
		(width 0.1016)
		(layer "In5.Cu")
		(net "SAS_EXP2CONN_TX_N_22")
	)
	(arc
		(start 51.29403 -83.604608)
		(mid 51.377867 -83.703984)
		(end 51.40706 -83.830668)
		(width 0.1016)
		(layer "In5.Cu")
		(net "SAS_EXP2CONN_TX_N_22")
	)
	(arc
		(start 134.0104 -90.3732)
		(mid 133.924085 -90.390369)
		(end 133.850888 -90.43924)
		(width 0.1016)
		(layer "In5.Cu")
		(net "SAS_EXP2CONN_TX_N_22")
	)
	(segment
		(start 52.999894 -79.590138)
		(end 52.999894 -80.618838)
		(width 0.1016)
		(layer "F.Cu")
		(net "SAS_EXP2CONN_TX_P_23")
	)
	(segment
		(start 53.198776 -81.836514)
		(end 52.917852 -82.117438)
		(width 0.1016)
		(layer "F.Cu")
		(net "SAS_EXP2CONN_TX_P_23")
	)
	(segment
		(start 53.101494 -80.720438)
		(end 53.126894 -80.720438)
		(width 0.1016)
		(layer "F.Cu")
		(net "SAS_EXP2CONN_TX_P_23")
	)
	(segment
		(start 131.5974 -91.313)
		(end 131.861814 -91.313)
		(width 0.1016)
		(layer "F.Cu")
		(net "SAS_EXP2CONN_TX_P_23")
	)
	(segment
		(start 53.228494 -80.822038)
		(end 53.228494 -81.764632)
		(width 0.1016)
		(layer "F.Cu")
		(net "SAS_EXP2CONN_TX_P_23")
	)
	(via
		(at 52.917852 -82.117438)
		(size 0.5588)
		(drill 0.3048)
		(layers "F.Cu" "B.Cu")
		(net "SAS_EXP2CONN_TX_P_23")
	)
	(via
		(at 132.207 -91.169998)
		(size 0.5588)
		(drill 0.3048)
		(layers "F.Cu" "B.Cu")
		(net "SAS_EXP2CONN_TX_P_23")
	)
	(arc
		(start 131.861814 -91.313)
		(mid 132.048635 -91.275839)
		(end 132.207 -91.169998)
		(width 0.1016)
		(layer "F.Cu")
		(net "SAS_EXP2CONN_TX_P_23")
	)
	(arc
		(start 53.228494 -81.764632)
		(mid 53.220775 -81.803527)
		(end 53.198776 -81.836514)
		(width 0.1016)
		(layer "F.Cu")
		(net "SAS_EXP2CONN_TX_P_23")
	)
	(arc
		(start 53.126894 -80.720438)
		(mid 53.198736 -80.750196)
		(end 53.228494 -80.822038)
		(width 0.1016)
		(layer "F.Cu")
		(net "SAS_EXP2CONN_TX_P_23")
	)
	(arc
		(start 52.999894 -80.618838)
		(mid 53.029652 -80.69068)
		(end 53.101494 -80.720438)
		(width 0.1016)
		(layer "F.Cu")
		(net "SAS_EXP2CONN_TX_P_23")
	)
	(segment
		(start 135.636 -140.582904)
		(end 135.636 -132.343144)
		(width 0.1016)
		(layer "In5.Cu")
		(net "SAS_EXP2CONN_TX_P_23")
	)
	(segment
		(start 55.19039 -154.17419)
		(end 58.848498 -157.832298)
		(width 0.1016)
		(layer "In5.Cu")
		(net "SAS_EXP2CONN_TX_P_23")
	)
	(segment
		(start 133.527546 -91.744546)
		(end 133.4516 -91.6686)
		(width 0.1016)
		(layer "In5.Cu")
		(net "SAS_EXP2CONN_TX_P_23")
	)
	(segment
		(start 59.530996 -158.115)
		(end 117.924326 -158.115)
		(width 0.1016)
		(layer "In5.Cu")
		(net "SAS_EXP2CONN_TX_P_23")
	)
	(segment
		(start 45.485812 -109.367574)
		(end 29.03982 -125.81382)
		(width 0.1016)
		(layer "In5.Cu")
		(net "SAS_EXP2CONN_TX_P_23")
	)
	(segment
		(start 28.194 -127.856742)
		(end 28.194 -150.70963)
		(width 0.1016)
		(layer "In5.Cu")
		(net "SAS_EXP2CONN_TX_P_23")
	)
	(segment
		(start 132.960364 -91.465146)
		(end 132.6642 -91.465146)
		(width 0.1016)
		(layer "In5.Cu")
		(net "SAS_EXP2CONN_TX_P_23")
	)
	(segment
		(start 130.17119 -96.65081)
		(end 133.5024 -93.3196)
		(width 0.1016)
		(layer "In5.Cu")
		(net "SAS_EXP2CONN_TX_P_23")
	)
	(segment
		(start 135.001 -130.81)
		(end 130.4925 -126.3015)
		(width 0.1016)
		(layer "In5.Cu")
		(net "SAS_EXP2CONN_TX_P_23")
	)
	(segment
		(start 47.6758 -101.267514)
		(end 47.6758 -104.520746)
		(width 0.1016)
		(layer "In5.Cu")
		(net "SAS_EXP2CONN_TX_P_23")
	)
	(segment
		(start 30.743144 -153.797)
		(end 54.2798 -153.797)
		(width 0.1016)
		(layer "In5.Cu")
		(net "SAS_EXP2CONN_TX_P_23")
	)
	(segment
		(start 52.917852 -82.117438)
		(end 53.023008 -82.222594)
		(width 0.1016)
		(layer "In5.Cu")
		(net "SAS_EXP2CONN_TX_P_23")
	)
	(segment
		(start 53.077872 -93.394784)
		(end 49.359566 -97.11309)
		(width 0.1016)
		(layer "In5.Cu")
		(net "SAS_EXP2CONN_TX_P_23")
	)
	(segment
		(start 132.387594 -91.350592)
		(end 132.207 -91.169998)
		(width 0.1016)
		(layer "In5.Cu")
		(net "SAS_EXP2CONN_TX_P_23")
	)
	(segment
		(start 135.0391 -142.024354)
		(end 135.0391 -142.0241)
		(width 0.1016)
		(layer "In5.Cu")
		(net "SAS_EXP2CONN_TX_P_23")
	)
	(segment
		(start 45.796962 -109.056424)
		(end 45.485812 -109.367574)
		(width 0.1016)
		(layer "In5.Cu")
		(net "SAS_EXP2CONN_TX_P_23")
	)
	(segment
		(start 133.731 -92.767658)
		(end 133.731 -92.236036)
		(width 0.1016)
		(layer "In5.Cu")
		(net "SAS_EXP2CONN_TX_P_23")
	)
	(segment
		(start 53.2638 -82.804)
		(end 53.2638 -92.945712)
		(width 0.1016)
		(layer "In5.Cu")
		(net "SAS_EXP2CONN_TX_P_23")
	)
	(segment
		(start 129.794 -124.615194)
		(end 129.794 -97.5614)
		(width 0.1016)
		(layer "In5.Cu")
		(net "SAS_EXP2CONN_TX_P_23")
	)
	(segment
		(start 29.03982 -125.81382)
		(end 29.040074 -125.81382)
		(width 0.1016)
		(layer "In5.Cu")
		(net "SAS_EXP2CONN_TX_P_23")
	)
	(segment
		(start 119.6721 -157.391354)
		(end 135.0391 -142.024354)
		(width 0.1016)
		(layer "In5.Cu")
		(net "SAS_EXP2CONN_TX_P_23")
	)
	(arc
		(start 132.6642 -91.465146)
		(mid 132.51451 -91.435371)
		(end 132.387594 -91.350592)
		(width 0.1016)
		(layer "In5.Cu")
		(net "SAS_EXP2CONN_TX_P_23")
	)
	(arc
		(start 117.924326 -158.115)
		(mid 118.870165 -157.926972)
		(end 119.6721 -157.391354)
		(width 0.1016)
		(layer "In5.Cu")
		(net "SAS_EXP2CONN_TX_P_23")
	)
	(arc
		(start 54.2798 -153.797)
		(mid 54.772612 -153.895026)
		(end 55.19039 -154.17419)
		(width 0.1016)
		(layer "In5.Cu")
		(net "SAS_EXP2CONN_TX_P_23")
	)
	(arc
		(start 133.4516 -91.6686)
		(mid 133.226233 -91.517952)
		(end 132.960364 -91.465146)
		(width 0.1016)
		(layer "In5.Cu")
		(net "SAS_EXP2CONN_TX_P_23")
	)
	(arc
		(start 53.2638 -92.945712)
		(mid 53.215464 -93.188716)
		(end 53.077872 -93.394784)
		(width 0.1016)
		(layer "In5.Cu")
		(net "SAS_EXP2CONN_TX_P_23")
	)
	(arc
		(start 135.636 -132.343144)
		(mid 135.470907 -131.513456)
		(end 135.001 -130.81)
		(width 0.1016)
		(layer "In5.Cu")
		(net "SAS_EXP2CONN_TX_P_23")
	)
	(arc
		(start 49.359566 -97.11309)
		(mid 48.112718 -99.026175)
		(end 47.6758 -101.267514)
		(width 0.1016)
		(layer "In5.Cu")
		(net "SAS_EXP2CONN_TX_P_23")
	)
	(arc
		(start 47.6758 -104.520746)
		(mid 47.187509 -106.975461)
		(end 45.796962 -109.056424)
		(width 0.1016)
		(layer "In5.Cu")
		(net "SAS_EXP2CONN_TX_P_23")
	)
	(arc
		(start 133.731 -92.236036)
		(mid 133.678153 -91.970067)
		(end 133.527546 -91.744546)
		(width 0.1016)
		(layer "In5.Cu")
		(net "SAS_EXP2CONN_TX_P_23")
	)
	(arc
		(start 53.023008 -82.222594)
		(mid 53.201246 -82.489345)
		(end 53.2638 -82.804)
		(width 0.1016)
		(layer "In5.Cu")
		(net "SAS_EXP2CONN_TX_P_23")
	)
	(arc
		(start 133.5024 -93.3196)
		(mid 133.671581 -93.066353)
		(end 133.731 -92.767658)
		(width 0.1016)
		(layer "In5.Cu")
		(net "SAS_EXP2CONN_TX_P_23")
	)
	(arc
		(start 129.794 -97.5614)
		(mid 129.892026 -97.068588)
		(end 130.17119 -96.65081)
		(width 0.1016)
		(layer "In5.Cu")
		(net "SAS_EXP2CONN_TX_P_23")
	)
	(arc
		(start 58.848498 -157.832298)
		(mid 59.161631 -158.041527)
		(end 59.530996 -158.115)
		(width 0.1016)
		(layer "In5.Cu")
		(net "SAS_EXP2CONN_TX_P_23")
	)
	(arc
		(start 29.21 -153.162)
		(mid 29.913412 -153.632005)
		(end 30.743144 -153.797)
		(width 0.1016)
		(layer "In5.Cu")
		(net "SAS_EXP2CONN_TX_P_23")
	)
	(arc
		(start 130.4925 -126.3015)
		(mid 129.975541 -125.527816)
		(end 129.794 -124.615194)
		(width 0.1016)
		(layer "In5.Cu")
		(net "SAS_EXP2CONN_TX_P_23")
	)
	(arc
		(start 135.0391 -142.0241)
		(mid 135.480893 -141.36286)
		(end 135.636 -140.582904)
		(width 0.1016)
		(layer "In5.Cu")
		(net "SAS_EXP2CONN_TX_P_23")
	)
	(arc
		(start 29.040074 -125.81382)
		(mid 28.413848 -126.751122)
		(end 28.194 -127.856742)
		(width 0.1016)
		(layer "In5.Cu")
		(net "SAS_EXP2CONN_TX_P_23")
	)
	(arc
		(start 28.194 -150.70963)
		(mid 28.45815 -152.036839)
		(end 29.21 -153.162)
		(width 0.1016)
		(layer "In5.Cu")
		(net "SAS_EXP2CONN_TX_P_23")
	)
	(segment
		(start 199.263 -164.592)
		(end 199.009 -164.846)
		(width 0.254)
		(layer "F.Cu")
		(net "P3V3_PG")
	)
	(segment
		(start 276.352 -116.2685)
		(end 276.352 -117.094)
		(width 0.254)
		(layer "F.Cu")
		(net "P3V3_PG")
	)
	(segment
		(start 199.771 -164.592)
		(end 199.263 -164.592)
		(width 0.254)
		(layer "F.Cu")
		(net "P3V3_PG")
	)
	(segment
		(start 197.9295 -164.846)
		(end 199.009 -164.846)
		(width 0.254)
		(layer "F.Cu")
		(net "P3V3_PG")
	)
	(via
		(at 199.009 -164.846)
		(size 0.5588)
		(drill 0.3048)
		(layers "F.Cu" "B.Cu")
		(net "P3V3_PG")
	)
	(via
		(at 251.206 -167.513)
		(size 0.5588)
		(drill 0.3048)
		(layers "F.Cu" "B.Cu")
		(net "P3V3_PG")
	)
	(via
		(at 199.771 -164.592)
		(size 0.7112)
		(drill 0.3556)
		(layers "F.Cu" "B.Cu")
		(net "P3V3_PG")
	)
	(via
		(at 276.352 -117.094)
		(size 0.508)
		(drill 0.254)
		(layers "F.Cu" "B.Cu")
		(net "P3V3_PG")
	)
	(segment
		(start 230.632 -168.021)
		(end 234.6198 -164.0332)
		(width 0.254)
		(layer "In2.Cu")
		(net "P3V3_PG")
	)
	(segment
		(start 247.7262 -164.0332)
		(end 251.206 -167.513)
		(width 0.254)
		(layer "In2.Cu")
		(net "P3V3_PG")
	)
	(segment
		(start 199.009 -164.846)
		(end 202.184 -168.021)
		(width 0.254)
		(layer "In2.Cu")
		(net "P3V3_PG")
	)
	(segment
		(start 202.184 -168.021)
		(end 230.632 -168.021)
		(width 0.254)
		(layer "In2.Cu")
		(net "P3V3_PG")
	)
	(segment
		(start 234.6198 -164.0332)
		(end 247.7262 -164.0332)
		(width 0.254)
		(layer "In2.Cu")
		(net "P3V3_PG")
	)
	(segment
		(start 251.206 -138.811)
		(end 251.206 -167.513)
		(width 0.254)
		(layer "In5.Cu")
		(net "P3V3_PG")
	)
	(segment
		(start 266.446 -127)
		(end 251.74829 -127)
		(width 0.254)
		(layer "In5.Cu")
		(net "P3V3_PG")
	)
	(segment
		(start 251.74829 -127)
		(end 250.7361 -128.01219)
		(width 0.254)
		(layer "In5.Cu")
		(net "P3V3_PG")
	)
	(segment
		(start 250.7361 -138.3411)
		(end 251.206 -138.811)
		(width 0.254)
		(layer "In5.Cu")
		(net "P3V3_PG")
	)
	(segment
		(start 250.7361 -128.01219)
		(end 250.7361 -138.3411)
		(width 0.254)
		(layer "In5.Cu")
		(net "P3V3_PG")
	)
	(segment
		(start 276.352 -117.094)
		(end 266.446 -127)
		(width 0.254)
		(layer "In5.Cu")
		(net "P3V3_PG")
	)
	(segment
		(start 41.901618 -80.720438)
		(end 41.926764 -80.720438)
		(width 0.1016)
		(layer "F.Cu")
		(net "SAS_EXP2CONN_TX_P_20")
	)
	(segment
		(start 132.111496 -87.39505)
		(end 133.400038 -87.39505)
		(width 0.1016)
		(layer "F.Cu")
		(net "SAS_EXP2CONN_TX_P_20")
	)
	(segment
		(start 131.5974 -87.249)
		(end 131.881118 -87.249)
		(width 0.1016)
		(layer "F.Cu")
		(net "SAS_EXP2CONN_TX_P_20")
	)
	(segment
		(start 133.485382 -87.359744)
		(end 133.731 -87.114126)
		(width 0.1016)
		(layer "F.Cu")
		(net "SAS_EXP2CONN_TX_P_20")
	)
	(segment
		(start 41.800018 -79.590138)
		(end 41.800018 -80.618838)
		(width 0.1016)
		(layer "F.Cu")
		(net "SAS_EXP2CONN_TX_P_20")
	)
	(segment
		(start 131.953 -87.278718)
		(end 132.039614 -87.365332)
		(width 0.1016)
		(layer "F.Cu")
		(net "SAS_EXP2CONN_TX_P_20")
	)
	(segment
		(start 42.028364 -80.822038)
		(end 42.028364 -82.984086)
		(width 0.1016)
		(layer "F.Cu")
		(net "SAS_EXP2CONN_TX_P_20")
	)
	(segment
		(start 41.907968 -83.27517)
		(end 41.693338 -83.489546)
		(width 0.1016)
		(layer "F.Cu")
		(net "SAS_EXP2CONN_TX_P_20")
	)
	(via
		(at 41.693338 -83.489546)
		(size 0.5588)
		(drill 0.3048)
		(layers "F.Cu" "B.Cu")
		(net "SAS_EXP2CONN_TX_P_20")
	)
	(via
		(at 133.731 -87.114126)
		(size 0.5588)
		(drill 0.3048)
		(layers "F.Cu" "B.Cu")
		(net "SAS_EXP2CONN_TX_P_20")
	)
	(arc
		(start 41.800018 -80.618838)
		(mid 41.829776 -80.69068)
		(end 41.901618 -80.720438)
		(width 0.1016)
		(layer "F.Cu")
		(net "SAS_EXP2CONN_TX_P_20")
	)
	(arc
		(start 41.926764 -80.720438)
		(mid 41.998606 -80.750196)
		(end 42.028364 -80.822038)
		(width 0.1016)
		(layer "F.Cu")
		(net "SAS_EXP2CONN_TX_P_20")
	)
	(arc
		(start 132.039614 -87.365332)
		(mid 132.072608 -87.387315)
		(end 132.111496 -87.39505)
		(width 0.1016)
		(layer "F.Cu")
		(net "SAS_EXP2CONN_TX_P_20")
	)
	(arc
		(start 131.881118 -87.249)
		(mid 131.920013 -87.256719)
		(end 131.953 -87.278718)
		(width 0.1016)
		(layer "F.Cu")
		(net "SAS_EXP2CONN_TX_P_20")
	)
	(arc
		(start 133.400038 -87.39505)
		(mid 133.446223 -87.385881)
		(end 133.485382 -87.359744)
		(width 0.1016)
		(layer "F.Cu")
		(net "SAS_EXP2CONN_TX_P_20")
	)
	(arc
		(start 42.028364 -82.984086)
		(mid 41.997125 -83.141606)
		(end 41.907968 -83.27517)
		(width 0.1016)
		(layer "F.Cu")
		(net "SAS_EXP2CONN_TX_P_20")
	)
	(segment
		(start 134.848346 -87.4268)
		(end 134.1882 -87.4268)
		(width 0.1016)
		(layer "In5.Cu")
		(net "SAS_EXP2CONN_TX_P_20")
	)
	(segment
		(start 133.941312 -87.324692)
		(end 133.731 -87.114126)
		(width 0.1016)
		(layer "In5.Cu")
		(net "SAS_EXP2CONN_TX_P_20")
	)
	(segment
		(start 135.2931 -95.4659)
		(end 136.0805 -94.6785)
		(width 0.1016)
		(layer "In5.Cu")
		(net "SAS_EXP2CONN_TX_P_20")
	)
	(segment
		(start 42.24782 -85.64118)
		(end 44.163742 -87.557102)
		(width 0.1016)
		(layer "In5.Cu")
		(net "SAS_EXP2CONN_TX_P_20")
	)
	(segment
		(start 135.633206 -87.753952)
		(end 135.628888 -87.749634)
		(width 0.1016)
		(layer "In5.Cu")
		(net "SAS_EXP2CONN_TX_P_20")
	)
	(segment
		(start 136.4742 -93.728032)
		(end 136.4742 -88.955118)
		(width 0.1016)
		(layer "In5.Cu")
		(net "SAS_EXP2CONN_TX_P_20")
	)
	(segment
		(start 44.246546 -92.486734)
		(end 44.246546 -92.818458)
		(width 0.1016)
		(layer "In5.Cu")
		(net "SAS_EXP2CONN_TX_P_20")
	)
	(segment
		(start 42.048684 -97.293684)
		(end 42.048684 -103.974138)
		(width 0.1016)
		(layer "In5.Cu")
		(net "SAS_EXP2CONN_TX_P_20")
	)
	(segment
		(start 21.971 -126.212346)
		(end 21.971 -152.302464)
		(width 0.1016)
		(layer "In5.Cu")
		(net "SAS_EXP2CONN_TX_P_20")
	)
	(segment
		(start 22.63902 -153.916126)
		(end 27.198574 -158.47568)
		(width 0.1016)
		(layer "In5.Cu")
		(net "SAS_EXP2CONN_TX_P_20")
	)
	(segment
		(start 141.097 -142.828264)
		(end 141.097 -130.235198)
		(width 0.1016)
		(layer "In5.Cu")
		(net "SAS_EXP2CONN_TX_P_20")
	)
	(segment
		(start 22.639274 -153.916126)
		(end 22.63902 -153.916126)
		(width 0.1016)
		(layer "In5.Cu")
		(net "SAS_EXP2CONN_TX_P_20")
	)
	(segment
		(start 121.793 -162.941)
		(end 140.525246 -144.208754)
		(width 0.1016)
		(layer "In5.Cu")
		(net "SAS_EXP2CONN_TX_P_20")
	)
	(segment
		(start 135.001 -122.74169)
		(end 135.001 -96.171004)
		(width 0.1016)
		(layer "In5.Cu")
		(net "SAS_EXP2CONN_TX_P_20")
	)
	(segment
		(start 136.219946 -88.340946)
		(end 135.632952 -87.753952)
		(width 0.1016)
		(layer "In5.Cu")
		(net "SAS_EXP2CONN_TX_P_20")
	)
	(segment
		(start 48.729392 -159.219392)
		(end 51.9684 -162.4584)
		(width 0.1016)
		(layer "In5.Cu")
		(net "SAS_EXP2CONN_TX_P_20")
	)
	(segment
		(start 42.048684 -103.974138)
		(end 42.04843 -103.973884)
		(width 0.1016)
		(layer "In5.Cu")
		(net "SAS_EXP2CONN_TX_P_20")
	)
	(segment
		(start 54.1147 -163.3474)
		(end 120.812306 -163.3474)
		(width 0.1016)
		(layer "In5.Cu")
		(net "SAS_EXP2CONN_TX_P_20")
	)
	(segment
		(start 44.246546 -92.818458)
		(end 44.2468 -92.818712)
		(width 0.1016)
		(layer "In5.Cu")
		(net "SAS_EXP2CONN_TX_P_20")
	)
	(segment
		(start 41.693338 -83.489546)
		(end 41.848786 -83.644994)
		(width 0.1016)
		(layer "In5.Cu")
		(net "SAS_EXP2CONN_TX_P_20")
	)
	(segment
		(start 41.9608 -83.915504)
		(end 41.9608 -84.947506)
		(width 0.1016)
		(layer "In5.Cu")
		(net "SAS_EXP2CONN_TX_P_20")
	)
	(segment
		(start 140.425932 -128.614932)
		(end 135.317992 -123.506992)
		(width 0.1016)
		(layer "In5.Cu")
		(net "SAS_EXP2CONN_TX_P_20")
	)
	(segment
		(start 28.474162 -159.004)
		(end 48.2092 -159.004)
		(width 0.1016)
		(layer "In5.Cu")
		(net "SAS_EXP2CONN_TX_P_20")
	)
	(segment
		(start 135.632952 -87.753952)
		(end 135.633206 -87.753952)
		(width 0.1016)
		(layer "In5.Cu")
		(net "SAS_EXP2CONN_TX_P_20")
	)
	(segment
		(start 44.2468 -87.757)
		(end 44.246546 -92.486734)
		(width 0.1016)
		(layer "In5.Cu")
		(net "SAS_EXP2CONN_TX_P_20")
	)
	(segment
		(start 43.07332 -95.65132)
		(end 42.485564 -96.23933)
		(width 0.1016)
		(layer "In5.Cu")
		(net "SAS_EXP2CONN_TX_P_20")
	)
	(segment
		(start 41.371774 -105.60812)
		(end 22.8219 -124.15774)
		(width 0.1016)
		(layer "In5.Cu")
		(net "SAS_EXP2CONN_TX_P_20")
	)
	(arc
		(start 136.4742 -88.955118)
		(mid 136.408231 -88.622707)
		(end 136.219946 -88.340946)
		(width 0.1016)
		(layer "In5.Cu")
		(net "SAS_EXP2CONN_TX_P_20")
	)
	(arc
		(start 48.2092 -159.004)
		(mid 48.49071 -159.059978)
		(end 48.729392 -159.219392)
		(width 0.1016)
		(layer "In5.Cu")
		(net "SAS_EXP2CONN_TX_P_20")
	)
	(arc
		(start 27.198574 -158.47568)
		(mid 27.783832 -158.866704)
		(end 28.474162 -159.004)
		(width 0.1016)
		(layer "In5.Cu")
		(net "SAS_EXP2CONN_TX_P_20")
	)
	(arc
		(start 22.8219 -124.15774)
		(mid 22.192141 -125.10043)
		(end 21.971 -126.212346)
		(width 0.1016)
		(layer "In5.Cu")
		(net "SAS_EXP2CONN_TX_P_20")
	)
	(arc
		(start 135.317992 -123.506992)
		(mid 135.083379 -123.155868)
		(end 135.001 -122.74169)
		(width 0.1016)
		(layer "In5.Cu")
		(net "SAS_EXP2CONN_TX_P_20")
	)
	(arc
		(start 42.04843 -103.973884)
		(mid 41.872637 -104.858306)
		(end 41.371774 -105.60812)
		(width 0.1016)
		(layer "In5.Cu")
		(net "SAS_EXP2CONN_TX_P_20")
	)
	(arc
		(start 134.1882 -87.4268)
		(mid 134.054591 -87.400317)
		(end 133.941312 -87.324692)
		(width 0.1016)
		(layer "In5.Cu")
		(net "SAS_EXP2CONN_TX_P_20")
	)
	(arc
		(start 41.848786 -83.644994)
		(mid 41.931714 -83.769105)
		(end 41.9608 -83.915504)
		(width 0.1016)
		(layer "In5.Cu")
		(net "SAS_EXP2CONN_TX_P_20")
	)
	(arc
		(start 120.812306 -163.3474)
		(mid 121.343045 -163.241678)
		(end 121.793 -162.941)
		(width 0.1016)
		(layer "In5.Cu")
		(net "SAS_EXP2CONN_TX_P_20")
	)
	(arc
		(start 141.097 -130.235198)
		(mid 140.922651 -129.358303)
		(end 140.425932 -128.614932)
		(width 0.1016)
		(layer "In5.Cu")
		(net "SAS_EXP2CONN_TX_P_20")
	)
	(arc
		(start 21.971 -152.302464)
		(mid 22.144649 -153.175748)
		(end 22.639274 -153.916126)
		(width 0.1016)
		(layer "In5.Cu")
		(net "SAS_EXP2CONN_TX_P_20")
	)
	(arc
		(start 51.9684 -162.4584)
		(mid 52.953131 -163.116376)
		(end 54.1147 -163.3474)
		(width 0.1016)
		(layer "In5.Cu")
		(net "SAS_EXP2CONN_TX_P_20")
	)
	(arc
		(start 140.525246 -144.208754)
		(mid 140.948424 -143.575379)
		(end 141.097 -142.828264)
		(width 0.1016)
		(layer "In5.Cu")
		(net "SAS_EXP2CONN_TX_P_20")
	)
	(arc
		(start 44.163742 -87.557102)
		(mid 44.225106 -87.648801)
		(end 44.2468 -87.757)
		(width 0.1016)
		(layer "In5.Cu")
		(net "SAS_EXP2CONN_TX_P_20")
	)
	(arc
		(start 44.2468 -92.818712)
		(mid 43.941825 -94.351747)
		(end 43.07332 -95.65132)
		(width 0.1016)
		(layer "In5.Cu")
		(net "SAS_EXP2CONN_TX_P_20")
	)
	(arc
		(start 135.001 -96.171004)
		(mid 135.076908 -95.789391)
		(end 135.2931 -95.4659)
		(width 0.1016)
		(layer "In5.Cu")
		(net "SAS_EXP2CONN_TX_P_20")
	)
	(arc
		(start 42.485564 -96.23933)
		(mid 42.162201 -96.723042)
		(end 42.048684 -97.293684)
		(width 0.1016)
		(layer "In5.Cu")
		(net "SAS_EXP2CONN_TX_P_20")
	)
	(arc
		(start 41.9608 -84.947506)
		(mid 42.03527 -85.322923)
		(end 42.24782 -85.64118)
		(width 0.1016)
		(layer "In5.Cu")
		(net "SAS_EXP2CONN_TX_P_20")
	)
	(arc
		(start 136.0805 -94.6785)
		(mid 136.371878 -94.242422)
		(end 136.4742 -93.728032)
		(width 0.1016)
		(layer "In5.Cu")
		(net "SAS_EXP2CONN_TX_P_20")
	)
	(arc
		(start 135.628888 -87.749634)
		(mid 135.270728 -87.510568)
		(end 134.848346 -87.4268)
		(width 0.1016)
		(layer "In5.Cu")
		(net "SAS_EXP2CONN_TX_P_20")
	)
	(segment
		(start 42.371264 -80.822038)
		(end 42.371264 -82.984086)
		(width 0.1016)
		(layer "F.Cu")
		(net "SAS_EXP2CONN_TX_N_20")
	)
	(segment
		(start 42.517314 -83.336638)
		(end 42.670222 -83.489546)
		(width 0.1016)
		(layer "F.Cu")
		(net "SAS_EXP2CONN_TX_N_20")
	)
	(segment
		(start 42.599864 -79.590138)
		(end 42.599864 -80.618838)
		(width 0.1016)
		(layer "F.Cu")
		(net "SAS_EXP2CONN_TX_N_20")
	)
	(segment
		(start 131.5974 -87.884)
		(end 131.881118 -87.884)
		(width 0.1016)
		(layer "F.Cu")
		(net "SAS_EXP2CONN_TX_N_20")
	)
	(segment
		(start 42.498264 -80.720438)
		(end 42.472864 -80.720438)
		(width 0.1016)
		(layer "F.Cu")
		(net "SAS_EXP2CONN_TX_N_20")
	)
	(segment
		(start 132.111496 -87.73795)
		(end 133.35 -87.73795)
		(width 0.1016)
		(layer "F.Cu")
		(net "SAS_EXP2CONN_TX_N_20")
	)
	(segment
		(start 131.953 -87.854282)
		(end 132.039614 -87.767668)
		(width 0.1016)
		(layer "F.Cu")
		(net "SAS_EXP2CONN_TX_N_20")
	)
	(segment
		(start 133.520434 -87.808562)
		(end 133.731 -88.019128)
		(width 0.1016)
		(layer "F.Cu")
		(net "SAS_EXP2CONN_TX_N_20")
	)
	(via
		(at 133.731 -88.019128)
		(size 0.5588)
		(drill 0.3048)
		(layers "F.Cu" "B.Cu")
		(net "SAS_EXP2CONN_TX_N_20")
	)
	(via
		(at 42.670222 -83.489546)
		(size 0.5588)
		(drill 0.3048)
		(layers "F.Cu" "B.Cu")
		(net "SAS_EXP2CONN_TX_N_20")
	)
	(arc
		(start 42.472864 -80.720438)
		(mid 42.401022 -80.750196)
		(end 42.371264 -80.822038)
		(width 0.1016)
		(layer "F.Cu")
		(net "SAS_EXP2CONN_TX_N_20")
	)
	(arc
		(start 42.371264 -82.984086)
		(mid 42.409218 -83.174893)
		(end 42.517314 -83.336638)
		(width 0.1016)
		(layer "F.Cu")
		(net "SAS_EXP2CONN_TX_N_20")
	)
	(arc
		(start 42.599864 -80.618838)
		(mid 42.570106 -80.69068)
		(end 42.498264 -80.720438)
		(width 0.1016)
		(layer "F.Cu")
		(net "SAS_EXP2CONN_TX_N_20")
	)
	(arc
		(start 133.35 -87.73795)
		(mid 133.442244 -87.756299)
		(end 133.520434 -87.808562)
		(width 0.1016)
		(layer "F.Cu")
		(net "SAS_EXP2CONN_TX_N_20")
	)
	(arc
		(start 132.039614 -87.767668)
		(mid 132.072608 -87.745685)
		(end 132.111496 -87.73795)
		(width 0.1016)
		(layer "F.Cu")
		(net "SAS_EXP2CONN_TX_N_20")
	)
	(arc
		(start 131.881118 -87.884)
		(mid 131.920013 -87.876281)
		(end 131.953 -87.854282)
		(width 0.1016)
		(layer "F.Cu")
		(net "SAS_EXP2CONN_TX_N_20")
	)
	(segment
		(start 136.144 -88.954864)
		(end 136.143746 -88.955118)
		(width 0.1016)
		(layer "In5.Cu")
		(net "SAS_EXP2CONN_TX_N_20")
	)
	(segment
		(start 135.21182 -123.86818)
		(end 135.084312 -123.740672)
		(width 0.1016)
		(layer "In5.Cu")
		(net "SAS_EXP2CONN_TX_N_20")
	)
	(segment
		(start 42.379138 -97.293684)
		(end 42.378884 -98.827844)
		(width 0.1016)
		(layer "In5.Cu")
		(net "SAS_EXP2CONN_TX_N_20")
	)
	(segment
		(start 135.05942 -95.23222)
		(end 135.84682 -94.44482)
		(width 0.1016)
		(layer "In5.Cu")
		(net "SAS_EXP2CONN_TX_N_20")
	)
	(segment
		(start 42.291 -84.023708)
		(end 42.291 -84.947506)
		(width 0.1016)
		(layer "In5.Cu")
		(net "SAS_EXP2CONN_TX_N_20")
	)
	(segment
		(start 22.3012 -126.2126)
		(end 22.3012 -152.302718)
		(width 0.1016)
		(layer "In5.Cu")
		(net "SAS_EXP2CONN_TX_N_20")
	)
	(segment
		(start 133.855206 -87.894922)
		(end 133.731 -88.019128)
		(width 0.1016)
		(layer "In5.Cu")
		(net "SAS_EXP2CONN_TX_N_20")
	)
	(segment
		(start 42.670222 -83.489546)
		(end 42.669968 -83.489546)
		(width 0.1016)
		(layer "In5.Cu")
		(net "SAS_EXP2CONN_TX_N_20")
	)
	(segment
		(start 51.106324 -161.128964)
		(end 52.20208 -162.22472)
		(width 0.1016)
		(layer "In5.Cu")
		(net "SAS_EXP2CONN_TX_N_20")
	)
	(segment
		(start 42.378884 -101.97846)
		(end 42.378884 -103.973884)
		(width 0.1016)
		(layer "In5.Cu")
		(net "SAS_EXP2CONN_TX_N_20")
	)
	(segment
		(start 50.730912 -160.43402)
		(end 50.946558 -160.649412)
		(width 0.1016)
		(layer "In5.Cu")
		(net "SAS_EXP2CONN_TX_N_20")
	)
	(segment
		(start 42.500804 -83.55965)
		(end 42.47134 -83.589114)
		(width 0.1016)
		(layer "In5.Cu")
		(net "SAS_EXP2CONN_TX_N_20")
	)
	(segment
		(start 129.94132 -154.32532)
		(end 130.175 -154.091894)
		(width 0.1016)
		(layer "In5.Cu")
		(net "SAS_EXP2CONN_TX_N_20")
	)
	(segment
		(start 135.98652 -88.574626)
		(end 135.395208 -87.983314)
		(width 0.1016)
		(layer "In5.Cu")
		(net "SAS_EXP2CONN_TX_N_20")
	)
	(segment
		(start 54.1147 -163.0172)
		(end 120.812052 -163.0172)
		(width 0.1016)
		(layer "In5.Cu")
		(net "SAS_EXP2CONN_TX_N_20")
	)
	(segment
		(start 134.6708 -122.741436)
		(end 134.6708 -96.17075)
		(width 0.1016)
		(layer "In5.Cu")
		(net "SAS_EXP2CONN_TX_N_20")
	)
	(segment
		(start 135.05942 -95.232474)
		(end 135.05942 -95.23222)
		(width 0.1016)
		(layer "In5.Cu")
		(net "SAS_EXP2CONN_TX_N_20")
	)
	(segment
		(start 42.604944 -101.22154)
		(end 42.604944 -101.52634)
		(width 0.1016)
		(layer "In5.Cu")
		(net "SAS_EXP2CONN_TX_N_20")
	)
	(segment
		(start 42.604944 -99.7077)
		(end 42.604944 -100.0125)
		(width 0.1016)
		(layer "In5.Cu")
		(net "SAS_EXP2CONN_TX_N_20")
	)
	(segment
		(start 28.474416 -158.6738)
		(end 48.208946 -158.6738)
		(width 0.1016)
		(layer "In5.Cu")
		(net "SAS_EXP2CONN_TX_N_20")
	)
	(segment
		(start 140.192506 -128.848612)
		(end 135.21182 -123.867926)
		(width 0.1016)
		(layer "In5.Cu")
		(net "SAS_EXP2CONN_TX_N_20")
	)
	(segment
		(start 41.6052 -105.8418)
		(end 23.05558 -124.39142)
		(width 0.1016)
		(layer "In5.Cu")
		(net "SAS_EXP2CONN_TX_N_20")
	)
	(segment
		(start 42.378884 -98.827844)
		(end 42.378884 -99.25558)
		(width 0.1016)
		(layer "In5.Cu")
		(net "SAS_EXP2CONN_TX_N_20")
	)
	(segment
		(start 43.307 -95.885)
		(end 42.719244 -96.47301)
		(width 0.1016)
		(layer "In5.Cu")
		(net "SAS_EXP2CONN_TX_N_20")
	)
	(segment
		(start 135.21182 -123.867926)
		(end 135.21182 -123.86818)
		(width 0.1016)
		(layer "In5.Cu")
		(net "SAS_EXP2CONN_TX_N_20")
	)
	(segment
		(start 121.55932 -162.707574)
		(end 121.55932 -162.70732)
		(width 0.1016)
		(layer "In5.Cu")
		(net "SAS_EXP2CONN_TX_N_20")
	)
	(segment
		(start 136.144 -93.727778)
		(end 136.144 -88.954864)
		(width 0.1016)
		(layer "In5.Cu")
		(net "SAS_EXP2CONN_TX_N_20")
	)
	(segment
		(start 140.7668 -142.828264)
		(end 140.7668 -130.235198)
		(width 0.1016)
		(layer "In5.Cu")
		(net "SAS_EXP2CONN_TX_N_20")
	)
	(segment
		(start 48.963072 -158.985712)
		(end 50.25136 -160.274)
		(width 0.1016)
		(layer "In5.Cu")
		(net "SAS_EXP2CONN_TX_N_20")
	)
	(segment
		(start 121.55932 -162.70732)
		(end 129.94132 -154.32532)
		(width 0.1016)
		(layer "In5.Cu")
		(net "SAS_EXP2CONN_TX_N_20")
	)
	(segment
		(start 22.8727 -153.682446)
		(end 27.432254 -158.242)
		(width 0.1016)
		(layer "In5.Cu")
		(net "SAS_EXP2CONN_TX_N_20")
	)
	(segment
		(start 42.4815 -85.4075)
		(end 44.397422 -87.323422)
		(width 0.1016)
		(layer "In5.Cu")
		(net "SAS_EXP2CONN_TX_N_20")
	)
	(segment
		(start 130.175 -154.091894)
		(end 140.29182 -143.975074)
		(width 0.1016)
		(layer "In5.Cu")
		(net "SAS_EXP2CONN_TX_N_20")
	)
	(segment
		(start 44.577 -87.757)
		(end 44.577 -92.818966)
		(width 0.1016)
		(layer "In5.Cu")
		(net "SAS_EXP2CONN_TX_N_20")
	)
	(segment
		(start 134.8486 -87.757)
		(end 134.1882 -87.757)
		(width 0.1016)
		(layer "In5.Cu")
		(net "SAS_EXP2CONN_TX_N_20")
	)
	(segment
		(start 42.378884 -100.46462)
		(end 42.378884 -100.76942)
		(width 0.1016)
		(layer "In5.Cu")
		(net "SAS_EXP2CONN_TX_N_20")
	)
	(arc
		(start 44.577 -92.818966)
		(mid 44.246939 -94.478294)
		(end 43.307 -95.885)
		(width 0.1016)
		(layer "In5.Cu")
		(net "SAS_EXP2CONN_TX_N_20")
	)
	(arc
		(start 140.29182 -143.975074)
		(mid 140.643389 -143.448913)
		(end 140.7668 -142.828264)
		(width 0.1016)
		(layer "In5.Cu")
		(net "SAS_EXP2CONN_TX_N_20")
	)
	(arc
		(start 42.378884 -103.973884)
		(mid 42.177804 -104.984781)
		(end 41.6052 -105.8418)
		(width 0.1016)
		(layer "In5.Cu")
		(net "SAS_EXP2CONN_TX_N_20")
	)
	(arc
		(start 42.378884 -100.76942)
		(mid 42.408123 -100.896081)
		(end 42.491914 -100.99548)
		(width 0.1016)
		(layer "In5.Cu")
		(net "SAS_EXP2CONN_TX_N_20")
	)
	(arc
		(start 42.604944 -100.0125)
		(mid 42.575705 -100.139161)
		(end 42.491914 -100.23856)
		(width 0.1016)
		(layer "In5.Cu")
		(net "SAS_EXP2CONN_TX_N_20")
	)
	(arc
		(start 136.143746 -88.955118)
		(mid 136.102981 -88.749235)
		(end 135.98652 -88.574626)
		(width 0.1016)
		(layer "In5.Cu")
		(net "SAS_EXP2CONN_TX_N_20")
	)
	(arc
		(start 135.395208 -87.983314)
		(mid 135.144408 -87.815798)
		(end 134.8486 -87.757)
		(width 0.1016)
		(layer "In5.Cu")
		(net "SAS_EXP2CONN_TX_N_20")
	)
	(arc
		(start 134.1882 -87.757)
		(mid 134.007988 -87.792846)
		(end 133.855206 -87.894922)
		(width 0.1016)
		(layer "In5.Cu")
		(net "SAS_EXP2CONN_TX_N_20")
	)
	(arc
		(start 27.432254 -158.242)
		(mid 27.910401 -158.561518)
		(end 28.474416 -158.6738)
		(width 0.1016)
		(layer "In5.Cu")
		(net "SAS_EXP2CONN_TX_N_20")
	)
	(arc
		(start 51.026568 -160.889188)
		(mid 51.037485 -161.01871)
		(end 51.106324 -161.128964)
		(width 0.1016)
		(layer "In5.Cu")
		(net "SAS_EXP2CONN_TX_N_20")
	)
	(arc
		(start 42.491914 -101.7524)
		(mid 42.408077 -101.851776)
		(end 42.378884 -101.97846)
		(width 0.1016)
		(layer "In5.Cu")
		(net "SAS_EXP2CONN_TX_N_20")
	)
	(arc
		(start 42.669968 -83.489546)
		(mid 42.578429 -83.507812)
		(end 42.500804 -83.55965)
		(width 0.1016)
		(layer "In5.Cu")
		(net "SAS_EXP2CONN_TX_N_20")
	)
	(arc
		(start 140.7668 -130.235198)
		(mid 140.617537 -129.484802)
		(end 140.192506 -128.848612)
		(width 0.1016)
		(layer "In5.Cu")
		(net "SAS_EXP2CONN_TX_N_20")
	)
	(arc
		(start 42.47134 -83.589114)
		(mid 42.337894 -83.78845)
		(end 42.291 -84.023708)
		(width 0.1016)
		(layer "In5.Cu")
		(net "SAS_EXP2CONN_TX_N_20")
	)
	(arc
		(start 22.3012 -152.302718)
		(mid 22.449728 -153.049421)
		(end 22.8727 -153.682446)
		(width 0.1016)
		(layer "In5.Cu")
		(net "SAS_EXP2CONN_TX_N_20")
	)
	(arc
		(start 52.20208 -162.22472)
		(mid 53.079568 -162.811195)
		(end 54.1147 -163.0172)
		(width 0.1016)
		(layer "In5.Cu")
		(net "SAS_EXP2CONN_TX_N_20")
	)
	(arc
		(start 135.084312 -123.740672)
		(mid 134.778149 -123.282189)
		(end 134.6708 -122.741436)
		(width 0.1016)
		(layer "In5.Cu")
		(net "SAS_EXP2CONN_TX_N_20")
	)
	(arc
		(start 120.812052 -163.0172)
		(mid 121.216483 -162.936696)
		(end 121.55932 -162.707574)
		(width 0.1016)
		(layer "In5.Cu")
		(net "SAS_EXP2CONN_TX_N_20")
	)
	(arc
		(start 42.491914 -100.23856)
		(mid 42.408077 -100.337936)
		(end 42.378884 -100.46462)
		(width 0.1016)
		(layer "In5.Cu")
		(net "SAS_EXP2CONN_TX_N_20")
	)
	(arc
		(start 42.491914 -99.48164)
		(mid 42.575751 -99.581016)
		(end 42.604944 -99.7077)
		(width 0.1016)
		(layer "In5.Cu")
		(net "SAS_EXP2CONN_TX_N_20")
	)
	(arc
		(start 50.491136 -160.35401)
		(mid 50.620681 -160.36506)
		(end 50.730912 -160.43402)
		(width 0.1016)
		(layer "In5.Cu")
		(net "SAS_EXP2CONN_TX_N_20")
	)
	(arc
		(start 48.208946 -158.6738)
		(mid 48.617023 -158.754766)
		(end 48.963072 -158.985712)
		(width 0.1016)
		(layer "In5.Cu")
		(net "SAS_EXP2CONN_TX_N_20")
	)
	(arc
		(start 50.946558 -160.649412)
		(mid 51.015492 -160.759642)
		(end 51.026568 -160.889188)
		(width 0.1016)
		(layer "In5.Cu")
		(net "SAS_EXP2CONN_TX_N_20")
	)
	(arc
		(start 135.84682 -94.44482)
		(mid 136.066692 -94.115853)
		(end 136.144 -93.727778)
		(width 0.1016)
		(layer "In5.Cu")
		(net "SAS_EXP2CONN_TX_N_20")
	)
	(arc
		(start 44.397422 -87.323422)
		(mid 44.530341 -87.522349)
		(end 44.577 -87.757)
		(width 0.1016)
		(layer "In5.Cu")
		(net "SAS_EXP2CONN_TX_N_20")
	)
	(arc
		(start 42.719244 -96.47301)
		(mid 42.467573 -96.849523)
		(end 42.379138 -97.293684)
		(width 0.1016)
		(layer "In5.Cu")
		(net "SAS_EXP2CONN_TX_N_20")
	)
	(arc
		(start 42.491914 -100.99548)
		(mid 42.575751 -101.094856)
		(end 42.604944 -101.22154)
		(width 0.1016)
		(layer "In5.Cu")
		(net "SAS_EXP2CONN_TX_N_20")
	)
	(arc
		(start 42.378884 -99.25558)
		(mid 42.408123 -99.382241)
		(end 42.491914 -99.48164)
		(width 0.1016)
		(layer "In5.Cu")
		(net "SAS_EXP2CONN_TX_N_20")
	)
	(arc
		(start 42.604944 -101.52634)
		(mid 42.575705 -101.653001)
		(end 42.491914 -101.7524)
		(width 0.1016)
		(layer "In5.Cu")
		(net "SAS_EXP2CONN_TX_N_20")
	)
	(arc
		(start 50.25136 -160.274)
		(mid 50.361579 -160.342997)
		(end 50.491136 -160.35401)
		(width 0.1016)
		(layer "In5.Cu")
		(net "SAS_EXP2CONN_TX_N_20")
	)
	(arc
		(start 134.6708 -96.17075)
		(mid 134.771857 -95.662994)
		(end 135.05942 -95.232474)
		(width 0.1016)
		(layer "In5.Cu")
		(net "SAS_EXP2CONN_TX_N_20")
	)
	(arc
		(start 42.291 -84.947506)
		(mid 42.340516 -85.196439)
		(end 42.4815 -85.4075)
		(width 0.1016)
		(layer "In5.Cu")
		(net "SAS_EXP2CONN_TX_N_20")
	)
	(arc
		(start 23.05558 -124.39142)
		(mid 22.497274 -125.226984)
		(end 22.3012 -126.2126)
		(width 0.1016)
		(layer "In5.Cu")
		(net "SAS_EXP2CONN_TX_N_20")
	)
	(segment
		(start 287.234884 -172.240194)
		(end 286.83966 -171.84497)
		(width 0.1143)
		(layer "F.Cu")
		(net "BMC_1V8_C_EN_R")
	)
	(via
		(at 280.035 -169.3672)
		(size 0.7112)
		(drill 0.3556)
		(layers "F.Cu" "B.Cu")
		(net "BMC_1V8_C_EN_R")
	)
	(via
		(at 286.83966 -171.84497)
		(size 0.508)
		(drill 0.254)
		(layers "F.Cu" "B.Cu")
		(net "BMC_1V8_C_EN_R")
	)
	(segment
		(start 283.393134 -171.163996)
		(end 283.648404 -171.419266)
		(width 0.1143)
		(layer "B.Cu")
		(net "BMC_1V8_C_EN_R")
	)
	(segment
		(start 281.831796 -171.163996)
		(end 283.393134 -171.163996)
		(width 0.1143)
		(layer "B.Cu")
		(net "BMC_1V8_C_EN_R")
	)
	(segment
		(start 286.222948 -171.419266)
		(end 286.648652 -171.84497)
		(width 0.1143)
		(layer "B.Cu")
		(net "BMC_1V8_C_EN_R")
	)
	(segment
		(start 277.1775 -166.37)
		(end 277.1775 -167.259)
		(width 0.1143)
		(layer "B.Cu")
		(net "BMC_1V8_C_EN_R")
	)
	(segment
		(start 277.1775 -167.259)
		(end 277.9395 -168.021)
		(width 0.1143)
		(layer "B.Cu")
		(net "BMC_1V8_C_EN_R")
	)
	(segment
		(start 283.648404 -171.419266)
		(end 286.222948 -171.419266)
		(width 0.1143)
		(layer "B.Cu")
		(net "BMC_1V8_C_EN_R")
	)
	(segment
		(start 280.035 -169.3672)
		(end 281.831796 -171.163996)
		(width 0.1143)
		(layer "B.Cu")
		(net "BMC_1V8_C_EN_R")
	)
	(segment
		(start 277.9395 -168.021)
		(end 278.6888 -168.021)
		(width 0.1143)
		(layer "B.Cu")
		(net "BMC_1V8_C_EN_R")
	)
	(segment
		(start 286.648652 -171.84497)
		(end 286.83966 -171.84497)
		(width 0.1143)
		(layer "B.Cu")
		(net "BMC_1V8_C_EN_R")
	)
	(segment
		(start 278.6888 -168.021)
		(end 280.035 -169.3672)
		(width 0.1143)
		(layer "B.Cu")
		(net "BMC_1V8_C_EN_R")
	)
	(segment
		(start 16.919448 -202.924156)
		(end 16.919448 -203.922376)
		(width 0.1143)
		(layer "F.Cu")
		(net "BMC_I2C10_EN")
	)
	(segment
		(start 16.833088 -203.836016)
		(end 16.919448 -203.922376)
		(width 0.1143)
		(layer "F.Cu")
		(net "BMC_I2C10_EN")
	)
	(segment
		(start 16.269208 -203.963016)
		(end 16.396208 -203.836016)
		(width 0.1143)
		(layer "F.Cu")
		(net "BMC_I2C10_EN")
	)
	(segment
		(start 16.919448 -203.922376)
		(end 16.919448 -205.258416)
		(width 0.1143)
		(layer "F.Cu")
		(net "BMC_I2C10_EN")
	)
	(segment
		(start 18.238216 -203.63688)
		(end 18.238216 -202.55738)
		(width 0.1143)
		(layer "F.Cu")
		(net "BMC_I2C10_EN")
	)
	(segment
		(start 16.396208 -203.836016)
		(end 16.833088 -203.836016)
		(width 0.1143)
		(layer "F.Cu")
		(net "BMC_I2C10_EN")
	)
	(segment
		(start 17.286224 -202.55738)
		(end 17.214088 -202.629516)
		(width 0.1143)
		(layer "F.Cu")
		(net "BMC_I2C10_EN")
	)
	(segment
		(start 16.269208 -205.258416)
		(end 16.269208 -203.963016)
		(width 0.1143)
		(layer "F.Cu")
		(net "BMC_I2C10_EN")
	)
	(segment
		(start 18.238216 -202.55738)
		(end 17.286224 -202.55738)
		(width 0.1143)
		(layer "F.Cu")
		(net "BMC_I2C10_EN")
	)
	(segment
		(start 17.214088 -202.629516)
		(end 16.919448 -202.924156)
		(width 0.1143)
		(layer "F.Cu")
		(net "BMC_I2C10_EN")
	)
	(via
		(at 18.238216 -203.63688)
		(size 0.7112)
		(drill 0.3556)
		(layers "F.Cu" "B.Cu")
		(net "BMC_I2C10_EN")
	)
	(segment
		(start 220.2815 -25.781)
		(end 221.6785 -25.781)
		(width 0.1143)
		(layer "F.Cu")
		(net "BMC_ID_LED_R")
	)
	(segment
		(start 220.091 -25.5905)
		(end 220.2815 -25.781)
		(width 0.1143)
		(layer "F.Cu")
		(net "BMC_ID_LED_R")
	)
	(segment
		(start 221.960948 -22.828504)
		(end 221.960948 -24.228552)
		(width 0.1143)
		(layer "F.Cu")
		(net "BMC_ID_LED_R")
	)
	(segment
		(start 221.960948 -24.228552)
		(end 221.6785 -24.511)
		(width 0.1143)
		(layer "F.Cu")
		(net "BMC_ID_LED_R")
	)
	(segment
		(start 221.6785 -25.781)
		(end 221.6785 -24.511)
		(width 0.1143)
		(layer "F.Cu")
		(net "BMC_ID_LED_R")
	)
	(via
		(at 221.6785 -24.511)
		(size 0.7112)
		(drill 0.3556)
		(layers "F.Cu" "B.Cu")
		(net "BMC_ID_LED_R")
	)
	(segment
		(start 23.059898 -191.020446)
		(end 23.059898 -194.624198)
		(width 0.1143)
		(layer "F.Cu")
		(net "I2C_IO_EXP_RESET#_PRST")
	)
	(segment
		(start 22.937216 -195.144644)
		(end 22.937216 -194.74688)
		(width 0.1143)
		(layer "F.Cu")
		(net "I2C_IO_EXP_RESET#_PRST")
	)
	(segment
		(start 23.059898 -194.624198)
		(end 22.937216 -194.74688)
		(width 0.1143)
		(layer "F.Cu")
		(net "I2C_IO_EXP_RESET#_PRST")
	)
	(segment
		(start 23.500588 -195.708016)
		(end 22.937216 -195.144644)
		(width 0.1143)
		(layer "F.Cu")
		(net "I2C_IO_EXP_RESET#_PRST")
	)
	(segment
		(start 24.580088 -195.898516)
		(end 24.389588 -195.708016)
		(width 0.1143)
		(layer "F.Cu")
		(net "I2C_IO_EXP_RESET#_PRST")
	)
	(segment
		(start 24.389588 -195.708016)
		(end 23.500588 -195.708016)
		(width 0.1143)
		(layer "F.Cu")
		(net "I2C_IO_EXP_RESET#_PRST")
	)
	(via
		(at 22.937216 -194.74688)
		(size 0.7112)
		(drill 0.3556)
		(layers "F.Cu" "B.Cu")
		(net "I2C_IO_EXP_RESET#_PRST")
	)
	(segment
		(start 90.932 -225.806)
		(end 91.2114 -226.0854)
		(width 0.1143)
		(layer "F.Cu")
		(net "I2C_IO_EXP_RESET#_FLT")
	)
	(segment
		(start 90.1065 -225.806)
		(end 90.932 -225.806)
		(width 0.1143)
		(layer "F.Cu")
		(net "I2C_IO_EXP_RESET#_FLT")
	)
	(segment
		(start 91.2114 -226.0854)
		(end 91.6686 -226.0854)
		(width 0.1143)
		(layer "F.Cu")
		(net "I2C_IO_EXP_RESET#_FLT")
	)
	(segment
		(start 88.2015 -226.822)
		(end 88.67775 -227.29825)
		(width 0.1143)
		(layer "F.Cu")
		(net "I2C_IO_EXP_RESET#_FLT")
	)
	(segment
		(start 88.67775 -227.29825)
		(end 89.82075 -227.29825)
		(width 0.1143)
		(layer "F.Cu")
		(net "I2C_IO_EXP_RESET#_FLT")
	)
	(segment
		(start 91.6686 -226.0854)
		(end 93.7006 -226.0854)
		(width 0.1143)
		(layer "F.Cu")
		(net "I2C_IO_EXP_RESET#_FLT")
	)
	(segment
		(start 90.1065 -226.822)
		(end 90.1065 -225.806)
		(width 0.1143)
		(layer "F.Cu")
		(net "I2C_IO_EXP_RESET#_FLT")
	)
	(segment
		(start 89.82075 -227.29825)
		(end 90.1065 -227.0125)
		(width 0.1143)
		(layer "F.Cu")
		(net "I2C_IO_EXP_RESET#_FLT")
	)
	(segment
		(start 90.1065 -227.0125)
		(end 90.1065 -226.822)
		(width 0.1143)
		(layer "F.Cu")
		(net "I2C_IO_EXP_RESET#_FLT")
	)
	(via
		(at 91.6686 -226.0854)
		(size 0.7112)
		(drill 0.3556)
		(layers "F.Cu" "B.Cu")
		(net "I2C_IO_EXP_RESET#_FLT")
	)
	(segment
		(start 18.873216 -214.24138)
		(end 18.873216 -215.19388)
		(width 0.1143)
		(layer "F.Cu")
		(net "I2C_IO_EXP_RESET#_PWR")
	)
	(segment
		(start 18.433542 -215.633554)
		(end 18.433542 -216.714578)
		(width 0.1143)
		(layer "F.Cu")
		(net "I2C_IO_EXP_RESET#_PWR")
	)
	(segment
		(start 20.016216 -214.24138)
		(end 20.016216 -214.81288)
		(width 0.1143)
		(layer "F.Cu")
		(net "I2C_IO_EXP_RESET#_PWR")
	)
	(segment
		(start 21.159216 -214.24138)
		(end 20.016216 -214.24138)
		(width 0.1143)
		(layer "F.Cu")
		(net "I2C_IO_EXP_RESET#_PWR")
	)
	(segment
		(start 18.873216 -215.19388)
		(end 18.433542 -215.633554)
		(width 0.1143)
		(layer "F.Cu")
		(net "I2C_IO_EXP_RESET#_PWR")
	)
	(segment
		(start 20.016216 -214.81288)
		(end 20.397216 -215.19388)
		(width 0.1143)
		(layer "F.Cu")
		(net "I2C_IO_EXP_RESET#_PWR")
	)
	(segment
		(start 20.016216 -214.24138)
		(end 18.873216 -214.24138)
		(width 0.1143)
		(layer "F.Cu")
		(net "I2C_IO_EXP_RESET#_PWR")
	)
	(via
		(at 20.397216 -215.19388)
		(size 0.7112)
		(drill 0.3556)
		(layers "F.Cu" "B.Cu")
		(net "I2C_IO_EXP_RESET#_PWR")
	)
	(segment
		(start 239.609376 -13.156438)
		(end 239.31372 -13.156438)
		(width 0.1143)
		(layer "F.Cu")
		(net "HB_OUT_R")
	)
	(segment
		(start 236.7915 -14.46276)
		(end 238.007652 -14.46276)
		(width 0.1143)
		(layer "F.Cu")
		(net "HB_OUT_R")
	)
	(segment
		(start 239.31372 -13.156438)
		(end 238.678212 -13.7922)
		(width 0.1143)
		(layer "F.Cu")
		(net "HB_OUT_R")
	)
	(segment
		(start 238.007652 -14.46276)
		(end 238.678212 -13.7922)
		(width 0.1143)
		(layer "F.Cu")
		(net "HB_OUT_R")
	)
	(via
		(at 238.678212 -13.7922)
		(size 0.7112)
		(drill 0.3556)
		(layers "F.Cu" "B.Cu")
		(net "HB_OUT_R")
	)
	(segment
		(start 326.0725 -170.18)
		(end 326.3265 -170.434)
		(width 0.1143)
		(layer "F.Cu")
		(net "BMC_UART_SWITCH_1R")
	)
	(segment
		(start 327.524872 -167.521636)
		(end 326.39 -167.5765)
		(width 0.1143)
		(layer "F.Cu")
		(net "BMC_UART_SWITCH_1R")
	)
	(segment
		(start 327.359772 -163.029646)
		(end 328.168 -163.029646)
		(width 0.1143)
		(layer "F.Cu")
		(net "BMC_UART_SWITCH_1R")
	)
	(segment
		(start 326.771 -165.735)
		(end 326.771 -165.989)
		(width 0.1143)
		(layer "F.Cu")
		(net "BMC_UART_SWITCH_1R")
	)
	(segment
		(start 326.771 -165.617398)
		(end 326.771 -165.735)
		(width 0.1143)
		(layer "F.Cu")
		(net "BMC_UART_SWITCH_1R")
	)
	(segment
		(start 325.755 -170.068494)
		(end 325.643494 -170.068494)
		(width 0.1143)
		(layer "F.Cu")
		(net "BMC_UART_SWITCH_1R")
	)
	(segment
		(start 325.866506 -170.18)
		(end 326.0725 -170.18)
		(width 0.1143)
		(layer "F.Cu")
		(net "BMC_UART_SWITCH_1R")
	)
	(segment
		(start 327.524872 -166.742872)
		(end 327.524872 -167.521636)
		(width 0.1143)
		(layer "F.Cu")
		(net "BMC_UART_SWITCH_1R")
	)
	(segment
		(start 328.112374 -173.029626)
		(end 327.232772 -173.029626)
		(width 0.1143)
		(layer "F.Cu")
		(net "BMC_UART_SWITCH_1R")
	)
	(segment
		(start 324.993 -169.926)
		(end 324.81901 -169.75201)
		(width 0.1143)
		(layer "F.Cu")
		(net "BMC_UART_SWITCH_1R")
	)
	(segment
		(start 328.305922 -163.167568)
		(end 328.305922 -164.923724)
		(width 0.1143)
		(layer "F.Cu")
		(net "BMC_UART_SWITCH_1R")
	)
	(segment
		(start 326.636126 -170.434)
		(end 327.232772 -171.030646)
		(width 0.1143)
		(layer "F.Cu")
		(net "BMC_UART_SWITCH_1R")
	)
	(segment
		(start 326.771 -165.989)
		(end 327.524872 -166.742872)
		(width 0.1143)
		(layer "F.Cu")
		(net "BMC_UART_SWITCH_1R")
	)
	(segment
		(start 328.20102 -165.028626)
		(end 327.359772 -165.028626)
		(width 0.1143)
		(layer "F.Cu")
		(net "BMC_UART_SWITCH_1R")
	)
	(segment
		(start 328.168 -163.029646)
		(end 328.305922 -163.167568)
		(width 0.1143)
		(layer "F.Cu")
		(net "BMC_UART_SWITCH_1R")
	)
	(segment
		(start 328.178922 -171.079922)
		(end 328.178922 -172.963078)
		(width 0.1143)
		(layer "F.Cu")
		(net "BMC_UART_SWITCH_1R")
	)
	(segment
		(start 328.305922 -164.923724)
		(end 328.20102 -165.028626)
		(width 0.1143)
		(layer "F.Cu")
		(net "BMC_UART_SWITCH_1R")
	)
	(segment
		(start 325.755 -170.068494)
		(end 325.866506 -170.18)
		(width 0.1143)
		(layer "F.Cu")
		(net "BMC_UART_SWITCH_1R")
	)
	(segment
		(start 325.501 -169.926)
		(end 324.993 -169.926)
		(width 0.1143)
		(layer "F.Cu")
		(net "BMC_UART_SWITCH_1R")
	)
	(segment
		(start 325.643494 -170.068494)
		(end 325.501 -169.926)
		(width 0.1143)
		(layer "F.Cu")
		(net "BMC_UART_SWITCH_1R")
	)
	(segment
		(start 328.178922 -172.963078)
		(end 328.112374 -173.029626)
		(width 0.1143)
		(layer "F.Cu")
		(net "BMC_UART_SWITCH_1R")
	)
	(segment
		(start 327.232772 -171.030646)
		(end 328.129646 -171.030646)
		(width 0.1143)
		(layer "F.Cu")
		(net "BMC_UART_SWITCH_1R")
	)
	(segment
		(start 324.104 -169.037)
		(end 324.81901 -169.75201)
		(width 0.1143)
		(layer "F.Cu")
		(net "BMC_UART_SWITCH_1R")
	)
	(segment
		(start 326.3265 -170.434)
		(end 326.636126 -170.434)
		(width 0.1143)
		(layer "F.Cu")
		(net "BMC_UART_SWITCH_1R")
	)
	(segment
		(start 324.104 -168.5925)
		(end 324.104 -169.037)
		(width 0.1143)
		(layer "F.Cu")
		(net "BMC_UART_SWITCH_1R")
	)
	(segment
		(start 328.129646 -171.030646)
		(end 328.178922 -171.079922)
		(width 0.1143)
		(layer "F.Cu")
		(net "BMC_UART_SWITCH_1R")
	)
	(segment
		(start 327.359772 -165.028626)
		(end 326.771 -165.617398)
		(width 0.1143)
		(layer "F.Cu")
		(net "BMC_UART_SWITCH_1R")
	)
	(via
		(at 325.755 -170.068494)
		(size 0.5588)
		(drill 0.3048)
		(layers "F.Cu" "B.Cu")
		(net "BMC_UART_SWITCH_1R")
	)
	(via
		(at 324.81901 -169.75201)
		(size 0.7112)
		(drill 0.3556)
		(layers "F.Cu" "B.Cu")
		(net "BMC_UART_SWITCH_1R")
	)
	(via
		(at 326.771 -165.735)
		(size 0.5588)
		(drill 0.3048)
		(layers "F.Cu" "B.Cu")
		(net "BMC_UART_SWITCH_1R")
	)
	(segment
		(start 325.755 -169.9895)
		(end 326.644 -169.1005)
		(width 0.1143)
		(layer "B.Cu")
		(net "BMC_UART_SWITCH_1R")
	)
	(segment
		(start 325.755 -170.068494)
		(end 325.755 -169.9895)
		(width 0.1143)
		(layer "B.Cu")
		(net "BMC_UART_SWITCH_1R")
	)
	(segment
		(start 326.644 -169.1005)
		(end 326.644 -165.862)
		(width 0.1143)
		(layer "B.Cu")
		(net "BMC_UART_SWITCH_1R")
	)
	(segment
		(start 326.644 -165.862)
		(end 326.771 -165.735)
		(width 0.1143)
		(layer "B.Cu")
		(net "BMC_UART_SWITCH_1R")
	)
	(segment
		(start 338.455 -166.37)
		(end 338.684362 -166.599362)
		(width 0.1143)
		(layer "F.Cu")
		(net "BMC_UART_SWITCH_R")
	)
	(segment
		(start 338.684362 -168.631362)
		(end 339.725 -169.672)
		(width 0.1143)
		(layer "F.Cu")
		(net "BMC_UART_SWITCH_R")
	)
	(segment
		(start 339.725 -169.672)
		(end 339.725 -170.942508)
		(width 0.1143)
		(layer "F.Cu")
		(net "BMC_UART_SWITCH_R")
	)
	(segment
		(start 340.868 -170.942)
		(end 340.867492 -170.942508)
		(width 0.1143)
		(layer "F.Cu")
		(net "BMC_UART_SWITCH_R")
	)
	(segment
		(start 338.700872 -170.950636)
		(end 339.716872 -170.950636)
		(width 0.1143)
		(layer "F.Cu")
		(net "BMC_UART_SWITCH_R")
	)
	(segment
		(start 340.867492 -170.942508)
		(end 339.725 -170.942508)
		(width 0.1143)
		(layer "F.Cu")
		(net "BMC_UART_SWITCH_R")
	)
	(segment
		(start 338.684362 -166.599362)
		(end 338.684362 -167.623236)
		(width 0.1143)
		(layer "F.Cu")
		(net "BMC_UART_SWITCH_R")
	)
	(segment
		(start 337.557872 -170.950636)
		(end 338.700872 -170.950636)
		(width 0.1143)
		(layer "F.Cu")
		(net "BMC_UART_SWITCH_R")
	)
	(segment
		(start 336.685382 -167.623236)
		(end 336.685382 -166.488618)
		(width 0.1143)
		(layer "F.Cu")
		(net "BMC_UART_SWITCH_R")
	)
	(segment
		(start 338.684362 -167.623236)
		(end 338.684362 -168.631362)
		(width 0.1143)
		(layer "F.Cu")
		(net "BMC_UART_SWITCH_R")
	)
	(segment
		(start 336.685382 -166.488618)
		(end 336.804 -166.37)
		(width 0.1143)
		(layer "F.Cu")
		(net "BMC_UART_SWITCH_R")
	)
	(segment
		(start 336.804 -166.37)
		(end 338.455 -166.37)
		(width 0.1143)
		(layer "F.Cu")
		(net "BMC_UART_SWITCH_R")
	)
	(segment
		(start 339.725 -170.942508)
		(end 339.716872 -170.950636)
		(width 0.1143)
		(layer "F.Cu")
		(net "BMC_UART_SWITCH_R")
	)
	(via
		(at 340.868 -170.942)
		(size 0.7112)
		(drill 0.3556)
		(layers "F.Cu" "B.Cu")
		(net "BMC_UART_SWITCH_R")
	)
	(segment
		(start 163.559998 -20.349972)
		(end 166.405306 -23.19528)
		(width 0.508)
		(layer "F.Cu")
		(net "RJ45_GND_7")
	)
	(segment
		(start 166.405306 -23.19528)
		(end 166.405306 -23.205186)
		(width 0.508)
		(layer "F.Cu")
		(net "RJ45_GND_7")
	)
	(segment
		(start 166.846504 -23.646384)
		(end 166.846504 -23.739856)
		(width 0.508)
		(layer "F.Cu")
		(net "RJ45_GND_7")
	)
	(segment
		(start 166.405306 -23.205186)
		(end 166.846504 -23.646384)
		(width 0.508)
		(layer "F.Cu")
		(net "RJ45_GND_7")
	)
	(segment
		(start 167.989504 -22.749764)
		(end 167.989504 -23.739856)
		(width 0.508)
		(layer "F.Cu")
		(net "RJ45_GND_1")
	)
	(segment
		(start 162.534854 -17.809972)
		(end 163.049712 -17.809972)
		(width 0.508)
		(layer "F.Cu")
		(net "RJ45_GND_1")
	)
	(segment
		(start 163.049712 -17.809972)
		(end 167.989504 -22.749764)
		(width 0.508)
		(layer "F.Cu")
		(net "RJ45_GND_1")
	)
	(segment
		(start 194.818 -117.7925)
		(end 194.818 -116.6495)
		(width 0.254)
		(layer "F.Cu")
		(net "P1V8_E_PG")
	)
	(segment
		(start 193.9925 -117.7925)
		(end 194.818 -117.7925)
		(width 0.254)
		(layer "F.Cu")
		(net "P1V8_E_PG")
	)
	(segment
		(start 193.802 -117.602)
		(end 193.9925 -117.7925)
		(width 0.254)
		(layer "F.Cu")
		(net "P1V8_E_PG")
	)
	(via
		(at 193.802 -117.602)
		(size 0.7112)
		(drill 0.3556)
		(layers "F.Cu" "B.Cu")
		(net "P1V8_E_PG")
	)
	(segment
		(start 324.95236 -157.13964)
		(end 325.03364 -157.13964)
		(width 0.1143)
		(layer "F.Cu")
		(net "IOC_UART_TX")
	)
	(segment
		(start 326.263 -164.529516)
		(end 325.946516 -164.846)
		(width 0.1143)
		(layer "F.Cu")
		(net "IOC_UART_TX")
	)
	(segment
		(start 325.26605 -164.48405)
		(end 325.628 -164.846)
		(width 0.1143)
		(layer "F.Cu")
		(net "IOC_UART_TX")
	)
	(segment
		(start 220.68028 -91.47302)
		(end 220.68028 -92.42552)
		(width 0.1143)
		(layer "F.Cu")
		(net "IOC_UART_TX")
	)
	(segment
		(start 327.359772 -164.529516)
		(end 326.263 -164.529516)
		(width 0.1143)
		(layer "F.Cu")
		(net "IOC_UART_TX")
	)
	(segment
		(start 325.03364 -157.13964)
		(end 325.26605 -157.37205)
		(width 0.1143)
		(layer "F.Cu")
		(net "IOC_UART_TX")
	)
	(segment
		(start 325.946516 -164.846)
		(end 325.628 -164.846)
		(width 0.1143)
		(layer "F.Cu")
		(net "IOC_UART_TX")
	)
	(segment
		(start 325.26605 -157.37205)
		(end 325.26605 -164.48405)
		(width 0.1143)
		(layer "F.Cu")
		(net "IOC_UART_TX")
	)
	(via
		(at 324.95236 -157.13964)
		(size 0.5588)
		(drill 0.3048)
		(layers "F.Cu" "B.Cu")
		(net "IOC_UART_TX")
	)
	(via
		(at 220.68028 -92.42552)
		(size 0.5588)
		(drill 0.3048)
		(layers "F.Cu" "B.Cu")
		(net "IOC_UART_TX")
	)
	(via
		(at 325.628 -164.846)
		(size 0.7112)
		(drill 0.3556)
		(layers "F.Cu" "B.Cu")
		(net "IOC_UART_TX")
	)
	(segment
		(start 220.8657 -92.61094)
		(end 229.20706 -92.61094)
		(width 0.127)
		(layer "In5.Cu")
		(net "IOC_UART_TX")
	)
	(segment
		(start 298.97705 -92.917518)
		(end 298.97705 -96.562418)
		(width 0.127)
		(layer "In5.Cu")
		(net "IOC_UART_TX")
	)
	(segment
		(start 220.68028 -92.42552)
		(end 220.8657 -92.61094)
		(width 0.127)
		(layer "In5.Cu")
		(net "IOC_UART_TX")
	)
	(segment
		(start 308.154324 -140.341604)
		(end 324.95236 -157.13964)
		(width 0.127)
		(layer "In5.Cu")
		(net "IOC_UART_TX")
	)
	(segment
		(start 298.3357 -101.928168)
		(end 298.8437 -102.436168)
		(width 0.127)
		(layer "In5.Cu")
		(net "IOC_UART_TX")
	)
	(segment
		(start 295.250362 -90.9447)
		(end 297.004232 -90.9447)
		(width 0.127)
		(layer "In5.Cu")
		(net "IOC_UART_TX")
	)
	(segment
		(start 304.384964 -140.341604)
		(end 308.154324 -140.341604)
		(width 0.127)
		(layer "In5.Cu")
		(net "IOC_UART_TX")
	)
	(segment
		(start 298.8437 -134.80034)
		(end 304.384964 -140.341604)
		(width 0.127)
		(layer "In5.Cu")
		(net "IOC_UART_TX")
	)
	(segment
		(start 265.43 -91.948)
		(end 266.60602 -90.77198)
		(width 0.127)
		(layer "In5.Cu")
		(net "IOC_UART_TX")
	)
	(segment
		(start 295.077642 -90.77198)
		(end 295.250362 -90.9447)
		(width 0.127)
		(layer "In5.Cu")
		(net "IOC_UART_TX")
	)
	(segment
		(start 266.60602 -90.77198)
		(end 295.077642 -90.77198)
		(width 0.127)
		(layer "In5.Cu")
		(net "IOC_UART_TX")
	)
	(segment
		(start 297.004232 -90.9447)
		(end 298.97705 -92.917518)
		(width 0.127)
		(layer "In5.Cu")
		(net "IOC_UART_TX")
	)
	(segment
		(start 229.20706 -92.61094)
		(end 229.87 -91.948)
		(width 0.127)
		(layer "In5.Cu")
		(net "IOC_UART_TX")
	)
	(segment
		(start 298.3357 -97.203768)
		(end 298.3357 -101.928168)
		(width 0.127)
		(layer "In5.Cu")
		(net "IOC_UART_TX")
	)
	(segment
		(start 298.97705 -96.562418)
		(end 298.3357 -97.203768)
		(width 0.127)
		(layer "In5.Cu")
		(net "IOC_UART_TX")
	)
	(segment
		(start 298.8437 -102.436168)
		(end 298.8437 -134.80034)
		(width 0.127)
		(layer "In5.Cu")
		(net "IOC_UART_TX")
	)
	(segment
		(start 229.87 -91.948)
		(end 265.43 -91.948)
		(width 0.127)
		(layer "In5.Cu")
		(net "IOC_UART_TX")
	)
	(segment
		(start 346.0115 -31.1785)
		(end 345.694 -31.496)
		(width 0.1143)
		(layer "F.Cu")
		(net "BMC_UART_SWITCH_1")
	)
	(segment
		(start 346.0115 -26.924)
		(end 346.0115 -31.1785)
		(width 0.1143)
		(layer "F.Cu")
		(net "BMC_UART_SWITCH_1")
	)
	(segment
		(start 327.406 -169.926)
		(end 326.8345 -169.3545)
		(width 0.1143)
		(layer "F.Cu")
		(net "BMC_UART_SWITCH_1")
	)
	(segment
		(start 324.673722 -168.295828)
		(end 324.104 -167.7035)
		(width 0.1143)
		(layer "F.Cu")
		(net "BMC_UART_SWITCH_1")
	)
	(segment
		(start 325.61784 -169.3545)
		(end 324.673722 -168.410382)
		(width 0.1143)
		(layer "F.Cu")
		(net "BMC_UART_SWITCH_1")
	)
	(segment
		(start 326.8345 -169.3545)
		(end 325.61784 -169.3545)
		(width 0.1143)
		(layer "F.Cu")
		(net "BMC_UART_SWITCH_1")
	)
	(segment
		(start 324.673722 -168.410382)
		(end 324.673722 -168.295828)
		(width 0.1143)
		(layer "F.Cu")
		(net "BMC_UART_SWITCH_1")
	)
	(segment
		(start 327.533 -169.926)
		(end 327.406 -169.926)
		(width 0.1143)
		(layer "F.Cu")
		(net "BMC_UART_SWITCH_1")
	)
	(segment
		(start 340.487 -31.496)
		(end 340.106 -31.877)
		(width 0.1143)
		(layer "F.Cu")
		(net "BMC_UART_SWITCH_1")
	)
	(segment
		(start 340.106 -31.877)
		(end 340.106 -69.596)
		(width 0.1143)
		(layer "F.Cu")
		(net "BMC_UART_SWITCH_1")
	)
	(segment
		(start 345.694 -31.496)
		(end 340.487 -31.496)
		(width 0.1143)
		(layer "F.Cu")
		(net "BMC_UART_SWITCH_1")
	)
	(segment
		(start 324.104 -167.7035)
		(end 324.358 -167.4495)
		(width 0.1143)
		(layer "F.Cu")
		(net "BMC_UART_SWITCH_1")
	)
	(segment
		(start 302.006 -189.4205)
		(end 302.8315 -189.4205)
		(width 0.1143)
		(layer "F.Cu")
		(net "BMC_UART_SWITCH_1")
	)
	(segment
		(start 302.8315 -189.4205)
		(end 302.895 -189.357)
		(width 0.1143)
		(layer "F.Cu")
		(net "BMC_UART_SWITCH_1")
	)
	(segment
		(start 324.358 -167.4495)
		(end 324.358 -166.624)
		(width 0.1143)
		(layer "F.Cu")
		(net "BMC_UART_SWITCH_1")
	)
	(via
		(at 340.106 -69.596)
		(size 0.5588)
		(drill 0.3048)
		(layers "F.Cu" "B.Cu")
		(net "BMC_UART_SWITCH_1")
	)
	(via
		(at 327.533 -169.926)
		(size 0.5588)
		(drill 0.3048)
		(layers "F.Cu" "B.Cu")
		(net "BMC_UART_SWITCH_1")
	)
	(via
		(at 302.895 -189.357)
		(size 0.5588)
		(drill 0.3048)
		(layers "F.Cu" "B.Cu")
		(net "BMC_UART_SWITCH_1")
	)
	(via
		(at 331.724 -84.963)
		(size 0.5588)
		(drill 0.3048)
		(layers "F.Cu" "B.Cu")
		(net "BMC_UART_SWITCH_1")
	)
	(via
		(at 324.358 -166.624)
		(size 0.7112)
		(drill 0.3556)
		(layers "F.Cu" "B.Cu")
		(net "BMC_UART_SWITCH_1")
	)
	(via
		(at 324.866 -189.63005)
		(size 0.5588)
		(drill 0.3048)
		(layers "F.Cu" "B.Cu")
		(net "BMC_UART_SWITCH_1")
	)
	(via
		(at 318.262 -129.794)
		(size 0.5588)
		(drill 0.3048)
		(layers "F.Cu" "B.Cu")
		(net "BMC_UART_SWITCH_1")
	)
	(segment
		(start 339.883496 -69.818504)
		(end 335.819496 -69.818504)
		(width 0.1143)
		(layer "B.Cu")
		(net "BMC_UART_SWITCH_1")
	)
	(segment
		(start 311.641236 -190.32855)
		(end 305.313842 -190.32855)
		(width 0.1143)
		(layer "B.Cu")
		(net "BMC_UART_SWITCH_1")
	)
	(segment
		(start 305.313842 -190.32855)
		(end 305.051206 -190.065914)
		(width 0.1143)
		(layer "B.Cu")
		(net "BMC_UART_SWITCH_1")
	)
	(segment
		(start 305.02225 -190.0428)
		(end 303.5808 -190.0428)
		(width 0.1143)
		(layer "B.Cu")
		(net "BMC_UART_SWITCH_1")
	)
	(segment
		(start 330.65085 -74.98715)
		(end 330.65085 -81.22285)
		(width 0.1143)
		(layer "B.Cu")
		(net "BMC_UART_SWITCH_1")
	)
	(segment
		(start 303.5808 -190.0428)
		(end 302.895 -189.357)
		(width 0.1143)
		(layer "B.Cu")
		(net "BMC_UART_SWITCH_1")
	)
	(segment
		(start 330.65085 -81.22285)
		(end 332.21295 -82.78495)
		(width 0.1143)
		(layer "B.Cu")
		(net "BMC_UART_SWITCH_1")
	)
	(segment
		(start 340.106 -69.596)
		(end 339.883496 -69.818504)
		(width 0.1143)
		(layer "B.Cu")
		(net "BMC_UART_SWITCH_1")
	)
	(segment
		(start 324.866 -189.63005)
		(end 324.71995 -189.484)
		(width 0.1143)
		(layer "B.Cu")
		(net "BMC_UART_SWITCH_1")
	)
	(segment
		(start 332.21295 -84.47405)
		(end 331.724 -84.963)
		(width 0.1143)
		(layer "B.Cu")
		(net "BMC_UART_SWITCH_1")
	)
	(segment
		(start 305.051206 -190.065914)
		(end 305.045364 -190.065914)
		(width 0.1143)
		(layer "B.Cu")
		(net "BMC_UART_SWITCH_1")
	)
	(segment
		(start 315.2521 -190.4619)
		(end 311.774586 -190.4619)
		(width 0.1143)
		(layer "B.Cu")
		(net "BMC_UART_SWITCH_1")
	)
	(segment
		(start 335.819496 -69.818504)
		(end 330.65085 -74.98715)
		(width 0.1143)
		(layer "B.Cu")
		(net "BMC_UART_SWITCH_1")
	)
	(segment
		(start 324.71995 -189.484)
		(end 316.23 -189.484)
		(width 0.1143)
		(layer "B.Cu")
		(net "BMC_UART_SWITCH_1")
	)
	(segment
		(start 311.774586 -190.4619)
		(end 311.641236 -190.32855)
		(width 0.1143)
		(layer "B.Cu")
		(net "BMC_UART_SWITCH_1")
	)
	(segment
		(start 316.23 -189.484)
		(end 315.2521 -190.4619)
		(width 0.1143)
		(layer "B.Cu")
		(net "BMC_UART_SWITCH_1")
	)
	(segment
		(start 305.045364 -190.065914)
		(end 305.02225 -190.0428)
		(width 0.1143)
		(layer "B.Cu")
		(net "BMC_UART_SWITCH_1")
	)
	(segment
		(start 332.21295 -82.78495)
		(end 332.21295 -84.47405)
		(width 0.1143)
		(layer "B.Cu")
		(net "BMC_UART_SWITCH_1")
	)
	(segment
		(start 319.532 -129.921)
		(end 330.2 -140.589)
		(width 0.127)
		(layer "In2.Cu")
		(net "BMC_UART_SWITCH_1")
	)
	(segment
		(start 330.2 -143.256)
		(end 330.835 -143.891)
		(width 0.127)
		(layer "In2.Cu")
		(net "BMC_UART_SWITCH_1")
	)
	(segment
		(start 327.152 -157.353)
		(end 327.152 -161.925)
		(width 0.127)
		(layer "In2.Cu")
		(net "BMC_UART_SWITCH_1")
	)
	(segment
		(start 330.2 -140.589)
		(end 330.2 -143.256)
		(width 0.127)
		(layer "In2.Cu")
		(net "BMC_UART_SWITCH_1")
	)
	(segment
		(start 325.247 -183.181244)
		(end 327.612248 -180.815996)
		(width 0.127)
		(layer "In2.Cu")
		(net "BMC_UART_SWITCH_1")
	)
	(segment
		(start 318.389 -129.921)
		(end 319.532 -129.921)
		(width 0.127)
		(layer "In2.Cu")
		(net "BMC_UART_SWITCH_1")
	)
	(segment
		(start 327.533 -167.767)
		(end 327.533 -169.926)
		(width 0.127)
		(layer "In2.Cu")
		(net "BMC_UART_SWITCH_1")
	)
	(segment
		(start 327.66 -162.433)
		(end 327.66 -167.64)
		(width 0.127)
		(layer "In2.Cu")
		(net "BMC_UART_SWITCH_1")
	)
	(segment
		(start 318.262 -129.794)
		(end 318.389 -129.921)
		(width 0.127)
		(layer "In2.Cu")
		(net "BMC_UART_SWITCH_1")
	)
	(segment
		(start 327.612248 -180.815996)
		(end 327.612248 -170.259248)
		(width 0.127)
		(layer "In2.Cu")
		(net "BMC_UART_SWITCH_1")
	)
	(segment
		(start 327.66 -167.64)
		(end 327.533 -167.767)
		(width 0.127)
		(layer "In2.Cu")
		(net "BMC_UART_SWITCH_1")
	)
	(segment
		(start 325.247 -189.24905)
		(end 325.247 -183.181244)
		(width 0.127)
		(layer "In2.Cu")
		(net "BMC_UART_SWITCH_1")
	)
	(segment
		(start 327.533 -170.18)
		(end 327.533 -169.926)
		(width 0.127)
		(layer "In2.Cu")
		(net "BMC_UART_SWITCH_1")
	)
	(segment
		(start 330.835 -153.67)
		(end 327.152 -157.353)
		(width 0.127)
		(layer "In2.Cu")
		(net "BMC_UART_SWITCH_1")
	)
	(segment
		(start 324.866 -189.63005)
		(end 325.247 -189.24905)
		(width 0.127)
		(layer "In2.Cu")
		(net "BMC_UART_SWITCH_1")
	)
	(segment
		(start 330.835 -143.891)
		(end 330.835 -153.67)
		(width 0.127)
		(layer "In2.Cu")
		(net "BMC_UART_SWITCH_1")
	)
	(segment
		(start 327.612248 -170.259248)
		(end 327.533 -170.18)
		(width 0.127)
		(layer "In2.Cu")
		(net "BMC_UART_SWITCH_1")
	)
	(segment
		(start 327.152 -161.925)
		(end 327.66 -162.433)
		(width 0.127)
		(layer "In2.Cu")
		(net "BMC_UART_SWITCH_1")
	)
	(segment
		(start 313.1693 -123.3043)
		(end 313.1693 -113.862104)
		(width 0.127)
		(layer "In5.Cu")
		(net "BMC_UART_SWITCH_1")
	)
	(segment
		(start 316.865 -110.109)
		(end 316.865 -109.474)
		(width 0.127)
		(layer "In5.Cu")
		(net "BMC_UART_SWITCH_1")
	)
	(segment
		(start 316.865 -109.474)
		(end 319.405 -106.934)
		(width 0.127)
		(layer "In5.Cu")
		(net "BMC_UART_SWITCH_1")
	)
	(segment
		(start 319.405 -106.934)
		(end 319.405 -100.457)
		(width 0.127)
		(layer "In5.Cu")
		(net "BMC_UART_SWITCH_1")
	)
	(segment
		(start 319.405 -100.457)
		(end 330.581 -89.281)
		(width 0.127)
		(layer "In5.Cu")
		(net "BMC_UART_SWITCH_1")
	)
	(segment
		(start 313.1693 -113.862104)
		(end 313.8932 -113.138204)
		(width 0.127)
		(layer "In5.Cu")
		(net "BMC_UART_SWITCH_1")
	)
	(segment
		(start 330.581 -89.281)
		(end 330.581 -86.106)
		(width 0.127)
		(layer "In5.Cu")
		(net "BMC_UART_SWITCH_1")
	)
	(segment
		(start 330.581 -86.106)
		(end 331.724 -84.963)
		(width 0.127)
		(layer "In5.Cu")
		(net "BMC_UART_SWITCH_1")
	)
	(segment
		(start 318.262 -129.794)
		(end 318.262 -128.397)
		(width 0.127)
		(layer "In5.Cu")
		(net "BMC_UART_SWITCH_1")
	)
	(segment
		(start 313.8932 -113.138204)
		(end 313.8932 -113.0808)
		(width 0.127)
		(layer "In5.Cu")
		(net "BMC_UART_SWITCH_1")
	)
	(segment
		(start 313.8932 -113.0808)
		(end 316.865 -110.109)
		(width 0.127)
		(layer "In5.Cu")
		(net "BMC_UART_SWITCH_1")
	)
	(segment
		(start 318.262 -128.397)
		(end 313.1693 -123.3043)
		(width 0.127)
		(layer "In5.Cu")
		(net "BMC_UART_SWITCH_1")
	)
	(segment
		(start 323.215508 -162.306508)
		(end 323.215508 -162.2806)
		(width 0.1143)
		(layer "F.Cu")
		(net "EXP_SMART_RX")
	)
	(segment
		(start 246.38254 -113.47704)
		(end 244.1448 -111.2393)
		(width 0.1143)
		(layer "F.Cu")
		(net "EXP_SMART_RX")
	)
	(segment
		(start 244.1448 -111.2393)
		(end 243.3193 -111.2393)
		(width 0.1143)
		(layer "F.Cu")
		(net "EXP_SMART_RX")
	)
	(segment
		(start 323.774054 -162.865054)
		(end 323.215508 -162.306508)
		(width 0.1143)
		(layer "F.Cu")
		(net "EXP_SMART_RX")
	)
	(segment
		(start 246.477028 -115.791488)
		(end 246.38254 -115.697)
		(width 0.1143)
		(layer "F.Cu")
		(net "EXP_SMART_RX")
	)
	(segment
		(start 323.031358 -167.442642)
		(end 323.774054 -166.699946)
		(width 0.1143)
		(layer "F.Cu")
		(net "EXP_SMART_RX")
	)
	(segment
		(start 246.38254 -115.697)
		(end 246.38254 -113.47704)
		(width 0.1143)
		(layer "F.Cu")
		(net "EXP_SMART_RX")
	)
	(segment
		(start 323.4055 -171.323)
		(end 323.031358 -170.948858)
		(width 0.1143)
		(layer "F.Cu")
		(net "EXP_SMART_RX")
	)
	(segment
		(start 323.774054 -166.699946)
		(end 323.774054 -162.865054)
		(width 0.1143)
		(layer "F.Cu")
		(net "EXP_SMART_RX")
	)
	(segment
		(start 323.031358 -170.948858)
		(end 323.031358 -167.442642)
		(width 0.1143)
		(layer "F.Cu")
		(net "EXP_SMART_RX")
	)
	(via
		(at 323.215508 -162.2806)
		(size 0.5588)
		(drill 0.3048)
		(layers "F.Cu" "B.Cu")
		(net "EXP_SMART_RX")
	)
	(via
		(at 246.477028 -115.791488)
		(size 0.5588)
		(drill 0.3048)
		(layers "F.Cu" "B.Cu")
		(net "EXP_SMART_RX")
	)
	(via
		(at 321.945 -158.877)
		(size 0.7112)
		(drill 0.3556)
		(layers "F.Cu" "B.Cu")
		(net "EXP_SMART_RX")
	)
	(segment
		(start 271.721326 -120.26265)
		(end 273.124676 -121.666)
		(width 0.1143)
		(layer "B.Cu")
		(net "EXP_SMART_RX")
	)
	(segment
		(start 295.718738 -121.40565)
		(end 304.737262 -121.40565)
		(width 0.1143)
		(layer "B.Cu")
		(net "EXP_SMART_RX")
	)
	(segment
		(start 246.477028 -115.791488)
		(end 246.38254 -115.885976)
		(width 0.1143)
		(layer "B.Cu")
		(net "EXP_SMART_RX")
	)
	(segment
		(start 247.91289 -120.26265)
		(end 271.721326 -120.26265)
		(width 0.1143)
		(layer "B.Cu")
		(net "EXP_SMART_RX")
	)
	(segment
		(start 323.215 -160.147)
		(end 321.945 -158.877)
		(width 0.1143)
		(layer "B.Cu")
		(net "EXP_SMART_RX")
	)
	(segment
		(start 320.3575 -139.579858)
		(end 320.3575 -157.2895)
		(width 0.1143)
		(layer "B.Cu")
		(net "EXP_SMART_RX")
	)
	(segment
		(start 318.34582 -132.70865)
		(end 320.65595 -135.01878)
		(width 0.1143)
		(layer "B.Cu")
		(net "EXP_SMART_RX")
	)
	(segment
		(start 310.72455 -128.517904)
		(end 311.345834 -129.139188)
		(width 0.1143)
		(layer "B.Cu")
		(net "EXP_SMART_RX")
	)
	(segment
		(start 311.360312 -129.139188)
		(end 314.929774 -132.70865)
		(width 0.1143)
		(layer "B.Cu")
		(net "EXP_SMART_RX")
	)
	(segment
		(start 320.65595 -139.281408)
		(end 320.3575 -139.579858)
		(width 0.1143)
		(layer "B.Cu")
		(net "EXP_SMART_RX")
	)
	(segment
		(start 295.458388 -121.666)
		(end 295.718738 -121.40565)
		(width 0.1143)
		(layer "B.Cu")
		(net "EXP_SMART_RX")
	)
	(segment
		(start 246.38254 -115.885976)
		(end 246.38254 -118.7323)
		(width 0.1143)
		(layer "B.Cu")
		(net "EXP_SMART_RX")
	)
	(segment
		(start 311.345834 -129.139188)
		(end 311.360312 -129.139188)
		(width 0.1143)
		(layer "B.Cu")
		(net "EXP_SMART_RX")
	)
	(segment
		(start 323.215 -162.280092)
		(end 323.215 -160.147)
		(width 0.1143)
		(layer "B.Cu")
		(net "EXP_SMART_RX")
	)
	(segment
		(start 246.38254 -118.7323)
		(end 247.91289 -120.26265)
		(width 0.1143)
		(layer "B.Cu")
		(net "EXP_SMART_RX")
	)
	(segment
		(start 320.65595 -135.01878)
		(end 320.65595 -139.281408)
		(width 0.1143)
		(layer "B.Cu")
		(net "EXP_SMART_RX")
	)
	(segment
		(start 273.124676 -121.666)
		(end 295.458388 -121.666)
		(width 0.1143)
		(layer "B.Cu")
		(net "EXP_SMART_RX")
	)
	(segment
		(start 304.737262 -121.40565)
		(end 310.72455 -127.392938)
		(width 0.1143)
		(layer "B.Cu")
		(net "EXP_SMART_RX")
	)
	(segment
		(start 320.3575 -157.2895)
		(end 321.945 -158.877)
		(width 0.1143)
		(layer "B.Cu")
		(net "EXP_SMART_RX")
	)
	(segment
		(start 310.72455 -127.392938)
		(end 310.72455 -128.517904)
		(width 0.1143)
		(layer "B.Cu")
		(net "EXP_SMART_RX")
	)
	(segment
		(start 323.215508 -162.2806)
		(end 323.215 -162.280092)
		(width 0.1143)
		(layer "B.Cu")
		(net "EXP_SMART_RX")
	)
	(segment
		(start 314.929774 -132.70865)
		(end 318.34582 -132.70865)
		(width 0.1143)
		(layer "B.Cu")
		(net "EXP_SMART_RX")
	)
	(segment
		(start 325.247 -171.323)
		(end 324.2945 -171.323)
		(width 0.1143)
		(layer "F.Cu")
		(net "EXP_UART_RX_R")
	)
	(segment
		(start 327.232772 -171.529756)
		(end 326.342756 -171.529756)
		(width 0.1143)
		(layer "F.Cu")
		(net "EXP_UART_RX_R")
	)
	(segment
		(start 326.342756 -171.529756)
		(end 326.136 -171.323)
		(width 0.1143)
		(layer "F.Cu")
		(net "EXP_UART_RX_R")
	)
	(segment
		(start 326.136 -171.323)
		(end 325.247 -171.323)
		(width 0.1143)
		(layer "F.Cu")
		(net "EXP_UART_RX_R")
	)
	(via
		(at 325.247 -171.323)
		(size 0.7112)
		(drill 0.3556)
		(layers "F.Cu" "B.Cu")
		(net "EXP_UART_RX_R")
	)
	(segment
		(start 339.716872 -172.601128)
		(end 337.82 -174.498)
		(width 0.1143)
		(layer "F.Cu")
		(net "BMC_UART_SWITCH_2")
	)
	(segment
		(start 299.72 -192.3415)
		(end 299.72 -193.421)
		(width 0.1143)
		(layer "F.Cu")
		(net "BMC_UART_SWITCH_2")
	)
	(segment
		(start 339.471 -35.2425)
		(end 339.471 -68.801996)
		(width 0.1143)
		(layer "F.Cu")
		(net "BMC_UART_SWITCH_2")
	)
	(segment
		(start 339.716872 -171.839636)
		(end 339.716872 -172.601128)
		(width 0.1143)
		(layer "F.Cu")
		(net "BMC_UART_SWITCH_2")
	)
	(segment
		(start 300.98365 -194.68465)
		(end 300.98365 -194.945)
		(width 0.1143)
		(layer "F.Cu")
		(net "BMC_UART_SWITCH_2")
	)
	(segment
		(start 299.72 -193.421)
		(end 300.98365 -194.68465)
		(width 0.1143)
		(layer "F.Cu")
		(net "BMC_UART_SWITCH_2")
	)
	(segment
		(start 337.82 -174.498)
		(end 333.1972 -174.498)
		(width 0.1143)
		(layer "F.Cu")
		(net "BMC_UART_SWITCH_2")
	)
	(segment
		(start 333.1972 -174.498)
		(end 333.0702 -174.625)
		(width 0.1143)
		(layer "F.Cu")
		(net "BMC_UART_SWITCH_2")
	)
	(via
		(at 326.771 -189.865)
		(size 0.7112)
		(drill 0.3556)
		(layers "F.Cu" "B.Cu")
		(net "BMC_UART_SWITCH_2")
	)
	(via
		(at 333.0702 -174.625)
		(size 0.5588)
		(drill 0.3048)
		(layers "F.Cu" "B.Cu")
		(net "BMC_UART_SWITCH_2")
	)
	(via
		(at 339.471 -68.801996)
		(size 0.5588)
		(drill 0.3048)
		(layers "F.Cu" "B.Cu")
		(net "BMC_UART_SWITCH_2")
	)
	(via
		(at 331.724 -83.566)
		(size 0.5588)
		(drill 0.3048)
		(layers "F.Cu" "B.Cu")
		(net "BMC_UART_SWITCH_2")
	)
	(via
		(at 300.98365 -194.945)
		(size 0.5588)
		(drill 0.3048)
		(layers "F.Cu" "B.Cu")
		(net "BMC_UART_SWITCH_2")
	)
	(via
		(at 332.2574 -190.0428)
		(size 0.5588)
		(drill 0.3048)
		(layers "F.Cu" "B.Cu")
		(net "BMC_UART_SWITCH_2")
	)
	(segment
		(start 331.089 -82.931)
		(end 331.724 -83.566)
		(width 0.1143)
		(layer "B.Cu")
		(net "BMC_UART_SWITCH_2")
	)
	(segment
		(start 327.152 -190.246)
		(end 326.771 -189.865)
		(width 0.1143)
		(layer "B.Cu")
		(net "BMC_UART_SWITCH_2")
	)
	(segment
		(start 331.089 -82.804)
		(end 331.089 -82.931)
		(width 0.1143)
		(layer "B.Cu")
		(net "BMC_UART_SWITCH_2")
	)
	(segment
		(start 300.98365 -194.945)
		(end 300.98365 -192.666112)
		(width 0.1143)
		(layer "B.Cu")
		(net "BMC_UART_SWITCH_2")
	)
	(segment
		(start 326.517 -190.119)
		(end 326.771 -189.865)
		(width 0.1143)
		(layer "B.Cu")
		(net "BMC_UART_SWITCH_2")
	)
	(segment
		(start 332.2574 -190.0428)
		(end 332.0542 -190.246)
		(width 0.1143)
		(layer "B.Cu")
		(net "BMC_UART_SWITCH_2")
	)
	(segment
		(start 311.404508 -190.90005)
		(end 311.537858 -191.0334)
		(width 0.1143)
		(layer "B.Cu")
		(net "BMC_UART_SWITCH_2")
	)
	(segment
		(start 332.0542 -190.246)
		(end 327.152 -190.246)
		(width 0.1143)
		(layer "B.Cu")
		(net "BMC_UART_SWITCH_2")
	)
	(segment
		(start 330.07935 -81.79435)
		(end 331.089 -82.804)
		(width 0.1143)
		(layer "B.Cu")
		(net "BMC_UART_SWITCH_2")
	)
	(segment
		(start 303.007776 -190.641986)
		(end 304.81905 -190.641986)
		(width 0.1143)
		(layer "B.Cu")
		(net "BMC_UART_SWITCH_2")
	)
	(segment
		(start 300.98365 -192.666112)
		(end 303.007776 -190.641986)
		(width 0.1143)
		(layer "B.Cu")
		(net "BMC_UART_SWITCH_2")
	)
	(segment
		(start 335.820004 -68.801996)
		(end 330.07935 -74.54265)
		(width 0.1143)
		(layer "B.Cu")
		(net "BMC_UART_SWITCH_2")
	)
	(segment
		(start 304.81905 -190.641986)
		(end 305.077114 -190.90005)
		(width 0.1143)
		(layer "B.Cu")
		(net "BMC_UART_SWITCH_2")
	)
	(segment
		(start 339.471 -68.801996)
		(end 335.820004 -68.801996)
		(width 0.1143)
		(layer "B.Cu")
		(net "BMC_UART_SWITCH_2")
	)
	(segment
		(start 311.537858 -191.0334)
		(end 315.5696 -191.0334)
		(width 0.1143)
		(layer "B.Cu")
		(net "BMC_UART_SWITCH_2")
	)
	(segment
		(start 330.07935 -74.54265)
		(end 330.07935 -81.79435)
		(width 0.1143)
		(layer "B.Cu")
		(net "BMC_UART_SWITCH_2")
	)
	(segment
		(start 315.5696 -191.0334)
		(end 316.484 -190.119)
		(width 0.1143)
		(layer "B.Cu")
		(net "BMC_UART_SWITCH_2")
	)
	(segment
		(start 316.484 -190.119)
		(end 326.517 -190.119)
		(width 0.1143)
		(layer "B.Cu")
		(net "BMC_UART_SWITCH_2")
	)
	(segment
		(start 305.077114 -190.90005)
		(end 311.404508 -190.90005)
		(width 0.1143)
		(layer "B.Cu")
		(net "BMC_UART_SWITCH_2")
	)
	(segment
		(start 328.785728 -133.80466)
		(end 326.9615 -131.980432)
		(width 0.127)
		(layer "In2.Cu")
		(net "BMC_UART_SWITCH_2")
	)
	(segment
		(start 333.0702 -174.625)
		(end 333.0702 -177.18151)
		(width 0.127)
		(layer "In2.Cu")
		(net "BMC_UART_SWITCH_2")
	)
	(segment
		(start 338.421218 -150.375366)
		(end 334.3402 -146.294348)
		(width 0.127)
		(layer "In2.Cu")
		(net "BMC_UART_SWITCH_2")
	)
	(segment
		(start 338.421218 -153.449782)
		(end 338.421218 -150.375366)
		(width 0.127)
		(layer "In2.Cu")
		(net "BMC_UART_SWITCH_2")
	)
	(segment
		(start 332.2574 -189.4332)
		(end 332.2574 -190.0428)
		(width 0.127)
		(layer "In2.Cu")
		(net "BMC_UART_SWITCH_2")
	)
	(segment
		(start 325.374 -101.854)
		(end 325.374 -89.916)
		(width 0.127)
		(layer "In2.Cu")
		(net "BMC_UART_SWITCH_2")
	)
	(segment
		(start 324.6247 -102.6033)
		(end 325.374 -101.854)
		(width 0.127)
		(layer "In2.Cu")
		(net "BMC_UART_SWITCH_2")
	)
	(segment
		(start 334.3402 -146.294348)
		(end 334.3402 -139.848844)
		(width 0.127)
		(layer "In2.Cu")
		(net "BMC_UART_SWITCH_2")
	)
	(segment
		(start 325.374 -89.916)
		(end 331.724 -83.566)
		(width 0.127)
		(layer "In2.Cu")
		(net "BMC_UART_SWITCH_2")
	)
	(segment
		(start 334.01 -173.609)
		(end 334.01 -157.861)
		(width 0.127)
		(layer "In2.Cu")
		(net "BMC_UART_SWITCH_2")
	)
	(segment
		(start 334.01 -157.861)
		(end 338.421218 -153.449782)
		(width 0.127)
		(layer "In2.Cu")
		(net "BMC_UART_SWITCH_2")
	)
	(segment
		(start 326.9615 -125.422152)
		(end 323.6595 -122.120152)
		(width 0.127)
		(layer "In2.Cu")
		(net "BMC_UART_SWITCH_2")
	)
	(segment
		(start 325.2343 -107.6833)
		(end 324.6247 -107.0737)
		(width 0.127)
		(layer "In2.Cu")
		(net "BMC_UART_SWITCH_2")
	)
	(segment
		(start 329.16114 -134.669784)
		(end 329.16114 -134.094728)
		(width 0.127)
		(layer "In2.Cu")
		(net "BMC_UART_SWITCH_2")
	)
	(segment
		(start 333.0702 -177.18151)
		(end 334.2132 -178.32451)
		(width 0.127)
		(layer "In2.Cu")
		(net "BMC_UART_SWITCH_2")
	)
	(segment
		(start 333.0702 -174.5488)
		(end 334.01 -173.609)
		(width 0.127)
		(layer "In2.Cu")
		(net "BMC_UART_SWITCH_2")
	)
	(segment
		(start 334.3402 -139.848844)
		(end 329.16114 -134.669784)
		(width 0.127)
		(layer "In2.Cu")
		(net "BMC_UART_SWITCH_2")
	)
	(segment
		(start 334.2132 -178.32451)
		(end 334.2132 -187.4774)
		(width 0.127)
		(layer "In2.Cu")
		(net "BMC_UART_SWITCH_2")
	)
	(segment
		(start 325.2343 -117.7417)
		(end 325.2343 -107.6833)
		(width 0.127)
		(layer "In2.Cu")
		(net "BMC_UART_SWITCH_2")
	)
	(segment
		(start 323.6595 -119.3165)
		(end 325.2343 -117.7417)
		(width 0.127)
		(layer "In2.Cu")
		(net "BMC_UART_SWITCH_2")
	)
	(segment
		(start 326.9615 -131.980432)
		(end 326.9615 -125.422152)
		(width 0.127)
		(layer "In2.Cu")
		(net "BMC_UART_SWITCH_2")
	)
	(segment
		(start 324.6247 -107.0737)
		(end 324.6247 -102.6033)
		(width 0.127)
		(layer "In2.Cu")
		(net "BMC_UART_SWITCH_2")
	)
	(segment
		(start 323.6595 -122.120152)
		(end 323.6595 -119.3165)
		(width 0.127)
		(layer "In2.Cu")
		(net "BMC_UART_SWITCH_2")
	)
	(segment
		(start 329.16114 -134.094728)
		(end 328.871072 -133.80466)
		(width 0.127)
		(layer "In2.Cu")
		(net "BMC_UART_SWITCH_2")
	)
	(segment
		(start 333.0702 -174.625)
		(end 333.0702 -174.5488)
		(width 0.127)
		(layer "In2.Cu")
		(net "BMC_UART_SWITCH_2")
	)
	(segment
		(start 328.871072 -133.80466)
		(end 328.785728 -133.80466)
		(width 0.127)
		(layer "In2.Cu")
		(net "BMC_UART_SWITCH_2")
	)
	(segment
		(start 334.2132 -187.4774)
		(end 332.2574 -189.4332)
		(width 0.127)
		(layer "In2.Cu")
		(net "BMC_UART_SWITCH_2")
	)
	(segment
		(start 290.703 -156.61005)
		(end 287.88995 -153.797)
		(width 0.1143)
		(layer "F.Cu")
		(net "CPU_BMC_UART_RX")
	)
	(segment
		(start 287.88995 -153.797)
		(end 280.924 -153.797)
		(width 0.1143)
		(layer "F.Cu")
		(net "CPU_BMC_UART_RX")
	)
	(segment
		(start 291.084 -160.1978)
		(end 291.084 -161.0995)
		(width 0.1143)
		(layer "F.Cu")
		(net "CPU_BMC_UART_RX")
	)
	(segment
		(start 253.746 -143.773144)
		(end 258.567428 -148.594572)
		(width 0.1143)
		(layer "F.Cu")
		(net "CPU_BMC_UART_RX")
	)
	(segment
		(start 291.211 -160.0708)
		(end 291.084 -160.1978)
		(width 0.1143)
		(layer "F.Cu")
		(net "CPU_BMC_UART_RX")
	)
	(segment
		(start 290.068 -158.9405)
		(end 291.211 -158.9405)
		(width 0.1143)
		(layer "F.Cu")
		(net "CPU_BMC_UART_RX")
	)
	(segment
		(start 291.211 -158.9405)
		(end 291.211 -160.0708)
		(width 0.1143)
		(layer "F.Cu")
		(net "CPU_BMC_UART_RX")
	)
	(segment
		(start 290.703 -158.3055)
		(end 290.703 -156.61005)
		(width 0.1143)
		(layer "F.Cu")
		(net "CPU_BMC_UART_RX")
	)
	(segment
		(start 290.068 -158.9405)
		(end 290.703 -158.3055)
		(width 0.1143)
		(layer "F.Cu")
		(net "CPU_BMC_UART_RX")
	)
	(segment
		(start 253.746 -137.2235)
		(end 253.746 -143.773144)
		(width 0.1143)
		(layer "F.Cu")
		(net "CPU_BMC_UART_RX")
	)
	(via
		(at 280.924 -153.797)
		(size 0.5588)
		(drill 0.3048)
		(layers "F.Cu" "B.Cu")
		(net "CPU_BMC_UART_RX")
	)
	(via
		(at 258.567428 -148.594572)
		(size 0.5588)
		(drill 0.3048)
		(layers "F.Cu" "B.Cu")
		(net "CPU_BMC_UART_RX")
	)
	(via
		(at 291.084 -160.1978)
		(size 0.7112)
		(drill 0.3556)
		(layers "F.Cu" "B.Cu")
		(net "CPU_BMC_UART_RX")
	)
	(segment
		(start 258.567428 -148.594572)
		(end 268.863572 -148.594572)
		(width 0.1143)
		(layer "B.Cu")
		(net "CPU_BMC_UART_RX")
	)
	(segment
		(start 274.066 -153.797)
		(end 280.924 -153.797)
		(width 0.1143)
		(layer "B.Cu")
		(net "CPU_BMC_UART_RX")
	)
	(segment
		(start 268.863572 -148.594572)
		(end 274.066 -153.797)
		(width 0.1143)
		(layer "B.Cu")
		(net "CPU_BMC_UART_RX")
	)
	(segment
		(start 323.4055 -172.974)
		(end 322.459858 -172.028358)
		(width 0.1143)
		(layer "F.Cu")
		(net "EXP_SMART_TX")
	)
	(segment
		(start 242.8748 -110.5408)
		(end 242.1763 -111.2393)
		(width 0.1143)
		(layer "F.Cu")
		(net "EXP_SMART_TX")
	)
	(segment
		(start 244.254528 -110.5408)
		(end 242.8748 -110.5408)
		(width 0.1143)
		(layer "F.Cu")
		(net "EXP_SMART_TX")
	)
	(segment
		(start 322.459858 -172.028358)
		(end 322.459858 -167.125142)
		(width 0.1143)
		(layer "F.Cu")
		(net "EXP_SMART_TX")
	)
	(segment
		(start 247.12295 -113.409222)
		(end 244.254528 -110.5408)
		(width 0.1143)
		(layer "F.Cu")
		(net "EXP_SMART_TX")
	)
	(segment
		(start 247.12295 -115.144804)
		(end 247.12295 -113.409222)
		(width 0.1143)
		(layer "F.Cu")
		(net "EXP_SMART_TX")
	)
	(segment
		(start 247.14581 -115.167664)
		(end 247.12295 -115.144804)
		(width 0.1143)
		(layer "F.Cu")
		(net "EXP_SMART_TX")
	)
	(segment
		(start 323.202554 -166.382446)
		(end 323.202554 -163.195)
		(width 0.1143)
		(layer "F.Cu")
		(net "EXP_SMART_TX")
	)
	(segment
		(start 322.459858 -167.125142)
		(end 323.202554 -166.382446)
		(width 0.1143)
		(layer "F.Cu")
		(net "EXP_SMART_TX")
	)
	(via
		(at 321.056 -155.829)
		(size 0.7112)
		(drill 0.3556)
		(layers "F.Cu" "B.Cu")
		(net "EXP_SMART_TX")
	)
	(via
		(at 247.14581 -115.167664)
		(size 0.5588)
		(drill 0.3048)
		(layers "F.Cu" "B.Cu")
		(net "EXP_SMART_TX")
	)
	(via
		(at 323.202554 -163.195)
		(size 0.5588)
		(drill 0.3048)
		(layers "F.Cu" "B.Cu")
		(net "EXP_SMART_TX")
	)
	(segment
		(start 320.929 -141.605)
		(end 320.929 -151.91105)
		(width 0.1143)
		(layer "B.Cu")
		(net "EXP_SMART_TX")
	)
	(segment
		(start 273.361404 -121.0945)
		(end 295.22166 -121.0945)
		(width 0.1143)
		(layer "B.Cu")
		(net "EXP_SMART_TX")
	)
	(segment
		(start 321.41795 -141.11605)
		(end 320.929 -141.605)
		(width 0.1143)
		(layer "B.Cu")
		(net "EXP_SMART_TX")
	)
	(segment
		(start 247.12295 -118.44909)
		(end 248.36501 -119.69115)
		(width 0.1143)
		(layer "B.Cu")
		(net "EXP_SMART_TX")
	)
	(segment
		(start 248.36501 -119.69115)
		(end 271.958054 -119.69115)
		(width 0.1143)
		(layer "B.Cu")
		(net "EXP_SMART_TX")
	)
	(segment
		(start 323.787262 -162.517074)
		(end 323.7865 -162.517836)
		(width 0.1143)
		(layer "B.Cu")
		(net "EXP_SMART_TX")
	)
	(segment
		(start 304.97399 -120.83415)
		(end 311.29605 -127.15621)
		(width 0.1143)
		(layer "B.Cu")
		(net "EXP_SMART_TX")
	)
	(segment
		(start 295.22166 -121.0945)
		(end 295.48201 -120.83415)
		(width 0.1143)
		(layer "B.Cu")
		(net "EXP_SMART_TX")
	)
	(segment
		(start 320.929 -151.91105)
		(end 321.056 -152.03805)
		(width 0.1143)
		(layer "B.Cu")
		(net "EXP_SMART_TX")
	)
	(segment
		(start 321.056 -152.03805)
		(end 321.056 -155.829)
		(width 0.1143)
		(layer "B.Cu")
		(net "EXP_SMART_TX")
	)
	(segment
		(start 247.14581 -115.167664)
		(end 247.12295 -115.190524)
		(width 0.1143)
		(layer "B.Cu")
		(net "EXP_SMART_TX")
	)
	(segment
		(start 271.958054 -119.69115)
		(end 273.361404 -121.0945)
		(width 0.1143)
		(layer "B.Cu")
		(net "EXP_SMART_TX")
	)
	(segment
		(start 311.596786 -128.567434)
		(end 315.166502 -132.13715)
		(width 0.1143)
		(layer "B.Cu")
		(net "EXP_SMART_TX")
	)
	(segment
		(start 323.787262 -162.044126)
		(end 323.787262 -162.517074)
		(width 0.1143)
		(layer "B.Cu")
		(net "EXP_SMART_TX")
	)
	(segment
		(start 323.7865 -162.517836)
		(end 323.7865 -162.611054)
		(width 0.1143)
		(layer "B.Cu")
		(net "EXP_SMART_TX")
	)
	(segment
		(start 321.41795 -134.972552)
		(end 321.41795 -141.11605)
		(width 0.1143)
		(layer "B.Cu")
		(net "EXP_SMART_TX")
	)
	(segment
		(start 323.7865 -162.043364)
		(end 323.787262 -162.044126)
		(width 0.1143)
		(layer "B.Cu")
		(net "EXP_SMART_TX")
	)
	(segment
		(start 247.12295 -115.190524)
		(end 247.12295 -118.44909)
		(width 0.1143)
		(layer "B.Cu")
		(net "EXP_SMART_TX")
	)
	(segment
		(start 311.29605 -128.281176)
		(end 311.582308 -128.567434)
		(width 0.1143)
		(layer "B.Cu")
		(net "EXP_SMART_TX")
	)
	(segment
		(start 323.7865 -162.611054)
		(end 323.202554 -163.195)
		(width 0.1143)
		(layer "B.Cu")
		(net "EXP_SMART_TX")
	)
	(segment
		(start 311.582308 -128.567434)
		(end 311.596786 -128.567434)
		(width 0.1143)
		(layer "B.Cu")
		(net "EXP_SMART_TX")
	)
	(segment
		(start 315.166502 -132.13715)
		(end 318.582548 -132.13715)
		(width 0.1143)
		(layer "B.Cu")
		(net "EXP_SMART_TX")
	)
	(segment
		(start 318.582548 -132.13715)
		(end 321.41795 -134.972552)
		(width 0.1143)
		(layer "B.Cu")
		(net "EXP_SMART_TX")
	)
	(segment
		(start 323.7865 -159.910272)
		(end 323.7865 -162.043364)
		(width 0.1143)
		(layer "B.Cu")
		(net "EXP_SMART_TX")
	)
	(segment
		(start 311.29605 -127.15621)
		(end 311.29605 -128.281176)
		(width 0.1143)
		(layer "B.Cu")
		(net "EXP_SMART_TX")
	)
	(segment
		(start 295.48201 -120.83415)
		(end 304.97399 -120.83415)
		(width 0.1143)
		(layer "B.Cu")
		(net "EXP_SMART_TX")
	)
	(segment
		(start 321.056 -157.179772)
		(end 323.7865 -159.910272)
		(width 0.1143)
		(layer "B.Cu")
		(net "EXP_SMART_TX")
	)
	(segment
		(start 321.056 -155.829)
		(end 321.056 -157.179772)
		(width 0.1143)
		(layer "B.Cu")
		(net "EXP_SMART_TX")
	)
	(segment
		(start 328.667872 -167.013128)
		(end 329.057 -166.624)
		(width 0.1143)
		(layer "F.Cu")
		(net "CPU_UART_RX_R")
	)
	(segment
		(start 329.4507 -166.2303)
		(end 329.057 -166.624)
		(width 0.1143)
		(layer "F.Cu")
		(net "CPU_UART_RX_R")
	)
	(segment
		(start 329.4507 -164.3253)
		(end 329.4507 -166.2303)
		(width 0.1143)
		(layer "F.Cu")
		(net "CPU_UART_RX_R")
	)
	(segment
		(start 328.667872 -167.521636)
		(end 328.667872 -167.013128)
		(width 0.1143)
		(layer "F.Cu")
		(net "CPU_UART_RX_R")
	)
	(segment
		(start 330.247244 -163.528756)
		(end 329.4507 -164.3253)
		(width 0.1143)
		(layer "F.Cu")
		(net "CPU_UART_RX_R")
	)
	(segment
		(start 331.499972 -163.528756)
		(end 330.247244 -163.528756)
		(width 0.1143)
		(layer "F.Cu")
		(net "CPU_UART_RX_R")
	)
	(via
		(at 329.057 -166.624)
		(size 0.7112)
		(drill 0.3556)
		(layers "F.Cu" "B.Cu")
		(net "CPU_UART_RX_R")
	)
	(segment
		(start 331.089 -166.243)
		(end 331.089 -166.497)
		(width 0.1143)
		(layer "F.Cu")
		(net "CPU_UART_TX_R")
	)
	(segment
		(start 331.499972 -164.529516)
		(end 330.643484 -164.529516)
		(width 0.1143)
		(layer "F.Cu")
		(net "CPU_UART_TX_R")
	)
	(segment
		(start 330.553822 -165.707822)
		(end 331.089 -166.243)
		(width 0.1143)
		(layer "F.Cu")
		(net "CPU_UART_TX_R")
	)
	(segment
		(start 330.445364 -167.140636)
		(end 331.089 -166.497)
		(width 0.1143)
		(layer "F.Cu")
		(net "CPU_UART_TX_R")
	)
	(segment
		(start 330.643484 -164.529516)
		(end 330.553822 -164.619178)
		(width 0.1143)
		(layer "F.Cu")
		(net "CPU_UART_TX_R")
	)
	(segment
		(start 330.191872 -167.140636)
		(end 330.445364 -167.140636)
		(width 0.1143)
		(layer "F.Cu")
		(net "CPU_UART_TX_R")
	)
	(segment
		(start 330.553822 -164.619178)
		(end 330.553822 -165.707822)
		(width 0.1143)
		(layer "F.Cu")
		(net "CPU_UART_TX_R")
	)
	(via
		(at 331.089 -166.497)
		(size 0.7112)
		(drill 0.3556)
		(layers "F.Cu" "B.Cu")
		(net "CPU_UART_TX_R")
	)
	(segment
		(start 338.185252 -167.623236)
		(end 338.185252 -169.560748)
		(width 0.1143)
		(layer "F.Cu")
		(net "UART2_TX")
	)
	(segment
		(start 331.372972 -173.029626)
		(end 332.053946 -173.7106)
		(width 0.1143)
		(layer "F.Cu")
		(net "UART2_TX")
	)
	(segment
		(start 332.053946 -173.7106)
		(end 334.0354 -173.7106)
		(width 0.1143)
		(layer "F.Cu")
		(net "UART2_TX")
	)
	(segment
		(start 334.0354 -173.7106)
		(end 336.296 -171.45)
		(width 0.1143)
		(layer "F.Cu")
		(net "UART2_TX")
	)
	(segment
		(start 338.185252 -169.560748)
		(end 336.296 -171.45)
		(width 0.1143)
		(layer "F.Cu")
		(net "UART2_TX")
	)
	(via
		(at 336.296 -171.45)
		(size 0.7112)
		(drill 0.3556)
		(layers "F.Cu" "B.Cu")
		(net "UART2_TX")
	)
	(segment
		(start 288.9885 -156.972)
		(end 287.8455 -156.972)
		(width 0.1143)
		(layer "F.Cu")
		(net "CPU_BMC_UART_TX")
	)
	(segment
		(start 281.178 -155.067)
		(end 280.924 -154.813)
		(width 0.1143)
		(layer "F.Cu")
		(net "CPU_BMC_UART_TX")
	)
	(segment
		(start 288.925 -157.0355)
		(end 288.925 -158.0515)
		(width 0.1143)
		(layer "F.Cu")
		(net "CPU_BMC_UART_TX")
	)
	(segment
		(start 259.334 -148.463)
		(end 259.334 -149.479)
		(width 0.1143)
		(layer "F.Cu")
		(net "CPU_BMC_UART_TX")
	)
	(segment
		(start 287.8455 -156.635704)
		(end 286.276796 -155.067)
		(width 0.1143)
		(layer "F.Cu")
		(net "CPU_BMC_UART_TX")
	)
	(segment
		(start 254.762 -137.2235)
		(end 254.762 -143.891)
		(width 0.1143)
		(layer "F.Cu")
		(net "CPU_BMC_UART_TX")
	)
	(segment
		(start 254.762 -143.891)
		(end 259.334 -148.463)
		(width 0.1143)
		(layer "F.Cu")
		(net "CPU_BMC_UART_TX")
	)
	(segment
		(start 288.9885 -156.972)
		(end 288.925 -157.0355)
		(width 0.1143)
		(layer "F.Cu")
		(net "CPU_BMC_UART_TX")
	)
	(segment
		(start 287.8455 -156.972)
		(end 287.8455 -156.635704)
		(width 0.1143)
		(layer "F.Cu")
		(net "CPU_BMC_UART_TX")
	)
	(segment
		(start 286.276796 -155.067)
		(end 281.178 -155.067)
		(width 0.1143)
		(layer "F.Cu")
		(net "CPU_BMC_UART_TX")
	)
	(via
		(at 280.924 -154.813)
		(size 0.5588)
		(drill 0.3048)
		(layers "F.Cu" "B.Cu")
		(net "CPU_BMC_UART_TX")
	)
	(via
		(at 259.334 -149.479)
		(size 0.5588)
		(drill 0.3048)
		(layers "F.Cu" "B.Cu")
		(net "CPU_BMC_UART_TX")
	)
	(via
		(at 276.352 -154.813)
		(size 0.7112)
		(drill 0.3556)
		(layers "F.Cu" "B.Cu")
		(net "CPU_BMC_UART_TX")
	)
	(segment
		(start 259.334 -149.479)
		(end 268.722856 -149.479)
		(width 0.1143)
		(layer "B.Cu")
		(net "CPU_BMC_UART_TX")
	)
	(segment
		(start 268.722856 -149.479)
		(end 274.056856 -154.813)
		(width 0.1143)
		(layer "B.Cu")
		(net "CPU_BMC_UART_TX")
	)
	(segment
		(start 276.352 -154.813)
		(end 280.924 -154.813)
		(width 0.1143)
		(layer "B.Cu")
		(net "CPU_BMC_UART_TX")
	)
	(segment
		(start 274.056856 -154.813)
		(end 276.352 -154.813)
		(width 0.1143)
		(layer "B.Cu")
		(net "CPU_BMC_UART_TX")
	)
	(segment
		(start 333.290418 -169.1132)
		(end 334.9498 -169.1132)
		(width 0.1143)
		(layer "F.Cu")
		(net "UART2_RX")
	)
	(segment
		(start 337.184492 -168.529508)
		(end 336.6008 -169.1132)
		(width 0.1143)
		(layer "F.Cu")
		(net "UART2_RX")
	)
	(segment
		(start 331.372972 -171.030646)
		(end 333.290418 -169.1132)
		(width 0.1143)
		(layer "F.Cu")
		(net "UART2_RX")
	)
	(segment
		(start 336.6008 -169.1132)
		(end 334.9498 -169.1132)
		(width 0.1143)
		(layer "F.Cu")
		(net "UART2_RX")
	)
	(segment
		(start 337.184492 -167.623236)
		(end 337.184492 -168.529508)
		(width 0.1143)
		(layer "F.Cu")
		(net "UART2_RX")
	)
	(via
		(at 334.9498 -169.1132)
		(size 0.7112)
		(drill 0.3556)
		(layers "F.Cu" "B.Cu")
		(net "UART2_RX")
	)
	(segment
		(start 219.41028 -91.47302)
		(end 219.41028 -92.42552)
		(width 0.1143)
		(layer "F.Cu")
		(net "IOC_UART_RX")
	)
	(segment
		(start 327.359772 -163.528756)
		(end 326.644 -163.528756)
		(width 0.1143)
		(layer "F.Cu")
		(net "IOC_UART_RX")
	)
	(segment
		(start 326.34555 -157.861)
		(end 326.34555 -160.502854)
		(width 0.1143)
		(layer "F.Cu")
		(net "IOC_UART_RX")
	)
	(segment
		(start 326.34555 -163.230306)
		(end 326.34555 -160.502854)
		(width 0.1143)
		(layer "F.Cu")
		(net "IOC_UART_RX")
	)
	(segment
		(start 326.644 -163.528756)
		(end 326.34555 -163.230306)
		(width 0.1143)
		(layer "F.Cu")
		(net "IOC_UART_RX")
	)
	(via
		(at 326.34555 -157.861)
		(size 0.5588)
		(drill 0.3048)
		(layers "F.Cu" "B.Cu")
		(net "IOC_UART_RX")
	)
	(via
		(at 326.34555 -160.502854)
		(size 0.7112)
		(drill 0.3556)
		(layers "F.Cu" "B.Cu")
		(net "IOC_UART_RX")
	)
	(via
		(at 219.41028 -92.42552)
		(size 0.5588)
		(drill 0.3048)
		(layers "F.Cu" "B.Cu")
		(net "IOC_UART_RX")
	)
	(segment
		(start 265.1252 -91.3638)
		(end 266.30122 -90.18778)
		(width 0.127)
		(layer "In5.Cu")
		(net "IOC_UART_RX")
	)
	(segment
		(start 219.90558 -91.93022)
		(end 221.011242 -91.93022)
		(width 0.127)
		(layer "In5.Cu")
		(net "IOC_UART_RX")
	)
	(segment
		(start 326.34555 -154.195018)
		(end 326.34555 -157.861)
		(width 0.127)
		(layer "In5.Cu")
		(net "IOC_UART_RX")
	)
	(segment
		(start 266.30122 -90.18778)
		(end 295.319704 -90.18778)
		(width 0.127)
		(layer "In5.Cu")
		(net "IOC_UART_RX")
	)
	(segment
		(start 221.011242 -91.93022)
		(end 221.056962 -91.97594)
		(width 0.127)
		(layer "In5.Cu")
		(net "IOC_UART_RX")
	)
	(segment
		(start 219.41028 -92.42552)
		(end 219.90558 -91.93022)
		(width 0.127)
		(layer "In5.Cu")
		(net "IOC_UART_RX")
	)
	(segment
		(start 295.492424 -90.3605)
		(end 297.246294 -90.3605)
		(width 0.127)
		(layer "In5.Cu")
		(net "IOC_UART_RX")
	)
	(segment
		(start 299.7073 -92.821506)
		(end 299.7073 -134.837678)
		(width 0.127)
		(layer "In5.Cu")
		(net "IOC_UART_RX")
	)
	(segment
		(start 309.763922 -139.757404)
		(end 318.977518 -148.971)
		(width 0.127)
		(layer "In5.Cu")
		(net "IOC_UART_RX")
	)
	(segment
		(start 321.121532 -148.971)
		(end 326.34555 -154.195018)
		(width 0.127)
		(layer "In5.Cu")
		(net "IOC_UART_RX")
	)
	(segment
		(start 228.57206 -91.97594)
		(end 229.1842 -91.3638)
		(width 0.127)
		(layer "In5.Cu")
		(net "IOC_UART_RX")
	)
	(segment
		(start 318.977518 -148.971)
		(end 321.121532 -148.971)
		(width 0.127)
		(layer "In5.Cu")
		(net "IOC_UART_RX")
	)
	(segment
		(start 229.1842 -91.3638)
		(end 265.1252 -91.3638)
		(width 0.127)
		(layer "In5.Cu")
		(net "IOC_UART_RX")
	)
	(segment
		(start 221.056962 -91.97594)
		(end 228.57206 -91.97594)
		(width 0.127)
		(layer "In5.Cu")
		(net "IOC_UART_RX")
	)
	(segment
		(start 297.246294 -90.3605)
		(end 299.7073 -92.821506)
		(width 0.127)
		(layer "In5.Cu")
		(net "IOC_UART_RX")
	)
	(segment
		(start 299.7073 -134.837678)
		(end 304.627026 -139.757404)
		(width 0.127)
		(layer "In5.Cu")
		(net "IOC_UART_RX")
	)
	(segment
		(start 304.627026 -139.757404)
		(end 309.763922 -139.757404)
		(width 0.127)
		(layer "In5.Cu")
		(net "IOC_UART_RX")
	)
	(segment
		(start 295.319704 -90.18778)
		(end 295.492424 -90.3605)
		(width 0.127)
		(layer "In5.Cu")
		(net "IOC_UART_RX")
	)
	(segment
		(start 338.185252 -164.988748)
		(end 337.83905 -165.33495)
		(width 0.1143)
		(layer "F.Cu")
		(net "UART1_TX")
	)
	(segment
		(start 331.499972 -165.028626)
		(end 333.830676 -165.028626)
		(width 0.1143)
		(layer "F.Cu")
		(net "UART1_TX")
	)
	(segment
		(start 333.830676 -165.028626)
		(end 334.137 -165.33495)
		(width 0.1143)
		(layer "F.Cu")
		(net "UART1_TX")
	)
	(segment
		(start 337.83905 -165.33495)
		(end 334.137 -165.33495)
		(width 0.1143)
		(layer "F.Cu")
		(net "UART1_TX")
	)
	(segment
		(start 338.185252 -163.483036)
		(end 338.185252 -164.988748)
		(width 0.1143)
		(layer "F.Cu")
		(net "UART1_TX")
	)
	(via
		(at 334.137 -165.33495)
		(size 0.7112)
		(drill 0.3556)
		(layers "F.Cu" "B.Cu")
		(net "UART1_TX")
	)
	(segment
		(start 327.232772 -172.530516)
		(end 326.198484 -172.530516)
		(width 0.1143)
		(layer "F.Cu")
		(net "EXP_UART_TX_R")
	)
	(segment
		(start 326.198484 -172.530516)
		(end 325.628 -173.101)
		(width 0.1143)
		(layer "F.Cu")
		(net "EXP_UART_TX_R")
	)
	(segment
		(start 324.4215 -173.101)
		(end 325.247 -173.101)
		(width 0.1143)
		(layer "F.Cu")
		(net "EXP_UART_TX_R")
	)
	(segment
		(start 324.2945 -172.974)
		(end 324.4215 -173.101)
		(width 0.1143)
		(layer "F.Cu")
		(net "EXP_UART_TX_R")
	)
	(segment
		(start 325.628 -173.101)
		(end 325.247 -173.101)
		(width 0.1143)
		(layer "F.Cu")
		(net "EXP_UART_TX_R")
	)
	(via
		(at 325.247 -173.101)
		(size 0.7112)
		(drill 0.3556)
		(layers "F.Cu" "B.Cu")
		(net "EXP_UART_TX_R")
	)
	(segment
		(start 332.651354 -163.029646)
		(end 332.816708 -163.195)
		(width 0.1143)
		(layer "F.Cu")
		(net "UART1_RX")
	)
	(segment
		(start 337.184492 -164.211508)
		(end 336.677 -164.719)
		(width 0.1143)
		(layer "F.Cu")
		(net "UART1_RX")
	)
	(segment
		(start 332.816708 -163.195)
		(end 333.883 -163.195)
		(width 0.1143)
		(layer "F.Cu")
		(net "UART1_RX")
	)
	(segment
		(start 336.042 -164.719)
		(end 334.518 -163.195)
		(width 0.1143)
		(layer "F.Cu")
		(net "UART1_RX")
	)
	(segment
		(start 336.677 -164.719)
		(end 336.042 -164.719)
		(width 0.1143)
		(layer "F.Cu")
		(net "UART1_RX")
	)
	(segment
		(start 331.499972 -163.029646)
		(end 332.651354 -163.029646)
		(width 0.1143)
		(layer "F.Cu")
		(net "UART1_RX")
	)
	(segment
		(start 334.518 -163.195)
		(end 333.883 -163.195)
		(width 0.1143)
		(layer "F.Cu")
		(net "UART1_RX")
	)
	(segment
		(start 337.184492 -163.483036)
		(end 337.184492 -164.211508)
		(width 0.1143)
		(layer "F.Cu")
		(net "UART1_RX")
	)
	(via
		(at 333.883 -163.195)
		(size 0.7112)
		(drill 0.3556)
		(layers "F.Cu" "B.Cu")
		(net "UART1_RX")
	)
	(segment
		(start 307.5686 -61.3664)
		(end 306.302664 -61.3664)
		(width 0.1143)
		(layer "F.Cu")
		(net "PMU_WAKE_N_R")
	)
	(segment
		(start 307.73497 -61.20003)
		(end 307.5686 -61.3664)
		(width 0.1143)
		(layer "F.Cu")
		(net "PMU_WAKE_N_R")
	)
	(segment
		(start 304.94986 -61.468)
		(end 304.717958 -61.699902)
		(width 0.1143)
		(layer "F.Cu")
		(net "PMU_WAKE_N_R")
	)
	(segment
		(start 302.21555 -62.05855)
		(end 304.35931 -62.05855)
		(width 0.1143)
		(layer "F.Cu")
		(net "PMU_WAKE_N_R")
	)
	(segment
		(start 304.35931 -62.05855)
		(end 304.717958 -61.699902)
		(width 0.1143)
		(layer "F.Cu")
		(net "PMU_WAKE_N_R")
	)
	(segment
		(start 306.201064 -61.468)
		(end 304.94986 -61.468)
		(width 0.1143)
		(layer "F.Cu")
		(net "PMU_WAKE_N_R")
	)
	(segment
		(start 302.133 -61.976)
		(end 302.21555 -62.05855)
		(width 0.1143)
		(layer "F.Cu")
		(net "PMU_WAKE_N_R")
	)
	(segment
		(start 300.9265 -61.976)
		(end 302.133 -61.976)
		(width 0.1143)
		(layer "F.Cu")
		(net "PMU_WAKE_N_R")
	)
	(segment
		(start 306.302664 -61.3664)
		(end 306.201064 -61.468)
		(width 0.1143)
		(layer "F.Cu")
		(net "PMU_WAKE_N_R")
	)
	(segment
		(start 308.675024 -61.20003)
		(end 307.73497 -61.20003)
		(width 0.1143)
		(layer "F.Cu")
		(net "PMU_WAKE_N_R")
	)
	(via
		(at 304.717958 -61.699902)
		(size 0.7112)
		(drill 0.3556)
		(layers "F.Cu" "B.Cu")
		(net "PMU_WAKE_N_R")
	)
	(segment
		(start 41.47947 -139.827)
		(end 41.51122 -139.79525)
		(width 0.1143)
		(layer "F.Cu")
		(net "BMC_RST_EXPANDER")
	)
	(segment
		(start 41.51122 -139.79525)
		(end 41.51122 -138.1125)
		(width 0.1143)
		(layer "F.Cu")
		(net "BMC_RST_EXPANDER")
	)
	(segment
		(start 287.234884 -169.840148)
		(end 287.629092 -169.44594)
		(width 0.1143)
		(layer "F.Cu")
		(net "BMC_RST_EXPANDER")
	)
	(segment
		(start 287.629092 -169.44594)
		(end 287.629092 -169.443908)
		(width 0.1143)
		(layer "F.Cu")
		(net "BMC_RST_EXPANDER")
	)
	(segment
		(start 41.47947 -140.9065)
		(end 41.47947 -139.827)
		(width 0.1143)
		(layer "F.Cu")
		(net "BMC_RST_EXPANDER")
	)
	(via
		(at 41.47947 -140.9065)
		(size 0.5588)
		(drill 0.3048)
		(layers "F.Cu" "B.Cu")
		(net "BMC_RST_EXPANDER")
	)
	(via
		(at 284.0228 -166.9796)
		(size 0.7112)
		(drill 0.3556)
		(layers "F.Cu" "B.Cu")
		(net "BMC_RST_EXPANDER")
	)
	(via
		(at 287.629092 -169.443908)
		(size 0.508)
		(drill 0.254)
		(layers "F.Cu" "B.Cu")
		(net "BMC_RST_EXPANDER")
	)
	(via
		(at 259.715 -161.925)
		(size 0.508)
		(drill 0.254)
		(layers "F.Cu" "B.Cu")
		(net "BMC_RST_EXPANDER")
	)
	(segment
		(start 287.629092 -169.443908)
		(end 286.487108 -169.443908)
		(width 0.1143)
		(layer "B.Cu")
		(net "BMC_RST_EXPANDER")
	)
	(segment
		(start 284.0228 -166.9796)
		(end 277.84425 -160.80105)
		(width 0.1143)
		(layer "B.Cu")
		(net "BMC_RST_EXPANDER")
	)
	(segment
		(start 260.83895 -160.80105)
		(end 259.715 -161.925)
		(width 0.1143)
		(layer "B.Cu")
		(net "BMC_RST_EXPANDER")
	)
	(segment
		(start 286.487108 -169.443908)
		(end 284.0228 -166.9796)
		(width 0.1143)
		(layer "B.Cu")
		(net "BMC_RST_EXPANDER")
	)
	(segment
		(start 277.84425 -160.80105)
		(end 260.83895 -160.80105)
		(width 0.1143)
		(layer "B.Cu")
		(net "BMC_RST_EXPANDER")
	)
	(segment
		(start 86.3473 -159.4993)
		(end 86.3473 -156.438346)
		(width 0.127)
		(layer "In2.Cu")
		(net "BMC_RST_EXPANDER")
	)
	(segment
		(start 204.351636 -163.9062)
		(end 202.916282 -162.470846)
		(width 0.127)
		(layer "In2.Cu")
		(net "BMC_RST_EXPANDER")
	)
	(segment
		(start 193.893186 -162.470846)
		(end 192.407032 -163.957)
		(width 0.127)
		(layer "In2.Cu")
		(net "BMC_RST_EXPANDER")
	)
	(segment
		(start 81.305654 -151.3967)
		(end 80.5307 -151.3967)
		(width 0.127)
		(layer "In2.Cu")
		(net "BMC_RST_EXPANDER")
	)
	(segment
		(start 43.241468 -151.003)
		(end 41.47947 -149.241002)
		(width 0.127)
		(layer "In2.Cu")
		(net "BMC_RST_EXPANDER")
	)
	(segment
		(start 202.916282 -162.470846)
		(end 193.893186 -162.470846)
		(width 0.127)
		(layer "In2.Cu")
		(net "BMC_RST_EXPANDER")
	)
	(segment
		(start 41.47947 -149.241002)
		(end 41.47947 -140.9065)
		(width 0.127)
		(layer "In2.Cu")
		(net "BMC_RST_EXPANDER")
	)
	(segment
		(start 86.3473 -156.438346)
		(end 81.305654 -151.3967)
		(width 0.127)
		(layer "In2.Cu")
		(net "BMC_RST_EXPANDER")
	)
	(segment
		(start 192.407032 -163.957)
		(end 171.620434 -163.957)
		(width 0.127)
		(layer "In2.Cu")
		(net "BMC_RST_EXPANDER")
	)
	(segment
		(start 99.348544 -170.543728)
		(end 97.448116 -168.6433)
		(width 0.127)
		(layer "In2.Cu")
		(net "BMC_RST_EXPANDER")
	)
	(segment
		(start 80.137 -151.003)
		(end 43.241468 -151.003)
		(width 0.127)
		(layer "In2.Cu")
		(net "BMC_RST_EXPANDER")
	)
	(segment
		(start 229.300532 -161.6583)
		(end 227.014532 -163.9443)
		(width 0.127)
		(layer "In2.Cu")
		(net "BMC_RST_EXPANDER")
	)
	(segment
		(start 80.5307 -151.3967)
		(end 80.137 -151.003)
		(width 0.127)
		(layer "In2.Cu")
		(net "BMC_RST_EXPANDER")
	)
	(segment
		(start 219.211398 -163.9443)
		(end 219.173298 -163.9062)
		(width 0.127)
		(layer "In2.Cu")
		(net "BMC_RST_EXPANDER")
	)
	(segment
		(start 97.448116 -168.6433)
		(end 95.4913 -168.6433)
		(width 0.127)
		(layer "In2.Cu")
		(net "BMC_RST_EXPANDER")
	)
	(segment
		(start 219.173298 -163.9062)
		(end 204.351636 -163.9062)
		(width 0.127)
		(layer "In2.Cu")
		(net "BMC_RST_EXPANDER")
	)
	(segment
		(start 171.620434 -163.957)
		(end 165.033706 -170.543728)
		(width 0.127)
		(layer "In2.Cu")
		(net "BMC_RST_EXPANDER")
	)
	(segment
		(start 165.033706 -170.543728)
		(end 99.348544 -170.543728)
		(width 0.127)
		(layer "In2.Cu")
		(net "BMC_RST_EXPANDER")
	)
	(segment
		(start 227.014532 -163.9443)
		(end 219.211398 -163.9443)
		(width 0.127)
		(layer "In2.Cu")
		(net "BMC_RST_EXPANDER")
	)
	(segment
		(start 259.715 -161.925)
		(end 259.4483 -161.6583)
		(width 0.127)
		(layer "In2.Cu")
		(net "BMC_RST_EXPANDER")
	)
	(segment
		(start 259.4483 -161.6583)
		(end 229.300532 -161.6583)
		(width 0.127)
		(layer "In2.Cu")
		(net "BMC_RST_EXPANDER")
	)
	(segment
		(start 95.4913 -168.6433)
		(end 86.3473 -159.4993)
		(width 0.127)
		(layer "In2.Cu")
		(net "BMC_RST_EXPANDER")
	)
	(segment
		(start 9.492488 -224.78238)
		(end 9.515348 -224.78238)
		(width 0.1143)
		(layer "F.Cu")
		(net "PEER_TRAY_BMC")
	)
	(segment
		(start 9.301988 -224.97288)
		(end 9.492488 -224.78238)
		(width 0.1143)
		(layer "F.Cu")
		(net "PEER_TRAY_BMC")
	)
	(segment
		(start 297.634914 -169.840148)
		(end 297.625516 -169.840148)
		(width 0.1143)
		(layer "F.Cu")
		(net "PEER_TRAY_BMC")
	)
	(segment
		(start 297.625516 -169.840148)
		(end 297.228768 -169.4434)
		(width 0.1143)
		(layer "F.Cu")
		(net "PEER_TRAY_BMC")
	)
	(segment
		(start 9.515348 -224.78238)
		(end 9.590532 -224.707196)
		(width 0.1143)
		(layer "F.Cu")
		(net "PEER_TRAY_BMC")
	)
	(segment
		(start 8.522716 -224.97288)
		(end 9.301988 -224.97288)
		(width 0.1143)
		(layer "F.Cu")
		(net "PEER_TRAY_BMC")
	)
	(via
		(at 192.405 -188.849)
		(size 0.5588)
		(drill 0.3048)
		(layers "F.Cu" "B.Cu")
		(net "PEER_TRAY_BMC")
	)
	(via
		(at 297.228768 -169.4434)
		(size 0.508)
		(drill 0.254)
		(layers "F.Cu" "B.Cu")
		(net "PEER_TRAY_BMC")
	)
	(via
		(at 192.278 -227.6856)
		(size 0.5588)
		(drill 0.3048)
		(layers "F.Cu" "B.Cu")
		(net "PEER_TRAY_BMC")
	)
	(via
		(at 9.590532 -224.707196)
		(size 0.5588)
		(drill 0.3048)
		(layers "F.Cu" "B.Cu")
		(net "PEER_TRAY_BMC")
	)
	(via
		(at 300.978824 -157.295088)
		(size 0.5588)
		(drill 0.3048)
		(layers "F.Cu" "B.Cu")
		(net "PEER_TRAY_BMC")
	)
	(via
		(at 329.946 -162.941)
		(size 0.5588)
		(drill 0.3048)
		(layers "F.Cu" "B.Cu")
		(net "PEER_TRAY_BMC")
	)
	(via
		(at 300.355 -158.369)
		(size 0.7112)
		(drill 0.3556)
		(layers "F.Cu" "B.Cu")
		(net "PEER_TRAY_BMC")
	)
	(segment
		(start 300.978824 -157.295088)
		(end 300.978824 -157.745176)
		(width 0.1143)
		(layer "B.Cu")
		(net "PEER_TRAY_BMC")
	)
	(segment
		(start 298.704 -166.028624)
		(end 297.3197 -167.412924)
		(width 0.1143)
		(layer "B.Cu")
		(net "PEER_TRAY_BMC")
	)
	(segment
		(start 298.831 -161.815018)
		(end 298.704 -161.942018)
		(width 0.1143)
		(layer "B.Cu")
		(net "PEER_TRAY_BMC")
	)
	(segment
		(start 300.978824 -157.745176)
		(end 300.355 -158.369)
		(width 0.1143)
		(layer "B.Cu")
		(net "PEER_TRAY_BMC")
	)
	(segment
		(start 192.278 -227.6856)
		(end 192.278 -227.584)
		(width 0.1143)
		(layer "B.Cu")
		(net "PEER_TRAY_BMC")
	)
	(segment
		(start 297.3197 -167.412924)
		(end 297.3197 -169.352468)
		(width 0.1143)
		(layer "B.Cu")
		(net "PEER_TRAY_BMC")
	)
	(segment
		(start 298.831 -159.893)
		(end 298.831 -161.815018)
		(width 0.1143)
		(layer "B.Cu")
		(net "PEER_TRAY_BMC")
	)
	(segment
		(start 300.355 -158.369)
		(end 298.831 -159.893)
		(width 0.1143)
		(layer "B.Cu")
		(net "PEER_TRAY_BMC")
	)
	(segment
		(start 192.278 -227.584)
		(end 192.405 -227.457)
		(width 0.1143)
		(layer "B.Cu")
		(net "PEER_TRAY_BMC")
	)
	(segment
		(start 192.405 -227.457)
		(end 192.405 -188.849)
		(width 0.1143)
		(layer "B.Cu")
		(net "PEER_TRAY_BMC")
	)
	(segment
		(start 297.3197 -169.352468)
		(end 297.228768 -169.4434)
		(width 0.1143)
		(layer "B.Cu")
		(net "PEER_TRAY_BMC")
	)
	(segment
		(start 298.704 -161.942018)
		(end 298.704 -166.028624)
		(width 0.1143)
		(layer "B.Cu")
		(net "PEER_TRAY_BMC")
	)
	(segment
		(start 329.946 -162.941)
		(end 329.946 -164.400738)
		(width 0.127)
		(layer "In2.Cu")
		(net "PEER_TRAY_BMC")
	)
	(segment
		(start 100.147628 -216.8398)
		(end 67.994276 -216.8398)
		(width 0.127)
		(layer "In2.Cu")
		(net "PEER_TRAY_BMC")
	)
	(segment
		(start 263.80821 -237.6297)
		(end 259.960364 -233.781854)
		(width 0.127)
		(layer "In2.Cu")
		(net "PEER_TRAY_BMC")
	)
	(segment
		(start 103.962454 -220.654626)
		(end 100.147628 -216.8398)
		(width 0.127)
		(layer "In2.Cu")
		(net "PEER_TRAY_BMC")
	)
	(segment
		(start 259.710428 -193.896488)
		(end 253.06274 -187.2488)
		(width 0.127)
		(layer "In2.Cu")
		(net "PEER_TRAY_BMC")
	)
	(segment
		(start 39.37 -218.821)
		(end 14.291564 -218.821)
		(width 0.127)
		(layer "In2.Cu")
		(net "PEER_TRAY_BMC")
	)
	(segment
		(start 329.946 -164.400738)
		(end 330.708 -165.162738)
		(width 0.127)
		(layer "In2.Cu")
		(net "PEER_TRAY_BMC")
	)
	(segment
		(start 330.073 -170.37177)
		(end 330.073 -181.864)
		(width 0.127)
		(layer "In2.Cu")
		(net "PEER_TRAY_BMC")
	)
	(segment
		(start 228.205538 -189.3062)
		(end 192.8622 -189.3062)
		(width 0.127)
		(layer "In2.Cu")
		(net "PEER_TRAY_BMC")
	)
	(segment
		(start 330.708 -165.162738)
		(end 330.708 -169.73677)
		(width 0.127)
		(layer "In2.Cu")
		(net "PEER_TRAY_BMC")
	)
	(segment
		(start 260.3627 -225.777044)
		(end 260.3627 -218.673172)
		(width 0.127)
		(layer "In2.Cu")
		(net "PEER_TRAY_BMC")
	)
	(segment
		(start 292.279832 -237.6297)
		(end 263.80821 -237.6297)
		(width 0.127)
		(layer "In2.Cu")
		(net "PEER_TRAY_BMC")
	)
	(segment
		(start 259.960364 -226.17938)
		(end 260.3627 -225.777044)
		(width 0.127)
		(layer "In2.Cu")
		(net "PEER_TRAY_BMC")
	)
	(segment
		(start 67.994276 -216.8398)
		(end 66.863976 -215.7095)
		(width 0.127)
		(layer "In2.Cu")
		(net "PEER_TRAY_BMC")
	)
	(segment
		(start 41.65346 -216.53754)
		(end 39.37 -218.821)
		(width 0.127)
		(layer "In2.Cu")
		(net "PEER_TRAY_BMC")
	)
	(segment
		(start 110.75162 -227.6856)
		(end 103.962454 -220.896434)
		(width 0.127)
		(layer "In2.Cu")
		(net "PEER_TRAY_BMC")
	)
	(segment
		(start 66.863976 -215.7095)
		(end 48.392334 -215.7095)
		(width 0.127)
		(layer "In2.Cu")
		(net "PEER_TRAY_BMC")
	)
	(segment
		(start 259.710428 -218.0209)
		(end 259.710428 -193.896488)
		(width 0.127)
		(layer "In2.Cu")
		(net "PEER_TRAY_BMC")
	)
	(segment
		(start 48.392334 -215.7095)
		(end 47.564294 -216.53754)
		(width 0.127)
		(layer "In2.Cu")
		(net "PEER_TRAY_BMC")
	)
	(segment
		(start 10.427716 -222.684848)
		(end 10.427716 -223.870012)
		(width 0.127)
		(layer "In2.Cu")
		(net "PEER_TRAY_BMC")
	)
	(segment
		(start 103.962454 -220.896434)
		(end 103.962454 -220.654626)
		(width 0.127)
		(layer "In2.Cu")
		(net "PEER_TRAY_BMC")
	)
	(segment
		(start 230.262938 -187.2488)
		(end 228.205538 -189.3062)
		(width 0.127)
		(layer "In2.Cu")
		(net "PEER_TRAY_BMC")
	)
	(segment
		(start 326.517 -185.42)
		(end 326.517 -203.392532)
		(width 0.127)
		(layer "In2.Cu")
		(net "PEER_TRAY_BMC")
	)
	(segment
		(start 330.073 -181.864)
		(end 326.517 -185.42)
		(width 0.127)
		(layer "In2.Cu")
		(net "PEER_TRAY_BMC")
	)
	(segment
		(start 192.278 -227.6856)
		(end 110.75162 -227.6856)
		(width 0.127)
		(layer "In2.Cu")
		(net "PEER_TRAY_BMC")
	)
	(segment
		(start 330.708 -169.73677)
		(end 330.073 -170.37177)
		(width 0.127)
		(layer "In2.Cu")
		(net "PEER_TRAY_BMC")
	)
	(segment
		(start 10.427716 -223.870012)
		(end 9.590532 -224.707196)
		(width 0.127)
		(layer "In2.Cu")
		(net "PEER_TRAY_BMC")
	)
	(segment
		(start 326.517 -203.392532)
		(end 292.279832 -237.6297)
		(width 0.127)
		(layer "In2.Cu")
		(net "PEER_TRAY_BMC")
	)
	(segment
		(start 14.291564 -218.821)
		(end 10.427716 -222.684848)
		(width 0.127)
		(layer "In2.Cu")
		(net "PEER_TRAY_BMC")
	)
	(segment
		(start 253.06274 -187.2488)
		(end 230.262938 -187.2488)
		(width 0.127)
		(layer "In2.Cu")
		(net "PEER_TRAY_BMC")
	)
	(segment
		(start 47.564294 -216.53754)
		(end 41.65346 -216.53754)
		(width 0.127)
		(layer "In2.Cu")
		(net "PEER_TRAY_BMC")
	)
	(segment
		(start 192.8622 -189.3062)
		(end 192.405 -188.849)
		(width 0.127)
		(layer "In2.Cu")
		(net "PEER_TRAY_BMC")
	)
	(segment
		(start 259.960364 -233.781854)
		(end 259.960364 -226.17938)
		(width 0.127)
		(layer "In2.Cu")
		(net "PEER_TRAY_BMC")
	)
	(segment
		(start 260.3627 -218.673172)
		(end 259.710428 -218.0209)
		(width 0.127)
		(layer "In2.Cu")
		(net "PEER_TRAY_BMC")
	)
	(segment
		(start 314.650882 -157.295088)
		(end 300.978824 -157.295088)
		(width 0.127)
		(layer "In5.Cu")
		(net "PEER_TRAY_BMC")
	)
	(segment
		(start 329.946 -162.049206)
		(end 327.802494 -159.9057)
		(width 0.127)
		(layer "In5.Cu")
		(net "PEER_TRAY_BMC")
	)
	(segment
		(start 327.802494 -159.9057)
		(end 317.261494 -159.9057)
		(width 0.127)
		(layer "In5.Cu")
		(net "PEER_TRAY_BMC")
	)
	(segment
		(start 317.261494 -159.9057)
		(end 314.650882 -157.295088)
		(width 0.127)
		(layer "In5.Cu")
		(net "PEER_TRAY_BMC")
	)
	(segment
		(start 329.946 -162.941)
		(end 329.946 -162.049206)
		(width 0.127)
		(layer "In5.Cu")
		(net "PEER_TRAY_BMC")
	)
	(segment
		(start 301.171356 -175.776636)
		(end 301.709836 -175.776636)
		(width 0.1143)
		(layer "F.Cu")
		(net "ADC_P1V8_STBY_BMC")
	)
	(segment
		(start 301.709836 -175.776636)
		(end 302.73625 -176.80305)
		(width 0.1143)
		(layer "F.Cu")
		(net "ADC_P1V8_STBY_BMC")
	)
	(segment
		(start 315.4172 -178.3842)
		(end 309.744872 -178.3842)
		(width 0.1143)
		(layer "F.Cu")
		(net "ADC_P1V8_STBY_BMC")
	)
	(segment
		(start 308.163722 -176.80305)
		(end 307.594 -176.80305)
		(width 0.1143)
		(layer "F.Cu")
		(net "ADC_P1V8_STBY_BMC")
	)
	(segment
		(start 317.5635 -179.705)
		(end 316.738 -179.705)
		(width 0.1143)
		(layer "F.Cu")
		(net "ADC_P1V8_STBY_BMC")
	)
	(segment
		(start 309.744872 -178.3842)
		(end 308.163722 -176.80305)
		(width 0.1143)
		(layer "F.Cu")
		(net "ADC_P1V8_STBY_BMC")
	)
	(segment
		(start 302.73625 -176.80305)
		(end 307.594 -176.80305)
		(width 0.1143)
		(layer "F.Cu")
		(net "ADC_P1V8_STBY_BMC")
	)
	(segment
		(start 300.834806 -175.440086)
		(end 301.171356 -175.776636)
		(width 0.1143)
		(layer "F.Cu")
		(net "ADC_P1V8_STBY_BMC")
	)
	(segment
		(start 316.738 -179.705)
		(end 315.4172 -178.3842)
		(width 0.1143)
		(layer "F.Cu")
		(net "ADC_P1V8_STBY_BMC")
	)
	(via
		(at 307.594 -176.80305)
		(size 0.7112)
		(drill 0.3556)
		(layers "F.Cu" "B.Cu")
		(net "ADC_P1V8_STBY_BMC")
	)
	(segment
		(start 316.0395 -193.548)
		(end 315.964062 -193.623438)
		(width 0.1143)
		(layer "F.Cu")
		(net "JTAG_BMC_TDO")
	)
	(segment
		(start 316.0395 -193.548)
		(end 316.0395 -191.897)
		(width 0.1143)
		(layer "F.Cu")
		(net "JTAG_BMC_TDO")
	)
	(segment
		(start 300.044358 -172.240194)
		(end 300.43501 -171.849542)
		(width 0.1143)
		(layer "F.Cu")
		(net "JTAG_BMC_TDO")
	)
	(segment
		(start 314.198 -190.5)
		(end 314.071 -190.5)
		(width 0.1143)
		(layer "F.Cu")
		(net "JTAG_BMC_TDO")
	)
	(segment
		(start 300.03496 -172.240194)
		(end 300.044358 -172.240194)
		(width 0.1143)
		(layer "F.Cu")
		(net "JTAG_BMC_TDO")
	)
	(segment
		(start 315.964062 -193.623438)
		(end 315.964062 -195.199)
		(width 0.1143)
		(layer "F.Cu")
		(net "JTAG_BMC_TDO")
	)
	(segment
		(start 316.0395 -191.897)
		(end 314.6425 -190.5)
		(width 0.1143)
		(layer "F.Cu")
		(net "JTAG_BMC_TDO")
	)
	(segment
		(start 314.071 -190.5)
		(end 313.436 -189.865)
		(width 0.1143)
		(layer "F.Cu")
		(net "JTAG_BMC_TDO")
	)
	(segment
		(start 314.6425 -190.5)
		(end 314.198 -190.5)
		(width 0.1143)
		(layer "F.Cu")
		(net "JTAG_BMC_TDO")
	)
	(via
		(at 300.43501 -171.849542)
		(size 0.508)
		(drill 0.254)
		(layers "F.Cu" "B.Cu")
		(net "JTAG_BMC_TDO")
	)
	(via
		(at 313.436 -189.865)
		(size 0.5588)
		(drill 0.3048)
		(layers "F.Cu" "B.Cu")
		(net "JTAG_BMC_TDO")
	)
	(segment
		(start 312.6613 -182.983632)
		(end 312.6613 -179.175156)
		(width 0.127)
		(layer "In2.Cu")
		(net "JTAG_BMC_TDO")
	)
	(segment
		(start 300.642274 -171.849542)
		(end 300.43501 -171.849542)
		(width 0.127)
		(layer "In2.Cu")
		(net "JTAG_BMC_TDO")
	)
	(segment
		(start 312.18378 -183.2737)
		(end 312.371232 -183.2737)
		(width 0.127)
		(layer "In2.Cu")
		(net "JTAG_BMC_TDO")
	)
	(segment
		(start 312.6613 -179.175156)
		(end 305.754786 -172.268642)
		(width 0.127)
		(layer "In2.Cu")
		(net "JTAG_BMC_TDO")
	)
	(segment
		(start 311.2897 -189.371732)
		(end 311.2897 -184.16778)
		(width 0.127)
		(layer "In2.Cu")
		(net "JTAG_BMC_TDO")
	)
	(segment
		(start 305.754786 -172.268642)
		(end 301.061374 -172.268642)
		(width 0.127)
		(layer "In2.Cu")
		(net "JTAG_BMC_TDO")
	)
	(segment
		(start 312.371232 -183.2737)
		(end 312.6613 -182.983632)
		(width 0.127)
		(layer "In2.Cu")
		(net "JTAG_BMC_TDO")
	)
	(segment
		(start 301.061374 -172.268642)
		(end 300.642274 -171.849542)
		(width 0.127)
		(layer "In2.Cu")
		(net "JTAG_BMC_TDO")
	)
	(segment
		(start 312.270394 -190.352426)
		(end 311.2897 -189.371732)
		(width 0.127)
		(layer "In2.Cu")
		(net "JTAG_BMC_TDO")
	)
	(segment
		(start 311.2897 -184.16778)
		(end 312.18378 -183.2737)
		(width 0.127)
		(layer "In2.Cu")
		(net "JTAG_BMC_TDO")
	)
	(segment
		(start 312.948574 -190.352426)
		(end 312.270394 -190.352426)
		(width 0.127)
		(layer "In2.Cu")
		(net "JTAG_BMC_TDO")
	)
	(segment
		(start 313.436 -189.865)
		(end 312.948574 -190.352426)
		(width 0.127)
		(layer "In2.Cu")
		(net "JTAG_BMC_TDO")
	)
	(segment
		(start 299.63999 -175.835056)
		(end 299.63999 -175.842168)
		(width 0.1143)
		(layer "F.Cu")
		(net "ADC_P3V3_STBY_BMC")
	)
	(segment
		(start 300.03496 -175.440086)
		(end 299.63999 -175.835056)
		(width 0.1143)
		(layer "F.Cu")
		(net "ADC_P3V3_STBY_BMC")
	)
	(via
		(at 313.69 -178.689)
		(size 0.7112)
		(drill 0.3556)
		(layers "F.Cu" "B.Cu")
		(net "ADC_P3V3_STBY_BMC")
	)
	(via
		(at 299.63999 -175.842168)
		(size 0.508)
		(drill 0.254)
		(layers "F.Cu" "B.Cu")
		(net "ADC_P3V3_STBY_BMC")
	)
	(segment
		(start 312.674 -178.689)
		(end 313.69 -178.689)
		(width 0.1143)
		(layer "B.Cu")
		(net "ADC_P3V3_STBY_BMC")
	)
	(segment
		(start 317.5635 -178.689)
		(end 313.69 -178.689)
		(width 0.1143)
		(layer "B.Cu")
		(net "ADC_P3V3_STBY_BMC")
	)
	(segment
		(start 309.2577 -175.2727)
		(end 312.674 -178.689)
		(width 0.1143)
		(layer "B.Cu")
		(net "ADC_P3V3_STBY_BMC")
	)
	(segment
		(start 302.768 -175.67402)
		(end 303.16932 -175.2727)
		(width 0.1143)
		(layer "B.Cu")
		(net "ADC_P3V3_STBY_BMC")
	)
	(segment
		(start 299.63999 -175.842168)
		(end 299.808138 -175.67402)
		(width 0.1143)
		(layer "B.Cu")
		(net "ADC_P3V3_STBY_BMC")
	)
	(segment
		(start 299.808138 -175.67402)
		(end 302.768 -175.67402)
		(width 0.1143)
		(layer "B.Cu")
		(net "ADC_P3V3_STBY_BMC")
	)
	(segment
		(start 303.16932 -175.2727)
		(end 309.2577 -175.2727)
		(width 0.1143)
		(layer "B.Cu")
		(net "ADC_P3V3_STBY_BMC")
	)
	(segment
		(start 299.23486 -175.440086)
		(end 298.838366 -175.83658)
		(width 0.1143)
		(layer "F.Cu")
		(net "ADC_P5V_STBY_BMC")
	)
	(segment
		(start 298.838366 -175.83658)
		(end 298.838366 -175.838104)
		(width 0.1143)
		(layer "F.Cu")
		(net "ADC_P5V_STBY_BMC")
	)
	(via
		(at 315.849 -177.673)
		(size 0.7112)
		(drill 0.3556)
		(layers "F.Cu" "B.Cu")
		(net "ADC_P5V_STBY_BMC")
	)
	(via
		(at 298.838366 -175.838104)
		(size 0.508)
		(drill 0.254)
		(layers "F.Cu" "B.Cu")
		(net "ADC_P5V_STBY_BMC")
	)
	(segment
		(start 300.256956 -175.43272)
		(end 299.708062 -175.43272)
		(width 0.0889)
		(layer "B.Cu")
		(net "ADC_P5V_STBY_BMC")
	)
	(segment
		(start 300.61408 -175.43272)
		(end 300.60138 -175.44542)
		(width 0.0889)
		(layer "B.Cu")
		(net "ADC_P5V_STBY_BMC")
	)
	(segment
		(start 298.887896 -175.838104)
		(end 298.838366 -175.838104)
		(width 0.0889)
		(layer "B.Cu")
		(net "ADC_P5V_STBY_BMC")
	)
	(segment
		(start 317.5635 -177.673)
		(end 315.849 -177.673)
		(width 0.1143)
		(layer "B.Cu")
		(net "ADC_P5V_STBY_BMC")
	)
	(segment
		(start 300.269656 -175.44542)
		(end 300.256956 -175.43272)
		(width 0.0889)
		(layer "B.Cu")
		(net "ADC_P5V_STBY_BMC")
	)
	(segment
		(start 315.849 -177.673)
		(end 312.547 -177.673)
		(width 0.1143)
		(layer "B.Cu")
		(net "ADC_P5V_STBY_BMC")
	)
	(segment
		(start 303.29632 -174.7774)
		(end 302.641 -175.43272)
		(width 0.1143)
		(layer "B.Cu")
		(net "ADC_P5V_STBY_BMC")
	)
	(segment
		(start 299.698664 -175.442118)
		(end 299.283882 -175.442118)
		(width 0.0889)
		(layer "B.Cu")
		(net "ADC_P5V_STBY_BMC")
	)
	(segment
		(start 309.6514 -174.7774)
		(end 303.29632 -174.7774)
		(width 0.1143)
		(layer "B.Cu")
		(net "ADC_P5V_STBY_BMC")
	)
	(segment
		(start 302.641 -175.43272)
		(end 300.61408 -175.43272)
		(width 0.0889)
		(layer "B.Cu")
		(net "ADC_P5V_STBY_BMC")
	)
	(segment
		(start 312.547 -177.673)
		(end 309.6514 -174.7774)
		(width 0.1143)
		(layer "B.Cu")
		(net "ADC_P5V_STBY_BMC")
	)
	(segment
		(start 300.60138 -175.44542)
		(end 300.269656 -175.44542)
		(width 0.0889)
		(layer "B.Cu")
		(net "ADC_P5V_STBY_BMC")
	)
	(segment
		(start 299.708062 -175.43272)
		(end 299.698664 -175.442118)
		(width 0.0889)
		(layer "B.Cu")
		(net "ADC_P5V_STBY_BMC")
	)
	(segment
		(start 299.283882 -175.442118)
		(end 298.887896 -175.838104)
		(width 0.0889)
		(layer "B.Cu")
		(net "ADC_P5V_STBY_BMC")
	)
	(segment
		(start 271.773396 -161.848038)
		(end 272.339308 -162.41395)
		(width 0.1143)
		(layer "F.Cu")
		(net "BMC_EN_P3V3")
	)
	(segment
		(start 271.773396 -157.657038)
		(end 271.773396 -161.848038)
		(width 0.1143)
		(layer "F.Cu")
		(net "BMC_EN_P3V3")
	)
	(segment
		(start 269.3035 -54.61)
		(end 269.1765 -54.483)
		(width 0.1143)
		(layer "F.Cu")
		(net "BMC_EN_P3V3")
	)
	(segment
		(start 257.2639 -95.282258)
		(end 263.271 -101.289358)
		(width 0.1143)
		(layer "F.Cu")
		(net "BMC_EN_P3V3")
	)
	(segment
		(start 267.73505 -153.618692)
		(end 271.773396 -157.657038)
		(width 0.1143)
		(layer "F.Cu")
		(net "BMC_EN_P3V3")
	)
	(segment
		(start 272.339308 -162.41395)
		(end 272.75155 -162.41395)
		(width 0.1143)
		(layer "F.Cu")
		(net "BMC_EN_P3V3")
	)
	(segment
		(start 263.271 -101.299772)
		(end 263.39165 -101.420422)
		(width 0.1143)
		(layer "F.Cu")
		(net "BMC_EN_P3V3")
	)
	(segment
		(start 272.75155 -162.41395)
		(end 273.7485 -161.417)
		(width 0.1143)
		(layer "F.Cu")
		(net "BMC_EN_P3V3")
	)
	(segment
		(start 263.39165 -101.420422)
		(end 263.39165 -120.988074)
		(width 0.1143)
		(layer "F.Cu")
		(net "BMC_EN_P3V3")
	)
	(segment
		(start 264.3886 -121.985024)
		(end 264.3886 -143.55826)
		(width 0.1143)
		(layer "F.Cu")
		(net "BMC_EN_P3V3")
	)
	(segment
		(start 220.864176 -57.404)
		(end 257.2639 -93.803724)
		(width 0.1143)
		(layer "F.Cu")
		(net "BMC_EN_P3V3")
	)
	(segment
		(start 267.1064 -54.483)
		(end 267.97 -54.483)
		(width 0.1143)
		(layer "F.Cu")
		(net "BMC_EN_P3V3")
	)
	(segment
		(start 264.3886 -143.55826)
		(end 267.73505 -146.90471)
		(width 0.1143)
		(layer "F.Cu")
		(net "BMC_EN_P3V3")
	)
	(segment
		(start 267.73505 -146.90471)
		(end 267.73505 -153.618692)
		(width 0.1143)
		(layer "F.Cu")
		(net "BMC_EN_P3V3")
	)
	(segment
		(start 257.2639 -93.803724)
		(end 257.2639 -95.282258)
		(width 0.1143)
		(layer "F.Cu")
		(net "BMC_EN_P3V3")
	)
	(segment
		(start 269.1765 -54.483)
		(end 267.97 -54.483)
		(width 0.1143)
		(layer "F.Cu")
		(net "BMC_EN_P3V3")
	)
	(segment
		(start 263.271 -101.289358)
		(end 263.271 -101.299772)
		(width 0.1143)
		(layer "F.Cu")
		(net "BMC_EN_P3V3")
	)
	(segment
		(start 263.39165 -120.988074)
		(end 264.3886 -121.985024)
		(width 0.1143)
		(layer "F.Cu")
		(net "BMC_EN_P3V3")
	)
	(via
		(at 267.1064 -54.483)
		(size 0.7112)
		(drill 0.3556)
		(layers "F.Cu" "B.Cu")
		(net "BMC_EN_P3V3")
	)
	(via
		(at 220.864176 -57.404)
		(size 0.5588)
		(drill 0.3048)
		(layers "F.Cu" "B.Cu")
		(net "BMC_EN_P3V3")
	)
	(via
		(at 267.97 -54.483)
		(size 0.508)
		(drill 0.254)
		(layers "F.Cu" "B.Cu")
		(net "BMC_EN_P3V3")
	)
	(segment
		(start 220.864176 -57.404)
		(end 221.302326 -57.84215)
		(width 0.1143)
		(layer "B.Cu")
		(net "BMC_EN_P3V3")
	)
	(segment
		(start 264.61085 -57.84215)
		(end 267.97 -54.483)
		(width 0.1143)
		(layer "B.Cu")
		(net "BMC_EN_P3V3")
	)
	(segment
		(start 221.302326 -57.84215)
		(end 264.61085 -57.84215)
		(width 0.1143)
		(layer "B.Cu")
		(net "BMC_EN_P3V3")
	)
	(segment
		(start 275.890228 -161.417)
		(end 279.789636 -165.316408)
		(width 0.1143)
		(layer "F.Cu")
		(net "BMC_EN_P3V3_R")
	)
	(segment
		(start 282.369006 -167.895778)
		(end 279.789636 -165.316408)
		(width 0.1143)
		(layer "F.Cu")
		(net "BMC_EN_P3V3_R")
	)
	(segment
		(start 283.309822 -167.895778)
		(end 282.369006 -167.895778)
		(width 0.1143)
		(layer "F.Cu")
		(net "BMC_EN_P3V3_R")
	)
	(segment
		(start 274.6375 -161.417)
		(end 275.890228 -161.417)
		(width 0.1143)
		(layer "F.Cu")
		(net "BMC_EN_P3V3_R")
	)
	(segment
		(start 283.654246 -168.240202)
		(end 283.309822 -167.895778)
		(width 0.1143)
		(layer "F.Cu")
		(net "BMC_EN_P3V3_R")
	)
	(segment
		(start 284.834838 -168.240202)
		(end 283.654246 -168.240202)
		(width 0.1143)
		(layer "F.Cu")
		(net "BMC_EN_P3V3_R")
	)
	(via
		(at 279.789636 -165.316408)
		(size 0.7112)
		(drill 0.3556)
		(layers "F.Cu" "B.Cu")
		(net "BMC_EN_P3V3_R")
	)
	(segment
		(start 276.855174 -160.26765)
		(end 276.855174 -160.274)
		(width 0.1143)
		(layer "F.Cu")
		(net "TP_BMC0_LPC_LAD1")
	)
	(segment
		(start 279.86355 -163.747958)
		(end 281.247596 -165.132004)
		(width 0.1143)
		(layer "F.Cu")
		(net "TP_BMC0_LPC_LAD1")
	)
	(segment
		(start 274.6375 -159.385)
		(end 275.972524 -159.385)
		(width 0.1143)
		(layer "F.Cu")
		(net "TP_BMC0_LPC_LAD1")
	)
	(segment
		(start 281.247596 -165.132004)
		(end 282.231592 -166.116)
		(width 0.1143)
		(layer "F.Cu")
		(net "TP_BMC0_LPC_LAD1")
	)
	(segment
		(start 282.231592 -166.116)
		(end 282.957524 -166.116)
		(width 0.1143)
		(layer "F.Cu")
		(net "TP_BMC0_LPC_LAD1")
	)
	(segment
		(start 275.972524 -159.385)
		(end 276.855174 -160.26765)
		(width 0.1143)
		(layer "F.Cu")
		(net "TP_BMC0_LPC_LAD1")
	)
	(segment
		(start 284.281626 -167.440102)
		(end 284.834838 -167.440102)
		(width 0.1143)
		(layer "F.Cu")
		(net "TP_BMC0_LPC_LAD1")
	)
	(segment
		(start 276.855174 -160.274)
		(end 279.86355 -163.282376)
		(width 0.1143)
		(layer "F.Cu")
		(net "TP_BMC0_LPC_LAD1")
	)
	(segment
		(start 282.957524 -166.116)
		(end 284.281626 -167.440102)
		(width 0.1143)
		(layer "F.Cu")
		(net "TP_BMC0_LPC_LAD1")
	)
	(segment
		(start 279.86355 -163.282376)
		(end 279.86355 -163.747958)
		(width 0.1143)
		(layer "F.Cu")
		(net "TP_BMC0_LPC_LAD1")
	)
	(via
		(at 281.247596 -165.132004)
		(size 0.7112)
		(drill 0.3556)
		(layers "F.Cu" "B.Cu")
		(net "TP_BMC0_LPC_LAD1")
	)
	(segment
		(start 286.434784 -168.240202)
		(end 286.147002 -168.240202)
		(width 0.1143)
		(layer "F.Cu")
		(net "TP_LPC_CPU_CLKOUT0")
	)
	(segment
		(start 280.6954 -163.6014)
		(end 280.543 -163.449)
		(width 0.1143)
		(layer "F.Cu")
		(net "TP_LPC_CPU_CLKOUT0")
	)
	(segment
		(start 285.510224 -167.827452)
		(end 285.247588 -167.564816)
		(width 0.1143)
		(layer "F.Cu")
		(net "TP_LPC_CPU_CLKOUT0")
	)
	(segment
		(start 283.5275 -165.6207)
		(end 282.5369 -165.6207)
		(width 0.1143)
		(layer "F.Cu")
		(net "TP_LPC_CPU_CLKOUT0")
	)
	(segment
		(start 282.5369 -165.6207)
		(end 280.6954 -163.7792)
		(width 0.1143)
		(layer "F.Cu")
		(net "TP_LPC_CPU_CLKOUT0")
	)
	(segment
		(start 285.247588 -167.340788)
		(end 283.5275 -165.6207)
		(width 0.1143)
		(layer "F.Cu")
		(net "TP_LPC_CPU_CLKOUT0")
	)
	(segment
		(start 286.147002 -168.240202)
		(end 285.734252 -167.827452)
		(width 0.1143)
		(layer "F.Cu")
		(net "TP_LPC_CPU_CLKOUT0")
	)
	(segment
		(start 280.6954 -163.7792)
		(end 280.6954 -163.6014)
		(width 0.1143)
		(layer "F.Cu")
		(net "TP_LPC_CPU_CLKOUT0")
	)
	(segment
		(start 280.162 -161.9885)
		(end 280.543 -162.3695)
		(width 0.1143)
		(layer "F.Cu")
		(net "TP_LPC_CPU_CLKOUT0")
	)
	(segment
		(start 280.543 -162.3695)
		(end 280.543 -163.449)
		(width 0.1143)
		(layer "F.Cu")
		(net "TP_LPC_CPU_CLKOUT0")
	)
	(segment
		(start 285.734252 -167.827452)
		(end 285.510224 -167.827452)
		(width 0.1143)
		(layer "F.Cu")
		(net "TP_LPC_CPU_CLKOUT0")
	)
	(segment
		(start 285.247588 -167.564816)
		(end 285.247588 -167.340788)
		(width 0.1143)
		(layer "F.Cu")
		(net "TP_LPC_CPU_CLKOUT0")
	)
	(via
		(at 280.543 -163.449)
		(size 0.7112)
		(drill 0.3556)
		(layers "F.Cu" "B.Cu")
		(net "TP_LPC_CPU_CLKOUT0")
	)
	(segment
		(start 286.36087 -167.878252)
		(end 286.584898 -167.878252)
		(width 0.1143)
		(layer "F.Cu")
		(net "TP_BMC0_LPC_LAD3")
	)
	(segment
		(start 287.234884 -169.024808)
		(end 287.234884 -169.040048)
		(width 0.1143)
		(layer "F.Cu")
		(net "TP_BMC0_LPC_LAD3")
	)
	(segment
		(start 282.194 -162.0901)
		(end 281.94 -162.3441)
		(width 0.1143)
		(layer "F.Cu")
		(net "TP_BMC0_LPC_LAD3")
	)
	(segment
		(start 283.227526 -164.6301)
		(end 283.534104 -164.6301)
		(width 0.1143)
		(layer "F.Cu")
		(net "TP_BMC0_LPC_LAD3")
	)
	(segment
		(start 285.996888 -167.51427)
		(end 286.36087 -167.878252)
		(width 0.1143)
		(layer "F.Cu")
		(net "TP_BMC0_LPC_LAD3")
	)
	(segment
		(start 281.94 -163.342574)
		(end 283.227526 -164.6301)
		(width 0.1143)
		(layer "F.Cu")
		(net "TP_BMC0_LPC_LAD3")
	)
	(segment
		(start 286.866584 -168.656508)
		(end 287.234884 -169.024808)
		(width 0.1143)
		(layer "F.Cu")
		(net "TP_BMC0_LPC_LAD3")
	)
	(segment
		(start 285.996888 -167.092884)
		(end 285.996888 -167.51427)
		(width 0.1143)
		(layer "F.Cu")
		(net "TP_BMC0_LPC_LAD3")
	)
	(segment
		(start 281.94 -162.3441)
		(end 281.94 -163.1442)
		(width 0.1143)
		(layer "F.Cu")
		(net "TP_BMC0_LPC_LAD3")
	)
	(segment
		(start 286.866584 -168.159938)
		(end 286.866584 -168.656508)
		(width 0.1143)
		(layer "F.Cu")
		(net "TP_BMC0_LPC_LAD3")
	)
	(segment
		(start 283.534104 -164.6301)
		(end 285.996888 -167.092884)
		(width 0.1143)
		(layer "F.Cu")
		(net "TP_BMC0_LPC_LAD3")
	)
	(segment
		(start 281.94 -163.1442)
		(end 281.94 -163.342574)
		(width 0.1143)
		(layer "F.Cu")
		(net "TP_BMC0_LPC_LAD3")
	)
	(segment
		(start 282.194 -161.9885)
		(end 282.194 -162.0901)
		(width 0.1143)
		(layer "F.Cu")
		(net "TP_BMC0_LPC_LAD3")
	)
	(segment
		(start 286.584898 -167.878252)
		(end 286.866584 -168.159938)
		(width 0.1143)
		(layer "F.Cu")
		(net "TP_BMC0_LPC_LAD3")
	)
	(via
		(at 281.94 -163.1442)
		(size 0.7112)
		(drill 0.3556)
		(layers "F.Cu" "B.Cu")
		(net "TP_BMC0_LPC_LAD3")
	)
	(segment
		(start 287.234884 -171.440094)
		(end 287.630108 -171.04487)
		(width 0.1143)
		(layer "F.Cu")
		(net "TP_BMC0_LPC_LAD2")
	)
	(via
		(at 287.630108 -171.04487)
		(size 0.508)
		(drill 0.254)
		(layers "F.Cu" "B.Cu")
		(net "TP_BMC0_LPC_LAD2")
	)
	(via
		(at 282.1178 -169.9768)
		(size 0.7112)
		(drill 0.3556)
		(layers "F.Cu" "B.Cu")
		(net "TP_BMC0_LPC_LAD2")
	)
	(segment
		(start 283.35605 -170.555412)
		(end 283.972254 -171.171616)
		(width 0.1143)
		(layer "B.Cu")
		(net "TP_BMC0_LPC_LAD2")
	)
	(segment
		(start 282.1178 -169.9768)
		(end 282.696412 -170.555412)
		(width 0.1143)
		(layer "B.Cu")
		(net "TP_BMC0_LPC_LAD2")
	)
	(segment
		(start 286.348932 -171.199556)
		(end 286.580326 -171.43095)
		(width 0.0889)
		(layer "B.Cu")
		(net "TP_BMC0_LPC_LAD2")
	)
	(segment
		(start 277.689818 -165.248336)
		(end 282.1178 -169.676318)
		(width 0.1143)
		(layer "B.Cu")
		(net "TP_BMC0_LPC_LAD2")
	)
	(segment
		(start 287.00095 -171.43095)
		(end 287.38703 -171.04487)
		(width 0.0889)
		(layer "B.Cu")
		(net "TP_BMC0_LPC_LAD2")
	)
	(segment
		(start 283.972254 -171.171616)
		(end 286.320992 -171.171616)
		(width 0.1143)
		(layer "B.Cu")
		(net "TP_BMC0_LPC_LAD2")
	)
	(segment
		(start 277.174452 -165.248336)
		(end 277.689818 -165.248336)
		(width 0.1143)
		(layer "B.Cu")
		(net "TP_BMC0_LPC_LAD2")
	)
	(segment
		(start 286.320992 -171.171616)
		(end 286.348932 -171.199556)
		(width 0.1143)
		(layer "B.Cu")
		(net "TP_BMC0_LPC_LAD2")
	)
	(segment
		(start 286.580326 -171.43095)
		(end 287.00095 -171.43095)
		(width 0.0889)
		(layer "B.Cu")
		(net "TP_BMC0_LPC_LAD2")
	)
	(segment
		(start 282.1178 -169.676318)
		(end 282.1178 -169.9768)
		(width 0.1143)
		(layer "B.Cu")
		(net "TP_BMC0_LPC_LAD2")
	)
	(segment
		(start 287.38703 -171.04487)
		(end 287.630108 -171.04487)
		(width 0.0889)
		(layer "B.Cu")
		(net "TP_BMC0_LPC_LAD2")
	)
	(segment
		(start 282.696412 -170.555412)
		(end 283.35605 -170.555412)
		(width 0.1143)
		(layer "B.Cu")
		(net "TP_BMC0_LPC_LAD2")
	)
	(segment
		(start 285.020766 -167.878252)
		(end 285.382716 -168.240202)
		(width 0.1143)
		(layer "F.Cu")
		(net "TP_BMC0_LPC_LAD0")
	)
	(segment
		(start 279.2984 -163.5506)
		(end 279.2984 -163.9824)
		(width 0.1143)
		(layer "F.Cu")
		(net "TP_BMC0_LPC_LAD0")
	)
	(segment
		(start 285.382716 -168.240202)
		(end 285.634938 -168.240202)
		(width 0.1143)
		(layer "F.Cu")
		(net "TP_BMC0_LPC_LAD0")
	)
	(segment
		(start 279.2984 -163.9824)
		(end 282.527502 -167.211502)
		(width 0.1143)
		(layer "F.Cu")
		(net "TP_BMC0_LPC_LAD0")
	)
	(segment
		(start 274.6375 -160.401)
		(end 275.84019 -160.401)
		(width 0.1143)
		(layer "F.Cu")
		(net "TP_BMC0_LPC_LAD0")
	)
	(segment
		(start 275.84019 -160.401)
		(end 276.576536 -160.696148)
		(width 0.1143)
		(layer "F.Cu")
		(net "TP_BMC0_LPC_LAD0")
	)
	(segment
		(start 283.992828 -167.878252)
		(end 285.020766 -167.878252)
		(width 0.1143)
		(layer "F.Cu")
		(net "TP_BMC0_LPC_LAD0")
	)
	(segment
		(start 282.527502 -167.211502)
		(end 283.326078 -167.211502)
		(width 0.1143)
		(layer "F.Cu")
		(net "TP_BMC0_LPC_LAD0")
	)
	(segment
		(start 277.951692 -162.07105)
		(end 278.23795 -162.357308)
		(width 0.1143)
		(layer "F.Cu")
		(net "TP_BMC0_LPC_LAD0")
	)
	(segment
		(start 277.951438 -162.07105)
		(end 277.951692 -162.07105)
		(width 0.1143)
		(layer "F.Cu")
		(net "TP_BMC0_LPC_LAD0")
	)
	(segment
		(start 278.23795 -162.357308)
		(end 278.23795 -162.49015)
		(width 0.1143)
		(layer "F.Cu")
		(net "TP_BMC0_LPC_LAD0")
	)
	(segment
		(start 276.576536 -160.696148)
		(end 277.951438 -162.07105)
		(width 0.1143)
		(layer "F.Cu")
		(net "TP_BMC0_LPC_LAD0")
	)
	(segment
		(start 283.326078 -167.211502)
		(end 283.992828 -167.878252)
		(width 0.1143)
		(layer "F.Cu")
		(net "TP_BMC0_LPC_LAD0")
	)
	(segment
		(start 278.23795 -162.49015)
		(end 279.2984 -163.5506)
		(width 0.1143)
		(layer "F.Cu")
		(net "TP_BMC0_LPC_LAD0")
	)
	(via
		(at 279.2984 -163.5506)
		(size 0.7112)
		(drill 0.3556)
		(layers "F.Cu" "B.Cu")
		(net "TP_BMC0_LPC_LAD0")
	)
	(segment
		(start 283.373576 -165.1254)
		(end 285.634938 -167.386762)
		(width 0.1143)
		(layer "F.Cu")
		(net "TP_LPC_CPU_FRAME_N")
	)
	(segment
		(start 282.841192 -165.1254)
		(end 283.373576 -165.1254)
		(width 0.1143)
		(layer "F.Cu")
		(net "TP_LPC_CPU_FRAME_N")
	)
	(segment
		(start 282.403296 -164.687504)
		(end 282.841192 -165.1254)
		(width 0.1143)
		(layer "F.Cu")
		(net "TP_LPC_CPU_FRAME_N")
	)
	(segment
		(start 285.634938 -167.386762)
		(end 285.634938 -167.440102)
		(width 0.1143)
		(layer "F.Cu")
		(net "TP_LPC_CPU_FRAME_N")
	)
	(segment
		(start 281.178 -161.9885)
		(end 281.178 -163.462208)
		(width 0.1143)
		(layer "F.Cu")
		(net "TP_LPC_CPU_FRAME_N")
	)
	(segment
		(start 281.178 -163.462208)
		(end 282.403296 -164.687504)
		(width 0.1143)
		(layer "F.Cu")
		(net "TP_LPC_CPU_FRAME_N")
	)
	(via
		(at 282.403296 -164.687504)
		(size 0.7112)
		(drill 0.3556)
		(layers "F.Cu" "B.Cu")
		(net "TP_LPC_CPU_FRAME_N")
	)
	(segment
		(start 283.083 -163.83)
		(end 283.1846 -163.7284)
		(width 0.1143)
		(layer "F.Cu")
		(net "TP_IRQ_CPU_SERIAL")
	)
	(segment
		(start 283.21 -162.9918)
		(end 283.1846 -163.0172)
		(width 0.1143)
		(layer "F.Cu")
		(net "TP_IRQ_CPU_SERIAL")
	)
	(segment
		(start 288.439606 -171.035472)
		(end 288.83483 -170.640248)
		(width 0.1143)
		(layer "F.Cu")
		(net "TP_IRQ_CPU_SERIAL")
	)
	(segment
		(start 283.1846 -163.7284)
		(end 283.1846 -163.0172)
		(width 0.1143)
		(layer "F.Cu")
		(net "TP_IRQ_CPU_SERIAL")
	)
	(segment
		(start 283.21 -161.9885)
		(end 283.21 -162.9918)
		(width 0.1143)
		(layer "F.Cu")
		(net "TP_IRQ_CPU_SERIAL")
	)
	(via
		(at 283.1846 -163.0172)
		(size 0.7112)
		(drill 0.3556)
		(layers "F.Cu" "B.Cu")
		(net "TP_IRQ_CPU_SERIAL")
	)
	(via
		(at 283.083 -163.83)
		(size 0.508)
		(drill 0.254)
		(layers "F.Cu" "B.Cu")
		(net "TP_IRQ_CPU_SERIAL")
	)
	(via
		(at 288.439606 -171.035472)
		(size 0.508)
		(drill 0.254)
		(layers "F.Cu" "B.Cu")
		(net "TP_IRQ_CPU_SERIAL")
	)
	(segment
		(start 287.350708 -169.037508)
		(end 287.797494 -169.037508)
		(width 0.1016)
		(layer "In2.Cu")
		(net "TP_IRQ_CPU_SERIAL")
	)
	(segment
		(start 288.439606 -170.810428)
		(end 288.439606 -171.035472)
		(width 0.1016)
		(layer "In2.Cu")
		(net "TP_IRQ_CPU_SERIAL")
	)
	(segment
		(start 283.083 -163.83)
		(end 284.353 -165.1)
		(width 0.127)
		(layer "In2.Cu")
		(net "TP_IRQ_CPU_SERIAL")
	)
	(segment
		(start 284.353 -166.0398)
		(end 287.274 -168.9608)
		(width 0.127)
		(layer "In2.Cu")
		(net "TP_IRQ_CPU_SERIAL")
	)
	(segment
		(start 284.353 -165.1)
		(end 284.353 -166.0398)
		(width 0.127)
		(layer "In2.Cu")
		(net "TP_IRQ_CPU_SERIAL")
	)
	(segment
		(start 288.035492 -169.275506)
		(end 288.035492 -169.61231)
		(width 0.1016)
		(layer "In2.Cu")
		(net "TP_IRQ_CPU_SERIAL")
	)
	(segment
		(start 288.03473 -169.613072)
		(end 288.03473 -170.405552)
		(width 0.1016)
		(layer "In2.Cu")
		(net "TP_IRQ_CPU_SERIAL")
	)
	(segment
		(start 287.797494 -169.037508)
		(end 288.035492 -169.275506)
		(width 0.1016)
		(layer "In2.Cu")
		(net "TP_IRQ_CPU_SERIAL")
	)
	(segment
		(start 287.274 -168.9608)
		(end 287.350708 -169.037508)
		(width 0.1016)
		(layer "In2.Cu")
		(net "TP_IRQ_CPU_SERIAL")
	)
	(segment
		(start 288.035492 -169.61231)
		(end 288.03473 -169.613072)
		(width 0.1016)
		(layer "In2.Cu")
		(net "TP_IRQ_CPU_SERIAL")
	)
	(segment
		(start 288.03473 -170.405552)
		(end 288.439606 -170.810428)
		(width 0.1016)
		(layer "In2.Cu")
		(net "TP_IRQ_CPU_SERIAL")
	)
	(segment
		(start 83.151472 -148.383498)
		(end 80.325722 -148.383498)
		(width 0.1143)
		(layer "F.Cu")
		(net "PEER_TRAY_R")
	)
	(segment
		(start 8.803386 -223.80321)
		(end 9.451594 -223.80321)
		(width 0.1143)
		(layer "F.Cu")
		(net "PEER_TRAY_R")
	)
	(segment
		(start 7.570216 -225.03638)
		(end 7.633716 -224.97288)
		(width 0.1143)
		(layer "F.Cu")
		(net "PEER_TRAY_R")
	)
	(segment
		(start 90.724482 -137.209276)
		(end 90.724482 -138.557)
		(width 0.1143)
		(layer "F.Cu")
		(net "PEER_TRAY_R")
	)
	(segment
		(start 90.932 -138.764518)
		(end 90.932 -140.60297)
		(width 0.1143)
		(layer "F.Cu")
		(net "PEER_TRAY_R")
	)
	(segment
		(start 90.932 -140.60297)
		(end 83.151472 -148.383498)
		(width 0.1143)
		(layer "F.Cu")
		(net "PEER_TRAY_R")
	)
	(segment
		(start 7.633716 -224.97288)
		(end 8.803386 -223.80321)
		(width 0.1143)
		(layer "F.Cu")
		(net "PEER_TRAY_R")
	)
	(segment
		(start 90.724482 -138.557)
		(end 90.932 -138.764518)
		(width 0.1143)
		(layer "F.Cu")
		(net "PEER_TRAY_R")
	)
	(segment
		(start 80.325722 -148.383498)
		(end 79.99222 -148.717)
		(width 0.1143)
		(layer "F.Cu")
		(net "PEER_TRAY_R")
	)
	(segment
		(start 7.570216 -226.17938)
		(end 7.570216 -225.03638)
		(width 0.1143)
		(layer "F.Cu")
		(net "PEER_TRAY_R")
	)
	(via
		(at 79.99222 -148.717)
		(size 0.5588)
		(drill 0.3048)
		(layers "F.Cu" "B.Cu")
		(net "PEER_TRAY_R")
	)
	(via
		(at 9.451594 -223.80321)
		(size 0.5588)
		(drill 0.3048)
		(layers "F.Cu" "B.Cu")
		(net "PEER_TRAY_R")
	)
	(via
		(at 16.225266 -213.329266)
		(size 0.7112)
		(drill 0.3556)
		(layers "F.Cu" "B.Cu")
		(net "PEER_TRAY_R")
	)
	(segment
		(start 13.80617 -216.31783)
		(end 14.249908 -216.31783)
		(width 0.1143)
		(layer "B.Cu")
		(net "PEER_TRAY_R")
	)
	(segment
		(start 17.243044 -211.78393)
		(end 16.511524 -211.78393)
		(width 0.1143)
		(layer "B.Cu")
		(net "PEER_TRAY_R")
	)
	(segment
		(start 38.608 -190.562738)
		(end 22.339808 -206.83093)
		(width 0.1143)
		(layer "B.Cu")
		(net "PEER_TRAY_R")
	)
	(segment
		(start 49.443894 -176.602644)
		(end 38.608 -187.438538)
		(width 0.1143)
		(layer "B.Cu")
		(net "PEER_TRAY_R")
	)
	(segment
		(start 50.938684 -175.1076)
		(end 49.443894 -176.60239)
		(width 0.1143)
		(layer "B.Cu")
		(net "PEER_TRAY_R")
	)
	(segment
		(start 58.846212 -175.0949)
		(end 50.951638 -175.0949)
		(width 0.1143)
		(layer "B.Cu")
		(net "PEER_TRAY_R")
	)
	(segment
		(start 9.451594 -223.80321)
		(end 9.945878 -223.308926)
		(width 0.1143)
		(layer "B.Cu")
		(net "PEER_TRAY_R")
	)
	(segment
		(start 64.0334 -169.907712)
		(end 58.846212 -175.0949)
		(width 0.1143)
		(layer "B.Cu")
		(net "PEER_TRAY_R")
	)
	(segment
		(start 9.906 -220.218)
		(end 13.80617 -216.31783)
		(width 0.1143)
		(layer "B.Cu")
		(net "PEER_TRAY_R")
	)
	(segment
		(start 21.305266 -207.721708)
		(end 17.243044 -211.78393)
		(width 0.1143)
		(layer "B.Cu")
		(net "PEER_TRAY_R")
	)
	(segment
		(start 50.938938 -175.1076)
		(end 50.938684 -175.1076)
		(width 0.1143)
		(layer "B.Cu")
		(net "PEER_TRAY_R")
	)
	(segment
		(start 64.0334 -165.43147)
		(end 64.0334 -169.907712)
		(width 0.1143)
		(layer "B.Cu")
		(net "PEER_TRAY_R")
	)
	(segment
		(start 50.951638 -175.0949)
		(end 50.938938 -175.1076)
		(width 0.1143)
		(layer "B.Cu")
		(net "PEER_TRAY_R")
	)
	(segment
		(start 38.608 -187.438538)
		(end 38.608 -190.562738)
		(width 0.1143)
		(layer "B.Cu")
		(net "PEER_TRAY_R")
	)
	(segment
		(start 9.945878 -222.616776)
		(end 9.906 -222.576898)
		(width 0.1143)
		(layer "B.Cu")
		(net "PEER_TRAY_R")
	)
	(segment
		(start 9.906 -222.576898)
		(end 9.906 -220.218)
		(width 0.1143)
		(layer "B.Cu")
		(net "PEER_TRAY_R")
	)
	(segment
		(start 9.945878 -223.308926)
		(end 9.945878 -222.616776)
		(width 0.1143)
		(layer "B.Cu")
		(net "PEER_TRAY_R")
	)
	(segment
		(start 22.339808 -206.83093)
		(end 21.591524 -206.83093)
		(width 0.1143)
		(layer "B.Cu")
		(net "PEER_TRAY_R")
	)
	(segment
		(start 79.99222 -149.47265)
		(end 64.0334 -165.43147)
		(width 0.1143)
		(layer "B.Cu")
		(net "PEER_TRAY_R")
	)
	(segment
		(start 16.225266 -212.070188)
		(end 16.225266 -213.329266)
		(width 0.1143)
		(layer "B.Cu")
		(net "PEER_TRAY_R")
	)
	(segment
		(start 16.225266 -214.342472)
		(end 16.225266 -213.329266)
		(width 0.1143)
		(layer "B.Cu")
		(net "PEER_TRAY_R")
	)
	(segment
		(start 14.249908 -216.31783)
		(end 16.225266 -214.342472)
		(width 0.1143)
		(layer "B.Cu")
		(net "PEER_TRAY_R")
	)
	(segment
		(start 79.99222 -148.717)
		(end 79.99222 -149.47265)
		(width 0.1143)
		(layer "B.Cu")
		(net "PEER_TRAY_R")
	)
	(segment
		(start 21.305266 -207.117188)
		(end 21.305266 -207.721708)
		(width 0.1143)
		(layer "B.Cu")
		(net "PEER_TRAY_R")
	)
	(segment
		(start 49.443894 -176.60239)
		(end 49.443894 -176.602644)
		(width 0.1143)
		(layer "B.Cu")
		(net "PEER_TRAY_R")
	)
	(segment
		(start 21.591524 -206.83093)
		(end 21.305266 -207.117188)
		(width 0.1143)
		(layer "B.Cu")
		(net "PEER_TRAY_R")
	)
	(segment
		(start 16.511524 -211.78393)
		(end 16.225266 -212.070188)
		(width 0.1143)
		(layer "B.Cu")
		(net "PEER_TRAY_R")
	)
	(segment
		(start 209.854292 -60.9473)
		(end 209.854292 -66.116708)
		(width 0.127)
		(layer "F.Cu")
		(net "PMU_PLTRST_N")
	)
	(segment
		(start 184.13476 -115.74526)
		(end 184.13476 -118.001288)
		(width 0.127)
		(layer "F.Cu")
		(net "PMU_PLTRST_N")
	)
	(segment
		(start 303.76876 -219.56776)
		(end 304.038 -219.837)
		(width 0.127)
		(layer "F.Cu")
		(net "PMU_PLTRST_N")
	)
	(segment
		(start 220.091 -26.4795)
		(end 216.9795 -26.4795)
		(width 0.127)
		(layer "F.Cu")
		(net "PMU_PLTRST_N")
	)
	(segment
		(start 330.3778 -150.4188)
		(end 330.3778 -146.258788)
		(width 0.127)
		(layer "F.Cu")
		(net "PMU_PLTRST_N")
	)
	(segment
		(start 184.15 -114.8842)
		(end 184.0865 -114.9477)
		(width 0.127)
		(layer "F.Cu")
		(net "PMU_PLTRST_N")
	)
	(segment
		(start 251.959618 -192.89395)
		(end 253.49835 -194.432682)
		(width 0.127)
		(layer "F.Cu")
		(net "PMU_PLTRST_N")
	)
	(segment
		(start 303.76876 -219.0115)
		(end 303.76876 -219.56776)
		(width 0.127)
		(layer "F.Cu")
		(net "PMU_PLTRST_N")
	)
	(segment
		(start 184.0865 -115.697)
		(end 184.13476 -115.74526)
		(width 0.127)
		(layer "F.Cu")
		(net "PMU_PLTRST_N")
	)
	(segment
		(start 256.921 -169.545)
		(end 256.921 -185.3184)
		(width 0.127)
		(layer "F.Cu")
		(net "PMU_PLTRST_N")
	)
	(segment
		(start 307.07076 -219.71)
		(end 307.07076 -219.0115)
		(width 0.127)
		(layer "F.Cu")
		(net "PMU_PLTRST_N")
	)
	(segment
		(start 254.2794 -196.696076)
		(end 254.2794 -197.231)
		(width 0.127)
		(layer "F.Cu")
		(net "PMU_PLTRST_N")
	)
	(segment
		(start 205.232 -80.391)
		(end 205.232 -80.509364)
		(width 0.127)
		(layer "F.Cu")
		(net "PMU_PLTRST_N")
	)
	(segment
		(start 302.26 -219.837)
		(end 303.0855 -219.0115)
		(width 0.127)
		(layer "F.Cu")
		(net "PMU_PLTRST_N")
	)
	(segment
		(start 333.468218 -144.503648)
		(end 332.388718 -144.503648)
		(width 0.127)
		(layer "F.Cu")
		(net "PMU_PLTRST_N")
	)
	(segment
		(start 164.41039 -154.76601)
		(end 166.275766 -154.76601)
		(width 0.127)
		(layer "F.Cu")
		(net "PMU_PLTRST_N")
	)
	(segment
		(start 253.49835 -194.432682)
		(end 253.49835 -195.915026)
		(width 0.127)
		(layer "F.Cu")
		(net "PMU_PLTRST_N")
	)
	(segment
		(start 251.083318 -192.89395)
		(end 251.959618 -192.89395)
		(width 0.127)
		(layer "F.Cu")
		(net "PMU_PLTRST_N")
	)
	(segment
		(start 209.854292 -66.116708)
		(end 209.423 -66.548)
		(width 0.127)
		(layer "F.Cu")
		(net "PMU_PLTRST_N")
	)
	(segment
		(start 204.207364 -81.534)
		(end 197.739 -81.534)
		(width 0.127)
		(layer "F.Cu")
		(net "PMU_PLTRST_N")
	)
	(segment
		(start 197.739 -81.534)
		(end 196.469 -82.804)
		(width 0.127)
		(layer "F.Cu")
		(net "PMU_PLTRST_N")
	)
	(segment
		(start 166.419276 -154.6225)
		(end 168.272968 -154.6225)
		(width 0.127)
		(layer "F.Cu")
		(net "PMU_PLTRST_N")
	)
	(segment
		(start 303.0855 -219.0115)
		(end 303.76876 -219.0115)
		(width 0.127)
		(layer "F.Cu")
		(net "PMU_PLTRST_N")
	)
	(segment
		(start 184.0865 -114.9477)
		(end 184.0865 -115.697)
		(width 0.127)
		(layer "F.Cu")
		(net "PMU_PLTRST_N")
	)
	(segment
		(start 319.338452 -59.69)
		(end 319.703958 -59.69)
		(width 0.127)
		(layer "F.Cu")
		(net "PMU_PLTRST_N")
	)
	(segment
		(start 166.275766 -154.76601)
		(end 166.419276 -154.6225)
		(width 0.127)
		(layer "F.Cu")
		(net "PMU_PLTRST_N")
	)
	(segment
		(start 168.323768 -154.5717)
		(end 171.2087 -154.5717)
		(width 0.127)
		(layer "F.Cu")
		(net "PMU_PLTRST_N")
	)
	(segment
		(start 304.038 -219.837)
		(end 306.94376 -219.837)
		(width 0.127)
		(layer "F.Cu")
		(net "PMU_PLTRST_N")
	)
	(segment
		(start 250.7107 -191.5287)
		(end 250.7107 -192.521332)
		(width 0.127)
		(layer "F.Cu")
		(net "PMU_PLTRST_N")
	)
	(segment
		(start 299.4025 -218.8845)
		(end 298.958 -218.44)
		(width 0.127)
		(layer "F.Cu")
		(net "PMU_PLTRST_N")
	)
	(segment
		(start 319.703958 -59.69)
		(end 320.211958 -60.198)
		(width 0.127)
		(layer "F.Cu")
		(net "PMU_PLTRST_N")
	)
	(segment
		(start 306.94376 -219.837)
		(end 307.07076 -219.71)
		(width 0.127)
		(layer "F.Cu")
		(net "PMU_PLTRST_N")
	)
	(segment
		(start 171.2087 -154.5717)
		(end 172.085 -155.448)
		(width 0.127)
		(layer "F.Cu")
		(net "PMU_PLTRST_N")
	)
	(segment
		(start 207.228948 -74.93)
		(end 206.713836 -75.445112)
		(width 0.127)
		(layer "F.Cu")
		(net "PMU_PLTRST_N")
	)
	(segment
		(start 168.272968 -154.6225)
		(end 168.323768 -154.5717)
		(width 0.127)
		(layer "F.Cu")
		(net "PMU_PLTRST_N")
	)
	(segment
		(start 332.13294 -144.503648)
		(end 332.388718 -144.503648)
		(width 0.127)
		(layer "F.Cu")
		(net "PMU_PLTRST_N")
	)
	(segment
		(start 206.713836 -75.445112)
		(end 206.713836 -78.909164)
		(width 0.127)
		(layer "F.Cu")
		(net "PMU_PLTRST_N")
	)
	(segment
		(start 208.312004 -74.93)
		(end 207.228948 -74.93)
		(width 0.127)
		(layer "F.Cu")
		(net "PMU_PLTRST_N")
	)
	(segment
		(start 209.423 -73.819004)
		(end 208.312004 -74.93)
		(width 0.127)
		(layer "F.Cu")
		(net "PMU_PLTRST_N")
	)
	(segment
		(start 205.232 -80.509364)
		(end 204.207364 -81.534)
		(width 0.127)
		(layer "F.Cu")
		(net "PMU_PLTRST_N")
	)
	(segment
		(start 206.713836 -78.909164)
		(end 205.232 -80.391)
		(width 0.127)
		(layer "F.Cu")
		(net "PMU_PLTRST_N")
	)
	(segment
		(start 256.921 -185.3184)
		(end 250.7107 -191.5287)
		(width 0.127)
		(layer "F.Cu")
		(net "PMU_PLTRST_N")
	)
	(segment
		(start 164.2618 -154.9146)
		(end 164.41039 -154.76601)
		(width 0.127)
		(layer "F.Cu")
		(net "PMU_PLTRST_N")
	)
	(segment
		(start 300.00575 -218.8845)
		(end 299.4025 -218.8845)
		(width 0.127)
		(layer "F.Cu")
		(net "PMU_PLTRST_N")
	)
	(segment
		(start 330.3778 -146.258788)
		(end 332.13294 -144.503648)
		(width 0.127)
		(layer "F.Cu")
		(net "PMU_PLTRST_N")
	)
	(segment
		(start 300.95825 -219.837)
		(end 302.26 -219.837)
		(width 0.127)
		(layer "F.Cu")
		(net "PMU_PLTRST_N")
	)
	(segment
		(start 300.00575 -218.8845)
		(end 300.95825 -219.837)
		(width 0.127)
		(layer "F.Cu")
		(net "PMU_PLTRST_N")
	)
	(segment
		(start 331.47 -151.511)
		(end 330.3778 -150.4188)
		(width 0.127)
		(layer "F.Cu")
		(net "PMU_PLTRST_N")
	)
	(segment
		(start 209.423 -66.548)
		(end 209.423 -73.819004)
		(width 0.127)
		(layer "F.Cu")
		(net "PMU_PLTRST_N")
	)
	(segment
		(start 162.3822 -154.9146)
		(end 164.2618 -154.9146)
		(width 0.127)
		(layer "F.Cu")
		(net "PMU_PLTRST_N")
	)
	(segment
		(start 253.49835 -195.915026)
		(end 254.2794 -196.696076)
		(width 0.127)
		(layer "F.Cu")
		(net "PMU_PLTRST_N")
	)
	(segment
		(start 216.9795 -26.4795)
		(end 211.328 -32.131)
		(width 0.127)
		(layer "F.Cu")
		(net "PMU_PLTRST_N")
	)
	(segment
		(start 250.7107 -192.521332)
		(end 251.083318 -192.89395)
		(width 0.127)
		(layer "F.Cu")
		(net "PMU_PLTRST_N")
	)
	(segment
		(start 211.328 -32.131)
		(end 211.328 -34.925)
		(width 0.127)
		(layer "F.Cu")
		(net "PMU_PLTRST_N")
	)
	(via
		(at 172.085 -155.448)
		(size 0.5588)
		(drill 0.3048)
		(layers "F.Cu" "B.Cu")
		(net "PMU_PLTRST_N")
	)
	(via
		(at 338.963 -161.544)
		(size 0.5588)
		(drill 0.3048)
		(layers "F.Cu" "B.Cu")
		(net "PMU_PLTRST_N")
	)
	(via
		(at 290.68395 -82.677)
		(size 0.508)
		(drill 0.254)
		(layers "F.Cu" "B.Cu")
		(net "PMU_PLTRST_N")
	)
	(via
		(at 286.004 -159.341566)
		(size 0.5588)
		(drill 0.3048)
		(layers "F.Cu" "B.Cu")
		(net "PMU_PLTRST_N")
	)
	(via
		(at 256.921 -169.545)
		(size 0.508)
		(drill 0.254)
		(layers "F.Cu" "B.Cu")
		(net "PMU_PLTRST_N")
	)
	(via
		(at 295.148 -243.99875)
		(size 0.5588)
		(drill 0.3048)
		(layers "F.Cu" "B.Cu")
		(net "PMU_PLTRST_N")
	)
	(via
		(at 209.854292 -60.9473)
		(size 0.5588)
		(drill 0.3048)
		(layers "F.Cu" "B.Cu")
		(net "PMU_PLTRST_N")
	)
	(via
		(at 209.43824 -220.61424)
		(size 0.5588)
		(drill 0.3048)
		(layers "F.Cu" "B.Cu")
		(net "PMU_PLTRST_N")
	)
	(via
		(at 184.15 -114.8842)
		(size 0.5588)
		(drill 0.3048)
		(layers "F.Cu" "B.Cu")
		(net "PMU_PLTRST_N")
	)
	(via
		(at 172.466 -219.7227)
		(size 0.5588)
		(drill 0.3048)
		(layers "F.Cu" "B.Cu")
		(net "PMU_PLTRST_N")
	)
	(via
		(at 331.47 -151.511)
		(size 0.508)
		(drill 0.254)
		(layers "F.Cu" "B.Cu")
		(net "PMU_PLTRST_N")
	)
	(via
		(at 211.328 -34.925)
		(size 0.5588)
		(drill 0.3048)
		(layers "F.Cu" "B.Cu")
		(net "PMU_PLTRST_N")
	)
	(via
		(at 277.749 -162.56)
		(size 0.5588)
		(drill 0.3048)
		(layers "F.Cu" "B.Cu")
		(net "PMU_PLTRST_N")
	)
	(via
		(at 296.291 -105.537)
		(size 0.5588)
		(drill 0.3048)
		(layers "F.Cu" "B.Cu")
		(net "PMU_PLTRST_N")
	)
	(via
		(at 298.958 -218.44)
		(size 0.5588)
		(drill 0.3048)
		(layers "F.Cu" "B.Cu")
		(net "PMU_PLTRST_N")
	)
	(via
		(at 135.382 -39.0652)
		(size 0.5588)
		(drill 0.3048)
		(layers "F.Cu" "B.Cu")
		(net "PMU_PLTRST_N")
	)
	(via
		(at 287.8328 -160.909)
		(size 0.7112)
		(drill 0.3556)
		(layers "F.Cu" "B.Cu")
		(net "PMU_PLTRST_N")
	)
	(via
		(at 332.388718 -144.503648)
		(size 0.7112)
		(drill 0.3556)
		(layers "F.Cu" "B.Cu")
		(net "PMU_PLTRST_N")
	)
	(via
		(at 320.211958 -60.198)
		(size 0.5588)
		(drill 0.3048)
		(layers "F.Cu" "B.Cu")
		(net "PMU_PLTRST_N")
	)
	(via
		(at 196.469 -82.804)
		(size 0.5588)
		(drill 0.3048)
		(layers "F.Cu" "B.Cu")
		(net "PMU_PLTRST_N")
	)
	(via
		(at 294.894 -137.541)
		(size 0.5588)
		(drill 0.3048)
		(layers "F.Cu" "B.Cu")
		(net "PMU_PLTRST_N")
	)
	(via
		(at 254.2794 -197.231)
		(size 0.508)
		(drill 0.254)
		(layers "F.Cu" "B.Cu")
		(net "PMU_PLTRST_N")
	)
	(segment
		(start 289.814 -160.909)
		(end 287.8328 -160.909)
		(width 0.127)
		(layer "B.Cu")
		(net "PMU_PLTRST_N")
	)
	(segment
		(start 298.577 -223.901)
		(end 298.577 -240.56975)
		(width 0.127)
		(layer "B.Cu")
		(net "PMU_PLTRST_N")
	)
	(segment
		(start 172.466 -219.7227)
		(end 172.466 -219.075)
		(width 0.127)
		(layer "B.Cu")
		(net "PMU_PLTRST_N")
	)
	(segment
		(start 283.854398 -148.580602)
		(end 294.894 -137.541)
		(width 0.127)
		(layer "B.Cu")
		(net "PMU_PLTRST_N")
	)
	(segment
		(start 184.15 -87.122)
		(end 184.15 -114.8842)
		(width 0.127)
		(layer "B.Cu")
		(net "PMU_PLTRST_N")
	)
	(segment
		(start 184.15 -114.8842)
		(end 184.15 -122.366532)
		(width 0.127)
		(layer "B.Cu")
		(net "PMU_PLTRST_N")
	)
	(segment
		(start 211.328 -59.473592)
		(end 211.328 -34.925)
		(width 0.127)
		(layer "B.Cu")
		(net "PMU_PLTRST_N")
	)
	(segment
		(start 172.0088 -155.3718)
		(end 172.085 -155.448)
		(width 0.127)
		(layer "B.Cu")
		(net "PMU_PLTRST_N")
	)
	(segment
		(start 196.469 -82.804)
		(end 194.437 -84.836)
		(width 0.127)
		(layer "B.Cu")
		(net "PMU_PLTRST_N")
	)
	(segment
		(start 288.925 -165.7985)
		(end 290.068 -164.6555)
		(width 0.127)
		(layer "B.Cu")
		(net "PMU_PLTRST_N")
	)
	(segment
		(start 338.201 -158.20644)
		(end 332.36916 -152.3746)
		(width 0.127)
		(layer "B.Cu")
		(net "PMU_PLTRST_N")
	)
	(segment
		(start 338.963 -161.544)
		(end 338.201 -160.782)
		(width 0.127)
		(layer "B.Cu")
		(net "PMU_PLTRST_N")
	)
	(segment
		(start 285.615634 -159.341566)
		(end 283.854398 -157.58033)
		(width 0.127)
		(layer "B.Cu")
		(net "PMU_PLTRST_N")
	)
	(segment
		(start 189.7507 -123.8123)
		(end 190.119 -123.444)
		(width 0.127)
		(layer "B.Cu")
		(net "PMU_PLTRST_N")
	)
	(segment
		(start 135.382 -38.1635)
		(end 135.382 -39.0652)
		(width 0.127)
		(layer "B.Cu")
		(net "PMU_PLTRST_N")
	)
	(segment
		(start 283.854398 -157.58033)
		(end 283.854398 -148.580602)
		(width 0.127)
		(layer "B.Cu")
		(net "PMU_PLTRST_N")
	)
	(segment
		(start 287.8328 -160.909)
		(end 287.208468 -160.909)
		(width 0.127)
		(layer "B.Cu")
		(net "PMU_PLTRST_N")
	)
	(segment
		(start 190.119 -123.444)
		(end 193.421 -123.444)
		(width 0.127)
		(layer "B.Cu")
		(net "PMU_PLTRST_N")
	)
	(segment
		(start 332.36916 -152.3746)
		(end 332.3336 -152.3746)
		(width 0.127)
		(layer "B.Cu")
		(net "PMU_PLTRST_N")
	)
	(segment
		(start 286.004 -159.704532)
		(end 286.004 -159.341566)
		(width 0.127)
		(layer "B.Cu")
		(net "PMU_PLTRST_N")
	)
	(segment
		(start 190.874396 -138.303)
		(end 184.871868 -138.303)
		(width 0.127)
		(layer "B.Cu")
		(net "PMU_PLTRST_N")
	)
	(segment
		(start 298.958 -223.52)
		(end 298.577 -223.901)
		(width 0.127)
		(layer "B.Cu")
		(net "PMU_PLTRST_N")
	)
	(segment
		(start 298.577 -240.56975)
		(end 295.148 -243.99875)
		(width 0.127)
		(layer "B.Cu")
		(net "PMU_PLTRST_N")
	)
	(segment
		(start 304.038 -64.389)
		(end 316.020958 -64.389)
		(width 0.127)
		(layer "B.Cu")
		(net "PMU_PLTRST_N")
	)
	(segment
		(start 185.595768 -123.8123)
		(end 189.7507 -123.8123)
		(width 0.127)
		(layer "B.Cu")
		(net "PMU_PLTRST_N")
	)
	(segment
		(start 171.35094 -217.95994)
		(end 171.35094 -191.40932)
		(width 0.127)
		(layer "B.Cu")
		(net "PMU_PLTRST_N")
	)
	(segment
		(start 194.437 -84.836)
		(end 186.436 -84.836)
		(width 0.127)
		(layer "B.Cu")
		(net "PMU_PLTRST_N")
	)
	(segment
		(start 316.020958 -64.389)
		(end 320.211958 -60.198)
		(width 0.127)
		(layer "B.Cu")
		(net "PMU_PLTRST_N")
	)
	(segment
		(start 193.8655 -135.311896)
		(end 190.874396 -138.303)
		(width 0.127)
		(layer "B.Cu")
		(net "PMU_PLTRST_N")
	)
	(segment
		(start 209.854292 -60.9473)
		(end 211.328 -59.473592)
		(width 0.127)
		(layer "B.Cu")
		(net "PMU_PLTRST_N")
	)
	(segment
		(start 298.958 -218.44)
		(end 298.958 -223.52)
		(width 0.127)
		(layer "B.Cu")
		(net "PMU_PLTRST_N")
	)
	(segment
		(start 286.004 -159.341566)
		(end 285.615634 -159.341566)
		(width 0.127)
		(layer "B.Cu")
		(net "PMU_PLTRST_N")
	)
	(segment
		(start 290.068 -161.163)
		(end 289.814 -160.909)
		(width 0.127)
		(layer "B.Cu")
		(net "PMU_PLTRST_N")
	)
	(segment
		(start 287.208468 -160.909)
		(end 286.004 -159.704532)
		(width 0.127)
		(layer "B.Cu")
		(net "PMU_PLTRST_N")
	)
	(segment
		(start 172.466 -219.075)
		(end 171.35094 -217.95994)
		(width 0.127)
		(layer "B.Cu")
		(net "PMU_PLTRST_N")
	)
	(segment
		(start 186.436 -84.836)
		(end 184.15 -87.122)
		(width 0.127)
		(layer "B.Cu")
		(net "PMU_PLTRST_N")
	)
	(segment
		(start 135.8265 -37.719)
		(end 135.382 -38.1635)
		(width 0.127)
		(layer "B.Cu")
		(net "PMU_PLTRST_N")
	)
	(segment
		(start 276.5425 -162.56)
		(end 277.749 -162.56)
		(width 0.127)
		(layer "B.Cu")
		(net "PMU_PLTRST_N")
	)
	(segment
		(start 184.871868 -138.303)
		(end 172.0088 -151.166068)
		(width 0.127)
		(layer "B.Cu")
		(net "PMU_PLTRST_N")
	)
	(segment
		(start 193.421 -123.444)
		(end 193.8655 -123.8885)
		(width 0.127)
		(layer "B.Cu")
		(net "PMU_PLTRST_N")
	)
	(segment
		(start 173.2153 -189.54496)
		(end 173.2153 -156.5783)
		(width 0.127)
		(layer "B.Cu")
		(net "PMU_PLTRST_N")
	)
	(segment
		(start 290.68395 -82.677)
		(end 290.68395 -77.74305)
		(width 0.127)
		(layer "B.Cu")
		(net "PMU_PLTRST_N")
	)
	(segment
		(start 290.68395 -77.74305)
		(end 304.038 -64.389)
		(width 0.127)
		(layer "B.Cu")
		(net "PMU_PLTRST_N")
	)
	(segment
		(start 338.201 -160.782)
		(end 338.201 -158.20644)
		(width 0.127)
		(layer "B.Cu")
		(net "PMU_PLTRST_N")
	)
	(segment
		(start 193.8655 -123.8885)
		(end 193.8655 -135.311896)
		(width 0.127)
		(layer "B.Cu")
		(net "PMU_PLTRST_N")
	)
	(segment
		(start 332.3336 -152.3746)
		(end 331.47 -151.511)
		(width 0.127)
		(layer "B.Cu")
		(net "PMU_PLTRST_N")
	)
	(segment
		(start 172.0088 -151.166068)
		(end 172.0088 -155.3718)
		(width 0.127)
		(layer "B.Cu")
		(net "PMU_PLTRST_N")
	)
	(segment
		(start 173.2153 -156.5783)
		(end 172.085 -155.448)
		(width 0.127)
		(layer "B.Cu")
		(net "PMU_PLTRST_N")
	)
	(segment
		(start 171.35094 -191.40932)
		(end 173.2153 -189.54496)
		(width 0.127)
		(layer "B.Cu")
		(net "PMU_PLTRST_N")
	)
	(segment
		(start 290.068 -164.6555)
		(end 290.068 -161.163)
		(width 0.127)
		(layer "B.Cu")
		(net "PMU_PLTRST_N")
	)
	(segment
		(start 184.15 -122.366532)
		(end 185.595768 -123.8123)
		(width 0.127)
		(layer "B.Cu")
		(net "PMU_PLTRST_N")
	)
	(segment
		(start 208.70418 -221.3483)
		(end 209.43824 -220.61424)
		(width 0.127)
		(layer "In2.Cu")
		(net "PMU_PLTRST_N")
	)
	(segment
		(start 260.0833 -166.3827)
		(end 266.022328 -166.3827)
		(width 0.127)
		(layer "In2.Cu")
		(net "PMU_PLTRST_N")
	)
	(segment
		(start 334.344772 -219.71)
		(end 339.725 -214.329772)
		(width 0.127)
		(layer "In2.Cu")
		(net "PMU_PLTRST_N")
	)
	(segment
		(start 338.963 -168.021)
		(end 338.963 -161.544)
		(width 0.127)
		(layer "In2.Cu")
		(net "PMU_PLTRST_N")
	)
	(segment
		(start 167.571928 -61.6839)
		(end 149.449028 -43.561)
		(width 0.127)
		(layer "In2.Cu")
		(net "PMU_PLTRST_N")
	)
	(segment
		(start 294.159432 -92.907866)
		(end 294.64 -93.388434)
		(width 0.127)
		(layer "In2.Cu")
		(net "PMU_PLTRST_N")
	)
	(segment
		(start 290.68395 -82.677)
		(end 290.68395 -84.168996)
		(width 0.127)
		(layer "In2.Cu")
		(net "PMU_PLTRST_N")
	)
	(segment
		(start 290.68395 -84.168996)
		(end 293.231316 -86.716362)
		(width 0.127)
		(layer "In2.Cu")
		(net "PMU_PLTRST_N")
	)
	(segment
		(start 266.518136 -166.878508)
		(end 273.019774 -166.878508)
		(width 0.127)
		(layer "In2.Cu")
		(net "PMU_PLTRST_N")
	)
	(segment
		(start 296.867326 -243.999004)
		(end 298.854368 -243.999004)
		(width 0.127)
		(layer "In2.Cu")
		(net "PMU_PLTRST_N")
	)
	(segment
		(start 298.854368 -243.999004)
		(end 323.143372 -219.71)
		(width 0.127)
		(layer "In2.Cu")
		(net "PMU_PLTRST_N")
	)
	(segment
		(start 294.49522 -92.056712)
		(end 294.159432 -92.3925)
		(width 0.127)
		(layer "In2.Cu")
		(net "PMU_PLTRST_N")
	)
	(segment
		(start 339.725 -168.783)
		(end 338.963 -168.021)
		(width 0.127)
		(layer "In2.Cu")
		(net "PMU_PLTRST_N")
	)
	(segment
		(start 296.867072 -243.99875)
		(end 296.867326 -243.999004)
		(width 0.127)
		(layer "In2.Cu")
		(net "PMU_PLTRST_N")
	)
	(segment
		(start 172.466 -219.7227)
		(end 174.0916 -221.3483)
		(width 0.127)
		(layer "In2.Cu")
		(net "PMU_PLTRST_N")
	)
	(segment
		(start 149.449028 -43.561)
		(end 139.8778 -43.561)
		(width 0.127)
		(layer "In2.Cu")
		(net "PMU_PLTRST_N")
	)
	(segment
		(start 277.749 -162.56)
		(end 284.174946 -162.56)
		(width 0.127)
		(layer "In2.Cu")
		(net "PMU_PLTRST_N")
	)
	(segment
		(start 286.004 -159.8041)
		(end 286.004 -159.341566)
		(width 0.127)
		(layer "In2.Cu")
		(net "PMU_PLTRST_N")
	)
	(segment
		(start 293.231316 -86.741762)
		(end 294.49522 -88.005666)
		(width 0.127)
		(layer "In2.Cu")
		(net "PMU_PLTRST_N")
	)
	(segment
		(start 323.143372 -219.71)
		(end 334.344772 -219.71)
		(width 0.127)
		(layer "In2.Cu")
		(net "PMU_PLTRST_N")
	)
	(segment
		(start 294.64 -102.997)
		(end 296.291 -104.648)
		(width 0.127)
		(layer "In2.Cu")
		(net "PMU_PLTRST_N")
	)
	(segment
		(start 286.255714 -160.055814)
		(end 286.004 -159.8041)
		(width 0.127)
		(layer "In2.Cu")
		(net "PMU_PLTRST_N")
	)
	(segment
		(start 266.022328 -166.3827)
		(end 266.518136 -166.878508)
		(width 0.127)
		(layer "In2.Cu")
		(net "PMU_PLTRST_N")
	)
	(segment
		(start 284.174946 -162.56)
		(end 286.255714 -160.479232)
		(width 0.127)
		(layer "In2.Cu")
		(net "PMU_PLTRST_N")
	)
	(segment
		(start 209.854292 -60.9473)
		(end 209.117692 -61.6839)
		(width 0.127)
		(layer "In2.Cu")
		(net "PMU_PLTRST_N")
	)
	(segment
		(start 293.231316 -86.716362)
		(end 293.231316 -86.741762)
		(width 0.127)
		(layer "In2.Cu")
		(net "PMU_PLTRST_N")
	)
	(segment
		(start 294.159432 -92.3925)
		(end 294.159432 -92.907866)
		(width 0.127)
		(layer "In2.Cu")
		(net "PMU_PLTRST_N")
	)
	(segment
		(start 256.921 -169.545)
		(end 260.0833 -166.3827)
		(width 0.127)
		(layer "In2.Cu")
		(net "PMU_PLTRST_N")
	)
	(segment
		(start 294.49522 -88.005666)
		(end 294.49522 -92.056712)
		(width 0.127)
		(layer "In2.Cu")
		(net "PMU_PLTRST_N")
	)
	(segment
		(start 286.255714 -160.479232)
		(end 286.255714 -160.055814)
		(width 0.127)
		(layer "In2.Cu")
		(net "PMU_PLTRST_N")
	)
	(segment
		(start 209.117692 -61.6839)
		(end 167.571928 -61.6839)
		(width 0.127)
		(layer "In2.Cu")
		(net "PMU_PLTRST_N")
	)
	(segment
		(start 294.64 -93.388434)
		(end 294.64 -102.997)
		(width 0.127)
		(layer "In2.Cu")
		(net "PMU_PLTRST_N")
	)
	(segment
		(start 139.8778 -43.561)
		(end 135.382 -39.0652)
		(width 0.127)
		(layer "In2.Cu")
		(net "PMU_PLTRST_N")
	)
	(segment
		(start 273.019774 -166.878508)
		(end 277.338282 -162.56)
		(width 0.127)
		(layer "In2.Cu")
		(net "PMU_PLTRST_N")
	)
	(segment
		(start 296.291 -104.648)
		(end 296.291 -105.537)
		(width 0.127)
		(layer "In2.Cu")
		(net "PMU_PLTRST_N")
	)
	(segment
		(start 277.338282 -162.56)
		(end 277.749 -162.56)
		(width 0.127)
		(layer "In2.Cu")
		(net "PMU_PLTRST_N")
	)
	(segment
		(start 174.0916 -221.3483)
		(end 208.70418 -221.3483)
		(width 0.127)
		(layer "In2.Cu")
		(net "PMU_PLTRST_N")
	)
	(segment
		(start 295.148 -243.99875)
		(end 296.867072 -243.99875)
		(width 0.127)
		(layer "In2.Cu")
		(net "PMU_PLTRST_N")
	)
	(segment
		(start 339.725 -214.329772)
		(end 339.725 -168.783)
		(width 0.127)
		(layer "In2.Cu")
		(net "PMU_PLTRST_N")
	)
	(segment
		(start 267.111988 -207.772)
		(end 271.78 -212.440012)
		(width 0.127)
		(layer "In5.Cu")
		(net "PMU_PLTRST_N")
	)
	(segment
		(start 211.025232 -219.54363)
		(end 209.954622 -220.61424)
		(width 0.127)
		(layer "In5.Cu")
		(net "PMU_PLTRST_N")
	)
	(segment
		(start 211.025232 -213.536276)
		(end 211.025232 -219.54363)
		(width 0.127)
		(layer "In5.Cu")
		(net "PMU_PLTRST_N")
	)
	(segment
		(start 275.480018 -243.99875)
		(end 295.148 -243.99875)
		(width 0.127)
		(layer "In5.Cu")
		(net "PMU_PLTRST_N")
	)
	(segment
		(start 271.78 -240.298732)
		(end 275.480018 -243.99875)
		(width 0.127)
		(layer "In5.Cu")
		(net "PMU_PLTRST_N")
	)
	(segment
		(start 253.746 -196.6976)
		(end 253.746 -195.556632)
		(width 0.127)
		(layer "In5.Cu")
		(net "PMU_PLTRST_N")
	)
	(segment
		(start 232.180384 -192.381124)
		(end 211.025232 -213.536276)
		(width 0.127)
		(layer "In5.Cu")
		(net "PMU_PLTRST_N")
	)
	(segment
		(start 296.291 -136.144)
		(end 294.894 -137.541)
		(width 0.127)
		(layer "In5.Cu")
		(net "PMU_PLTRST_N")
	)
	(segment
		(start 253.746 -195.556632)
		(end 250.570492 -192.381124)
		(width 0.127)
		(layer "In5.Cu")
		(net "PMU_PLTRST_N")
	)
	(segment
		(start 254.2794 -197.231)
		(end 253.746 -196.6976)
		(width 0.127)
		(layer "In5.Cu")
		(net "PMU_PLTRST_N")
	)
	(segment
		(start 264.8204 -207.772)
		(end 267.111988 -207.772)
		(width 0.127)
		(layer "In5.Cu")
		(net "PMU_PLTRST_N")
	)
	(segment
		(start 296.291 -105.537)
		(end 296.291 -136.144)
		(width 0.127)
		(layer "In5.Cu")
		(net "PMU_PLTRST_N")
	)
	(segment
		(start 271.78 -212.440012)
		(end 271.78 -240.298732)
		(width 0.127)
		(layer "In5.Cu")
		(net "PMU_PLTRST_N")
	)
	(segment
		(start 209.954622 -220.61424)
		(end 209.43824 -220.61424)
		(width 0.127)
		(layer "In5.Cu")
		(net "PMU_PLTRST_N")
	)
	(segment
		(start 254.2794 -197.231)
		(end 264.8204 -207.772)
		(width 0.127)
		(layer "In5.Cu")
		(net "PMU_PLTRST_N")
	)
	(segment
		(start 250.570492 -192.381124)
		(end 232.180384 -192.381124)
		(width 0.127)
		(layer "In5.Cu")
		(net "PMU_PLTRST_N")
	)
	(segment
		(start 183.896 -49.149)
		(end 183.5785 -49.149)
		(width 0.1143)
		(layer "F.Cu")
		(net "PRSNT_AND_2")
	)
	(segment
		(start 185.65876 -50.84064)
		(end 185.65876 -50.02911)
		(width 0.1143)
		(layer "F.Cu")
		(net "PRSNT_AND_2")
	)
	(segment
		(start 184.2008 -50.7873)
		(end 183.5785 -50.165)
		(width 0.1143)
		(layer "F.Cu")
		(net "PRSNT_AND_2")
	)
	(segment
		(start 184.2008 -51.308)
		(end 184.2008 -50.7873)
		(width 0.1143)
		(layer "F.Cu")
		(net "PRSNT_AND_2")
	)
	(segment
		(start 184.4294 -49.6824)
		(end 183.896 -49.149)
		(width 0.1143)
		(layer "F.Cu")
		(net "PRSNT_AND_2")
	)
	(segment
		(start 183.5785 -49.149)
		(end 183.5785 -50.165)
		(width 0.1143)
		(layer "F.Cu")
		(net "PRSNT_AND_2")
	)
	(segment
		(start 184.2008 -51.308)
		(end 185.1914 -51.308)
		(width 0.1143)
		(layer "F.Cu")
		(net "PRSNT_AND_2")
	)
	(segment
		(start 185.1914 -51.308)
		(end 185.65876 -50.84064)
		(width 0.1143)
		(layer "F.Cu")
		(net "PRSNT_AND_2")
	)
	(via
		(at 184.4294 -49.6824)
		(size 0.7112)
		(drill 0.3556)
		(layers "F.Cu" "B.Cu")
		(net "PRSNT_AND_2")
	)
	(segment
		(start 58.40095 -209.06105)
		(end 57.912 -209.55)
		(width 0.1143)
		(layer "F.Cu")
		(net "BMC_I2C_SCL_10")
	)
	(segment
		(start 302.768 -91.010486)
		(end 301.038514 -89.281)
		(width 0.1143)
		(layer "F.Cu")
		(net "BMC_I2C_SCL_10")
	)
	(segment
		(start 15.618968 -203.526136)
		(end 15.618968 -203.963016)
		(width 0.1143)
		(layer "F.Cu")
		(net "BMC_I2C_SCL_10")
	)
	(segment
		(start 334.706468 -214.884)
		(end 334.800702 -214.978234)
		(width 0.1143)
		(layer "F.Cu")
		(net "BMC_I2C_SCL_10")
	)
	(segment
		(start 307.086 -158.837122)
		(end 311.65673 -154.266392)
		(width 0.1143)
		(layer "F.Cu")
		(net "BMC_I2C_SCL_10")
	)
	(segment
		(start 16.071088 -203.074016)
		(end 15.618968 -203.526136)
		(width 0.1143)
		(layer "F.Cu")
		(net "BMC_I2C_SCL_10")
	)
	(segment
		(start 302.768 -91.7575)
		(end 302.768 -91.010486)
		(width 0.1143)
		(layer "F.Cu")
		(net "BMC_I2C_SCL_10")
	)
	(segment
		(start 197.1294 -25.5524)
		(end 259.715 -88.138)
		(width 0.1143)
		(layer "F.Cu")
		(net "BMC_I2C_SCL_10")
	)
	(segment
		(start 310.49595 -136.106408)
		(end 310.49595 -128.41605)
		(width 0.1143)
		(layer "F.Cu")
		(net "BMC_I2C_SCL_10")
	)
	(segment
		(start 63.313564 -209.06105)
		(end 58.40095 -209.06105)
		(width 0.1143)
		(layer "F.Cu")
		(net "BMC_I2C_SCL_10")
	)
	(segment
		(start 118.3005 -72.771)
		(end 118.8593 -72.2122)
		(width 0.1143)
		(layer "F.Cu")
		(net "BMC_I2C_SCL_10")
	)
	(segment
		(start 311.65673 -142.913608)
		(end 309.77205 -141.028928)
		(width 0.1143)
		(layer "F.Cu")
		(net "BMC_I2C_SCL_10")
	)
	(segment
		(start 311.65673 -154.266392)
		(end 311.65673 -142.913608)
		(width 0.1143)
		(layer "F.Cu")
		(net "BMC_I2C_SCL_10")
	)
	(segment
		(start 118.8593 -72.2122)
		(end 118.8593 -66.2051)
		(width 0.1143)
		(layer "F.Cu")
		(net "BMC_I2C_SCL_10")
	)
	(segment
		(start 57.912 -210.6295)
		(end 57.912 -209.55)
		(width 0.1143)
		(layer "F.Cu")
		(net "BMC_I2C_SCL_10")
	)
	(segment
		(start 319.5193 -205.5495)
		(end 309.88 -205.5495)
		(width 0.1143)
		(layer "F.Cu")
		(net "BMC_I2C_SCL_10")
	)
	(segment
		(start 332.359 -211.8995)
		(end 332.359 -213.614)
		(width 0.1143)
		(layer "F.Cu")
		(net "BMC_I2C_SCL_10")
	)
	(segment
		(start 68.58 -214.327486)
		(end 63.313564 -209.06105)
		(width 0.1143)
		(layer "F.Cu")
		(net "BMC_I2C_SCL_10")
	)
	(segment
		(start 259.715 -88.138)
		(end 259.842 -88.138)
		(width 0.1143)
		(layer "F.Cu")
		(net "BMC_I2C_SCL_10")
	)
	(segment
		(start 16.071088 -202.629516)
		(end 16.071088 -203.074016)
		(width 0.1143)
		(layer "F.Cu")
		(net "BMC_I2C_SCL_10")
	)
	(segment
		(start 95.504 -219.984828)
		(end 95.514414 -219.974414)
		(width 0.1143)
		(layer "F.Cu")
		(net "BMC_I2C_SCL_10")
	)
	(segment
		(start 35.827716 -205.28788)
		(end 37.211 -205.28788)
		(width 0.1143)
		(layer "F.Cu")
		(net "BMC_I2C_SCL_10")
	)
	(segment
		(start 301.038514 -89.281)
		(end 300.736 -89.281)
		(width 0.1143)
		(layer "F.Cu")
		(net "BMC_I2C_SCL_10")
	)
	(segment
		(start 15.618968 -203.963016)
		(end 15.618968 -205.258416)
		(width 0.1143)
		(layer "F.Cu")
		(net "BMC_I2C_SCL_10")
	)
	(segment
		(start 335.661 -215.838532)
		(end 334.800702 -214.978234)
		(width 0.1143)
		(layer "F.Cu")
		(net "BMC_I2C_SCL_10")
	)
	(segment
		(start 197.1294 -19.6469)
		(end 197.1294 -25.5524)
		(width 0.1143)
		(layer "F.Cu")
		(net "BMC_I2C_SCL_10")
	)
	(segment
		(start 307.086 -160.2105)
		(end 307.086 -158.837122)
		(width 0.1143)
		(layer "F.Cu")
		(net "BMC_I2C_SCL_10")
	)
	(segment
		(start 95.504 -220.9165)
		(end 95.504 -219.984828)
		(width 0.1143)
		(layer "F.Cu")
		(net "BMC_I2C_SCL_10")
	)
	(segment
		(start 335.661 -216.916)
		(end 335.661 -215.838532)
		(width 0.1143)
		(layer "F.Cu")
		(net "BMC_I2C_SCL_10")
	)
	(segment
		(start 309.77205 -141.028928)
		(end 309.77205 -136.830308)
		(width 0.1143)
		(layer "F.Cu")
		(net "BMC_I2C_SCL_10")
	)
	(segment
		(start 333.629 -214.884)
		(end 334.706468 -214.884)
		(width 0.1143)
		(layer "F.Cu")
		(net "BMC_I2C_SCL_10")
	)
	(segment
		(start 68.58 -219.837)
		(end 68.58 -214.327486)
		(width 0.1143)
		(layer "F.Cu")
		(net "BMC_I2C_SCL_10")
	)
	(segment
		(start 309.77205 -136.830308)
		(end 310.49595 -136.106408)
		(width 0.1143)
		(layer "F.Cu")
		(net "BMC_I2C_SCL_10")
	)
	(segment
		(start 310.49595 -128.41605)
		(end 311.785 -127.127)
		(width 0.1143)
		(layer "F.Cu")
		(net "BMC_I2C_SCL_10")
	)
	(segment
		(start 332.359 -213.614)
		(end 333.629 -214.884)
		(width 0.1143)
		(layer "F.Cu")
		(net "BMC_I2C_SCL_10")
	)
	(segment
		(start 118.8593 -66.2051)
		(end 118.5418 -65.8876)
		(width 0.1143)
		(layer "F.Cu")
		(net "BMC_I2C_SCL_10")
	)
	(segment
		(start 290.1315 -65.659)
		(end 291.084 -65.659)
		(width 0.1143)
		(layer "F.Cu")
		(net "BMC_I2C_SCL_10")
	)
	(segment
		(start 193.6115 -16.129)
		(end 197.1294 -19.6469)
		(width 0.1143)
		(layer "F.Cu")
		(net "BMC_I2C_SCL_10")
	)
	(segment
		(start 302.1965 -92.329)
		(end 302.768 -91.7575)
		(width 0.1143)
		(layer "F.Cu")
		(net "BMC_I2C_SCL_10")
	)
	(via
		(at 319.5193 -205.5495)
		(size 0.5588)
		(drill 0.3048)
		(layers "F.Cu" "B.Cu")
		(net "BMC_I2C_SCL_10")
	)
	(via
		(at 15.618968 -203.963016)
		(size 0.5588)
		(drill 0.3048)
		(layers "F.Cu" "B.Cu")
		(net "BMC_I2C_SCL_10")
	)
	(via
		(at 29.337 -215.519)
		(size 0.5588)
		(drill 0.3048)
		(layers "F.Cu" "B.Cu")
		(net "BMC_I2C_SCL_10")
	)
	(via
		(at 143.87322 -93.091)
		(size 0.5588)
		(drill 0.3048)
		(layers "F.Cu" "B.Cu")
		(net "BMC_I2C_SCL_10")
	)
	(via
		(at 259.842 -88.138)
		(size 0.5588)
		(drill 0.3048)
		(layers "F.Cu" "B.Cu")
		(net "BMC_I2C_SCL_10")
	)
	(via
		(at 57.912 -209.55)
		(size 0.5588)
		(drill 0.3048)
		(layers "F.Cu" "B.Cu")
		(net "BMC_I2C_SCL_10")
	)
	(via
		(at 312.370978 -215.138)
		(size 0.5588)
		(drill 0.3048)
		(layers "F.Cu" "B.Cu")
		(net "BMC_I2C_SCL_10")
	)
	(via
		(at 334.800702 -214.978234)
		(size 0.5588)
		(drill 0.3048)
		(layers "F.Cu" "B.Cu")
		(net "BMC_I2C_SCL_10")
	)
	(via
		(at 118.5418 -65.8876)
		(size 0.5588)
		(drill 0.3048)
		(layers "F.Cu" "B.Cu")
		(net "BMC_I2C_SCL_10")
	)
	(via
		(at 328.549 -150.622)
		(size 0.5588)
		(drill 0.3048)
		(layers "F.Cu" "B.Cu")
		(net "BMC_I2C_SCL_10")
	)
	(via
		(at 68.58 -219.837)
		(size 0.5588)
		(drill 0.3048)
		(layers "F.Cu" "B.Cu")
		(net "BMC_I2C_SCL_10")
	)
	(via
		(at 335.788 -179.197)
		(size 0.5588)
		(drill 0.3048)
		(layers "F.Cu" "B.Cu")
		(net "BMC_I2C_SCL_10")
	)
	(via
		(at 99.695 -182.499)
		(size 0.5588)
		(drill 0.3048)
		(layers "F.Cu" "B.Cu")
		(net "BMC_I2C_SCL_10")
	)
	(via
		(at 95.514414 -219.974414)
		(size 0.5588)
		(drill 0.3048)
		(layers "F.Cu" "B.Cu")
		(net "BMC_I2C_SCL_10")
	)
	(via
		(at 37.211 -205.28788)
		(size 0.5588)
		(drill 0.3048)
		(layers "F.Cu" "B.Cu")
		(net "BMC_I2C_SCL_10")
	)
	(via
		(at 311.785 -127.127)
		(size 0.5588)
		(drill 0.3048)
		(layers "F.Cu" "B.Cu")
		(net "BMC_I2C_SCL_10")
	)
	(via
		(at 335.407 -170.561)
		(size 0.7112)
		(drill 0.3556)
		(layers "F.Cu" "B.Cu")
		(net "BMC_I2C_SCL_10")
	)
	(via
		(at 291.084 -65.659)
		(size 0.5588)
		(drill 0.3048)
		(layers "F.Cu" "B.Cu")
		(net "BMC_I2C_SCL_10")
	)
	(via
		(at 300.736 -89.281)
		(size 0.5588)
		(drill 0.3048)
		(layers "F.Cu" "B.Cu")
		(net "BMC_I2C_SCL_10")
	)
	(via
		(at 135.795766 -79.037434)
		(size 0.5588)
		(drill 0.3048)
		(layers "F.Cu" "B.Cu")
		(net "BMC_I2C_SCL_10")
	)
	(segment
		(start 335.407 -170.561)
		(end 335.407 -169.778934)
		(width 0.1143)
		(layer "B.Cu")
		(net "BMC_I2C_SCL_10")
	)
	(segment
		(start 335.407 -169.778934)
		(end 335.785714 -169.40022)
		(width 0.1143)
		(layer "B.Cu")
		(net "BMC_I2C_SCL_10")
	)
	(segment
		(start 137.933684 -87.932006)
		(end 137.933684 -81.545684)
		(width 0.1143)
		(layer "B.Cu")
		(net "BMC_I2C_SCL_10")
	)
	(segment
		(start 332.923642 -158.115)
		(end 332.073758 -158.115)
		(width 0.1143)
		(layer "B.Cu")
		(net "BMC_I2C_SCL_10")
	)
	(segment
		(start 330.00315 -156.044392)
		(end 330.00315 -152.07615)
		(width 0.1143)
		(layer "B.Cu")
		(net "BMC_I2C_SCL_10")
	)
	(segment
		(start 135.80491 -79.037434)
		(end 135.795766 -79.037434)
		(width 0.1143)
		(layer "B.Cu")
		(net "BMC_I2C_SCL_10")
	)
	(segment
		(start 335.785714 -169.40022)
		(end 335.785714 -160.977072)
		(width 0.1143)
		(layer "B.Cu")
		(net "BMC_I2C_SCL_10")
	)
	(segment
		(start 298.9707 -87.5157)
		(end 300.736 -89.281)
		(width 0.1143)
		(layer "B.Cu")
		(net "BMC_I2C_SCL_10")
	)
	(segment
		(start 332.073758 -158.115)
		(end 330.00315 -156.044392)
		(width 0.1143)
		(layer "B.Cu")
		(net "BMC_I2C_SCL_10")
	)
	(segment
		(start 135.805926 -79.03845)
		(end 135.80491 -79.037434)
		(width 0.1143)
		(layer "B.Cu")
		(net "BMC_I2C_SCL_10")
	)
	(segment
		(start 30.938216 -211.560664)
		(end 30.938216 -213.917784)
		(width 0.1143)
		(layer "B.Cu")
		(net "BMC_I2C_SCL_10")
	)
	(segment
		(start 137.933684 -81.545684)
		(end 137.39495 -81.00695)
		(width 0.1143)
		(layer "B.Cu")
		(net "BMC_I2C_SCL_10")
	)
	(segment
		(start 140.95857 -94.3991)
		(end 141.55547 -94.996)
		(width 0.1143)
		(layer "B.Cu")
		(net "BMC_I2C_SCL_10")
	)
	(segment
		(start 141.55547 -94.996)
		(end 142.85722 -94.996)
		(width 0.1143)
		(layer "B.Cu")
		(net "BMC_I2C_SCL_10")
	)
	(segment
		(start 137.224516 -80.32877)
		(end 137.224516 -79.896716)
		(width 0.1143)
		(layer "B.Cu")
		(net "BMC_I2C_SCL_10")
	)
	(segment
		(start 98.201734 -217.287094)
		(end 95.514414 -219.974414)
		(width 0.1143)
		(layer "B.Cu")
		(net "BMC_I2C_SCL_10")
	)
	(segment
		(start 335.785714 -160.977072)
		(end 332.923642 -158.115)
		(width 0.1143)
		(layer "B.Cu")
		(net "BMC_I2C_SCL_10")
	)
	(segment
		(start 335.6737 -178.5747)
		(end 335.788 -178.689)
		(width 0.1143)
		(layer "B.Cu")
		(net "BMC_I2C_SCL_10")
	)
	(segment
		(start 335.788 -178.689)
		(end 335.788 -179.197)
		(width 0.1143)
		(layer "B.Cu")
		(net "BMC_I2C_SCL_10")
	)
	(segment
		(start 98.201734 -183.992266)
		(end 98.201734 -217.287094)
		(width 0.1143)
		(layer "B.Cu")
		(net "BMC_I2C_SCL_10")
	)
	(segment
		(start 30.938216 -213.917784)
		(end 29.337 -215.519)
		(width 0.1143)
		(layer "B.Cu")
		(net "BMC_I2C_SCL_10")
	)
	(segment
		(start 259.842 -88.138)
		(end 260.4643 -87.5157)
		(width 0.1143)
		(layer "B.Cu")
		(net "BMC_I2C_SCL_10")
	)
	(segment
		(start 335.407 -170.561)
		(end 335.407 -170.794172)
		(width 0.1143)
		(layer "B.Cu")
		(net "BMC_I2C_SCL_10")
	)
	(segment
		(start 335.407 -170.794172)
		(end 335.6737 -171.060872)
		(width 0.1143)
		(layer "B.Cu")
		(net "BMC_I2C_SCL_10")
	)
	(segment
		(start 137.39495 -80.499204)
		(end 137.224516 -80.32877)
		(width 0.1143)
		(layer "B.Cu")
		(net "BMC_I2C_SCL_10")
	)
	(segment
		(start 99.695 -182.499)
		(end 98.201734 -183.992266)
		(width 0.1143)
		(layer "B.Cu")
		(net "BMC_I2C_SCL_10")
	)
	(segment
		(start 136.36625 -79.03845)
		(end 135.805926 -79.03845)
		(width 0.1143)
		(layer "B.Cu")
		(net "BMC_I2C_SCL_10")
	)
	(segment
		(start 143.87322 -92.175076)
		(end 142.642844 -90.9447)
		(width 0.1143)
		(layer "B.Cu")
		(net "BMC_I2C_SCL_10")
	)
	(segment
		(start 137.224516 -79.896716)
		(end 136.36625 -79.03845)
		(width 0.1143)
		(layer "B.Cu")
		(net "BMC_I2C_SCL_10")
	)
	(segment
		(start 143.87322 -93.091)
		(end 143.87322 -92.175076)
		(width 0.1143)
		(layer "B.Cu")
		(net "BMC_I2C_SCL_10")
	)
	(segment
		(start 142.642844 -90.9447)
		(end 140.946378 -90.9447)
		(width 0.1143)
		(layer "B.Cu")
		(net "BMC_I2C_SCL_10")
	)
	(segment
		(start 335.6737 -171.060872)
		(end 335.6737 -178.5747)
		(width 0.1143)
		(layer "B.Cu")
		(net "BMC_I2C_SCL_10")
	)
	(segment
		(start 330.00315 -152.07615)
		(end 328.549 -150.622)
		(width 0.1143)
		(layer "B.Cu")
		(net "BMC_I2C_SCL_10")
	)
	(segment
		(start 140.946378 -90.9447)
		(end 137.933684 -87.932006)
		(width 0.1143)
		(layer "B.Cu")
		(net "BMC_I2C_SCL_10")
	)
	(segment
		(start 260.4643 -87.5157)
		(end 298.9707 -87.5157)
		(width 0.1143)
		(layer "B.Cu")
		(net "BMC_I2C_SCL_10")
	)
	(segment
		(start 137.39495 -81.00695)
		(end 137.39495 -80.499204)
		(width 0.1143)
		(layer "B.Cu")
		(net "BMC_I2C_SCL_10")
	)
	(segment
		(start 142.85722 -94.996)
		(end 143.87322 -93.98)
		(width 0.1143)
		(layer "B.Cu")
		(net "BMC_I2C_SCL_10")
	)
	(segment
		(start 143.87322 -93.98)
		(end 143.87322 -93.091)
		(width 0.1143)
		(layer "B.Cu")
		(net "BMC_I2C_SCL_10")
	)
	(segment
		(start 37.211 -205.28788)
		(end 30.938216 -211.560664)
		(width 0.1143)
		(layer "B.Cu")
		(net "BMC_I2C_SCL_10")
	)
	(segment
		(start 85.935566 -221.869)
		(end 82.720434 -221.869)
		(width 0.127)
		(layer "In2.Cu")
		(net "BMC_I2C_SCL_10")
	)
	(segment
		(start 122.31497 -68.961)
		(end 119.24157 -65.8876)
		(width 0.127)
		(layer "In2.Cu")
		(net "BMC_I2C_SCL_10")
	)
	(segment
		(start 292.608 -74.928476)
		(end 295.4147 -77.735176)
		(width 0.127)
		(layer "In2.Cu")
		(net "BMC_I2C_SCL_10")
	)
	(segment
		(start 299.3517 -102.2223)
		(end 300.101 -101.473)
		(width 0.127)
		(layer "In2.Cu")
		(net "BMC_I2C_SCL_10")
	)
	(segment
		(start 256.570734 -91.4273)
		(end 232.986072 -91.4273)
		(width 0.127)
		(layer "In2.Cu")
		(net "BMC_I2C_SCL_10")
	)
	(segment
		(start 82.720434 -221.869)
		(end 80.434434 -219.583)
		(width 0.127)
		(layer "In2.Cu")
		(net "BMC_I2C_SCL_10")
	)
	(segment
		(start 296.486072 -79.246984)
		(end 296.926508 -79.246984)
		(width 0.127)
		(layer "In2.Cu")
		(net "BMC_I2C_SCL_10")
	)
	(segment
		(start 119.24157 -65.8876)
		(end 118.5418 -65.8876)
		(width 0.127)
		(layer "In2.Cu")
		(net "BMC_I2C_SCL_10")
	)
	(segment
		(start 300.101 -95.504)
		(end 300.736 -94.869)
		(width 0.127)
		(layer "In2.Cu")
		(net "BMC_I2C_SCL_10")
	)
	(segment
		(start 299.3517 -113.717832)
		(end 299.3517 -102.2223)
		(width 0.127)
		(layer "In2.Cu")
		(net "BMC_I2C_SCL_10")
	)
	(segment
		(start 292.608 -69.85)
		(end 292.608 -74.928476)
		(width 0.127)
		(layer "In2.Cu")
		(net "BMC_I2C_SCL_10")
	)
	(segment
		(start 300.101 -101.473)
		(end 300.101 -95.504)
		(width 0.127)
		(layer "In2.Cu")
		(net "BMC_I2C_SCL_10")
	)
	(segment
		(start 132.667502 -74.010774)
		(end 127.617728 -68.961)
		(width 0.127)
		(layer "In2.Cu")
		(net "BMC_I2C_SCL_10")
	)
	(segment
		(start 291.8587 -66.4337)
		(end 291.8587 -69.1007)
		(width 0.127)
		(layer "In2.Cu")
		(net "BMC_I2C_SCL_10")
	)
	(segment
		(start 42.176446 -205.28788)
		(end 37.211 -205.28788)
		(width 0.127)
		(layer "In2.Cu")
		(net "BMC_I2C_SCL_10")
	)
	(segment
		(start 335.788 -179.197)
		(end 335.788 -213.990936)
		(width 0.127)
		(layer "In2.Cu")
		(net "BMC_I2C_SCL_10")
	)
	(segment
		(start 317.02248 -131.614418)
		(end 318.962024 -131.614418)
		(width 0.127)
		(layer "In2.Cu")
		(net "BMC_I2C_SCL_10")
	)
	(segment
		(start 291.8587 -69.1007)
		(end 292.608 -69.85)
		(width 0.127)
		(layer "In2.Cu")
		(net "BMC_I2C_SCL_10")
	)
	(segment
		(start 259.842 -88.138)
		(end 259.842 -88.156034)
		(width 0.127)
		(layer "In2.Cu")
		(net "BMC_I2C_SCL_10")
	)
	(segment
		(start 68.834 -219.583)
		(end 68.58 -219.837)
		(width 0.127)
		(layer "In2.Cu")
		(net "BMC_I2C_SCL_10")
	)
	(segment
		(start 217.22842 -85.6361)
		(end 188.219334 -85.6361)
		(width 0.127)
		(layer "In2.Cu")
		(net "BMC_I2C_SCL_10")
	)
	(segment
		(start 144.877282 -92.964254)
		(end 143.999966 -92.964254)
		(width 0.127)
		(layer "In2.Cu")
		(net "BMC_I2C_SCL_10")
	)
	(segment
		(start 328.041 -143.469868)
		(end 329.184 -144.612868)
		(width 0.127)
		(layer "In2.Cu")
		(net "BMC_I2C_SCL_10")
	)
	(segment
		(start 295.704768 -78.77175)
		(end 296.010838 -78.77175)
		(width 0.127)
		(layer "In2.Cu")
		(net "BMC_I2C_SCL_10")
	)
	(segment
		(start 328.041 -140.693394)
		(end 328.041 -143.469868)
		(width 0.127)
		(layer "In2.Cu")
		(net "BMC_I2C_SCL_10")
	)
	(segment
		(start 291.084 -65.659)
		(end 291.8587 -66.4337)
		(width 0.127)
		(layer "In2.Cu")
		(net "BMC_I2C_SCL_10")
	)
	(segment
		(start 299.847 -88.392)
		(end 300.736 -89.281)
		(width 0.127)
		(layer "In2.Cu")
		(net "BMC_I2C_SCL_10")
	)
	(segment
		(start 135.795766 -78.336902)
		(end 132.667502 -75.208384)
		(width 0.127)
		(layer "In2.Cu")
		(net "BMC_I2C_SCL_10")
	)
	(segment
		(start 312.978546 -127.570484)
		(end 317.02248 -131.614418)
		(width 0.127)
		(layer "In2.Cu")
		(net "BMC_I2C_SCL_10")
	)
	(segment
		(start 95.514414 -219.974414)
		(end 95.123 -219.583)
		(width 0.127)
		(layer "In2.Cu")
		(net "BMC_I2C_SCL_10")
	)
	(segment
		(start 132.667502 -75.208384)
		(end 132.667502 -74.010774)
		(width 0.127)
		(layer "In2.Cu")
		(net "BMC_I2C_SCL_10")
	)
	(segment
		(start 143.999966 -92.964254)
		(end 143.87322 -93.091)
		(width 0.127)
		(layer "In2.Cu")
		(net "BMC_I2C_SCL_10")
	)
	(segment
		(start 308.864 -124.587)
		(end 308.864 -123.230132)
		(width 0.127)
		(layer "In2.Cu")
		(net "BMC_I2C_SCL_10")
	)
	(segment
		(start 312.370978 -214.968836)
		(end 319.5193 -207.820514)
		(width 0.127)
		(layer "In2.Cu")
		(net "BMC_I2C_SCL_10")
	)
	(segment
		(start 232.986072 -91.4273)
		(end 228.609652 -87.05088)
		(width 0.127)
		(layer "In2.Cu")
		(net "BMC_I2C_SCL_10")
	)
	(segment
		(start 311.404 -127.127)
		(end 308.864 -124.587)
		(width 0.127)
		(layer "In2.Cu")
		(net "BMC_I2C_SCL_10")
	)
	(segment
		(start 312.370978 -215.138)
		(end 312.370978 -214.968836)
		(width 0.127)
		(layer "In2.Cu")
		(net "BMC_I2C_SCL_10")
	)
	(segment
		(start 312.720482 -127.570484)
		(end 312.978546 -127.570484)
		(width 0.127)
		(layer "In2.Cu")
		(net "BMC_I2C_SCL_10")
	)
	(segment
		(start 312.260996 -127.110998)
		(end 312.720482 -127.570484)
		(width 0.127)
		(layer "In2.Cu")
		(net "BMC_I2C_SCL_10")
	)
	(segment
		(start 296.010838 -78.77175)
		(end 296.486072 -79.246984)
		(width 0.127)
		(layer "In2.Cu")
		(net "BMC_I2C_SCL_10")
	)
	(segment
		(start 127.617728 -68.961)
		(end 122.31497 -68.961)
		(width 0.127)
		(layer "In2.Cu")
		(net "BMC_I2C_SCL_10")
	)
	(segment
		(start 182.923434 -90.932)
		(end 146.909536 -90.932)
		(width 0.127)
		(layer "In2.Cu")
		(net "BMC_I2C_SCL_10")
	)
	(segment
		(start 319.5193 -207.820514)
		(end 319.5193 -205.5495)
		(width 0.127)
		(layer "In2.Cu")
		(net "BMC_I2C_SCL_10")
	)
	(segment
		(start 57.912 -209.55)
		(end 57.2897 -210.1723)
		(width 0.127)
		(layer "In2.Cu")
		(net "BMC_I2C_SCL_10")
	)
	(segment
		(start 308.864 -123.230132)
		(end 299.3517 -113.717832)
		(width 0.127)
		(layer "In2.Cu")
		(net "BMC_I2C_SCL_10")
	)
	(segment
		(start 218.6432 -87.05088)
		(end 217.22842 -85.6361)
		(width 0.127)
		(layer "In2.Cu")
		(net "BMC_I2C_SCL_10")
	)
	(segment
		(start 300.736 -94.869)
		(end 300.736 -89.281)
		(width 0.127)
		(layer "In2.Cu")
		(net "BMC_I2C_SCL_10")
	)
	(segment
		(start 329.184 -149.562566)
		(end 328.549 -150.197566)
		(width 0.127)
		(layer "In2.Cu")
		(net "BMC_I2C_SCL_10")
	)
	(segment
		(start 318.962024 -131.614418)
		(end 328.041 -140.693394)
		(width 0.127)
		(layer "In2.Cu")
		(net "BMC_I2C_SCL_10")
	)
	(segment
		(start 146.909536 -90.932)
		(end 144.877282 -92.964254)
		(width 0.127)
		(layer "In2.Cu")
		(net "BMC_I2C_SCL_10")
	)
	(segment
		(start 228.609652 -87.05088)
		(end 218.6432 -87.05088)
		(width 0.127)
		(layer "In2.Cu")
		(net "BMC_I2C_SCL_10")
	)
	(segment
		(start 311.785 -127.127)
		(end 311.801002 -127.110998)
		(width 0.127)
		(layer "In2.Cu")
		(net "BMC_I2C_SCL_10")
	)
	(segment
		(start 311.785 -127.127)
		(end 311.404 -127.127)
		(width 0.127)
		(layer "In2.Cu")
		(net "BMC_I2C_SCL_10")
	)
	(segment
		(start 328.549 -150.197566)
		(end 328.549 -150.622)
		(width 0.127)
		(layer "In2.Cu")
		(net "BMC_I2C_SCL_10")
	)
	(segment
		(start 80.434434 -219.583)
		(end 68.834 -219.583)
		(width 0.127)
		(layer "In2.Cu")
		(net "BMC_I2C_SCL_10")
	)
	(segment
		(start 299.847 -82.167476)
		(end 299.847 -88.392)
		(width 0.127)
		(layer "In2.Cu")
		(net "BMC_I2C_SCL_10")
	)
	(segment
		(start 295.4147 -78.481682)
		(end 295.704768 -78.77175)
		(width 0.127)
		(layer "In2.Cu")
		(net "BMC_I2C_SCL_10")
	)
	(segment
		(start 259.842 -88.156034)
		(end 256.570734 -91.4273)
		(width 0.127)
		(layer "In2.Cu")
		(net "BMC_I2C_SCL_10")
	)
	(segment
		(start 88.221566 -219.583)
		(end 85.935566 -221.869)
		(width 0.127)
		(layer "In2.Cu")
		(net "BMC_I2C_SCL_10")
	)
	(segment
		(start 95.123 -219.583)
		(end 88.221566 -219.583)
		(width 0.127)
		(layer "In2.Cu")
		(net "BMC_I2C_SCL_10")
	)
	(segment
		(start 57.2897 -210.1723)
		(end 47.060866 -210.1723)
		(width 0.127)
		(layer "In2.Cu")
		(net "BMC_I2C_SCL_10")
	)
	(segment
		(start 188.219334 -85.6361)
		(end 182.923434 -90.932)
		(width 0.127)
		(layer "In2.Cu")
		(net "BMC_I2C_SCL_10")
	)
	(segment
		(start 335.788 -213.990936)
		(end 334.800702 -214.978234)
		(width 0.127)
		(layer "In2.Cu")
		(net "BMC_I2C_SCL_10")
	)
	(segment
		(start 135.795766 -79.037434)
		(end 135.795766 -78.336902)
		(width 0.127)
		(layer "In2.Cu")
		(net "BMC_I2C_SCL_10")
	)
	(segment
		(start 47.060866 -210.1723)
		(end 42.176446 -205.28788)
		(width 0.127)
		(layer "In2.Cu")
		(net "BMC_I2C_SCL_10")
	)
	(segment
		(start 311.801002 -127.110998)
		(end 312.260996 -127.110998)
		(width 0.127)
		(layer "In2.Cu")
		(net "BMC_I2C_SCL_10")
	)
	(segment
		(start 296.926508 -79.246984)
		(end 299.847 -82.167476)
		(width 0.127)
		(layer "In2.Cu")
		(net "BMC_I2C_SCL_10")
	)
	(segment
		(start 295.4147 -77.735176)
		(end 295.4147 -78.481682)
		(width 0.127)
		(layer "In2.Cu")
		(net "BMC_I2C_SCL_10")
	)
	(segment
		(start 329.184 -144.612868)
		(end 329.184 -149.562566)
		(width 0.127)
		(layer "In2.Cu")
		(net "BMC_I2C_SCL_10")
	)
	(segment
		(start 334.800702 -214.978234)
		(end 312.530744 -214.978234)
		(width 0.127)
		(layer "In5.Cu")
		(net "BMC_I2C_SCL_10")
	)
	(segment
		(start 15.618968 -203.963016)
		(end 17.416526 -203.963016)
		(width 0.127)
		(layer "In5.Cu")
		(net "BMC_I2C_SCL_10")
	)
	(segment
		(start 100.838 -182.499)
		(end 102.743 -180.594)
		(width 0.127)
		(layer "In5.Cu")
		(net "BMC_I2C_SCL_10")
	)
	(segment
		(start 28.71978 -214.90178)
		(end 29.337 -215.519)
		(width 0.127)
		(layer "In5.Cu")
		(net "BMC_I2C_SCL_10")
	)
	(segment
		(start 25.118568 -212.529166)
		(end 27.491182 -214.90178)
		(width 0.127)
		(layer "In5.Cu")
		(net "BMC_I2C_SCL_10")
	)
	(segment
		(start 145.034 -114.173)
		(end 145.034 -94.488)
		(width 0.127)
		(layer "In5.Cu")
		(net "BMC_I2C_SCL_10")
	)
	(segment
		(start 99.695 -182.499)
		(end 100.838 -182.499)
		(width 0.127)
		(layer "In5.Cu")
		(net "BMC_I2C_SCL_10")
	)
	(segment
		(start 25.118568 -211.665058)
		(end 25.118568 -212.529166)
		(width 0.127)
		(layer "In5.Cu")
		(net "BMC_I2C_SCL_10")
	)
	(segment
		(start 116.967 -180.594)
		(end 150.114 -147.447)
		(width 0.127)
		(layer "In5.Cu")
		(net "BMC_I2C_SCL_10")
	)
	(segment
		(start 102.743 -180.594)
		(end 116.967 -180.594)
		(width 0.127)
		(layer "In5.Cu")
		(net "BMC_I2C_SCL_10")
	)
	(segment
		(start 17.416526 -203.963016)
		(end 25.118568 -211.665058)
		(width 0.127)
		(layer "In5.Cu")
		(net "BMC_I2C_SCL_10")
	)
	(segment
		(start 143.87322 -93.32722)
		(end 143.87322 -93.091)
		(width 0.127)
		(layer "In5.Cu")
		(net "BMC_I2C_SCL_10")
	)
	(segment
		(start 312.530744 -214.978234)
		(end 312.370978 -215.138)
		(width 0.127)
		(layer "In5.Cu")
		(net "BMC_I2C_SCL_10")
	)
	(segment
		(start 145.034 -94.488)
		(end 143.87322 -93.32722)
		(width 0.127)
		(layer "In5.Cu")
		(net "BMC_I2C_SCL_10")
	)
	(segment
		(start 150.114 -119.253)
		(end 145.034 -114.173)
		(width 0.127)
		(layer "In5.Cu")
		(net "BMC_I2C_SCL_10")
	)
	(segment
		(start 150.114 -147.447)
		(end 150.114 -119.253)
		(width 0.127)
		(layer "In5.Cu")
		(net "BMC_I2C_SCL_10")
	)
	(segment
		(start 27.491182 -214.90178)
		(end 28.71978 -214.90178)
		(width 0.127)
		(layer "In5.Cu")
		(net "BMC_I2C_SCL_10")
	)
	(segment
		(start 93.7006 -225.43516)
		(end 92.08516 -225.43516)
		(width 0.1143)
		(layer "F.Cu")
		(net "FAULT_SCL")
	)
	(segment
		(start 92.08516 -225.43516)
		(end 91.313 -224.663)
		(width 0.1143)
		(layer "F.Cu")
		(net "FAULT_SCL")
	)
	(segment
		(start 90.1065 -224.663)
		(end 91.059 -224.663)
		(width 0.1143)
		(layer "F.Cu")
		(net "FAULT_SCL")
	)
	(segment
		(start 95.504 -224.536)
		(end 94.60484 -225.43516)
		(width 0.1143)
		(layer "F.Cu")
		(net "FAULT_SCL")
	)
	(segment
		(start 91.313 -224.663)
		(end 91.059 -224.663)
		(width 0.1143)
		(layer "F.Cu")
		(net "FAULT_SCL")
	)
	(segment
		(start 95.504 -221.8055)
		(end 95.504 -224.536)
		(width 0.1143)
		(layer "F.Cu")
		(net "FAULT_SCL")
	)
	(segment
		(start 94.60484 -225.43516)
		(end 93.7006 -225.43516)
		(width 0.1143)
		(layer "F.Cu")
		(net "FAULT_SCL")
	)
	(via
		(at 91.059 -224.663)
		(size 0.7112)
		(drill 0.3556)
		(layers "F.Cu" "B.Cu")
		(net "FAULT_SCL")
	)
	(segment
		(start 218.567 -183.007)
		(end 218.567 -184.1754)
		(width 0.1143)
		(layer "F.Cu")
		(net "HB_A_IN_EXP")
	)
	(segment
		(start 217.87485 -188.798454)
		(end 219.068396 -189.992)
		(width 0.1143)
		(layer "F.Cu")
		(net "HB_A_IN_EXP")
	)
	(segment
		(start 216.535 -184.4802)
		(end 216.4842 -184.531)
		(width 0.1143)
		(layer "F.Cu")
		(net "HB_A_IN_EXP")
	)
	(segment
		(start 219.068396 -189.992)
		(end 219.7862 -189.992)
		(width 0.1143)
		(layer "F.Cu")
		(net "HB_A_IN_EXP")
	)
	(segment
		(start 217.678 -182.88)
		(end 217.805 -183.007)
		(width 0.1143)
		(layer "F.Cu")
		(net "HB_A_IN_EXP")
	)
	(segment
		(start 220.7006 -189.992)
		(end 219.7862 -189.992)
		(width 0.1143)
		(layer "F.Cu")
		(net "HB_A_IN_EXP")
	)
	(segment
		(start 218.567 -184.1754)
		(end 217.87485 -184.86755)
		(width 0.1143)
		(layer "F.Cu")
		(net "HB_A_IN_EXP")
	)
	(segment
		(start 221.107 -188.087)
		(end 221.107 -189.5856)
		(width 0.1143)
		(layer "F.Cu")
		(net "HB_A_IN_EXP")
	)
	(segment
		(start 217.805 -183.007)
		(end 218.567 -183.007)
		(width 0.1143)
		(layer "F.Cu")
		(net "HB_A_IN_EXP")
	)
	(segment
		(start 216.2175 -181.737)
		(end 216.535 -182.0545)
		(width 0.1143)
		(layer "F.Cu")
		(net "HB_A_IN_EXP")
	)
	(segment
		(start 217.87485 -184.86755)
		(end 217.87485 -188.798454)
		(width 0.1143)
		(layer "F.Cu")
		(net "HB_A_IN_EXP")
	)
	(segment
		(start 216.535 -182.0545)
		(end 216.535 -182.88)
		(width 0.1143)
		(layer "F.Cu")
		(net "HB_A_IN_EXP")
	)
	(segment
		(start 216.535 -182.88)
		(end 216.535 -184.4802)
		(width 0.1143)
		(layer "F.Cu")
		(net "HB_A_IN_EXP")
	)
	(segment
		(start 216.535 -182.88)
		(end 217.678 -182.88)
		(width 0.1143)
		(layer "F.Cu")
		(net "HB_A_IN_EXP")
	)
	(segment
		(start 221.107 -189.5856)
		(end 220.7006 -189.992)
		(width 0.1143)
		(layer "F.Cu")
		(net "HB_A_IN_EXP")
	)
	(via
		(at 219.7862 -189.992)
		(size 0.7112)
		(drill 0.3556)
		(layers "F.Cu" "B.Cu")
		(net "HB_A_IN_EXP")
	)
	(segment
		(start 220.967554 -180.135022)
		(end 220.967554 -180.280818)
		(width 0.1143)
		(layer "F.Cu")
		(net "HB_A_OUT_EXP")
	)
	(segment
		(start 220.971872 -180.285136)
		(end 221.107 -180.420264)
		(width 0.1143)
		(layer "F.Cu")
		(net "HB_A_OUT_EXP")
	)
	(segment
		(start 220.967554 -180.280818)
		(end 220.971872 -180.285136)
		(width 0.1143)
		(layer "F.Cu")
		(net "HB_A_OUT_EXP")
	)
	(segment
		(start 221.107 -185.674)
		(end 222.377 -186.944)
		(width 0.1143)
		(layer "F.Cu")
		(net "HB_A_OUT_EXP")
	)
	(segment
		(start 220.844872 -179.078636)
		(end 220.844872 -180.01234)
		(width 0.1143)
		(layer "F.Cu")
		(net "HB_A_OUT_EXP")
	)
	(segment
		(start 222.766636 -179.078636)
		(end 222.885 -179.197)
		(width 0.1143)
		(layer "F.Cu")
		(net "HB_A_OUT_EXP")
	)
	(segment
		(start 221.860872 -179.078636)
		(end 222.766636 -179.078636)
		(width 0.1143)
		(layer "F.Cu")
		(net "HB_A_OUT_EXP")
	)
	(segment
		(start 222.377 -186.944)
		(end 222.377 -188.087)
		(width 0.1143)
		(layer "F.Cu")
		(net "HB_A_OUT_EXP")
	)
	(segment
		(start 220.844872 -180.01234)
		(end 220.967554 -180.135022)
		(width 0.1143)
		(layer "F.Cu")
		(net "HB_A_OUT_EXP")
	)
	(segment
		(start 221.860872 -179.078636)
		(end 220.844872 -179.078636)
		(width 0.1143)
		(layer "F.Cu")
		(net "HB_A_OUT_EXP")
	)
	(segment
		(start 221.107 -183.007)
		(end 221.107 -185.674)
		(width 0.1143)
		(layer "F.Cu")
		(net "HB_A_OUT_EXP")
	)
	(segment
		(start 221.107 -180.420264)
		(end 221.107 -183.007)
		(width 0.1143)
		(layer "F.Cu")
		(net "HB_A_OUT_EXP")
	)
	(via
		(at 222.885 -179.197)
		(size 0.7112)
		(drill 0.3556)
		(layers "F.Cu" "B.Cu")
		(net "HB_A_OUT_EXP")
	)
	(segment
		(start 220.33865 -187.58535)
		(end 219.837 -188.087)
		(width 0.1143)
		(layer "F.Cu")
		(net "DIVIDER 1_IN_EXP")
	)
	(segment
		(start 219.828872 -179.459636)
		(end 220.33865 -179.969414)
		(width 0.1143)
		(layer "F.Cu")
		(net "DIVIDER 1_IN_EXP")
	)
	(segment
		(start 218.539314 -179.403248)
		(end 218.44 -179.303934)
		(width 0.1143)
		(layer "F.Cu")
		(net "DIVIDER 1_IN_EXP")
	)
	(segment
		(start 218.595702 -179.459636)
		(end 219.828872 -179.459636)
		(width 0.1143)
		(layer "F.Cu")
		(net "DIVIDER 1_IN_EXP")
	)
	(segment
		(start 220.33865 -179.969414)
		(end 220.33865 -187.58535)
		(width 0.1143)
		(layer "F.Cu")
		(net "DIVIDER 1_IN_EXP")
	)
	(segment
		(start 218.44 -179.303934)
		(end 218.44 -178.308)
		(width 0.1143)
		(layer "F.Cu")
		(net "DIVIDER 1_IN_EXP")
	)
	(segment
		(start 218.539314 -179.403248)
		(end 218.595702 -179.459636)
		(width 0.1143)
		(layer "F.Cu")
		(net "DIVIDER 1_IN_EXP")
	)
	(via
		(at 218.44 -178.308)
		(size 0.7112)
		(drill 0.3556)
		(layers "F.Cu" "B.Cu")
		(net "DIVIDER 1_IN_EXP")
	)
	(segment
		(start 15.126716 -220.52788)
		(end 17.021302 -220.52788)
		(width 0.1143)
		(layer "F.Cu")
		(net "PWR_SDA")
	)
	(segment
		(start 15.126716 -224.08388)
		(end 16.079216 -224.08388)
		(width 0.1143)
		(layer "F.Cu")
		(net "PWR_SDA")
	)
	(segment
		(start 17.783302 -223.141794)
		(end 17.783302 -222.325438)
		(width 0.1143)
		(layer "F.Cu")
		(net "PWR_SDA")
	)
	(segment
		(start 17.783302 -221.28988)
		(end 17.783302 -222.325438)
		(width 0.1143)
		(layer "F.Cu")
		(net "PWR_SDA")
	)
	(segment
		(start 17.021302 -220.52788)
		(end 17.783302 -221.28988)
		(width 0.1143)
		(layer "F.Cu")
		(net "PWR_SDA")
	)
	(segment
		(start 16.841216 -224.08388)
		(end 17.783302 -223.141794)
		(width 0.1143)
		(layer "F.Cu")
		(net "PWR_SDA")
	)
	(segment
		(start 16.079216 -224.08388)
		(end 16.841216 -224.08388)
		(width 0.1143)
		(layer "F.Cu")
		(net "PWR_SDA")
	)
	(via
		(at 16.079216 -224.08388)
		(size 0.7112)
		(drill 0.3556)
		(layers "F.Cu" "B.Cu")
		(net "PWR_SDA")
	)
	(segment
		(start 219.075 -180.348636)
		(end 219.828872 -180.348636)
		(width 0.1143)
		(layer "F.Cu")
		(net "DIVIDER 2_IN_EXP")
	)
	(segment
		(start 219.828872 -180.348636)
		(end 219.837 -180.356764)
		(width 0.1143)
		(layer "F.Cu")
		(net "DIVIDER 2_IN_EXP")
	)
	(segment
		(start 217.8685 -181.6735)
		(end 217.805 -181.6735)
		(width 0.1143)
		(layer "F.Cu")
		(net "DIVIDER 2_IN_EXP")
	)
	(segment
		(start 218.5035 -180.594)
		(end 218.5035 -181.0385)
		(width 0.1143)
		(layer "F.Cu")
		(net "DIVIDER 2_IN_EXP")
	)
	(segment
		(start 218.5035 -181.0385)
		(end 217.8685 -181.6735)
		(width 0.1143)
		(layer "F.Cu")
		(net "DIVIDER 2_IN_EXP")
	)
	(segment
		(start 219.837 -180.356764)
		(end 219.837 -183.007)
		(width 0.1143)
		(layer "F.Cu")
		(net "DIVIDER 2_IN_EXP")
	)
	(segment
		(start 218.829636 -180.594)
		(end 219.075 -180.348636)
		(width 0.1143)
		(layer "F.Cu")
		(net "DIVIDER 2_IN_EXP")
	)
	(segment
		(start 218.5035 -180.594)
		(end 218.829636 -180.594)
		(width 0.1143)
		(layer "F.Cu")
		(net "DIVIDER 2_IN_EXP")
	)
	(via
		(at 217.805 -181.6735)
		(size 0.7112)
		(drill 0.3556)
		(layers "F.Cu" "B.Cu")
		(net "DIVIDER 2_IN_EXP")
	)
	(segment
		(start 221.860872 -178.189636)
		(end 221.359984 -177.688748)
		(width 0.1143)
		(layer "F.Cu")
		(net "INVERTER_G1_EXP")
	)
	(segment
		(start 222.622364 -178.189636)
		(end 221.860872 -178.189636)
		(width 0.1143)
		(layer "F.Cu")
		(net "INVERTER_G1_EXP")
	)
	(segment
		(start 221.359984 -177.688748)
		(end 221.359984 -176.558194)
		(width 0.1143)
		(layer "F.Cu")
		(net "INVERTER_G1_EXP")
	)
	(segment
		(start 222.885 -177.927)
		(end 222.622364 -178.189636)
		(width 0.1143)
		(layer "F.Cu")
		(net "INVERTER_G1_EXP")
	)
	(via
		(at 222.885 -177.927)
		(size 0.7112)
		(drill 0.3556)
		(layers "F.Cu" "B.Cu")
		(net "INVERTER_G1_EXP")
	)
	(segment
		(start 310.278272 -172.339)
		(end 310.595772 -172.6565)
		(width 0.1143)
		(layer "F.Cu")
		(net "BMC_RXD5_R")
	)
	(segment
		(start 314.307982 -173.0375)
		(end 314.5155 -173.0375)
		(width 0.1143)
		(layer "F.Cu")
		(net "BMC_RXD5_R")
	)
	(segment
		(start 314.5155 -173.0375)
		(end 314.96 -173.482)
		(width 0.1143)
		(layer "F.Cu")
		(net "BMC_RXD5_R")
	)
	(segment
		(start 315.087 -173.609)
		(end 314.96 -173.482)
		(width 0.1143)
		(layer "F.Cu")
		(net "BMC_RXD5_R")
	)
	(segment
		(start 313.926982 -172.6565)
		(end 314.307982 -173.0375)
		(width 0.1143)
		(layer "F.Cu")
		(net "BMC_RXD5_R")
	)
	(segment
		(start 310.261 -172.339)
		(end 310.278272 -172.339)
		(width 0.1143)
		(layer "F.Cu")
		(net "BMC_RXD5_R")
	)
	(segment
		(start 317.5635 -173.736)
		(end 317.4365 -173.609)
		(width 0.1143)
		(layer "F.Cu")
		(net "BMC_RXD5_R")
	)
	(segment
		(start 310.595772 -172.6565)
		(end 313.926982 -172.6565)
		(width 0.1143)
		(layer "F.Cu")
		(net "BMC_RXD5_R")
	)
	(segment
		(start 302.159924 -172.007022)
		(end 303.288954 -172.007022)
		(width 0.1143)
		(layer "F.Cu")
		(net "BMC_RXD5_R")
	)
	(segment
		(start 309.446422 -172.240194)
		(end 310.162194 -172.240194)
		(width 0.1143)
		(layer "F.Cu")
		(net "BMC_RXD5_R")
	)
	(segment
		(start 310.162194 -172.240194)
		(end 310.261 -172.339)
		(width 0.1143)
		(layer "F.Cu")
		(net "BMC_RXD5_R")
	)
	(segment
		(start 301.634906 -172.240194)
		(end 301.926752 -172.240194)
		(width 0.1143)
		(layer "F.Cu")
		(net "BMC_RXD5_R")
	)
	(segment
		(start 317.4365 -173.609)
		(end 315.087 -173.609)
		(width 0.1143)
		(layer "F.Cu")
		(net "BMC_RXD5_R")
	)
	(segment
		(start 301.926752 -172.240194)
		(end 302.159924 -172.007022)
		(width 0.1143)
		(layer "F.Cu")
		(net "BMC_RXD5_R")
	)
	(segment
		(start 303.288954 -172.007022)
		(end 303.619154 -171.676822)
		(width 0.1143)
		(layer "F.Cu")
		(net "BMC_RXD5_R")
	)
	(segment
		(start 308.88305 -171.676822)
		(end 309.446422 -172.240194)
		(width 0.1143)
		(layer "F.Cu")
		(net "BMC_RXD5_R")
	)
	(segment
		(start 303.619154 -171.676822)
		(end 308.88305 -171.676822)
		(width 0.1143)
		(layer "F.Cu")
		(net "BMC_RXD5_R")
	)
	(via
		(at 314.96 -173.482)
		(size 0.7112)
		(drill 0.3556)
		(layers "F.Cu" "B.Cu")
		(net "BMC_RXD5_R")
	)
	(segment
		(start 218.694 -172.72)
		(end 218.694 -173.584108)
		(width 0.1143)
		(layer "F.Cu")
		(net "HB_EXP_TO_BMC")
	)
	(segment
		(start 219.59443 -176.558194)
		(end 218.622372 -175.586136)
		(width 0.1143)
		(layer "F.Cu")
		(net "HB_EXP_TO_BMC")
	)
	(segment
		(start 297.634914 -181.840124)
		(end 298.030138 -181.4449)
		(width 0.1143)
		(layer "F.Cu")
		(net "HB_EXP_TO_BMC")
	)
	(segment
		(start 220.709744 -178.054508)
		(end 220.709744 -176.558194)
		(width 0.1143)
		(layer "F.Cu")
		(net "HB_EXP_TO_BMC")
	)
	(segment
		(start 218.622372 -173.655736)
		(end 218.622372 -175.586136)
		(width 0.1143)
		(layer "F.Cu")
		(net "HB_EXP_TO_BMC")
	)
	(segment
		(start 220.709744 -176.558194)
		(end 219.59443 -176.558194)
		(width 0.1143)
		(layer "F.Cu")
		(net "HB_EXP_TO_BMC")
	)
	(segment
		(start 218.694 -173.584108)
		(end 218.622372 -173.655736)
		(width 0.1143)
		(layer "F.Cu")
		(net "HB_EXP_TO_BMC")
	)
	(segment
		(start 220.844872 -178.189636)
		(end 220.709744 -178.054508)
		(width 0.1143)
		(layer "F.Cu")
		(net "HB_EXP_TO_BMC")
	)
	(via
		(at 218.694 -172.72)
		(size 0.7112)
		(drill 0.3556)
		(layers "F.Cu" "B.Cu")
		(net "HB_EXP_TO_BMC")
	)
	(via
		(at 298.030138 -181.4449)
		(size 0.508)
		(drill 0.254)
		(layers "F.Cu" "B.Cu")
		(net "HB_EXP_TO_BMC")
	)
	(via
		(at 218.622372 -173.655736)
		(size 0.5588)
		(drill 0.3048)
		(layers "F.Cu" "B.Cu")
		(net "HB_EXP_TO_BMC")
	)
	(segment
		(start 218.622372 -173.655736)
		(end 218.766136 -173.7995)
		(width 0.127)
		(layer "In2.Cu")
		(net "HB_EXP_TO_BMC")
	)
	(segment
		(start 298.030138 -181.660546)
		(end 298.030138 -181.4449)
		(width 0.0889)
		(layer "In2.Cu")
		(net "HB_EXP_TO_BMC")
	)
	(segment
		(start 280.6319 -195.4911)
		(end 285.768288 -190.354712)
		(width 0.127)
		(layer "In2.Cu")
		(net "HB_EXP_TO_BMC")
	)
	(segment
		(start 218.766136 -173.7995)
		(end 253.997968 -173.7995)
		(width 0.127)
		(layer "In2.Cu")
		(net "HB_EXP_TO_BMC")
	)
	(segment
		(start 297.630596 -182.060088)
		(end 298.030138 -181.660546)
		(width 0.0889)
		(layer "In2.Cu")
		(net "HB_EXP_TO_BMC")
	)
	(segment
		(start 285.768288 -190.354712)
		(end 285.974536 -190.354712)
		(width 0.127)
		(layer "In2.Cu")
		(net "HB_EXP_TO_BMC")
	)
	(segment
		(start 291.168836 -189.865)
		(end 295.886378 -185.147458)
		(width 0.127)
		(layer "In2.Cu")
		(net "HB_EXP_TO_BMC")
	)
	(segment
		(start 286.464248 -189.865)
		(end 291.168836 -189.865)
		(width 0.127)
		(layer "In2.Cu")
		(net "HB_EXP_TO_BMC")
	)
	(segment
		(start 285.974536 -190.354712)
		(end 286.464248 -189.865)
		(width 0.127)
		(layer "In2.Cu")
		(net "HB_EXP_TO_BMC")
	)
	(segment
		(start 295.886378 -184.554622)
		(end 297.561 -182.88)
		(width 0.127)
		(layer "In2.Cu")
		(net "HB_EXP_TO_BMC")
	)
	(segment
		(start 253.997968 -173.7995)
		(end 275.689568 -195.4911)
		(width 0.127)
		(layer "In2.Cu")
		(net "HB_EXP_TO_BMC")
	)
	(segment
		(start 297.630596 -182.810404)
		(end 297.630596 -182.060088)
		(width 0.0889)
		(layer "In2.Cu")
		(net "HB_EXP_TO_BMC")
	)
	(segment
		(start 295.886378 -185.147458)
		(end 295.886378 -184.554622)
		(width 0.127)
		(layer "In2.Cu")
		(net "HB_EXP_TO_BMC")
	)
	(segment
		(start 297.561 -182.88)
		(end 297.630596 -182.810404)
		(width 0.0889)
		(layer "In2.Cu")
		(net "HB_EXP_TO_BMC")
	)
	(segment
		(start 275.689568 -195.4911)
		(end 280.6319 -195.4911)
		(width 0.127)
		(layer "In2.Cu")
		(net "HB_EXP_TO_BMC")
	)
	(segment
		(start 300.03496 -184.24017)
		(end 300.03496 -184.344564)
		(width 0.1143)
		(layer "F.Cu")
		(net "HB_OUT_BMC")
	)
	(segment
		(start 300.03496 -184.344564)
		(end 300.983396 -185.293)
		(width 0.1143)
		(layer "F.Cu")
		(net "HB_OUT_BMC")
	)
	(segment
		(start 302.748442 -186.944762)
		(end 303.107852 -186.944762)
		(width 0.1143)
		(layer "F.Cu")
		(net "HB_OUT_BMC")
	)
	(segment
		(start 302.453548 -186.829446)
		(end 302.633126 -186.829446)
		(width 0.1143)
		(layer "F.Cu")
		(net "HB_OUT_BMC")
	)
	(segment
		(start 303.25314 -187.09005)
		(end 303.882552 -187.09005)
		(width 0.1143)
		(layer "F.Cu")
		(net "HB_OUT_BMC")
	)
	(segment
		(start 302.633126 -186.829446)
		(end 302.748442 -186.944762)
		(width 0.1143)
		(layer "F.Cu")
		(net "HB_OUT_BMC")
	)
	(segment
		(start 300.983396 -185.359294)
		(end 302.453548 -186.829446)
		(width 0.1143)
		(layer "F.Cu")
		(net "HB_OUT_BMC")
	)
	(segment
		(start 303.882552 -187.09005)
		(end 303.911 -187.118498)
		(width 0.1143)
		(layer "F.Cu")
		(net "HB_OUT_BMC")
	)
	(segment
		(start 303.107852 -186.944762)
		(end 303.25314 -187.09005)
		(width 0.1143)
		(layer "F.Cu")
		(net "HB_OUT_BMC")
	)
	(segment
		(start 202.692 -184.9755)
		(end 202.692 -179.324)
		(width 0.1143)
		(layer "F.Cu")
		(net "HB_OUT_BMC")
	)
	(segment
		(start 300.983396 -185.293)
		(end 300.983396 -185.359294)
		(width 0.1143)
		(layer "F.Cu")
		(net "HB_OUT_BMC")
	)
	(via
		(at 303.911 -187.118498)
		(size 0.5588)
		(drill 0.3048)
		(layers "F.Cu" "B.Cu")
		(net "HB_OUT_BMC")
	)
	(via
		(at 202.692 -179.324)
		(size 0.5588)
		(drill 0.3048)
		(layers "F.Cu" "B.Cu")
		(net "HB_OUT_BMC")
	)
	(via
		(at 303.0474 -187.1726)
		(size 0.7112)
		(drill 0.3556)
		(layers "F.Cu" "B.Cu")
		(net "HB_OUT_BMC")
	)
	(segment
		(start 303.856898 -187.1726)
		(end 303.0474 -187.1726)
		(width 0.1143)
		(layer "B.Cu")
		(net "HB_OUT_BMC")
	)
	(segment
		(start 303.911 -187.118498)
		(end 303.856898 -187.1726)
		(width 0.1143)
		(layer "B.Cu")
		(net "HB_OUT_BMC")
	)
	(segment
		(start 267.8176 -190.197232)
		(end 267.8176 -190.155068)
		(width 0.127)
		(layer "In2.Cu")
		(net "HB_OUT_BMC")
	)
	(segment
		(start 279.039828 -198.628)
		(end 269.809468 -198.628)
		(width 0.127)
		(layer "In2.Cu")
		(net "HB_OUT_BMC")
	)
	(segment
		(start 295.1226 -192.405)
		(end 285.262828 -192.405)
		(width 0.127)
		(layer "In2.Cu")
		(net "HB_OUT_BMC")
	)
	(segment
		(start 269.809468 -198.628)
		(end 269.0495 -197.868032)
		(width 0.127)
		(layer "In2.Cu")
		(net "HB_OUT_BMC")
	)
	(segment
		(start 207.6323 -174.3837)
		(end 202.692 -179.324)
		(width 0.127)
		(layer "In2.Cu")
		(net "HB_OUT_BMC")
	)
	(segment
		(start 303.911 -187.118498)
		(end 300.409102 -187.118498)
		(width 0.127)
		(layer "In2.Cu")
		(net "HB_OUT_BMC")
	)
	(segment
		(start 229.728268 -175.0568)
		(end 229.055168 -174.3837)
		(width 0.127)
		(layer "In2.Cu")
		(net "HB_OUT_BMC")
	)
	(segment
		(start 269.0495 -191.429132)
		(end 267.8176 -190.197232)
		(width 0.127)
		(layer "In2.Cu")
		(net "HB_OUT_BMC")
	)
	(segment
		(start 269.0495 -197.868032)
		(end 269.0495 -191.429132)
		(width 0.127)
		(layer "In2.Cu")
		(net "HB_OUT_BMC")
	)
	(segment
		(start 285.262828 -192.405)
		(end 279.039828 -198.628)
		(width 0.127)
		(layer "In2.Cu")
		(net "HB_OUT_BMC")
	)
	(segment
		(start 300.409102 -187.118498)
		(end 295.1226 -192.405)
		(width 0.127)
		(layer "In2.Cu")
		(net "HB_OUT_BMC")
	)
	(segment
		(start 229.055168 -174.3837)
		(end 207.6323 -174.3837)
		(width 0.127)
		(layer "In2.Cu")
		(net "HB_OUT_BMC")
	)
	(segment
		(start 252.719332 -175.0568)
		(end 229.728268 -175.0568)
		(width 0.127)
		(layer "In2.Cu")
		(net "HB_OUT_BMC")
	)
	(segment
		(start 267.8176 -190.155068)
		(end 252.719332 -175.0568)
		(width 0.127)
		(layer "In2.Cu")
		(net "HB_OUT_BMC")
	)
	(segment
		(start 306.798726 -163.482274)
		(end 308.102 -162.179)
		(width 0.1143)
		(layer "F.Cu")
		(net "BMC0_SMB10_DAT")
	)
	(segment
		(start 308.102 -162.179)
		(end 308.102 -161.0995)
		(width 0.1143)
		(layer "F.Cu")
		(net "BMC0_SMB10_DAT")
	)
	(segment
		(start 300.472856 -167.134794)
		(end 302.04537 -165.56228)
		(width 0.1143)
		(layer "F.Cu")
		(net "BMC0_SMB10_DAT")
	)
	(segment
		(start 306.10175 -164.180774)
		(end 306.10175 -164.17925)
		(width 0.1143)
		(layer "F.Cu")
		(net "BMC0_SMB10_DAT")
	)
	(segment
		(start 305.7652 -164.5158)
		(end 305.78425 -164.49675)
		(width 0.1143)
		(layer "F.Cu")
		(net "BMC0_SMB10_DAT")
	)
	(segment
		(start 302.04537 -165.56228)
		(end 302.381666 -165.56228)
		(width 0.1143)
		(layer "F.Cu")
		(net "BMC0_SMB10_DAT")
	)
	(segment
		(start 300.472856 -167.649144)
		(end 300.472856 -167.134794)
		(width 0.1143)
		(layer "F.Cu")
		(net "BMC0_SMB10_DAT")
	)
	(segment
		(start 306.798726 -163.493196)
		(end 306.798726 -163.482274)
		(width 0.1143)
		(layer "F.Cu")
		(net "BMC0_SMB10_DAT")
	)
	(segment
		(start 305.78425 -164.49675)
		(end 305.785774 -164.49675)
		(width 0.1143)
		(layer "F.Cu")
		(net "BMC0_SMB10_DAT")
	)
	(segment
		(start 300.03496 -168.08704)
		(end 300.472856 -167.649144)
		(width 0.1143)
		(layer "F.Cu")
		(net "BMC0_SMB10_DAT")
	)
	(segment
		(start 300.03496 -168.240202)
		(end 300.03496 -168.08704)
		(width 0.1143)
		(layer "F.Cu")
		(net "BMC0_SMB10_DAT")
	)
	(segment
		(start 305.785774 -164.49675)
		(end 306.10175 -164.180774)
		(width 0.1143)
		(layer "F.Cu")
		(net "BMC0_SMB10_DAT")
	)
	(segment
		(start 306.787804 -163.493196)
		(end 306.798726 -163.493196)
		(width 0.1143)
		(layer "F.Cu")
		(net "BMC0_SMB10_DAT")
	)
	(segment
		(start 302.381666 -165.56228)
		(end 303.428146 -164.5158)
		(width 0.1143)
		(layer "F.Cu")
		(net "BMC0_SMB10_DAT")
	)
	(segment
		(start 306.10175 -164.17925)
		(end 306.787804 -163.493196)
		(width 0.1143)
		(layer "F.Cu")
		(net "BMC0_SMB10_DAT")
	)
	(segment
		(start 303.428146 -164.5158)
		(end 305.7652 -164.5158)
		(width 0.1143)
		(layer "F.Cu")
		(net "BMC0_SMB10_DAT")
	)
	(via
		(at 306.798726 -163.493196)
		(size 0.7112)
		(drill 0.3556)
		(layers "F.Cu" "B.Cu")
		(net "BMC0_SMB10_DAT")
	)
	(segment
		(start 307.086 -161.0995)
		(end 307.086 -161.859468)
		(width 0.1143)
		(layer "F.Cu")
		(net "BMC0_SMB10_CLK")
	)
	(segment
		(start 303.53 -163.322)
		(end 303.202594 -163.322)
		(width 0.1143)
		(layer "F.Cu")
		(net "BMC0_SMB10_CLK")
	)
	(segment
		(start 303.202594 -163.322)
		(end 301.671736 -164.852858)
		(width 0.1143)
		(layer "F.Cu")
		(net "BMC0_SMB10_CLK")
	)
	(segment
		(start 301.671736 -165.205664)
		(end 299.593 -167.2844)
		(width 0.1143)
		(layer "F.Cu")
		(net "BMC0_SMB10_CLK")
	)
	(segment
		(start 299.23486 -168.88714)
		(end 299.23486 -169.040048)
		(width 0.1143)
		(layer "F.Cu")
		(net "BMC0_SMB10_CLK")
	)
	(segment
		(start 299.593 -167.2844)
		(end 299.593 -168.529)
		(width 0.1143)
		(layer "F.Cu")
		(net "BMC0_SMB10_CLK")
	)
	(segment
		(start 307.086 -161.859468)
		(end 305.623468 -163.322)
		(width 0.1143)
		(layer "F.Cu")
		(net "BMC0_SMB10_CLK")
	)
	(segment
		(start 299.593 -168.529)
		(end 299.23486 -168.88714)
		(width 0.1143)
		(layer "F.Cu")
		(net "BMC0_SMB10_CLK")
	)
	(segment
		(start 305.623468 -163.322)
		(end 303.53 -163.322)
		(width 0.1143)
		(layer "F.Cu")
		(net "BMC0_SMB10_CLK")
	)
	(segment
		(start 301.671736 -164.852858)
		(end 301.671736 -165.205664)
		(width 0.1143)
		(layer "F.Cu")
		(net "BMC0_SMB10_CLK")
	)
	(via
		(at 303.53 -163.322)
		(size 0.7112)
		(drill 0.3556)
		(layers "F.Cu" "B.Cu")
		(net "BMC0_SMB10_CLK")
	)
	(segment
		(start 300.439074 -172.635926)
		(end 300.439074 -172.635164)
		(width 0.1143)
		(layer "F.Cu")
		(net "BMC0_SMB14_SDA")
	)
	(segment
		(start 300.03496 -173.04004)
		(end 300.439074 -172.635926)
		(width 0.1143)
		(layer "F.Cu")
		(net "BMC0_SMB14_SDA")
	)
	(via
		(at 300.439074 -172.635164)
		(size 0.508)
		(drill 0.254)
		(layers "F.Cu" "B.Cu")
		(net "BMC0_SMB14_SDA")
	)
	(via
		(at 316.357 -173.609)
		(size 0.7112)
		(drill 0.3556)
		(layers "F.Cu" "B.Cu")
		(net "BMC0_SMB14_SDA")
	)
	(segment
		(start 311.548018 -172.57395)
		(end 311.14619 -172.172122)
		(width 0.1143)
		(layer "B.Cu")
		(net "BMC0_SMB14_SDA")
	)
	(segment
		(start 316.357 -173.609)
		(end 314.833 -173.609)
		(width 0.1143)
		(layer "B.Cu")
		(net "BMC0_SMB14_SDA")
	)
	(segment
		(start 314.833 -173.609)
		(end 313.79795 -172.57395)
		(width 0.1143)
		(layer "B.Cu")
		(net "BMC0_SMB14_SDA")
	)
	(segment
		(start 301.406306 -172.262292)
		(end 300.811946 -172.262292)
		(width 0.1143)
		(layer "B.Cu")
		(net "BMC0_SMB14_SDA")
	)
	(segment
		(start 300.811946 -172.262292)
		(end 300.439074 -172.635164)
		(width 0.1143)
		(layer "B.Cu")
		(net "BMC0_SMB14_SDA")
	)
	(segment
		(start 311.14619 -172.172122)
		(end 301.496476 -172.172122)
		(width 0.1143)
		(layer "B.Cu")
		(net "BMC0_SMB14_SDA")
	)
	(segment
		(start 313.79795 -172.57395)
		(end 311.548018 -172.57395)
		(width 0.1143)
		(layer "B.Cu")
		(net "BMC0_SMB14_SDA")
	)
	(segment
		(start 317.5635 -173.609)
		(end 316.357 -173.609)
		(width 0.1143)
		(layer "B.Cu")
		(net "BMC0_SMB14_SDA")
	)
	(segment
		(start 301.496476 -172.172122)
		(end 301.406306 -172.262292)
		(width 0.1143)
		(layer "B.Cu")
		(net "BMC0_SMB14_SDA")
	)
	(segment
		(start 299.621702 -172.653198)
		(end 299.621702 -172.646086)
		(width 0.1143)
		(layer "F.Cu")
		(net "BMC0_SMB14_CLK")
	)
	(segment
		(start 299.621702 -172.646086)
		(end 299.635418 -172.63237)
		(width 0.1143)
		(layer "F.Cu")
		(net "BMC0_SMB14_CLK")
	)
	(segment
		(start 299.23486 -173.04004)
		(end 299.621702 -172.653198)
		(width 0.1143)
		(layer "F.Cu")
		(net "BMC0_SMB14_CLK")
	)
	(via
		(at 313.69 -174.625)
		(size 0.7112)
		(drill 0.3556)
		(layers "F.Cu" "B.Cu")
		(net "BMC0_SMB14_CLK")
	)
	(via
		(at 299.635418 -172.63237)
		(size 0.508)
		(drill 0.254)
		(layers "F.Cu" "B.Cu")
		(net "BMC0_SMB14_CLK")
	)
	(segment
		(start 310.940958 -172.667422)
		(end 312.898536 -174.625)
		(width 0.1143)
		(layer "B.Cu")
		(net "BMC0_SMB14_CLK")
	)
	(segment
		(start 300.990762 -172.667422)
		(end 310.940958 -172.667422)
		(width 0.1143)
		(layer "B.Cu")
		(net "BMC0_SMB14_CLK")
	)
	(segment
		(start 300.267878 -173.047914)
		(end 300.61027 -173.047914)
		(width 0.1143)
		(layer "B.Cu")
		(net "BMC0_SMB14_CLK")
	)
	(segment
		(start 312.898536 -174.625)
		(end 313.69 -174.625)
		(width 0.1143)
		(layer "B.Cu")
		(net "BMC0_SMB14_CLK")
	)
	(segment
		(start 299.635418 -172.63237)
		(end 299.852334 -172.63237)
		(width 0.1143)
		(layer "B.Cu")
		(net "BMC0_SMB14_CLK")
	)
	(segment
		(start 313.69 -174.625)
		(end 317.5635 -174.625)
		(width 0.1143)
		(layer "B.Cu")
		(net "BMC0_SMB14_CLK")
	)
	(segment
		(start 299.852334 -172.63237)
		(end 300.267878 -173.047914)
		(width 0.1143)
		(layer "B.Cu")
		(net "BMC0_SMB14_CLK")
	)
	(segment
		(start 300.61027 -173.047914)
		(end 300.990762 -172.667422)
		(width 0.1143)
		(layer "B.Cu")
		(net "BMC0_SMB14_CLK")
	)
	(segment
		(start 277.4188 -65.5574)
		(end 275.59 -63.7286)
		(width 0.254)
		(layer "F.Cu")
		(net "VSENSE_HSC_MSB")
	)
	(segment
		(start 280.378916 -68.517516)
		(end 277.4188 -65.5574)
		(width 0.254)
		(layer "F.Cu")
		(net "VSENSE_HSC_MSB")
	)
	(segment
		(start 273.558 -62.992)
		(end 273.558 -60.452)
		(width 0.254)
		(layer "F.Cu")
		(net "VSENSE_HSC_MSB")
	)
	(segment
		(start 282.020772 -68.517516)
		(end 280.378916 -68.517516)
		(width 0.254)
		(layer "F.Cu")
		(net "VSENSE_HSC_MSB")
	)
	(segment
		(start 274.2946 -63.7286)
		(end 273.558 -62.992)
		(width 0.254)
		(layer "F.Cu")
		(net "VSENSE_HSC_MSB")
	)
	(segment
		(start 275.59 -63.7286)
		(end 274.2946 -63.7286)
		(width 0.254)
		(layer "F.Cu")
		(net "VSENSE_HSC_MSB")
	)
	(via
		(at 277.4188 -65.5574)
		(size 0.7112)
		(drill 0.3556)
		(layers "F.Cu" "B.Cu")
		(net "VSENSE_HSC_MSB")
	)
	(segment
		(start 279.273 -65.0875)
		(end 279.4381 -65.0875)
		(width 0.1143)
		(layer "F.Cu")
		(net "VR_HSC_TIMER_MSB")
	)
	(segment
		(start 280.2382 -65.8876)
		(end 280.2128 -65.8622)
		(width 0.1143)
		(layer "F.Cu")
		(net "VR_HSC_TIMER_MSB")
	)
	(segment
		(start 279.4381 -65.0875)
		(end 280.2128 -65.8622)
		(width 0.1143)
		(layer "F.Cu")
		(net "VR_HSC_TIMER_MSB")
	)
	(segment
		(start 282.020772 -67.017646)
		(end 281.012646 -67.017646)
		(width 0.1143)
		(layer "F.Cu")
		(net "VR_HSC_TIMER_MSB")
	)
	(segment
		(start 280.2382 -66.2432)
		(end 280.2382 -65.8876)
		(width 0.1143)
		(layer "F.Cu")
		(net "VR_HSC_TIMER_MSB")
	)
	(segment
		(start 281.012646 -67.017646)
		(end 280.2382 -66.2432)
		(width 0.1143)
		(layer "F.Cu")
		(net "VR_HSC_TIMER_MSB")
	)
	(via
		(at 280.2128 -65.8622)
		(size 0.7112)
		(drill 0.3556)
		(layers "F.Cu" "B.Cu")
		(net "VR_HSC_TIMER_MSB")
	)
	(segment
		(start 281.423872 -65.223136)
		(end 282.897072 -65.223136)
		(width 0.1143)
		(layer "F.Cu")
		(net "PRSNT_EN_HPIC")
	)
	(segment
		(start 283.083 -68.017136)
		(end 284.861 -66.239136)
		(width 0.1143)
		(layer "F.Cu")
		(net "PRSNT_EN_HPIC")
	)
	(segment
		(start 281.423872 -65.223136)
		(end 280.488136 -65.223136)
		(width 0.1143)
		(layer "F.Cu")
		(net "PRSNT_EN_HPIC")
	)
	(segment
		(start 282.020772 -68.017136)
		(end 283.083 -68.017136)
		(width 0.1143)
		(layer "F.Cu")
		(net "PRSNT_EN_HPIC")
	)
	(segment
		(start 282.897072 -65.223136)
		(end 283.074872 -65.045336)
		(width 0.1143)
		(layer "F.Cu")
		(net "PRSNT_EN_HPIC")
	)
	(segment
		(start 186.95924 -52.07889)
		(end 198.66229 -52.07889)
		(width 0.1143)
		(layer "F.Cu")
		(net "PRSNT_EN_HPIC")
	)
	(segment
		(start 284.48 -65.024)
		(end 284.861 -65.405)
		(width 0.1143)
		(layer "F.Cu")
		(net "PRSNT_EN_HPIC")
	)
	(segment
		(start 279.019 -60.325)
		(end 275.463 -56.769)
		(width 0.1143)
		(layer "F.Cu")
		(net "PRSNT_EN_HPIC")
	)
	(segment
		(start 283.074872 -65.045336)
		(end 283.096208 -65.024)
		(width 0.1143)
		(layer "F.Cu")
		(net "PRSNT_EN_HPIC")
	)
	(segment
		(start 283.096208 -65.024)
		(end 284.48 -65.024)
		(width 0.1143)
		(layer "F.Cu")
		(net "PRSNT_EN_HPIC")
	)
	(segment
		(start 284.861 -66.239136)
		(end 284.861 -65.405)
		(width 0.1143)
		(layer "F.Cu")
		(net "PRSNT_EN_HPIC")
	)
	(segment
		(start 279.019 -63.754)
		(end 279.019 -60.325)
		(width 0.1143)
		(layer "F.Cu")
		(net "PRSNT_EN_HPIC")
	)
	(segment
		(start 198.66229 -52.07889)
		(end 207.772 -61.1886)
		(width 0.1143)
		(layer "F.Cu")
		(net "PRSNT_EN_HPIC")
	)
	(segment
		(start 280.488136 -65.223136)
		(end 279.019 -63.754)
		(width 0.1143)
		(layer "F.Cu")
		(net "PRSNT_EN_HPIC")
	)
	(via
		(at 284.861 -65.405)
		(size 0.7112)
		(drill 0.3556)
		(layers "F.Cu" "B.Cu")
		(net "PRSNT_EN_HPIC")
	)
	(via
		(at 207.772 -61.1886)
		(size 0.5588)
		(drill 0.3048)
		(layers "F.Cu" "B.Cu")
		(net "PRSNT_EN_HPIC")
	)
	(via
		(at 275.463 -56.769)
		(size 0.508)
		(drill 0.254)
		(layers "F.Cu" "B.Cu")
		(net "PRSNT_EN_HPIC")
	)
	(segment
		(start 216.662 -56.261)
		(end 265.383772 -56.261)
		(width 0.1143)
		(layer "B.Cu")
		(net "PRSNT_EN_HPIC")
	)
	(segment
		(start 265.383772 -56.261)
		(end 267.625322 -54.01945)
		(width 0.1143)
		(layer "B.Cu")
		(net "PRSNT_EN_HPIC")
	)
	(segment
		(start 267.625322 -54.01945)
		(end 268.39545 -54.01945)
		(width 0.1143)
		(layer "B.Cu")
		(net "PRSNT_EN_HPIC")
	)
	(segment
		(start 208.01965 -61.43625)
		(end 211.48675 -61.43625)
		(width 0.1143)
		(layer "B.Cu")
		(net "PRSNT_EN_HPIC")
	)
	(segment
		(start 207.772 -61.1886)
		(end 208.01965 -61.43625)
		(width 0.1143)
		(layer "B.Cu")
		(net "PRSNT_EN_HPIC")
	)
	(segment
		(start 268.39545 -54.01945)
		(end 271.145 -56.769)
		(width 0.1143)
		(layer "B.Cu")
		(net "PRSNT_EN_HPIC")
	)
	(segment
		(start 271.145 -56.769)
		(end 275.463 -56.769)
		(width 0.1143)
		(layer "B.Cu")
		(net "PRSNT_EN_HPIC")
	)
	(segment
		(start 211.48675 -61.43625)
		(end 216.662 -56.261)
		(width 0.1143)
		(layer "B.Cu")
		(net "PRSNT_EN_HPIC")
	)
	(segment
		(start 286.999426 -68.680076)
		(end 287.107122 -68.787772)
		(width 0.1143)
		(layer "F.Cu")
		(net "VR_HSC_GATE_MSB")
	)
	(segment
		(start 286.160972 -68.517516)
		(end 286.830516 -68.517516)
		(width 0.1143)
		(layer "F.Cu")
		(net "VR_HSC_GATE_MSB")
	)
	(segment
		(start 286.993076 -68.680076)
		(end 286.999426 -68.680076)
		(width 0.1143)
		(layer "F.Cu")
		(net "VR_HSC_GATE_MSB")
	)
	(segment
		(start 287.107122 -68.787772)
		(end 287.107122 -68.794122)
		(width 0.1143)
		(layer "F.Cu")
		(net "VR_HSC_GATE_MSB")
	)
	(segment
		(start 287.528 -71.065136)
		(end 288.163 -71.700136)
		(width 0.1143)
		(layer "F.Cu")
		(net "VR_HSC_GATE_MSB")
	)
	(segment
		(start 287.528 -69.215)
		(end 287.528 -71.065136)
		(width 0.1143)
		(layer "F.Cu")
		(net "VR_HSC_GATE_MSB")
	)
	(segment
		(start 289.234372 -71.700136)
		(end 288.163 -71.700136)
		(width 0.1143)
		(layer "F.Cu")
		(net "VR_HSC_GATE_MSB")
	)
	(segment
		(start 287.107122 -68.794122)
		(end 287.528 -69.215)
		(width 0.1143)
		(layer "F.Cu")
		(net "VR_HSC_GATE_MSB")
	)
	(segment
		(start 286.830516 -68.517516)
		(end 286.993076 -68.680076)
		(width 0.1143)
		(layer "F.Cu")
		(net "VR_HSC_GATE_MSB")
	)
	(segment
		(start 289.234372 -72.716136)
		(end 289.234372 -71.700136)
		(width 0.1143)
		(layer "F.Cu")
		(net "VR_HSC_GATE_MSB")
	)
	(via
		(at 288.163 -71.700136)
		(size 0.7112)
		(drill 0.3556)
		(layers "F.Cu" "B.Cu")
		(net "VR_HSC_GATE_MSB")
	)
	(segment
		(start 290.123372 -72.716136)
		(end 290.122864 -72.716644)
		(width 0.1143)
		(layer "F.Cu")
		(net "VR_HSC_GATE_R_MSB")
	)
	(segment
		(start 290.122864 -72.716644)
		(end 290.122864 -73.795636)
		(width 0.1143)
		(layer "F.Cu")
		(net "VR_HSC_GATE_R_MSB")
	)
	(segment
		(start 290.122864 -73.795636)
		(end 289.814 -74.1045)
		(width 0.1143)
		(layer "F.Cu")
		(net "VR_HSC_GATE_R_MSB")
	)
	(segment
		(start 289.814 -74.168)
		(end 289.1409 -74.8411)
		(width 0.1143)
		(layer "F.Cu")
		(net "VR_HSC_GATE_R_MSB")
	)
	(segment
		(start 265.43 -66.04)
		(end 265.43 -67.7164)
		(width 0.1143)
		(layer "F.Cu")
		(net "VR_HSC_GATE_R_MSB")
	)
	(segment
		(start 289.1409 -74.8411)
		(end 288.6583 -74.8411)
		(width 0.1143)
		(layer "F.Cu")
		(net "VR_HSC_GATE_R_MSB")
	)
	(segment
		(start 289.814 -74.1045)
		(end 289.814 -74.168)
		(width 0.1143)
		(layer "F.Cu")
		(net "VR_HSC_GATE_R_MSB")
	)
	(via
		(at 288.6583 -74.8411)
		(size 0.5588)
		(drill 0.3048)
		(layers "F.Cu" "B.Cu")
		(net "VR_HSC_GATE_R_MSB")
	)
	(via
		(at 289.814 -74.1045)
		(size 0.7112)
		(drill 0.3556)
		(layers "F.Cu" "B.Cu")
		(net "VR_HSC_GATE_R_MSB")
	)
	(via
		(at 265.43 -67.7164)
		(size 0.508)
		(drill 0.254)
		(layers "F.Cu" "B.Cu")
		(net "VR_HSC_GATE_R_MSB")
	)
	(segment
		(start 278.765 -68.072)
		(end 285.5341 -74.8411)
		(width 0.1143)
		(layer "B.Cu")
		(net "VR_HSC_GATE_R_MSB")
	)
	(segment
		(start 265.43 -67.7164)
		(end 265.7856 -68.072)
		(width 0.1143)
		(layer "B.Cu")
		(net "VR_HSC_GATE_R_MSB")
	)
	(segment
		(start 265.7856 -68.072)
		(end 278.765 -68.072)
		(width 0.1143)
		(layer "B.Cu")
		(net "VR_HSC_GATE_R_MSB")
	)
	(segment
		(start 285.5341 -74.8411)
		(end 288.6583 -74.8411)
		(width 0.1143)
		(layer "B.Cu")
		(net "VR_HSC_GATE_R_MSB")
	)
	(segment
		(start 191.5668 -56.9468)
		(end 185.43524 -56.9468)
		(width 0.1143)
		(layer "F.Cu")
		(net "PRSNT_MSB_A1")
	)
	(segment
		(start 181.737 -45.9105)
		(end 184.339992 -45.9105)
		(width 0.1143)
		(layer "F.Cu")
		(net "PRSNT_MSB_A1")
	)
	(segment
		(start 181.2925 -46.355)
		(end 181.737 -45.9105)
		(width 0.1143)
		(layer "F.Cu")
		(net "PRSNT_MSB_A1")
	)
	(segment
		(start 198.12 -63.5)
		(end 191.5668 -56.9468)
		(width 0.1143)
		(layer "F.Cu")
		(net "PRSNT_MSB_A1")
	)
	(segment
		(start 185.43524 -56.9468)
		(end 181.2925 -52.80406)
		(width 0.1143)
		(layer "F.Cu")
		(net "PRSNT_MSB_A1")
	)
	(segment
		(start 188.943742 -45.6565)
		(end 188.139832 -44.85259)
		(width 0.1143)
		(layer "F.Cu")
		(net "PRSNT_MSB_A1")
	)
	(segment
		(start 184.699402 -44.85259)
		(end 184.339992 -45.212)
		(width 0.1143)
		(layer "F.Cu")
		(net "PRSNT_MSB_A1")
	)
	(segment
		(start 184.339992 -45.212)
		(end 184.339992 -45.9105)
		(width 0.1143)
		(layer "F.Cu")
		(net "PRSNT_MSB_A1")
	)
	(segment
		(start 188.139832 -44.85259)
		(end 184.699402 -44.85259)
		(width 0.1143)
		(layer "F.Cu")
		(net "PRSNT_MSB_A1")
	)
	(segment
		(start 181.2925 -52.80406)
		(end 181.2925 -46.355)
		(width 0.1143)
		(layer "F.Cu")
		(net "PRSNT_MSB_A1")
	)
	(via
		(at 198.12 -63.5)
		(size 0.508)
		(drill 0.254)
		(layers "F.Cu" "B.Cu")
		(net "PRSNT_MSB_A1")
	)
	(segment
		(start 224.6376 -67.831462)
		(end 224.6376 -74.817986)
		(width 0.127)
		(layer "In2.Cu")
		(net "PRSNT_MSB_A1")
	)
	(segment
		(start 198.12 -63.5)
		(end 220.306138 -63.5)
		(width 0.127)
		(layer "In2.Cu")
		(net "PRSNT_MSB_A1")
	)
	(segment
		(start 220.306138 -63.5)
		(end 224.6376 -67.831462)
		(width 0.127)
		(layer "In2.Cu")
		(net "PRSNT_MSB_A1")
	)
	(segment
		(start 223.705166 -75.75042)
		(end 221.449646 -75.75042)
		(width 0.127)
		(layer "In2.Cu")
		(net "PRSNT_MSB_A1")
	)
	(segment
		(start 224.6376 -74.817986)
		(end 223.705166 -75.75042)
		(width 0.127)
		(layer "In2.Cu")
		(net "PRSNT_MSB_A1")
	)
	(segment
		(start 186.689492 -48.640492)
		(end 186.689492 -48.133)
		(width 0.1143)
		(layer "F.Cu")
		(net "PRSNT_MSB_AND_1")
	)
	(segment
		(start 189.927992 -47.625)
		(end 189.927992 -47.5615)
		(width 0.1143)
		(layer "F.Cu")
		(net "PRSNT_MSB_AND_1")
	)
	(segment
		(start 187.641992 -48.133)
		(end 189.419992 -48.133)
		(width 0.1143)
		(layer "F.Cu")
		(net "PRSNT_MSB_AND_1")
	)
	(segment
		(start 186.95924 -50.02911)
		(end 186.95924 -48.91024)
		(width 0.1143)
		(layer "F.Cu")
		(net "PRSNT_MSB_AND_1")
	)
	(segment
		(start 187.641992 -48.133)
		(end 186.689492 -48.133)
		(width 0.1143)
		(layer "F.Cu")
		(net "PRSNT_MSB_AND_1")
	)
	(segment
		(start 193.539364 -46.681136)
		(end 190.808356 -46.681136)
		(width 0.1143)
		(layer "F.Cu")
		(net "PRSNT_MSB_AND_1")
	)
	(segment
		(start 186.95924 -48.91024)
		(end 186.689492 -48.640492)
		(width 0.1143)
		(layer "F.Cu")
		(net "PRSNT_MSB_AND_1")
	)
	(segment
		(start 190.808356 -46.681136)
		(end 189.927992 -47.5615)
		(width 0.1143)
		(layer "F.Cu")
		(net "PRSNT_MSB_AND_1")
	)
	(segment
		(start 189.419992 -48.133)
		(end 189.927992 -47.625)
		(width 0.1143)
		(layer "F.Cu")
		(net "PRSNT_MSB_AND_1")
	)
	(via
		(at 187.641992 -48.133)
		(size 0.7112)
		(drill 0.3556)
		(layers "F.Cu" "B.Cu")
		(net "PRSNT_MSB_AND_1")
	)
	(segment
		(start 282.151582 -168.486582)
		(end 276.73935 -163.07435)
		(width 0.1143)
		(layer "F.Cu")
		(net "PRSNT_CONTROL_BMC")
	)
	(segment
		(start 270.891 -157.861)
		(end 267.081 -154.051)
		(width 0.1143)
		(layer "F.Cu")
		(net "PRSNT_CONTROL_BMC")
	)
	(segment
		(start 222.898208 -60.325)
		(end 256.6924 -94.119192)
		(width 0.1143)
		(layer "F.Cu")
		(net "PRSNT_CONTROL_BMC")
	)
	(segment
		(start 181.9148 -50.9397)
		(end 181.9148 -52.563268)
		(width 0.1143)
		(layer "F.Cu")
		(net "PRSNT_CONTROL_BMC")
	)
	(segment
		(start 270.891 -161.77387)
		(end 270.891 -157.861)
		(width 0.1143)
		(layer "F.Cu")
		(net "PRSNT_CONTROL_BMC")
	)
	(segment
		(start 262.6995 -101.5365)
		(end 262.82015 -101.65715)
		(width 0.1143)
		(layer "F.Cu")
		(net "PRSNT_CONTROL_BMC")
	)
	(segment
		(start 196.764402 -56.134)
		(end 200.533 -59.902598)
		(width 0.1143)
		(layer "F.Cu")
		(net "PRSNT_CONTROL_BMC")
	)
	(segment
		(start 221.0054 -60.325)
		(end 222.898208 -60.325)
		(width 0.1143)
		(layer "F.Cu")
		(net "PRSNT_CONTROL_BMC")
	)
	(segment
		(start 256.6924 -94.119192)
		(end 256.6924 -95.518986)
		(width 0.1143)
		(layer "F.Cu")
		(net "PRSNT_CONTROL_BMC")
	)
	(segment
		(start 181.9148 -52.563268)
		(end 185.485532 -56.134)
		(width 0.1143)
		(layer "F.Cu")
		(net "PRSNT_CONTROL_BMC")
	)
	(segment
		(start 285.197042 -168.602152)
		(end 283.744162 -168.602152)
		(width 0.1143)
		(layer "F.Cu")
		(net "PRSNT_CONTROL_BMC")
	)
	(segment
		(start 263.8171 -143.794988)
		(end 267.081 -147.058888)
		(width 0.1143)
		(layer "F.Cu")
		(net "PRSNT_CONTROL_BMC")
	)
	(segment
		(start 262.82015 -121.26595)
		(end 263.8171 -122.2629)
		(width 0.1143)
		(layer "F.Cu")
		(net "PRSNT_CONTROL_BMC")
	)
	(segment
		(start 267.081 -154.051)
		(end 267.081 -152.654)
		(width 0.1143)
		(layer "F.Cu")
		(net "PRSNT_CONTROL_BMC")
	)
	(segment
		(start 263.8171 -122.2629)
		(end 263.8171 -143.794988)
		(width 0.1143)
		(layer "F.Cu")
		(net "PRSNT_CONTROL_BMC")
	)
	(segment
		(start 267.081 -147.058888)
		(end 267.081 -152.654)
		(width 0.1143)
		(layer "F.Cu")
		(net "PRSNT_CONTROL_BMC")
	)
	(segment
		(start 262.6995 -101.526086)
		(end 262.6995 -101.5365)
		(width 0.1143)
		(layer "F.Cu")
		(net "PRSNT_CONTROL_BMC")
	)
	(segment
		(start 272.19148 -163.07435)
		(end 270.891 -161.77387)
		(width 0.1143)
		(layer "F.Cu")
		(net "PRSNT_CONTROL_BMC")
	)
	(segment
		(start 276.73935 -163.07435)
		(end 272.19148 -163.07435)
		(width 0.1143)
		(layer "F.Cu")
		(net "PRSNT_CONTROL_BMC")
	)
	(segment
		(start 262.82015 -101.65715)
		(end 262.82015 -121.26595)
		(width 0.1143)
		(layer "F.Cu")
		(net "PRSNT_CONTROL_BMC")
	)
	(segment
		(start 285.634938 -169.040048)
		(end 285.197042 -168.602152)
		(width 0.1143)
		(layer "F.Cu")
		(net "PRSNT_CONTROL_BMC")
	)
	(segment
		(start 182.6895 -50.165)
		(end 181.9148 -50.9397)
		(width 0.1143)
		(layer "F.Cu")
		(net "PRSNT_CONTROL_BMC")
	)
	(segment
		(start 185.485532 -56.134)
		(end 196.764402 -56.134)
		(width 0.1143)
		(layer "F.Cu")
		(net "PRSNT_CONTROL_BMC")
	)
	(segment
		(start 283.628592 -168.486582)
		(end 282.151582 -168.486582)
		(width 0.1143)
		(layer "F.Cu")
		(net "PRSNT_CONTROL_BMC")
	)
	(segment
		(start 256.6924 -95.518986)
		(end 262.6995 -101.526086)
		(width 0.1143)
		(layer "F.Cu")
		(net "PRSNT_CONTROL_BMC")
	)
	(segment
		(start 283.744162 -168.602152)
		(end 283.628592 -168.486582)
		(width 0.1143)
		(layer "F.Cu")
		(net "PRSNT_CONTROL_BMC")
	)
	(via
		(at 267.081 -152.654)
		(size 0.7112)
		(drill 0.3556)
		(layers "F.Cu" "B.Cu")
		(net "PRSNT_CONTROL_BMC")
	)
	(via
		(at 221.0054 -60.325)
		(size 0.5588)
		(drill 0.3048)
		(layers "F.Cu" "B.Cu")
		(net "PRSNT_CONTROL_BMC")
	)
	(via
		(at 200.533 -59.902598)
		(size 0.5588)
		(drill 0.3048)
		(layers "F.Cu" "B.Cu")
		(net "PRSNT_CONTROL_BMC")
	)
	(segment
		(start 200.872598 -59.563)
		(end 200.533 -59.902598)
		(width 0.127)
		(layer "In2.Cu")
		(net "PRSNT_CONTROL_BMC")
	)
	(segment
		(start 221.0054 -60.325)
		(end 220.2434 -59.563)
		(width 0.127)
		(layer "In2.Cu")
		(net "PRSNT_CONTROL_BMC")
	)
	(segment
		(start 220.2434 -59.563)
		(end 200.872598 -59.563)
		(width 0.127)
		(layer "In2.Cu")
		(net "PRSNT_CONTROL_BMC")
	)
	(segment
		(start 301.49546 -170.303698)
		(end 301.96155 -170.303698)
		(width 0.1143)
		(layer "F.Cu")
		(net "BMC0_SMB7_CLK")
	)
	(segment
		(start 303.4157 -170.2943)
		(end 303.657 -170.053)
		(width 0.1143)
		(layer "F.Cu")
		(net "BMC0_SMB7_CLK")
	)
	(segment
		(start 301.96155 -170.303698)
		(end 301.970948 -170.2943)
		(width 0.1143)
		(layer "F.Cu")
		(net "BMC0_SMB7_CLK")
	)
	(segment
		(start 303.657 -170.053)
		(end 313.4614 -170.053)
		(width 0.1143)
		(layer "F.Cu")
		(net "BMC0_SMB7_CLK")
	)
	(segment
		(start 300.834806 -170.640248)
		(end 301.15891 -170.640248)
		(width 0.1143)
		(layer "F.Cu")
		(net "BMC0_SMB7_CLK")
	)
	(segment
		(start 313.4614 -170.053)
		(end 314.5282 -168.9862)
		(width 0.1143)
		(layer "F.Cu")
		(net "BMC0_SMB7_CLK")
	)
	(segment
		(start 317.0809 -168.9354)
		(end 317.5635 -169.418)
		(width 0.1143)
		(layer "F.Cu")
		(net "BMC0_SMB7_CLK")
	)
	(segment
		(start 316.70117 -168.9354)
		(end 317.0809 -168.9354)
		(width 0.1143)
		(layer "F.Cu")
		(net "BMC0_SMB7_CLK")
	)
	(segment
		(start 301.15891 -170.640248)
		(end 301.49546 -170.303698)
		(width 0.1143)
		(layer "F.Cu")
		(net "BMC0_SMB7_CLK")
	)
	(segment
		(start 315.7728 -168.9354)
		(end 316.70117 -168.9354)
		(width 0.1143)
		(layer "F.Cu")
		(net "BMC0_SMB7_CLK")
	)
	(segment
		(start 314.5282 -168.9862)
		(end 315.722 -168.9862)
		(width 0.1143)
		(layer "F.Cu")
		(net "BMC0_SMB7_CLK")
	)
	(segment
		(start 315.722 -168.9862)
		(end 315.7728 -168.9354)
		(width 0.1143)
		(layer "F.Cu")
		(net "BMC0_SMB7_CLK")
	)
	(segment
		(start 301.970948 -170.2943)
		(end 303.4157 -170.2943)
		(width 0.1143)
		(layer "F.Cu")
		(net "BMC0_SMB7_CLK")
	)
	(via
		(at 316.70117 -168.9354)
		(size 0.7112)
		(drill 0.3556)
		(layers "F.Cu" "B.Cu")
		(net "BMC0_SMB7_CLK")
	)
	(segment
		(start 299.23486 -168.240202)
		(end 299.226986 -168.240202)
		(width 0.1143)
		(layer "F.Cu")
		(net "BMC0_SMB9_DAT")
	)
	(segment
		(start 299.226986 -168.240202)
		(end 298.832524 -168.634664)
		(width 0.1143)
		(layer "F.Cu")
		(net "BMC0_SMB9_DAT")
	)
	(via
		(at 300.482 -166.624)
		(size 0.7112)
		(drill 0.3556)
		(layers "F.Cu" "B.Cu")
		(net "BMC0_SMB9_DAT")
	)
	(via
		(at 298.832524 -168.634664)
		(size 0.508)
		(drill 0.254)
		(layers "F.Cu" "B.Cu")
		(net "BMC0_SMB9_DAT")
	)
	(segment
		(start 305.4985 -163.703)
		(end 303.403 -163.703)
		(width 0.1143)
		(layer "B.Cu")
		(net "BMC0_SMB9_DAT")
	)
	(segment
		(start 300.482 -166.624)
		(end 298.832524 -168.273476)
		(width 0.1143)
		(layer "B.Cu")
		(net "BMC0_SMB9_DAT")
	)
	(segment
		(start 298.832524 -168.273476)
		(end 298.832524 -168.634664)
		(width 0.1143)
		(layer "B.Cu")
		(net "BMC0_SMB9_DAT")
	)
	(segment
		(start 303.403 -163.703)
		(end 300.482 -166.624)
		(width 0.1143)
		(layer "B.Cu")
		(net "BMC0_SMB9_DAT")
	)
	(segment
		(start 308.102 -161.0995)
		(end 305.4985 -163.703)
		(width 0.1143)
		(layer "B.Cu")
		(net "BMC0_SMB9_DAT")
	)
	(segment
		(start 298.43476 -172.240194)
		(end 298.829984 -171.84497)
		(width 0.1143)
		(layer "F.Cu")
		(net "BMC0_SMB8_CLK")
	)
	(segment
		(start 298.829984 -171.84497)
		(end 298.839636 -171.84497)
		(width 0.1143)
		(layer "F.Cu")
		(net "BMC0_SMB8_CLK")
	)
	(via
		(at 316.6618 -171.577)
		(size 0.7112)
		(drill 0.3556)
		(layers "F.Cu" "B.Cu")
		(net "BMC0_SMB8_CLK")
	)
	(via
		(at 298.839636 -171.84497)
		(size 0.508)
		(drill 0.254)
		(layers "F.Cu" "B.Cu")
		(net "BMC0_SMB8_CLK")
	)
	(segment
		(start 317.5635 -171.577)
		(end 316.6618 -171.577)
		(width 0.1143)
		(layer "B.Cu")
		(net "BMC0_SMB8_CLK")
	)
	(segment
		(start 315.23305 -171.08805)
		(end 303.65065 -171.08805)
		(width 0.1143)
		(layer "B.Cu")
		(net "BMC0_SMB8_CLK")
	)
	(segment
		(start 300.864778 -170.835828)
		(end 299.855636 -171.84497)
		(width 0.1143)
		(layer "B.Cu")
		(net "BMC0_SMB8_CLK")
	)
	(segment
		(start 315.722 -171.577)
		(end 315.23305 -171.08805)
		(width 0.1143)
		(layer "B.Cu")
		(net "BMC0_SMB8_CLK")
	)
	(segment
		(start 316.6618 -171.577)
		(end 315.722 -171.577)
		(width 0.1143)
		(layer "B.Cu")
		(net "BMC0_SMB8_CLK")
	)
	(segment
		(start 303.65065 -171.08805)
		(end 303.398428 -170.835828)
		(width 0.1143)
		(layer "B.Cu")
		(net "BMC0_SMB8_CLK")
	)
	(segment
		(start 303.398428 -170.835828)
		(end 300.864778 -170.835828)
		(width 0.1143)
		(layer "B.Cu")
		(net "BMC0_SMB8_CLK")
	)
	(segment
		(start 299.855636 -171.84497)
		(end 298.839636 -171.84497)
		(width 0.1143)
		(layer "B.Cu")
		(net "BMC0_SMB8_CLK")
	)
	(segment
		(start 300.03496 -171.440094)
		(end 300.432978 -171.042076)
		(width 0.1143)
		(layer "F.Cu")
		(net "BMC0_SMB8_DAT")
	)
	(segment
		(start 302.180498 -171.042076)
		(end 302.387 -171.248578)
		(width 0.1143)
		(layer "F.Cu")
		(net "BMC0_SMB8_DAT")
	)
	(segment
		(start 300.432978 -171.042076)
		(end 302.180498 -171.042076)
		(width 0.1143)
		(layer "F.Cu")
		(net "BMC0_SMB8_DAT")
	)
	(via
		(at 315.087 -172.593)
		(size 0.7112)
		(drill 0.3556)
		(layers "F.Cu" "B.Cu")
		(net "BMC0_SMB8_DAT")
	)
	(via
		(at 302.387 -171.248578)
		(size 0.508)
		(drill 0.254)
		(layers "F.Cu" "B.Cu")
		(net "BMC0_SMB8_DAT")
	)
	(segment
		(start 303.173892 -171.248578)
		(end 302.387 -171.248578)
		(width 0.1143)
		(layer "B.Cu")
		(net "BMC0_SMB8_DAT")
	)
	(segment
		(start 303.508664 -171.58335)
		(end 303.173892 -171.248578)
		(width 0.1143)
		(layer "B.Cu")
		(net "BMC0_SMB8_DAT")
	)
	(segment
		(start 315.214 -172.72)
		(end 315.087 -172.593)
		(width 0.1143)
		(layer "B.Cu")
		(net "BMC0_SMB8_DAT")
	)
	(segment
		(start 315.087 -172.593)
		(end 314.833 -172.593)
		(width 0.1143)
		(layer "B.Cu")
		(net "BMC0_SMB8_DAT")
	)
	(segment
		(start 317.5635 -172.593)
		(end 315.214 -172.72)
		(width 0.1143)
		(layer "B.Cu")
		(net "BMC0_SMB8_DAT")
	)
	(segment
		(start 314.30595 -172.06595)
		(end 313.944 -172.06595)
		(width 0.1143)
		(layer "B.Cu")
		(net "BMC0_SMB8_DAT")
	)
	(segment
		(start 313.944 -172.06595)
		(end 313.4614 -171.58335)
		(width 0.1143)
		(layer "B.Cu")
		(net "BMC0_SMB8_DAT")
	)
	(segment
		(start 314.833 -172.593)
		(end 314.30595 -172.06595)
		(width 0.1143)
		(layer "B.Cu")
		(net "BMC0_SMB8_DAT")
	)
	(segment
		(start 313.4614 -171.58335)
		(end 303.508664 -171.58335)
		(width 0.1143)
		(layer "B.Cu")
		(net "BMC0_SMB8_DAT")
	)
	(segment
		(start 316.4205 -167.894)
		(end 315.087 -167.894)
		(width 0.1143)
		(layer "F.Cu")
		(net "BMC0_SMB7_DAT")
	)
	(segment
		(start 303.657 -169.545)
		(end 303.34585 -169.85615)
		(width 0.1143)
		(layer "F.Cu")
		(net "BMC0_SMB7_DAT")
	)
	(segment
		(start 315.087 -167.894)
		(end 314.579 -168.402)
		(width 0.1143)
		(layer "F.Cu")
		(net "BMC0_SMB7_DAT")
	)
	(segment
		(start 312.993532 -169.545)
		(end 303.657 -169.545)
		(width 0.1143)
		(layer "F.Cu")
		(net "BMC0_SMB7_DAT")
	)
	(segment
		(start 301.650908 -169.85615)
		(end 301.634906 -169.840148)
		(width 0.1143)
		(layer "F.Cu")
		(net "BMC0_SMB7_DAT")
	)
	(segment
		(start 314.136532 -168.402)
		(end 312.993532 -169.545)
		(width 0.1143)
		(layer "F.Cu")
		(net "BMC0_SMB7_DAT")
	)
	(segment
		(start 314.579 -168.402)
		(end 314.136532 -168.402)
		(width 0.1143)
		(layer "F.Cu")
		(net "BMC0_SMB7_DAT")
	)
	(segment
		(start 303.34585 -169.85615)
		(end 301.650908 -169.85615)
		(width 0.1143)
		(layer "F.Cu")
		(net "BMC0_SMB7_DAT")
	)
	(via
		(at 314.579 -168.402)
		(size 0.7112)
		(drill 0.3556)
		(layers "F.Cu" "B.Cu")
		(net "BMC0_SMB7_DAT")
	)
	(segment
		(start 298.43476 -169.040048)
		(end 298.034964 -168.640252)
		(width 0.1143)
		(layer "F.Cu")
		(net "BMC0_SMB9_CLK")
	)
	(segment
		(start 298.034964 -168.640252)
		(end 298.026328 -168.640252)
		(width 0.1143)
		(layer "F.Cu")
		(net "BMC0_SMB9_CLK")
	)
	(via
		(at 298.026328 -168.640252)
		(size 0.508)
		(drill 0.254)
		(layers "F.Cu" "B.Cu")
		(net "BMC0_SMB9_CLK")
	)
	(via
		(at 303.911 -162.56)
		(size 0.7112)
		(drill 0.3556)
		(layers "F.Cu" "B.Cu")
		(net "BMC0_SMB9_CLK")
	)
	(segment
		(start 298.026328 -167.409622)
		(end 298.026328 -168.640252)
		(width 0.1143)
		(layer "B.Cu")
		(net "BMC0_SMB9_CLK")
	)
	(segment
		(start 303.911 -162.56)
		(end 303.7078 -162.56)
		(width 0.1143)
		(layer "B.Cu")
		(net "BMC0_SMB9_CLK")
	)
	(segment
		(start 303.7078 -162.56)
		(end 299.2882 -166.9796)
		(width 0.1143)
		(layer "B.Cu")
		(net "BMC0_SMB9_CLK")
	)
	(segment
		(start 305.6255 -162.56)
		(end 303.911 -162.56)
		(width 0.1143)
		(layer "B.Cu")
		(net "BMC0_SMB9_CLK")
	)
	(segment
		(start 299.2882 -166.9796)
		(end 298.45635 -166.9796)
		(width 0.1143)
		(layer "B.Cu")
		(net "BMC0_SMB9_CLK")
	)
	(segment
		(start 298.45635 -166.9796)
		(end 298.026328 -167.409622)
		(width 0.1143)
		(layer "B.Cu")
		(net "BMC0_SMB9_CLK")
	)
	(segment
		(start 307.086 -161.0995)
		(end 305.6255 -162.56)
		(width 0.1143)
		(layer "B.Cu")
		(net "BMC0_SMB9_CLK")
	)
	(segment
		(start 319.3034 -168.7322)
		(end 319.4685 -168.5671)
		(width 0.1143)
		(layer "F.Cu")
		(net "BMC_I2C_B_SDA")
	)
	(segment
		(start 319.4685 -168.5671)
		(end 319.4685 -167.894)
		(width 0.1143)
		(layer "F.Cu")
		(net "BMC_I2C_B_SDA")
	)
	(segment
		(start 181.131972 -204.537056)
		(end 182.566056 -204.537056)
		(width 0.1143)
		(layer "F.Cu")
		(net "BMC_I2C_B_SDA")
	)
	(segment
		(start 319.4685 -167.894)
		(end 318.389 -167.894)
		(width 0.1143)
		(layer "F.Cu")
		(net "BMC_I2C_B_SDA")
	)
	(segment
		(start 182.566056 -204.537056)
		(end 183.388 -205.359)
		(width 0.1143)
		(layer "F.Cu")
		(net "BMC_I2C_B_SDA")
	)
	(segment
		(start 317.3095 -167.894)
		(end 318.389 -167.894)
		(width 0.1143)
		(layer "F.Cu")
		(net "BMC_I2C_B_SDA")
	)
	(via
		(at 319.3034 -168.7322)
		(size 0.5588)
		(drill 0.3048)
		(layers "F.Cu" "B.Cu")
		(net "BMC_I2C_B_SDA")
	)
	(via
		(at 318.389 -167.894)
		(size 0.7112)
		(drill 0.3556)
		(layers "F.Cu" "B.Cu")
		(net "BMC_I2C_B_SDA")
	)
	(via
		(at 183.388 -205.359)
		(size 0.5588)
		(drill 0.3048)
		(layers "F.Cu" "B.Cu")
		(net "BMC_I2C_B_SDA")
	)
	(via
		(at 333.0194 -166.7256)
		(size 0.5588)
		(drill 0.3048)
		(layers "F.Cu" "B.Cu")
		(net "BMC_I2C_B_SDA")
	)
	(segment
		(start 327.955148 -187.791852)
		(end 332.486 -183.261)
		(width 0.127)
		(layer "In2.Cu")
		(net "BMC_I2C_B_SDA")
	)
	(segment
		(start 258.148328 -231.033574)
		(end 258.148328 -233.514646)
		(width 0.127)
		(layer "In2.Cu")
		(net "BMC_I2C_B_SDA")
	)
	(segment
		(start 215.199468 -204.597)
		(end 231.455468 -188.341)
		(width 0.127)
		(layer "In2.Cu")
		(net "BMC_I2C_B_SDA")
	)
	(segment
		(start 332.486 -170.761152)
		(end 333.35595 -169.891202)
		(width 0.127)
		(layer "In2.Cu")
		(net "BMC_I2C_B_SDA")
	)
	(segment
		(start 183.388 -205.3463)
		(end 184.1373 -204.597)
		(width 0.127)
		(layer "In2.Cu")
		(net "BMC_I2C_B_SDA")
	)
	(segment
		(start 333.35595 -169.891202)
		(end 333.35595 -167.06215)
		(width 0.127)
		(layer "In2.Cu")
		(net "BMC_I2C_B_SDA")
	)
	(segment
		(start 258.148328 -233.514646)
		(end 263.355582 -238.7219)
		(width 0.127)
		(layer "In2.Cu")
		(net "BMC_I2C_B_SDA")
	)
	(segment
		(start 263.355582 -238.7219)
		(end 294.573198 -238.7219)
		(width 0.127)
		(layer "In2.Cu")
		(net "BMC_I2C_B_SDA")
	)
	(segment
		(start 258.3561 -194.242436)
		(end 258.3561 -230.825802)
		(width 0.127)
		(layer "In2.Cu")
		(net "BMC_I2C_B_SDA")
	)
	(segment
		(start 252.454664 -188.341)
		(end 258.3561 -194.242436)
		(width 0.127)
		(layer "In2.Cu")
		(net "BMC_I2C_B_SDA")
	)
	(segment
		(start 258.3561 -230.825802)
		(end 258.148328 -231.033574)
		(width 0.127)
		(layer "In2.Cu")
		(net "BMC_I2C_B_SDA")
	)
	(segment
		(start 183.388 -205.359)
		(end 183.388 -205.3463)
		(width 0.127)
		(layer "In2.Cu")
		(net "BMC_I2C_B_SDA")
	)
	(segment
		(start 327.955148 -205.33995)
		(end 327.955148 -187.791852)
		(width 0.127)
		(layer "In2.Cu")
		(net "BMC_I2C_B_SDA")
	)
	(segment
		(start 333.35595 -167.06215)
		(end 333.0194 -166.7256)
		(width 0.127)
		(layer "In2.Cu")
		(net "BMC_I2C_B_SDA")
	)
	(segment
		(start 231.455468 -188.341)
		(end 252.454664 -188.341)
		(width 0.127)
		(layer "In2.Cu")
		(net "BMC_I2C_B_SDA")
	)
	(segment
		(start 184.1373 -204.597)
		(end 215.199468 -204.597)
		(width 0.127)
		(layer "In2.Cu")
		(net "BMC_I2C_B_SDA")
	)
	(segment
		(start 294.573198 -238.7219)
		(end 327.955148 -205.33995)
		(width 0.127)
		(layer "In2.Cu")
		(net "BMC_I2C_B_SDA")
	)
	(segment
		(start 332.486 -183.261)
		(end 332.486 -170.761152)
		(width 0.127)
		(layer "In2.Cu")
		(net "BMC_I2C_B_SDA")
	)
	(segment
		(start 325.647304 -168.58742)
		(end 326.086724 -168.148)
		(width 0.127)
		(layer "In5.Cu")
		(net "BMC_I2C_B_SDA")
	)
	(segment
		(start 321.759834 -168.148)
		(end 324.79742 -168.148)
		(width 0.127)
		(layer "In5.Cu")
		(net "BMC_I2C_B_SDA")
	)
	(segment
		(start 332.7146 -167.0304)
		(end 333.0194 -166.7256)
		(width 0.127)
		(layer "In5.Cu")
		(net "BMC_I2C_B_SDA")
	)
	(segment
		(start 327.9394 -167.0304)
		(end 332.7146 -167.0304)
		(width 0.127)
		(layer "In5.Cu")
		(net "BMC_I2C_B_SDA")
	)
	(segment
		(start 319.3034 -168.7322)
		(end 321.175634 -168.7322)
		(width 0.127)
		(layer "In5.Cu")
		(net "BMC_I2C_B_SDA")
	)
	(segment
		(start 321.175634 -168.7322)
		(end 321.759834 -168.148)
		(width 0.127)
		(layer "In5.Cu")
		(net "BMC_I2C_B_SDA")
	)
	(segment
		(start 326.8218 -168.148)
		(end 327.9394 -167.0304)
		(width 0.127)
		(layer "In5.Cu")
		(net "BMC_I2C_B_SDA")
	)
	(segment
		(start 324.79742 -168.148)
		(end 325.23684 -168.58742)
		(width 0.127)
		(layer "In5.Cu")
		(net "BMC_I2C_B_SDA")
	)
	(segment
		(start 326.086724 -168.148)
		(end 326.8218 -168.148)
		(width 0.127)
		(layer "In5.Cu")
		(net "BMC_I2C_B_SDA")
	)
	(segment
		(start 325.23684 -168.58742)
		(end 325.647304 -168.58742)
		(width 0.127)
		(layer "In5.Cu")
		(net "BMC_I2C_B_SDA")
	)
	(segment
		(start 319.99555 -165.81755)
		(end 320.701162 -165.81755)
		(width 0.1143)
		(layer "F.Cu")
		(net "BMC_I2C_C_SCL")
	)
	(segment
		(start 320.77025 -165.748462)
		(end 321.423538 -165.748462)
		(width 0.1143)
		(layer "F.Cu")
		(net "BMC_I2C_C_SCL")
	)
	(segment
		(start 320.701162 -165.81755)
		(end 320.77025 -165.748462)
		(width 0.1143)
		(layer "F.Cu")
		(net "BMC_I2C_C_SCL")
	)
	(segment
		(start 172.085 -196.469)
		(end 172.212 -196.596)
		(width 0.1143)
		(layer "F.Cu")
		(net "BMC_I2C_C_SCL")
	)
	(segment
		(start 173.784514 -196.388736)
		(end 174.343314 -195.829936)
		(width 0.1143)
		(layer "F.Cu")
		(net "BMC_I2C_C_SCL")
	)
	(segment
		(start 175.053752 -195.520056)
		(end 177.499772 -195.520056)
		(width 0.1143)
		(layer "F.Cu")
		(net "BMC_I2C_C_SCL")
	)
	(segment
		(start 174.343314 -195.829936)
		(end 174.743872 -195.829936)
		(width 0.1143)
		(layer "F.Cu")
		(net "BMC_I2C_C_SCL")
	)
	(segment
		(start 318.4525 -165.354)
		(end 319.4685 -165.354)
		(width 0.1143)
		(layer "F.Cu")
		(net "BMC_I2C_C_SCL")
	)
	(segment
		(start 173.406308 -196.596)
		(end 173.473872 -196.528436)
		(width 0.1143)
		(layer "F.Cu")
		(net "BMC_I2C_C_SCL")
	)
	(segment
		(start 173.473872 -196.528436)
		(end 173.613572 -196.388736)
		(width 0.1143)
		(layer "F.Cu")
		(net "BMC_I2C_C_SCL")
	)
	(segment
		(start 172.212 -196.596)
		(end 173.406308 -196.596)
		(width 0.1143)
		(layer "F.Cu")
		(net "BMC_I2C_C_SCL")
	)
	(segment
		(start 319.532 -165.354)
		(end 319.99555 -165.81755)
		(width 0.1143)
		(layer "F.Cu")
		(net "BMC_I2C_C_SCL")
	)
	(segment
		(start 180.66385 -147.12315)
		(end 180.234336 -147.12315)
		(width 0.1143)
		(layer "F.Cu")
		(net "BMC_I2C_C_SCL")
	)
	(segment
		(start 173.954186 -153.4033)
		(end 173.482 -153.4033)
		(width 0.1143)
		(layer "F.Cu")
		(net "BMC_I2C_C_SCL")
	)
	(segment
		(start 182.006748 -146.431)
		(end 181.1655 -146.431)
		(width 0.1143)
		(layer "F.Cu")
		(net "BMC_I2C_C_SCL")
	)
	(segment
		(start 182.458868 -146.88312)
		(end 182.006748 -146.431)
		(width 0.1143)
		(layer "F.Cu")
		(net "BMC_I2C_C_SCL")
	)
	(segment
		(start 180.234336 -147.12315)
		(end 173.954186 -153.4033)
		(width 0.1143)
		(layer "F.Cu")
		(net "BMC_I2C_C_SCL")
	)
	(segment
		(start 319.4685 -165.354)
		(end 319.532 -165.354)
		(width 0.1143)
		(layer "F.Cu")
		(net "BMC_I2C_C_SCL")
	)
	(segment
		(start 173.613572 -196.388736)
		(end 173.784514 -196.388736)
		(width 0.1143)
		(layer "F.Cu")
		(net "BMC_I2C_C_SCL")
	)
	(segment
		(start 181.1655 -146.6215)
		(end 180.66385 -147.12315)
		(width 0.1143)
		(layer "F.Cu")
		(net "BMC_I2C_C_SCL")
	)
	(segment
		(start 174.743872 -195.829936)
		(end 175.053752 -195.520056)
		(width 0.1143)
		(layer "F.Cu")
		(net "BMC_I2C_C_SCL")
	)
	(segment
		(start 321.423538 -165.748462)
		(end 321.437 -165.735)
		(width 0.1143)
		(layer "F.Cu")
		(net "BMC_I2C_C_SCL")
	)
	(segment
		(start 181.1655 -146.431)
		(end 181.1655 -146.6215)
		(width 0.1143)
		(layer "F.Cu")
		(net "BMC_I2C_C_SCL")
	)
	(segment
		(start 183.7944 -146.88312)
		(end 182.458868 -146.88312)
		(width 0.1143)
		(layer "F.Cu")
		(net "BMC_I2C_C_SCL")
	)
	(via
		(at 321.437 -165.735)
		(size 0.5588)
		(drill 0.3048)
		(layers "F.Cu" "B.Cu")
		(net "BMC_I2C_C_SCL")
	)
	(via
		(at 293.1414 -137.0584)
		(size 0.7112)
		(drill 0.3556)
		(layers "F.Cu" "B.Cu")
		(net "BMC_I2C_C_SCL")
	)
	(via
		(at 307.34 -136.3472)
		(size 0.5588)
		(drill 0.3048)
		(layers "F.Cu" "B.Cu")
		(net "BMC_I2C_C_SCL")
	)
	(via
		(at 291.465 -137.668)
		(size 0.5588)
		(drill 0.3048)
		(layers "F.Cu" "B.Cu")
		(net "BMC_I2C_C_SCL")
	)
	(via
		(at 173.482 -153.4033)
		(size 0.5588)
		(drill 0.3048)
		(layers "F.Cu" "B.Cu")
		(net "BMC_I2C_C_SCL")
	)
	(via
		(at 172.085 -196.469)
		(size 0.5588)
		(drill 0.3048)
		(layers "F.Cu" "B.Cu")
		(net "BMC_I2C_C_SCL")
	)
	(segment
		(start 172.35805 -191.111886)
		(end 172.35805 -196.19595)
		(width 0.1143)
		(layer "B.Cu")
		(net "BMC_I2C_C_SCL")
	)
	(segment
		(start 293.1414 -137.0584)
		(end 292.5318 -137.668)
		(width 0.1143)
		(layer "B.Cu")
		(net "BMC_I2C_C_SCL")
	)
	(segment
		(start 173.71695 -153.63825)
		(end 173.71695 -189.752986)
		(width 0.1143)
		(layer "B.Cu")
		(net "BMC_I2C_C_SCL")
	)
	(segment
		(start 307.34 -136.3472)
		(end 306.7812 -136.906)
		(width 0.1143)
		(layer "B.Cu")
		(net "BMC_I2C_C_SCL")
	)
	(segment
		(start 293.2938 -136.906)
		(end 293.1414 -137.0584)
		(width 0.1143)
		(layer "B.Cu")
		(net "BMC_I2C_C_SCL")
	)
	(segment
		(start 292.5318 -137.668)
		(end 291.465 -137.668)
		(width 0.1143)
		(layer "B.Cu")
		(net "BMC_I2C_C_SCL")
	)
	(segment
		(start 173.482 -153.4033)
		(end 173.71695 -153.63825)
		(width 0.1143)
		(layer "B.Cu")
		(net "BMC_I2C_C_SCL")
	)
	(segment
		(start 173.71695 -189.752986)
		(end 172.35805 -191.111886)
		(width 0.1143)
		(layer "B.Cu")
		(net "BMC_I2C_C_SCL")
	)
	(segment
		(start 172.35805 -196.19595)
		(end 172.085 -196.469)
		(width 0.1143)
		(layer "B.Cu")
		(net "BMC_I2C_C_SCL")
	)
	(segment
		(start 306.7812 -136.906)
		(end 293.2938 -136.906)
		(width 0.1143)
		(layer "B.Cu")
		(net "BMC_I2C_C_SCL")
	)
	(segment
		(start 312.293 -139.192)
		(end 315.499242 -142.398242)
		(width 0.127)
		(layer "In2.Cu")
		(net "BMC_I2C_C_SCL")
	)
	(segment
		(start 307.3908 -136.3472)
		(end 308.5973 -135.1407)
		(width 0.127)
		(layer "In2.Cu")
		(net "BMC_I2C_C_SCL")
	)
	(segment
		(start 286.809434 -137.16)
		(end 290.957 -137.16)
		(width 0.127)
		(layer "In2.Cu")
		(net "BMC_I2C_C_SCL")
	)
	(segment
		(start 268.7193 -153.621232)
		(end 268.7193 -153.032968)
		(width 0.127)
		(layer "In2.Cu")
		(net "BMC_I2C_C_SCL")
	)
	(segment
		(start 315.499242 -142.398242)
		(end 315.499242 -150.399242)
		(width 0.127)
		(layer "In2.Cu")
		(net "BMC_I2C_C_SCL")
	)
	(segment
		(start 319.9003 -154.8003)
		(end 319.9003 -164.474398)
		(width 0.127)
		(layer "In2.Cu")
		(net "BMC_I2C_C_SCL")
	)
	(segment
		(start 319.9003 -164.474398)
		(end 320.906902 -165.481)
		(width 0.127)
		(layer "In2.Cu")
		(net "BMC_I2C_C_SCL")
	)
	(segment
		(start 236.431582 -153.4033)
		(end 236.939582 -153.9113)
		(width 0.127)
		(layer "In2.Cu")
		(net "BMC_I2C_C_SCL")
	)
	(segment
		(start 315.499242 -150.399242)
		(end 319.9003 -154.8003)
		(width 0.127)
		(layer "In2.Cu")
		(net "BMC_I2C_C_SCL")
	)
	(segment
		(start 236.939582 -153.9113)
		(end 268.429232 -153.9113)
		(width 0.127)
		(layer "In2.Cu")
		(net "BMC_I2C_C_SCL")
	)
	(segment
		(start 290.957 -137.16)
		(end 291.465 -137.668)
		(width 0.127)
		(layer "In2.Cu")
		(net "BMC_I2C_C_SCL")
	)
	(segment
		(start 307.34 -136.3472)
		(end 307.3908 -136.3472)
		(width 0.127)
		(layer "In2.Cu")
		(net "BMC_I2C_C_SCL")
	)
	(segment
		(start 321.183 -165.481)
		(end 321.437 -165.735)
		(width 0.127)
		(layer "In2.Cu")
		(net "BMC_I2C_C_SCL")
	)
	(segment
		(start 308.5973 -135.1407)
		(end 311.063132 -135.1407)
		(width 0.127)
		(layer "In2.Cu")
		(net "BMC_I2C_C_SCL")
	)
	(segment
		(start 311.063132 -135.1407)
		(end 312.293 -136.370568)
		(width 0.127)
		(layer "In2.Cu")
		(net "BMC_I2C_C_SCL")
	)
	(segment
		(start 268.429232 -153.9113)
		(end 268.7193 -153.621232)
		(width 0.127)
		(layer "In2.Cu")
		(net "BMC_I2C_C_SCL")
	)
	(segment
		(start 320.906902 -165.481)
		(end 321.183 -165.481)
		(width 0.127)
		(layer "In2.Cu")
		(net "BMC_I2C_C_SCL")
	)
	(segment
		(start 268.7193 -153.032968)
		(end 269.542768 -152.2095)
		(width 0.127)
		(layer "In2.Cu")
		(net "BMC_I2C_C_SCL")
	)
	(segment
		(start 271.759934 -152.2095)
		(end 286.809434 -137.16)
		(width 0.127)
		(layer "In2.Cu")
		(net "BMC_I2C_C_SCL")
	)
	(segment
		(start 173.482 -153.4033)
		(end 236.431582 -153.4033)
		(width 0.127)
		(layer "In2.Cu")
		(net "BMC_I2C_C_SCL")
	)
	(segment
		(start 312.293 -136.370568)
		(end 312.293 -139.192)
		(width 0.127)
		(layer "In2.Cu")
		(net "BMC_I2C_C_SCL")
	)
	(segment
		(start 269.542768 -152.2095)
		(end 271.759934 -152.2095)
		(width 0.127)
		(layer "In2.Cu")
		(net "BMC_I2C_C_SCL")
	)
	(segment
		(start 319.532 -166.878)
		(end 320.09715 -166.31285)
		(width 0.1143)
		(layer "F.Cu")
		(net "BMC_I2C_C_SDA")
	)
	(segment
		(start 181.46014 -147.53336)
		(end 181.1655 -147.828)
		(width 0.1143)
		(layer "F.Cu")
		(net "BMC_I2C_C_SDA")
	)
	(segment
		(start 181.1655 -148.9075)
		(end 176.149 -153.924)
		(width 0.1143)
		(layer "F.Cu")
		(net "BMC_I2C_C_SDA")
	)
	(segment
		(start 320.906394 -166.31285)
		(end 320.970402 -166.248842)
		(width 0.1143)
		(layer "F.Cu")
		(net "BMC_I2C_C_SDA")
	)
	(segment
		(start 318.4525 -166.878)
		(end 319.4685 -166.878)
		(width 0.1143)
		(layer "F.Cu")
		(net "BMC_I2C_C_SDA")
	)
	(segment
		(start 186.817 -196.083936)
		(end 186.817 -195.977764)
		(width 0.1143)
		(layer "F.Cu")
		(net "BMC_I2C_C_SDA")
	)
	(segment
		(start 186.817 -195.977764)
		(end 186.110372 -195.271136)
		(width 0.1143)
		(layer "F.Cu")
		(net "BMC_I2C_C_SDA")
	)
	(segment
		(start 186.110372 -195.271136)
		(end 186.059572 -195.321936)
		(width 0.1143)
		(layer "F.Cu")
		(net "BMC_I2C_C_SDA")
	)
	(segment
		(start 183.7944 -147.53336)
		(end 181.46014 -147.53336)
		(width 0.1143)
		(layer "F.Cu")
		(net "BMC_I2C_C_SDA")
	)
	(segment
		(start 320.970402 -166.248842)
		(end 322.049394 -166.248842)
		(width 0.1143)
		(layer "F.Cu")
		(net "BMC_I2C_C_SDA")
	)
	(segment
		(start 184.705752 -195.520056)
		(end 181.639972 -195.520056)
		(width 0.1143)
		(layer "F.Cu")
		(net "BMC_I2C_C_SDA")
	)
	(segment
		(start 322.049394 -166.248842)
		(end 322.27647 -166.47287)
		(width 0.1143)
		(layer "F.Cu")
		(net "BMC_I2C_C_SDA")
	)
	(segment
		(start 186.059572 -195.321936)
		(end 184.903872 -195.321936)
		(width 0.1143)
		(layer "F.Cu")
		(net "BMC_I2C_C_SDA")
	)
	(segment
		(start 181.1655 -147.828)
		(end 181.1655 -148.9075)
		(width 0.1143)
		(layer "F.Cu")
		(net "BMC_I2C_C_SDA")
	)
	(segment
		(start 319.4685 -166.878)
		(end 319.532 -166.878)
		(width 0.1143)
		(layer "F.Cu")
		(net "BMC_I2C_C_SDA")
	)
	(segment
		(start 184.903872 -195.321936)
		(end 184.705752 -195.520056)
		(width 0.1143)
		(layer "F.Cu")
		(net "BMC_I2C_C_SDA")
	)
	(segment
		(start 176.149 -153.924)
		(end 174.879 -153.924)
		(width 0.1143)
		(layer "F.Cu")
		(net "BMC_I2C_C_SDA")
	)
	(segment
		(start 320.09715 -166.31285)
		(end 320.906394 -166.31285)
		(width 0.1143)
		(layer "F.Cu")
		(net "BMC_I2C_C_SDA")
	)
	(via
		(at 306.4256 -136.3472)
		(size 0.5588)
		(drill 0.3048)
		(layers "F.Cu" "B.Cu")
		(net "BMC_I2C_C_SDA")
	)
	(via
		(at 322.27647 -166.47287)
		(size 0.5588)
		(drill 0.3048)
		(layers "F.Cu" "B.Cu")
		(net "BMC_I2C_C_SDA")
	)
	(via
		(at 290.449 -137.668)
		(size 0.5588)
		(drill 0.3048)
		(layers "F.Cu" "B.Cu")
		(net "BMC_I2C_C_SDA")
	)
	(via
		(at 186.817 -196.083936)
		(size 0.5588)
		(drill 0.3048)
		(layers "F.Cu" "B.Cu")
		(net "BMC_I2C_C_SDA")
	)
	(via
		(at 291.211 -136.906)
		(size 0.7112)
		(drill 0.3556)
		(layers "F.Cu" "B.Cu")
		(net "BMC_I2C_C_SDA")
	)
	(via
		(at 174.879 -153.924)
		(size 0.5588)
		(drill 0.3048)
		(layers "F.Cu" "B.Cu")
		(net "BMC_I2C_C_SDA")
	)
	(segment
		(start 174.879 -153.924)
		(end 185.761122 -164.806122)
		(width 0.1143)
		(layer "B.Cu")
		(net "BMC_I2C_C_SDA")
	)
	(segment
		(start 185.761122 -164.806122)
		(end 185.761122 -192.730628)
		(width 0.1143)
		(layer "B.Cu")
		(net "BMC_I2C_C_SDA")
	)
	(segment
		(start 306.3748 -136.398)
		(end 291.719 -136.398)
		(width 0.1143)
		(layer "B.Cu")
		(net "BMC_I2C_C_SDA")
	)
	(segment
		(start 306.4256 -136.3472)
		(end 306.3748 -136.398)
		(width 0.1143)
		(layer "B.Cu")
		(net "BMC_I2C_C_SDA")
	)
	(segment
		(start 186.817 -195.834)
		(end 186.817 -196.083936)
		(width 0.1143)
		(layer "B.Cu")
		(net "BMC_I2C_C_SDA")
	)
	(segment
		(start 291.211 -136.906)
		(end 290.449 -137.668)
		(width 0.1143)
		(layer "B.Cu")
		(net "BMC_I2C_C_SDA")
	)
	(segment
		(start 186.110372 -193.079878)
		(end 186.110372 -195.127372)
		(width 0.1143)
		(layer "B.Cu")
		(net "BMC_I2C_C_SDA")
	)
	(segment
		(start 186.110372 -195.127372)
		(end 186.817 -195.834)
		(width 0.1143)
		(layer "B.Cu")
		(net "BMC_I2C_C_SDA")
	)
	(segment
		(start 185.761122 -192.730628)
		(end 186.110372 -193.079878)
		(width 0.1143)
		(layer "B.Cu")
		(net "BMC_I2C_C_SDA")
	)
	(segment
		(start 291.719 -136.398)
		(end 291.211 -136.906)
		(width 0.1143)
		(layer "B.Cu")
		(net "BMC_I2C_C_SDA")
	)
	(segment
		(start 313.329828 -136.603232)
		(end 313.317128 -136.615932)
		(width 0.127)
		(layer "In2.Cu")
		(net "BMC_I2C_C_SDA")
	)
	(segment
		(start 313.317128 -139.497562)
		(end 316.357 -142.537434)
		(width 0.127)
		(layer "In2.Cu")
		(net "BMC_I2C_C_SDA")
	)
	(segment
		(start 321.945254 -165.524688)
		(end 321.945254 -166.141654)
		(width 0.127)
		(layer "In2.Cu")
		(net "BMC_I2C_C_SDA")
	)
	(segment
		(start 320.802 -154.94)
		(end 320.802 -164.657532)
		(width 0.127)
		(layer "In2.Cu")
		(net "BMC_I2C_C_SDA")
	)
	(segment
		(start 311.527698 -134.8867)
		(end 312.498232 -134.8867)
		(width 0.127)
		(layer "In2.Cu")
		(net "BMC_I2C_C_SDA")
	)
	(segment
		(start 321.945254 -166.141654)
		(end 322.27647 -166.47287)
		(width 0.127)
		(layer "In2.Cu")
		(net "BMC_I2C_C_SDA")
	)
	(segment
		(start 308.1401 -134.6327)
		(end 311.273698 -134.6327)
		(width 0.127)
		(layer "In2.Cu")
		(net "BMC_I2C_C_SDA")
	)
	(segment
		(start 176.1617 -153.9113)
		(end 176.149 -153.924)
		(width 0.127)
		(layer "In2.Cu")
		(net "BMC_I2C_C_SDA")
	)
	(segment
		(start 321.393566 -164.973)
		(end 321.945254 -165.524688)
		(width 0.127)
		(layer "In2.Cu")
		(net "BMC_I2C_C_SDA")
	)
	(segment
		(start 176.149 -153.924)
		(end 174.879 -153.924)
		(width 0.127)
		(layer "In2.Cu")
		(net "BMC_I2C_C_SDA")
	)
	(segment
		(start 320.802 -164.657532)
		(end 321.117468 -164.973)
		(width 0.127)
		(layer "In2.Cu")
		(net "BMC_I2C_C_SDA")
	)
	(segment
		(start 290.449 -137.668)
		(end 287.02 -137.668)
		(width 0.127)
		(layer "In2.Cu")
		(net "BMC_I2C_C_SDA")
	)
	(segment
		(start 312.498232 -134.8867)
		(end 313.329828 -135.718296)
		(width 0.127)
		(layer "In2.Cu")
		(net "BMC_I2C_C_SDA")
	)
	(segment
		(start 321.117468 -164.973)
		(end 321.393566 -164.973)
		(width 0.127)
		(layer "In2.Cu")
		(net "BMC_I2C_C_SDA")
	)
	(segment
		(start 236.221016 -153.9113)
		(end 176.1617 -153.9113)
		(width 0.127)
		(layer "In2.Cu")
		(net "BMC_I2C_C_SDA")
	)
	(segment
		(start 311.273698 -134.6327)
		(end 311.527698 -134.8867)
		(width 0.127)
		(layer "In2.Cu")
		(net "BMC_I2C_C_SDA")
	)
	(segment
		(start 236.729016 -154.4193)
		(end 236.221016 -153.9113)
		(width 0.127)
		(layer "In2.Cu")
		(net "BMC_I2C_C_SDA")
	)
	(segment
		(start 313.317128 -136.615932)
		(end 313.317128 -139.497562)
		(width 0.127)
		(layer "In2.Cu")
		(net "BMC_I2C_C_SDA")
	)
	(segment
		(start 287.02 -137.668)
		(end 270.2687 -154.4193)
		(width 0.127)
		(layer "In2.Cu")
		(net "BMC_I2C_C_SDA")
	)
	(segment
		(start 306.4256 -136.3472)
		(end 308.1401 -134.6327)
		(width 0.127)
		(layer "In2.Cu")
		(net "BMC_I2C_C_SDA")
	)
	(segment
		(start 316.357 -142.537434)
		(end 316.357 -150.495)
		(width 0.127)
		(layer "In2.Cu")
		(net "BMC_I2C_C_SDA")
	)
	(segment
		(start 270.2687 -154.4193)
		(end 236.729016 -154.4193)
		(width 0.127)
		(layer "In2.Cu")
		(net "BMC_I2C_C_SDA")
	)
	(segment
		(start 316.357 -150.495)
		(end 320.802 -154.94)
		(width 0.127)
		(layer "In2.Cu")
		(net "BMC_I2C_C_SDA")
	)
	(segment
		(start 313.329828 -135.718296)
		(end 313.329828 -136.603232)
		(width 0.127)
		(layer "In2.Cu")
		(net "BMC_I2C_C_SDA")
	)
	(segment
		(start 319.4685 -169.545)
		(end 319.4685 -169.3545)
		(width 0.1143)
		(layer "F.Cu")
		(net "BMC_I2C_B_SCL")
	)
	(segment
		(start 319.4685 -169.3545)
		(end 319.7606 -169.0624)
		(width 0.1143)
		(layer "F.Cu")
		(net "BMC_I2C_B_SCL")
	)
	(segment
		(start 319.7606 -169.0624)
		(end 321.564 -169.0624)
		(width 0.1143)
		(layer "F.Cu")
		(net "BMC_I2C_B_SCL")
	)
	(segment
		(start 176.107344 -204.537056)
		(end 175.5902 -205.0542)
		(width 0.1143)
		(layer "F.Cu")
		(net "BMC_I2C_B_SCL")
	)
	(segment
		(start 318.4525 -169.418)
		(end 319.4685 -169.545)
		(width 0.1143)
		(layer "F.Cu")
		(net "BMC_I2C_B_SCL")
	)
	(segment
		(start 321.564 -169.926)
		(end 321.564 -169.0624)
		(width 0.1143)
		(layer "F.Cu")
		(net "BMC_I2C_B_SCL")
	)
	(segment
		(start 176.991772 -204.537056)
		(end 176.107344 -204.537056)
		(width 0.1143)
		(layer "F.Cu")
		(net "BMC_I2C_B_SCL")
	)
	(via
		(at 321.564 -169.0624)
		(size 0.5588)
		(drill 0.3048)
		(layers "F.Cu" "B.Cu")
		(net "BMC_I2C_B_SCL")
	)
	(via
		(at 332.84795 -167.655748)
		(size 0.5588)
		(drill 0.3048)
		(layers "F.Cu" "B.Cu")
		(net "BMC_I2C_B_SCL")
	)
	(via
		(at 321.564 -169.926)
		(size 0.7112)
		(drill 0.3556)
		(layers "F.Cu" "B.Cu")
		(net "BMC_I2C_B_SCL")
	)
	(via
		(at 175.5902 -205.0542)
		(size 0.5588)
		(drill 0.3048)
		(layers "F.Cu" "B.Cu")
		(net "BMC_I2C_B_SCL")
	)
	(segment
		(start 214.988394 -204.089)
		(end 231.244394 -187.833)
		(width 0.127)
		(layer "In2.Cu")
		(net "BMC_I2C_B_SCL")
	)
	(segment
		(start 259.7785 -225.534982)
		(end 259.207 -226.106482)
		(width 0.127)
		(layer "In2.Cu")
		(net "BMC_I2C_B_SCL")
	)
	(segment
		(start 182.499 -204.089)
		(end 214.988394 -204.089)
		(width 0.127)
		(layer "In2.Cu")
		(net "BMC_I2C_B_SCL")
	)
	(segment
		(start 258.656328 -233.30408)
		(end 263.566148 -238.2139)
		(width 0.127)
		(layer "In2.Cu")
		(net "BMC_I2C_B_SCL")
	)
	(segment
		(start 331.5462 -183.3245)
		(end 331.5462 -170.982386)
		(width 0.127)
		(layer "In2.Cu")
		(net "BMC_I2C_B_SCL")
	)
	(segment
		(start 252.66523 -187.833)
		(end 258.957572 -194.125342)
		(width 0.127)
		(layer "In2.Cu")
		(net "BMC_I2C_B_SCL")
	)
	(segment
		(start 258.957572 -194.125342)
		(end 258.957572 -220.415104)
		(width 0.127)
		(layer "In2.Cu")
		(net "BMC_I2C_B_SCL")
	)
	(segment
		(start 258.957572 -220.415104)
		(end 259.7785 -221.236032)
		(width 0.127)
		(layer "In2.Cu")
		(net "BMC_I2C_B_SCL")
	)
	(segment
		(start 259.207 -230.693468)
		(end 258.656328 -231.24414)
		(width 0.127)
		(layer "In2.Cu")
		(net "BMC_I2C_B_SCL")
	)
	(segment
		(start 327.152 -187.7187)
		(end 331.5462 -183.3245)
		(width 0.127)
		(layer "In2.Cu")
		(net "BMC_I2C_B_SCL")
	)
	(segment
		(start 259.207 -226.106482)
		(end 259.207 -230.693468)
		(width 0.127)
		(layer "In2.Cu")
		(net "BMC_I2C_B_SCL")
	)
	(segment
		(start 332.84795 -169.680636)
		(end 332.84795 -167.655748)
		(width 0.127)
		(layer "In2.Cu")
		(net "BMC_I2C_B_SCL")
	)
	(segment
		(start 327.152 -205.424532)
		(end 327.152 -187.7187)
		(width 0.127)
		(layer "In2.Cu")
		(net "BMC_I2C_B_SCL")
	)
	(segment
		(start 258.656328 -231.24414)
		(end 258.656328 -233.30408)
		(width 0.127)
		(layer "In2.Cu")
		(net "BMC_I2C_B_SCL")
	)
	(segment
		(start 181.5338 -205.0542)
		(end 182.499 -204.089)
		(width 0.127)
		(layer "In2.Cu")
		(net "BMC_I2C_B_SCL")
	)
	(segment
		(start 231.244394 -187.833)
		(end 252.66523 -187.833)
		(width 0.127)
		(layer "In2.Cu")
		(net "BMC_I2C_B_SCL")
	)
	(segment
		(start 259.7785 -221.236032)
		(end 259.7785 -225.534982)
		(width 0.127)
		(layer "In2.Cu")
		(net "BMC_I2C_B_SCL")
	)
	(segment
		(start 294.362632 -238.2139)
		(end 327.152 -205.424532)
		(width 0.127)
		(layer "In2.Cu")
		(net "BMC_I2C_B_SCL")
	)
	(segment
		(start 175.5902 -205.0542)
		(end 181.5338 -205.0542)
		(width 0.127)
		(layer "In2.Cu")
		(net "BMC_I2C_B_SCL")
	)
	(segment
		(start 263.566148 -238.2139)
		(end 294.362632 -238.2139)
		(width 0.127)
		(layer "In2.Cu")
		(net "BMC_I2C_B_SCL")
	)
	(segment
		(start 331.5462 -170.982386)
		(end 332.84795 -169.680636)
		(width 0.127)
		(layer "In2.Cu")
		(net "BMC_I2C_B_SCL")
	)
	(segment
		(start 332.84795 -167.655748)
		(end 332.357984 -167.655748)
		(width 0.127)
		(layer "In5.Cu")
		(net "BMC_I2C_B_SCL")
	)
	(segment
		(start 332.357984 -167.655748)
		(end 331.522832 -168.4909)
		(width 0.127)
		(layer "In5.Cu")
		(net "BMC_I2C_B_SCL")
	)
	(segment
		(start 331.522832 -168.4909)
		(end 331.112368 -168.4909)
		(width 0.127)
		(layer "In5.Cu")
		(net "BMC_I2C_B_SCL")
	)
	(segment
		(start 325.159878 -169.291)
		(end 324.931278 -169.0624)
		(width 0.127)
		(layer "In5.Cu")
		(net "BMC_I2C_B_SCL")
	)
	(segment
		(start 324.931278 -169.0624)
		(end 321.564 -169.0624)
		(width 0.127)
		(layer "In5.Cu")
		(net "BMC_I2C_B_SCL")
	)
	(segment
		(start 327.6473 -168.4147)
		(end 326.771 -169.291)
		(width 0.127)
		(layer "In5.Cu")
		(net "BMC_I2C_B_SCL")
	)
	(segment
		(start 326.771 -169.291)
		(end 325.159878 -169.291)
		(width 0.127)
		(layer "In5.Cu")
		(net "BMC_I2C_B_SCL")
	)
	(segment
		(start 331.036168 -168.4147)
		(end 327.6473 -168.4147)
		(width 0.127)
		(layer "In5.Cu")
		(net "BMC_I2C_B_SCL")
	)
	(segment
		(start 331.112368 -168.4909)
		(end 331.036168 -168.4147)
		(width 0.127)
		(layer "In5.Cu")
		(net "BMC_I2C_B_SCL")
	)
	(segment
		(start 274.6375 -168.021)
		(end 275.0185 -168.402)
		(width 0.1143)
		(layer "F.Cu")
		(net "I2C_BMC_10G_ALERT#")
	)
	(segment
		(start 275.0185 -168.402)
		(end 275.867876 -168.402)
		(width 0.1143)
		(layer "F.Cu")
		(net "I2C_BMC_10G_ALERT#")
	)
	(segment
		(start 268.63675 -167.17645)
		(end 273.628358 -167.17645)
		(width 0.1143)
		(layer "F.Cu")
		(net "I2C_BMC_10G_ALERT#")
	)
	(segment
		(start 286.225996 -173.84014)
		(end 286.434784 -173.84014)
		(width 0.1143)
		(layer "F.Cu")
		(net "I2C_BMC_10G_ALERT#")
	)
	(segment
		(start 273.679412 -167.187626)
		(end 273.679666 -167.18788)
		(width 0.1143)
		(layer "F.Cu")
		(net "I2C_BMC_10G_ALERT#")
	)
	(segment
		(start 277.81885 -168.34485)
		(end 282.470606 -172.996606)
		(width 0.1143)
		(layer "F.Cu")
		(net "I2C_BMC_10G_ALERT#")
	)
	(segment
		(start 297.434 -66.256916)
		(end 297.434 -62.103)
		(width 0.1143)
		(layer "F.Cu")
		(net "I2C_BMC_10G_ALERT#")
	)
	(segment
		(start 275.925026 -168.34485)
		(end 277.81885 -168.34485)
		(width 0.1143)
		(layer "F.Cu")
		(net "I2C_BMC_10G_ALERT#")
	)
	(segment
		(start 274.190968 -167.574468)
		(end 274.6375 -168.021)
		(width 0.1143)
		(layer "F.Cu")
		(net "I2C_BMC_10G_ALERT#")
	)
	(segment
		(start 290.632388 -81.376012)
		(end 290.632388 -73.058528)
		(width 0.1143)
		(layer "F.Cu")
		(net "I2C_BMC_10G_ALERT#")
	)
	(segment
		(start 285.864046 -173.47819)
		(end 286.225996 -173.84014)
		(width 0.1143)
		(layer "F.Cu")
		(net "I2C_BMC_10G_ALERT#")
	)
	(segment
		(start 273.960336 -167.468042)
		(end 274.190968 -167.574468)
		(width 0.1143)
		(layer "F.Cu")
		(net "I2C_BMC_10G_ALERT#")
	)
	(segment
		(start 282.470606 -172.996606)
		(end 284.287214 -172.996606)
		(width 0.1143)
		(layer "F.Cu")
		(net "I2C_BMC_10G_ALERT#")
	)
	(segment
		(start 275.867876 -168.402)
		(end 275.925026 -168.34485)
		(width 0.1143)
		(layer "F.Cu")
		(net "I2C_BMC_10G_ALERT#")
	)
	(segment
		(start 273.679666 -167.18788)
		(end 273.960336 -167.468042)
		(width 0.1143)
		(layer "F.Cu")
		(net "I2C_BMC_10G_ALERT#")
	)
	(segment
		(start 284.287214 -172.996606)
		(end 284.768798 -173.47819)
		(width 0.1143)
		(layer "F.Cu")
		(net "I2C_BMC_10G_ALERT#")
	)
	(segment
		(start 290.2204 -81.788)
		(end 290.632388 -81.376012)
		(width 0.1143)
		(layer "F.Cu")
		(net "I2C_BMC_10G_ALERT#")
	)
	(segment
		(start 267.9446 -167.8686)
		(end 268.63675 -167.17645)
		(width 0.1143)
		(layer "F.Cu")
		(net "I2C_BMC_10G_ALERT#")
	)
	(segment
		(start 299.339 -60.198)
		(end 300.0375 -60.198)
		(width 0.1143)
		(layer "F.Cu")
		(net "I2C_BMC_10G_ALERT#")
	)
	(segment
		(start 290.2204 -83.87715)
		(end 290.2204 -81.788)
		(width 0.1143)
		(layer "F.Cu")
		(net "I2C_BMC_10G_ALERT#")
	)
	(segment
		(start 297.434 -62.103)
		(end 299.339 -60.198)
		(width 0.1143)
		(layer "F.Cu")
		(net "I2C_BMC_10G_ALERT#")
	)
	(segment
		(start 273.628358 -167.17645)
		(end 273.679412 -167.187626)
		(width 0.1143)
		(layer "F.Cu")
		(net "I2C_BMC_10G_ALERT#")
	)
	(segment
		(start 284.768798 -173.47819)
		(end 285.864046 -173.47819)
		(width 0.1143)
		(layer "F.Cu")
		(net "I2C_BMC_10G_ALERT#")
	)
	(segment
		(start 291.24656 -91.40444)
		(end 291.24656 -84.90331)
		(width 0.1143)
		(layer "F.Cu")
		(net "I2C_BMC_10G_ALERT#")
	)
	(segment
		(start 290.632388 -73.058528)
		(end 297.434 -66.256916)
		(width 0.1143)
		(layer "F.Cu")
		(net "I2C_BMC_10G_ALERT#")
	)
	(segment
		(start 291.24656 -84.90331)
		(end 290.2204 -83.87715)
		(width 0.1143)
		(layer "F.Cu")
		(net "I2C_BMC_10G_ALERT#")
	)
	(via
		(at 267.97 -168.783)
		(size 0.7112)
		(drill 0.3556)
		(layers "F.Cu" "B.Cu")
		(net "I2C_BMC_10G_ALERT#")
	)
	(via
		(at 267.9446 -167.8686)
		(size 0.5588)
		(drill 0.3048)
		(layers "F.Cu" "B.Cu")
		(net "I2C_BMC_10G_ALERT#")
	)
	(via
		(at 291.24656 -91.40444)
		(size 0.5588)
		(drill 0.3048)
		(layers "F.Cu" "B.Cu")
		(net "I2C_BMC_10G_ALERT#")
	)
	(segment
		(start 267.97 -168.783)
		(end 267.97 -167.894)
		(width 0.1143)
		(layer "B.Cu")
		(net "I2C_BMC_10G_ALERT#")
	)
	(segment
		(start 267.97 -167.894)
		(end 267.9446 -167.8686)
		(width 0.1143)
		(layer "B.Cu")
		(net "I2C_BMC_10G_ALERT#")
	)
	(segment
		(start 269.113 -151.003)
		(end 269.113 -144.018)
		(width 0.127)
		(layer "In5.Cu")
		(net "I2C_BMC_10G_ALERT#")
	)
	(segment
		(start 269.621 -132.08)
		(end 289.2806 -112.4204)
		(width 0.127)
		(layer "In5.Cu")
		(net "I2C_BMC_10G_ALERT#")
	)
	(segment
		(start 269.621 -143.51)
		(end 269.621 -132.08)
		(width 0.127)
		(layer "In5.Cu")
		(net "I2C_BMC_10G_ALERT#")
	)
	(segment
		(start 289.2806 -93.4974)
		(end 291.24656 -91.53144)
		(width 0.127)
		(layer "In5.Cu")
		(net "I2C_BMC_10G_ALERT#")
	)
	(segment
		(start 267.9446 -167.8686)
		(end 268.732 -167.0812)
		(width 0.127)
		(layer "In5.Cu")
		(net "I2C_BMC_10G_ALERT#")
	)
	(segment
		(start 289.2806 -112.4204)
		(end 289.2806 -93.4974)
		(width 0.127)
		(layer "In5.Cu")
		(net "I2C_BMC_10G_ALERT#")
	)
	(segment
		(start 269.113 -144.018)
		(end 269.621 -143.51)
		(width 0.127)
		(layer "In5.Cu")
		(net "I2C_BMC_10G_ALERT#")
	)
	(segment
		(start 270.637 -152.527)
		(end 269.113 -151.003)
		(width 0.127)
		(layer "In5.Cu")
		(net "I2C_BMC_10G_ALERT#")
	)
	(segment
		(start 291.24656 -91.53144)
		(end 291.24656 -91.40444)
		(width 0.127)
		(layer "In5.Cu")
		(net "I2C_BMC_10G_ALERT#")
	)
	(segment
		(start 270.637 -157.734)
		(end 270.637 -152.527)
		(width 0.127)
		(layer "In5.Cu")
		(net "I2C_BMC_10G_ALERT#")
	)
	(segment
		(start 268.732 -159.639)
		(end 270.637 -157.734)
		(width 0.127)
		(layer "In5.Cu")
		(net "I2C_BMC_10G_ALERT#")
	)
	(segment
		(start 268.732 -167.0812)
		(end 268.732 -159.639)
		(width 0.127)
		(layer "In5.Cu")
		(net "I2C_BMC_10G_ALERT#")
	)
	(segment
		(start 299.654468 -61.468)
		(end 298.4373 -62.685168)
		(width 0.1143)
		(layer "F.Cu")
		(net "BMC_10G_SDA_2")
	)
	(segment
		(start 293.99992 -83.94192)
		(end 293.99992 -91.85148)
		(width 0.1143)
		(layer "F.Cu")
		(net "BMC_10G_SDA_2")
	)
	(segment
		(start 298.4373 -66.65468)
		(end 291.75075 -73.34123)
		(width 0.1143)
		(layer "F.Cu")
		(net "BMC_10G_SDA_2")
	)
	(segment
		(start 291.75075 -73.34123)
		(end 291.75075 -81.69275)
		(width 0.1143)
		(layer "F.Cu")
		(net "BMC_10G_SDA_2")
	)
	(segment
		(start 302.749458 -61.468)
		(end 299.654468 -61.468)
		(width 0.1143)
		(layer "F.Cu")
		(net "BMC_10G_SDA_2")
	)
	(segment
		(start 298.4373 -62.685168)
		(end 298.4373 -66.65468)
		(width 0.1143)
		(layer "F.Cu")
		(net "BMC_10G_SDA_2")
	)
	(segment
		(start 291.75075 -81.69275)
		(end 293.99992 -83.94192)
		(width 0.1143)
		(layer "F.Cu")
		(net "BMC_10G_SDA_2")
	)
	(segment
		(start 302.876458 -61.595)
		(end 302.749458 -61.468)
		(width 0.1143)
		(layer "F.Cu")
		(net "BMC_10G_SDA_2")
	)
	(via
		(at 293.99992 -91.85148)
		(size 0.5588)
		(drill 0.3048)
		(layers "F.Cu" "B.Cu")
		(net "BMC_10G_SDA_2")
	)
	(via
		(at 270.51 -171.958)
		(size 0.7112)
		(drill 0.3556)
		(layers "F.Cu" "B.Cu")
		(net "BMC_10G_SDA_2")
	)
	(via
		(at 271.399 -171.958)
		(size 0.5588)
		(drill 0.3048)
		(layers "F.Cu" "B.Cu")
		(net "BMC_10G_SDA_2")
	)
	(segment
		(start 274.6375 -171.577)
		(end 273.7485 -172.466)
		(width 0.1143)
		(layer "B.Cu")
		(net "BMC_10G_SDA_2")
	)
	(segment
		(start 272.288 -172.593)
		(end 271.653 -171.958)
		(width 0.1143)
		(layer "B.Cu")
		(net "BMC_10G_SDA_2")
	)
	(segment
		(start 273.7485 -172.466)
		(end 273.7485 -172.593)
		(width 0.1143)
		(layer "B.Cu")
		(net "BMC_10G_SDA_2")
	)
	(segment
		(start 270.51 -171.958)
		(end 271.399 -171.958)
		(width 0.1143)
		(layer "B.Cu")
		(net "BMC_10G_SDA_2")
	)
	(segment
		(start 271.653 -171.958)
		(end 271.399 -171.958)
		(width 0.1143)
		(layer "B.Cu")
		(net "BMC_10G_SDA_2")
	)
	(segment
		(start 273.7485 -172.593)
		(end 272.288 -172.593)
		(width 0.1143)
		(layer "B.Cu")
		(net "BMC_10G_SDA_2")
	)
	(segment
		(start 293.220394 -91.948)
		(end 291.211 -93.957394)
		(width 0.127)
		(layer "In5.Cu")
		(net "BMC_10G_SDA_2")
	)
	(segment
		(start 271.2847 -165.078918)
		(end 271.2847 -165.489382)
		(width 0.127)
		(layer "In5.Cu")
		(net "BMC_10G_SDA_2")
	)
	(segment
		(start 291.211 -114.808)
		(end 280.543 -125.476)
		(width 0.127)
		(layer "In5.Cu")
		(net "BMC_10G_SDA_2")
	)
	(segment
		(start 271.2847 -165.489382)
		(end 271.47774 -165.682422)
		(width 0.127)
		(layer "In5.Cu")
		(net "BMC_10G_SDA_2")
	)
	(segment
		(start 271.47774 -171.87926)
		(end 271.399 -171.958)
		(width 0.127)
		(layer "In5.Cu")
		(net "BMC_10G_SDA_2")
	)
	(segment
		(start 273.812 -162.551618)
		(end 271.2847 -165.078918)
		(width 0.127)
		(layer "In5.Cu")
		(net "BMC_10G_SDA_2")
	)
	(segment
		(start 293.9034 -91.948)
		(end 293.220394 -91.948)
		(width 0.127)
		(layer "In5.Cu")
		(net "BMC_10G_SDA_2")
	)
	(segment
		(start 271.653 -132.969)
		(end 271.653 -148.59)
		(width 0.127)
		(layer "In5.Cu")
		(net "BMC_10G_SDA_2")
	)
	(segment
		(start 271.47774 -165.682422)
		(end 271.47774 -171.87926)
		(width 0.127)
		(layer "In5.Cu")
		(net "BMC_10G_SDA_2")
	)
	(segment
		(start 280.543 -125.476)
		(end 279.146 -125.476)
		(width 0.127)
		(layer "In5.Cu")
		(net "BMC_10G_SDA_2")
	)
	(segment
		(start 271.145 -149.098)
		(end 271.145 -150.114)
		(width 0.127)
		(layer "In5.Cu")
		(net "BMC_10G_SDA_2")
	)
	(segment
		(start 271.145 -150.114)
		(end 273.812 -152.781)
		(width 0.127)
		(layer "In5.Cu")
		(net "BMC_10G_SDA_2")
	)
	(segment
		(start 279.146 -125.476)
		(end 271.653 -132.969)
		(width 0.127)
		(layer "In5.Cu")
		(net "BMC_10G_SDA_2")
	)
	(segment
		(start 271.653 -148.59)
		(end 271.145 -149.098)
		(width 0.127)
		(layer "In5.Cu")
		(net "BMC_10G_SDA_2")
	)
	(segment
		(start 291.211 -93.957394)
		(end 291.211 -114.808)
		(width 0.127)
		(layer "In5.Cu")
		(net "BMC_10G_SDA_2")
	)
	(segment
		(start 293.99992 -91.85148)
		(end 293.9034 -91.948)
		(width 0.127)
		(layer "In5.Cu")
		(net "BMC_10G_SDA_2")
	)
	(segment
		(start 273.812 -152.781)
		(end 273.812 -162.551618)
		(width 0.127)
		(layer "In5.Cu")
		(net "BMC_10G_SDA_2")
	)
	(segment
		(start 302.876458 -60.452)
		(end 302.876458 -60.579)
		(width 0.1143)
		(layer "F.Cu")
		(net "BMC_10G_SCL_2")
	)
	(segment
		(start 297.9293 -62.492636)
		(end 297.9293 -66.462148)
		(width 0.1143)
		(layer "F.Cu")
		(net "BMC_10G_SCL_2")
	)
	(segment
		(start 292.26256 -83.09356)
		(end 292.26256 -91.40444)
		(width 0.1143)
		(layer "F.Cu")
		(net "BMC_10G_SCL_2")
	)
	(segment
		(start 291.127688 -73.26376)
		(end 291.127688 -81.958688)
		(width 0.1143)
		(layer "F.Cu")
		(net "BMC_10G_SCL_2")
	)
	(segment
		(start 297.9293 -66.462148)
		(end 291.127688 -73.26376)
		(width 0.1143)
		(layer "F.Cu")
		(net "BMC_10G_SCL_2")
	)
	(segment
		(start 299.536358 -60.885578)
		(end 297.9293 -62.492636)
		(width 0.1143)
		(layer "F.Cu")
		(net "BMC_10G_SCL_2")
	)
	(segment
		(start 302.56988 -60.885578)
		(end 299.536358 -60.885578)
		(width 0.1143)
		(layer "F.Cu")
		(net "BMC_10G_SCL_2")
	)
	(segment
		(start 302.876458 -60.579)
		(end 302.56988 -60.885578)
		(width 0.1143)
		(layer "F.Cu")
		(net "BMC_10G_SCL_2")
	)
	(segment
		(start 291.127688 -81.958688)
		(end 292.26256 -83.09356)
		(width 0.1143)
		(layer "F.Cu")
		(net "BMC_10G_SCL_2")
	)
	(via
		(at 292.26256 -91.40444)
		(size 0.5588)
		(drill 0.3048)
		(layers "F.Cu" "B.Cu")
		(net "BMC_10G_SCL_2")
	)
	(via
		(at 268.859 -167.8686)
		(size 0.5588)
		(drill 0.3048)
		(layers "F.Cu" "B.Cu")
		(net "BMC_10G_SCL_2")
	)
	(via
		(at 270.8402 -167.3352)
		(size 0.7112)
		(drill 0.3556)
		(layers "F.Cu" "B.Cu")
		(net "BMC_10G_SCL_2")
	)
	(segment
		(start 270.8402 -167.3352)
		(end 270.87195 -167.30345)
		(width 0.1143)
		(layer "B.Cu")
		(net "BMC_10G_SCL_2")
	)
	(segment
		(start 270.87195 -167.30345)
		(end 273.256248 -167.30345)
		(width 0.1143)
		(layer "B.Cu")
		(net "BMC_10G_SCL_2")
	)
	(segment
		(start 273.7485 -167.795702)
		(end 273.7485 -169.545)
		(width 0.1143)
		(layer "B.Cu")
		(net "BMC_10G_SCL_2")
	)
	(segment
		(start 274.6375 -170.47083)
		(end 273.7485 -169.58183)
		(width 0.1143)
		(layer "B.Cu")
		(net "BMC_10G_SCL_2")
	)
	(segment
		(start 269.3924 -167.3352)
		(end 270.8402 -167.3352)
		(width 0.1143)
		(layer "B.Cu")
		(net "BMC_10G_SCL_2")
	)
	(segment
		(start 273.256248 -167.30345)
		(end 273.7485 -167.795702)
		(width 0.1143)
		(layer "B.Cu")
		(net "BMC_10G_SCL_2")
	)
	(segment
		(start 268.859 -167.8686)
		(end 269.3924 -167.3352)
		(width 0.1143)
		(layer "B.Cu")
		(net "BMC_10G_SCL_2")
	)
	(segment
		(start 273.7485 -169.58183)
		(end 273.7485 -169.545)
		(width 0.1143)
		(layer "B.Cu")
		(net "BMC_10G_SCL_2")
	)
	(segment
		(start 274.6375 -170.561)
		(end 274.6375 -170.47083)
		(width 0.1143)
		(layer "B.Cu")
		(net "BMC_10G_SCL_2")
	)
	(segment
		(start 269.621 -144.272)
		(end 270.129 -143.764)
		(width 0.127)
		(layer "In5.Cu")
		(net "BMC_10G_SCL_2")
	)
	(segment
		(start 269.24 -167.4876)
		(end 269.24 -159.893)
		(width 0.127)
		(layer "In5.Cu")
		(net "BMC_10G_SCL_2")
	)
	(segment
		(start 290.195 -93.472)
		(end 292.26256 -91.40444)
		(width 0.127)
		(layer "In5.Cu")
		(net "BMC_10G_SCL_2")
	)
	(segment
		(start 269.24 -159.893)
		(end 271.145 -157.988)
		(width 0.127)
		(layer "In5.Cu")
		(net "BMC_10G_SCL_2")
	)
	(segment
		(start 271.145 -152.273)
		(end 269.621 -150.749)
		(width 0.127)
		(layer "In5.Cu")
		(net "BMC_10G_SCL_2")
	)
	(segment
		(start 270.129 -132.334)
		(end 290.195 -112.268)
		(width 0.127)
		(layer "In5.Cu")
		(net "BMC_10G_SCL_2")
	)
	(segment
		(start 269.621 -150.749)
		(end 269.621 -144.272)
		(width 0.127)
		(layer "In5.Cu")
		(net "BMC_10G_SCL_2")
	)
	(segment
		(start 290.195 -112.268)
		(end 290.195 -93.472)
		(width 0.127)
		(layer "In5.Cu")
		(net "BMC_10G_SCL_2")
	)
	(segment
		(start 268.859 -167.8686)
		(end 269.24 -167.4876)
		(width 0.127)
		(layer "In5.Cu")
		(net "BMC_10G_SCL_2")
	)
	(segment
		(start 271.145 -157.988)
		(end 271.145 -152.273)
		(width 0.127)
		(layer "In5.Cu")
		(net "BMC_10G_SCL_2")
	)
	(segment
		(start 270.129 -143.764)
		(end 270.129 -132.334)
		(width 0.127)
		(layer "In5.Cu")
		(net "BMC_10G_SCL_2")
	)
	(segment
		(start 311.3405 -188.087)
		(end 311.3405 -187.8965)
		(width 0.1143)
		(layer "F.Cu")
		(net "HB_B_SIDE_IN")
	)
	(segment
		(start 311.3405 -187.8965)
		(end 312.293 -186.944)
		(width 0.1143)
		(layer "F.Cu")
		(net "HB_B_SIDE_IN")
	)
	(segment
		(start 312.293 -186.944)
		(end 314.833 -186.944)
		(width 0.1143)
		(layer "F.Cu")
		(net "HB_B_SIDE_IN")
	)
	(segment
		(start 95.8215 -249.4915)
		(end 94.914212 -249.4915)
		(width 0.1143)
		(layer "F.Cu")
		(net "HB_B_SIDE_IN")
	)
	(segment
		(start 314.833 -186.944)
		(end 315.214 -186.563)
		(width 0.1143)
		(layer "F.Cu")
		(net "HB_B_SIDE_IN")
	)
	(via
		(at 331.47 -187.8965)
		(size 0.5588)
		(drill 0.3048)
		(layers "F.Cu" "B.Cu")
		(net "HB_B_SIDE_IN")
	)
	(via
		(at 315.214 -186.563)
		(size 0.5588)
		(drill 0.3048)
		(layers "F.Cu" "B.Cu")
		(net "HB_B_SIDE_IN")
	)
	(via
		(at 330.327 -187.8965)
		(size 0.7112)
		(drill 0.3556)
		(layers "F.Cu" "B.Cu")
		(net "HB_B_SIDE_IN")
	)
	(via
		(at 95.8215 -249.4915)
		(size 0.5588)
		(drill 0.3048)
		(layers "F.Cu" "B.Cu")
		(net "HB_B_SIDE_IN")
	)
	(segment
		(start 331.47 -187.8965)
		(end 330.327 -187.8965)
		(width 0.1143)
		(layer "B.Cu")
		(net "HB_B_SIDE_IN")
	)
	(segment
		(start 330.327 -187.8965)
		(end 328.9935 -187.8965)
		(width 0.1143)
		(layer "B.Cu")
		(net "HB_B_SIDE_IN")
	)
	(segment
		(start 318.714628 -186.817)
		(end 315.468 -186.817)
		(width 0.1143)
		(layer "B.Cu")
		(net "HB_B_SIDE_IN")
	)
	(segment
		(start 319.419478 -187.52185)
		(end 318.714628 -186.817)
		(width 0.1143)
		(layer "B.Cu")
		(net "HB_B_SIDE_IN")
	)
	(segment
		(start 328.9935 -187.8965)
		(end 328.61885 -187.52185)
		(width 0.1143)
		(layer "B.Cu")
		(net "HB_B_SIDE_IN")
	)
	(segment
		(start 315.468 -186.817)
		(end 315.214 -186.563)
		(width 0.1143)
		(layer "B.Cu")
		(net "HB_B_SIDE_IN")
	)
	(segment
		(start 328.61885 -187.52185)
		(end 319.419478 -187.52185)
		(width 0.1143)
		(layer "B.Cu")
		(net "HB_B_SIDE_IN")
	)
	(segment
		(start 187.333382 -246.888)
		(end 212.3694 -221.851982)
		(width 0.127)
		(layer "In2.Cu")
		(net "HB_B_SIDE_IN")
	)
	(segment
		(start 121.664222 -248.667778)
		(end 123.317 -247.015)
		(width 0.127)
		(layer "In2.Cu")
		(net "HB_B_SIDE_IN")
	)
	(segment
		(start 252.7427 -234.037378)
		(end 262.240522 -243.5352)
		(width 0.127)
		(layer "In2.Cu")
		(net "HB_B_SIDE_IN")
	)
	(segment
		(start 172.466 -246.888)
		(end 187.333382 -246.888)
		(width 0.127)
		(layer "In2.Cu")
		(net "HB_B_SIDE_IN")
	)
	(segment
		(start 123.317 -247.015)
		(end 172.339 -247.015)
		(width 0.127)
		(layer "In2.Cu")
		(net "HB_B_SIDE_IN")
	)
	(segment
		(start 334.8863 -213.436962)
		(end 334.8863 -203.745846)
		(width 0.127)
		(layer "In2.Cu")
		(net "HB_B_SIDE_IN")
	)
	(segment
		(start 251.201174 -194.463416)
		(end 252.7427 -196.004942)
		(width 0.127)
		(layer "In2.Cu")
		(net "HB_B_SIDE_IN")
	)
	(segment
		(start 331.597 -188.0235)
		(end 331.47 -187.8965)
		(width 0.127)
		(layer "In2.Cu")
		(net "HB_B_SIDE_IN")
	)
	(segment
		(start 333.8322 -214.491062)
		(end 334.8863 -213.436962)
		(width 0.127)
		(layer "In2.Cu")
		(net "HB_B_SIDE_IN")
	)
	(segment
		(start 275.375116 -243.5352)
		(end 276.130766 -242.77955)
		(width 0.127)
		(layer "In2.Cu")
		(net "HB_B_SIDE_IN")
	)
	(segment
		(start 332.867 -197.277228)
		(end 331.597 -196.007228)
		(width 0.127)
		(layer "In2.Cu")
		(net "HB_B_SIDE_IN")
	)
	(segment
		(start 276.130766 -242.77955)
		(end 297.372278 -242.77955)
		(width 0.127)
		(layer "In2.Cu")
		(net "HB_B_SIDE_IN")
	)
	(segment
		(start 212.3694 -221.851982)
		(end 212.3694 -216.192862)
		(width 0.127)
		(layer "In2.Cu")
		(net "HB_B_SIDE_IN")
	)
	(segment
		(start 334.8863 -203.745846)
		(end 332.867 -201.726546)
		(width 0.127)
		(layer "In2.Cu")
		(net "HB_B_SIDE_IN")
	)
	(segment
		(start 297.372278 -242.77955)
		(end 323.362828 -216.789)
		(width 0.127)
		(layer "In2.Cu")
		(net "HB_B_SIDE_IN")
	)
	(segment
		(start 97.205038 -248.667778)
		(end 121.664222 -248.667778)
		(width 0.127)
		(layer "In2.Cu")
		(net "HB_B_SIDE_IN")
	)
	(segment
		(start 252.7427 -196.004942)
		(end 252.7427 -234.037378)
		(width 0.127)
		(layer "In2.Cu")
		(net "HB_B_SIDE_IN")
	)
	(segment
		(start 172.339 -247.015)
		(end 172.466 -246.888)
		(width 0.127)
		(layer "In2.Cu")
		(net "HB_B_SIDE_IN")
	)
	(segment
		(start 333.186532 -216.789)
		(end 333.8322 -216.143332)
		(width 0.127)
		(layer "In2.Cu")
		(net "HB_B_SIDE_IN")
	)
	(segment
		(start 331.597 -196.007228)
		(end 331.597 -188.0235)
		(width 0.127)
		(layer "In2.Cu")
		(net "HB_B_SIDE_IN")
	)
	(segment
		(start 212.3694 -216.192862)
		(end 234.098846 -194.463416)
		(width 0.127)
		(layer "In2.Cu")
		(net "HB_B_SIDE_IN")
	)
	(segment
		(start 333.8322 -216.143332)
		(end 333.8322 -214.491062)
		(width 0.127)
		(layer "In2.Cu")
		(net "HB_B_SIDE_IN")
	)
	(segment
		(start 262.240522 -243.5352)
		(end 275.375116 -243.5352)
		(width 0.127)
		(layer "In2.Cu")
		(net "HB_B_SIDE_IN")
	)
	(segment
		(start 234.098846 -194.463416)
		(end 251.201174 -194.463416)
		(width 0.127)
		(layer "In2.Cu")
		(net "HB_B_SIDE_IN")
	)
	(segment
		(start 95.8215 -249.4915)
		(end 96.381316 -249.4915)
		(width 0.127)
		(layer "In2.Cu")
		(net "HB_B_SIDE_IN")
	)
	(segment
		(start 96.381316 -249.4915)
		(end 97.205038 -248.667778)
		(width 0.127)
		(layer "In2.Cu")
		(net "HB_B_SIDE_IN")
	)
	(segment
		(start 323.362828 -216.789)
		(end 333.186532 -216.789)
		(width 0.127)
		(layer "In2.Cu")
		(net "HB_B_SIDE_IN")
	)
	(segment
		(start 332.867 -201.726546)
		(end 332.867 -197.277228)
		(width 0.127)
		(layer "In2.Cu")
		(net "HB_B_SIDE_IN")
	)
	(segment
		(start 310.4515 -182.499)
		(end 309.88 -182.499)
		(width 0.1143)
		(layer "F.Cu")
		(net "FAN_PWM_PCIE_BMC")
	)
	(segment
		(start 309.88 -182.499)
		(end 309.5371 -182.8419)
		(width 0.1143)
		(layer "F.Cu")
		(net "FAN_PWM_PCIE_BMC")
	)
	(segment
		(start 309.5371 -182.8419)
		(end 309.38216 -182.8419)
		(width 0.1143)
		(layer "F.Cu")
		(net "FAN_PWM_PCIE_BMC")
	)
	(segment
		(start 299.612304 -181.46268)
		(end 299.621956 -181.46268)
		(width 0.1143)
		(layer "F.Cu")
		(net "FAN_PWM_PCIE_BMC")
	)
	(segment
		(start 299.23486 -181.840124)
		(end 299.612304 -181.46268)
		(width 0.1143)
		(layer "F.Cu")
		(net "FAN_PWM_PCIE_BMC")
	)
	(segment
		(start 299.621956 -181.46268)
		(end 299.644562 -181.440074)
		(width 0.1143)
		(layer "F.Cu")
		(net "FAN_PWM_PCIE_BMC")
	)
	(via
		(at 309.38216 -182.8419)
		(size 0.508)
		(drill 0.254)
		(layers "F.Cu" "B.Cu")
		(net "FAN_PWM_PCIE_BMC")
	)
	(via
		(at 309.38216 -181.864)
		(size 0.7112)
		(drill 0.3556)
		(layers "F.Cu" "B.Cu")
		(net "FAN_PWM_PCIE_BMC")
	)
	(via
		(at 299.644562 -181.440074)
		(size 0.508)
		(drill 0.254)
		(layers "F.Cu" "B.Cu")
		(net "FAN_PWM_PCIE_BMC")
	)
	(segment
		(start 309.38216 -182.8419)
		(end 309.38216 -181.864)
		(width 0.1143)
		(layer "B.Cu")
		(net "FAN_PWM_PCIE_BMC")
	)
	(segment
		(start 301.046388 -182.8419)
		(end 299.644562 -181.440074)
		(width 0.127)
		(layer "In2.Cu")
		(net "FAN_PWM_PCIE_BMC")
	)
	(segment
		(start 309.38216 -182.8419)
		(end 301.046388 -182.8419)
		(width 0.127)
		(layer "In2.Cu")
		(net "FAN_PWM_PCIE_BMC")
	)
	(segment
		(start 291.012626 -166.740332)
		(end 290.898326 -166.854632)
		(width 0.1143)
		(layer "F.Cu")
		(net "BMC_RXD1")
	)
	(segment
		(start 290.898326 -167.72255)
		(end 291.234876 -168.0591)
		(width 0.1143)
		(layer "F.Cu")
		(net "BMC_RXD1")
	)
	(segment
		(start 291.084 -161.9885)
		(end 291.084 -162.56)
		(width 0.1143)
		(layer "F.Cu")
		(net "BMC_RXD1")
	)
	(segment
		(start 290.898326 -166.854632)
		(end 290.898326 -167.72255)
		(width 0.1143)
		(layer "F.Cu")
		(net "BMC_RXD1")
	)
	(segment
		(start 290.957 -164.104828)
		(end 291.012626 -164.160454)
		(width 0.1143)
		(layer "F.Cu")
		(net "BMC_RXD1")
	)
	(segment
		(start 290.957 -162.687)
		(end 290.957 -163.703)
		(width 0.1143)
		(layer "F.Cu")
		(net "BMC_RXD1")
	)
	(segment
		(start 291.234876 -168.0591)
		(end 291.234876 -168.240202)
		(width 0.1143)
		(layer "F.Cu")
		(net "BMC_RXD1")
	)
	(segment
		(start 291.012626 -164.160454)
		(end 291.012626 -166.740332)
		(width 0.1143)
		(layer "F.Cu")
		(net "BMC_RXD1")
	)
	(segment
		(start 290.957 -163.703)
		(end 290.957 -164.104828)
		(width 0.1143)
		(layer "F.Cu")
		(net "BMC_RXD1")
	)
	(segment
		(start 291.084 -162.56)
		(end 290.957 -162.687)
		(width 0.1143)
		(layer "F.Cu")
		(net "BMC_RXD1")
	)
	(via
		(at 290.957 -163.703)
		(size 0.7112)
		(drill 0.3556)
		(layers "F.Cu" "B.Cu")
		(net "BMC_RXD1")
	)
	(segment
		(start 6.427216 -224.59188)
		(end 7.31266 -223.706436)
		(width 0.1143)
		(layer "F.Cu")
		(net "SAS_SEB_PEER_PRSNT_BMC")
	)
	(segment
		(start 251.206 -192.3161)
		(end 251.46 -192.3161)
		(width 0.1143)
		(layer "F.Cu")
		(net "SAS_SEB_PEER_PRSNT_BMC")
	)
	(segment
		(start 6.427216 -226.17938)
		(end 6.427216 -224.59188)
		(width 0.1143)
		(layer "F.Cu")
		(net "SAS_SEB_PEER_PRSNT_BMC")
	)
	(segment
		(start 251.46 -192.3161)
		(end 261.6581 -182.118)
		(width 0.1143)
		(layer "F.Cu")
		(net "SAS_SEB_PEER_PRSNT_BMC")
	)
	(segment
		(start 261.6581 -182.118)
		(end 270.764 -182.118)
		(width 0.1143)
		(layer "F.Cu")
		(net "SAS_SEB_PEER_PRSNT_BMC")
	)
	(segment
		(start 9.456928 -222.819468)
		(end 8.199628 -222.819468)
		(width 0.1143)
		(layer "F.Cu")
		(net "SAS_SEB_PEER_PRSNT_BMC")
	)
	(segment
		(start 8.199628 -222.819468)
		(end 7.31266 -223.706436)
		(width 0.1143)
		(layer "F.Cu")
		(net "SAS_SEB_PEER_PRSNT_BMC")
	)
	(via
		(at 251.206 -192.3161)
		(size 0.5588)
		(drill 0.3048)
		(layers "F.Cu" "B.Cu")
		(net "SAS_SEB_PEER_PRSNT_BMC")
	)
	(via
		(at 9.456928 -222.819468)
		(size 0.5588)
		(drill 0.3048)
		(layers "F.Cu" "B.Cu")
		(net "SAS_SEB_PEER_PRSNT_BMC")
	)
	(via
		(at 270.764 -182.118)
		(size 0.5588)
		(drill 0.3048)
		(layers "F.Cu" "B.Cu")
		(net "SAS_SEB_PEER_PRSNT_BMC")
	)
	(via
		(at 271.399 -174.498)
		(size 0.5588)
		(drill 0.3048)
		(layers "F.Cu" "B.Cu")
		(net "SAS_SEB_PEER_PRSNT_BMC")
	)
	(via
		(at 7.31266 -223.706436)
		(size 0.7112)
		(drill 0.3556)
		(layers "F.Cu" "B.Cu")
		(net "SAS_SEB_PEER_PRSNT_BMC")
	)
	(segment
		(start 272.998692 -173.97095)
		(end 273.360642 -173.609)
		(width 0.1143)
		(layer "B.Cu")
		(net "SAS_SEB_PEER_PRSNT_BMC")
	)
	(segment
		(start 271.682972 -173.114716)
		(end 272.53946 -173.97095)
		(width 0.1143)
		(layer "B.Cu")
		(net "SAS_SEB_PEER_PRSNT_BMC")
	)
	(segment
		(start 271.399 -174.498)
		(end 271.682972 -174.214028)
		(width 0.1143)
		(layer "B.Cu")
		(net "SAS_SEB_PEER_PRSNT_BMC")
	)
	(segment
		(start 272.53946 -173.97095)
		(end 272.998692 -173.97095)
		(width 0.1143)
		(layer "B.Cu")
		(net "SAS_SEB_PEER_PRSNT_BMC")
	)
	(segment
		(start 271.682972 -174.214028)
		(end 271.682972 -173.114716)
		(width 0.1143)
		(layer "B.Cu")
		(net "SAS_SEB_PEER_PRSNT_BMC")
	)
	(segment
		(start 273.360642 -173.609)
		(end 273.7485 -173.609)
		(width 0.1143)
		(layer "B.Cu")
		(net "SAS_SEB_PEER_PRSNT_BMC")
	)
	(segment
		(start 210.693 -216.216738)
		(end 210.693 -220.185742)
		(width 0.127)
		(layer "In2.Cu")
		(net "SAS_SEB_PEER_PRSNT_BMC")
	)
	(segment
		(start 66.496438 -214.5157)
		(end 42.4053 -214.5157)
		(width 0.127)
		(layer "In2.Cu")
		(net "SAS_SEB_PEER_PRSNT_BMC")
	)
	(segment
		(start 109.769402 -225.87712)
		(end 108.458 -224.565718)
		(width 0.127)
		(layer "In2.Cu")
		(net "SAS_SEB_PEER_PRSNT_BMC")
	)
	(segment
		(start 100.38969 -216.2556)
		(end 68.236338 -216.2556)
		(width 0.127)
		(layer "In2.Cu")
		(net "SAS_SEB_PEER_PRSNT_BMC")
	)
	(segment
		(start 68.236338 -216.2556)
		(end 66.496438 -214.5157)
		(width 0.127)
		(layer "In2.Cu")
		(net "SAS_SEB_PEER_PRSNT_BMC")
	)
	(segment
		(start 129.08788 -225.87712)
		(end 109.769402 -225.87712)
		(width 0.127)
		(layer "In2.Cu")
		(net "SAS_SEB_PEER_PRSNT_BMC")
	)
	(segment
		(start 210.693 -220.185742)
		(end 206.990442 -223.8883)
		(width 0.127)
		(layer "In2.Cu")
		(net "SAS_SEB_PEER_PRSNT_BMC")
	)
	(segment
		(start 206.990442 -223.8883)
		(end 131.0767 -223.8883)
		(width 0.127)
		(layer "In2.Cu")
		(net "SAS_SEB_PEER_PRSNT_BMC")
	)
	(segment
		(start 38.6842 -218.2368)
		(end 14.039596 -218.2368)
		(width 0.127)
		(layer "In2.Cu")
		(net "SAS_SEB_PEER_PRSNT_BMC")
	)
	(segment
		(start 131.0767 -223.8883)
		(end 129.08788 -225.87712)
		(width 0.127)
		(layer "In2.Cu")
		(net "SAS_SEB_PEER_PRSNT_BMC")
	)
	(segment
		(start 42.4053 -214.5157)
		(end 38.6842 -218.2368)
		(width 0.127)
		(layer "In2.Cu")
		(net "SAS_SEB_PEER_PRSNT_BMC")
	)
	(segment
		(start 234.123738 -192.786)
		(end 210.693 -216.216738)
		(width 0.127)
		(layer "In2.Cu")
		(net "SAS_SEB_PEER_PRSNT_BMC")
	)
	(segment
		(start 251.206 -192.3161)
		(end 250.7361 -192.786)
		(width 0.127)
		(layer "In2.Cu")
		(net "SAS_SEB_PEER_PRSNT_BMC")
	)
	(segment
		(start 250.7361 -192.786)
		(end 234.123738 -192.786)
		(width 0.127)
		(layer "In2.Cu")
		(net "SAS_SEB_PEER_PRSNT_BMC")
	)
	(segment
		(start 108.458 -224.32391)
		(end 100.38969 -216.2556)
		(width 0.127)
		(layer "In2.Cu")
		(net "SAS_SEB_PEER_PRSNT_BMC")
	)
	(segment
		(start 14.039596 -218.2368)
		(end 9.456928 -222.819468)
		(width 0.127)
		(layer "In2.Cu")
		(net "SAS_SEB_PEER_PRSNT_BMC")
	)
	(segment
		(start 108.458 -224.565718)
		(end 108.458 -224.32391)
		(width 0.127)
		(layer "In2.Cu")
		(net "SAS_SEB_PEER_PRSNT_BMC")
	)
	(segment
		(start 270.764 -182.118)
		(end 270.764 -175.133)
		(width 0.127)
		(layer "In5.Cu")
		(net "SAS_SEB_PEER_PRSNT_BMC")
	)
	(segment
		(start 270.764 -175.133)
		(end 271.399 -174.498)
		(width 0.127)
		(layer "In5.Cu")
		(net "SAS_SEB_PEER_PRSNT_BMC")
	)
	(segment
		(start 85.92947 -143.844772)
		(end 83.152742 -146.6215)
		(width 0.1143)
		(layer "F.Cu")
		(net "BUS_SW_EN")
	)
	(segment
		(start 6.54812 -211.38388)
		(end 8.967216 -211.38388)
		(width 0.1143)
		(layer "F.Cu")
		(net "BUS_SW_EN")
	)
	(segment
		(start 84.94141 -138.52144)
		(end 84.987638 -138.52144)
		(width 0.1143)
		(layer "F.Cu")
		(net "BUS_SW_EN")
	)
	(segment
		(start 80.7085 -146.6215)
		(end 79.502 -147.828)
		(width 0.1143)
		(layer "F.Cu")
		(net "BUS_SW_EN")
	)
	(segment
		(start 84.94141 -137.1854)
		(end 84.94141 -138.52144)
		(width 0.1143)
		(layer "F.Cu")
		(net "BUS_SW_EN")
	)
	(segment
		(start 84.987638 -138.52144)
		(end 85.92947 -139.463272)
		(width 0.1143)
		(layer "F.Cu")
		(net "BUS_SW_EN")
	)
	(segment
		(start 85.92947 -139.463272)
		(end 85.92947 -143.844772)
		(width 0.1143)
		(layer "F.Cu")
		(net "BUS_SW_EN")
	)
	(segment
		(start 5.855716 -212.076284)
		(end 6.54812 -211.38388)
		(width 0.1143)
		(layer "F.Cu")
		(net "BUS_SW_EN")
	)
	(segment
		(start 5.855716 -213.54288)
		(end 5.855716 -212.076284)
		(width 0.1143)
		(layer "F.Cu")
		(net "BUS_SW_EN")
	)
	(segment
		(start 83.152742 -146.6215)
		(end 80.7085 -146.6215)
		(width 0.1143)
		(layer "F.Cu")
		(net "BUS_SW_EN")
	)
	(via
		(at 8.967216 -211.38388)
		(size 0.5588)
		(drill 0.3048)
		(layers "F.Cu" "B.Cu")
		(net "BUS_SW_EN")
	)
	(via
		(at 13.39088 -211.38388)
		(size 0.7112)
		(drill 0.3556)
		(layers "F.Cu" "B.Cu")
		(net "BUS_SW_EN")
	)
	(via
		(at 79.502 -147.828)
		(size 0.5588)
		(drill 0.3048)
		(layers "F.Cu" "B.Cu")
		(net "BUS_SW_EN")
	)
	(segment
		(start 13.39088 -211.38388)
		(end 8.967216 -211.38388)
		(width 0.1143)
		(layer "B.Cu")
		(net "BUS_SW_EN")
	)
	(segment
		(start 21.742908 -205.90383)
		(end 21.710396 -205.90383)
		(width 0.1143)
		(layer "B.Cu")
		(net "BUS_SW_EN")
	)
	(segment
		(start 37.973 -187.26531)
		(end 37.973 -189.673992)
		(width 0.1143)
		(layer "B.Cu")
		(net "BUS_SW_EN")
	)
	(segment
		(start 79.502 -148.398738)
		(end 79.42072 -148.480018)
		(width 0.1143)
		(layer "B.Cu")
		(net "BUS_SW_EN")
	)
	(segment
		(start 15.698216 -211.38388)
		(end 13.39088 -211.38388)
		(width 0.1143)
		(layer "B.Cu")
		(net "BUS_SW_EN")
	)
	(segment
		(start 15.937484 -211.144612)
		(end 15.698216 -211.38388)
		(width 0.1143)
		(layer "B.Cu")
		(net "BUS_SW_EN")
	)
	(segment
		(start 79.502 -147.828)
		(end 79.502 -148.398738)
		(width 0.1143)
		(layer "B.Cu")
		(net "BUS_SW_EN")
	)
	(segment
		(start 22.029166 -205.617572)
		(end 21.742908 -205.90383)
		(width 0.1143)
		(layer "B.Cu")
		(net "BUS_SW_EN")
	)
	(segment
		(start 58.609484 -174.5234)
		(end 50.714656 -174.5234)
		(width 0.1143)
		(layer "B.Cu")
		(net "BUS_SW_EN")
	)
	(segment
		(start 17.074134 -211.144612)
		(end 15.937484 -211.144612)
		(width 0.1143)
		(layer "B.Cu")
		(net "BUS_SW_EN")
	)
	(segment
		(start 63.4619 -165.194742)
		(end 63.4619 -169.670984)
		(width 0.1143)
		(layer "B.Cu")
		(net "BUS_SW_EN")
	)
	(segment
		(start 19.442938 -208.775808)
		(end 17.074134 -211.144612)
		(width 0.1143)
		(layer "B.Cu")
		(net "BUS_SW_EN")
	)
	(segment
		(start 19.442938 -208.171288)
		(end 19.442938 -208.775808)
		(width 0.1143)
		(layer "B.Cu")
		(net "BUS_SW_EN")
	)
	(segment
		(start 50.714656 -174.5234)
		(end 48.872394 -176.365662)
		(width 0.1143)
		(layer "B.Cu")
		(net "BUS_SW_EN")
	)
	(segment
		(start 79.42072 -149.235922)
		(end 63.4619 -165.194742)
		(width 0.1143)
		(layer "B.Cu")
		(net "BUS_SW_EN")
	)
	(segment
		(start 63.4619 -169.670984)
		(end 58.609484 -174.5234)
		(width 0.1143)
		(layer "B.Cu")
		(net "BUS_SW_EN")
	)
	(segment
		(start 37.973 -189.673992)
		(end 22.029166 -205.617572)
		(width 0.1143)
		(layer "B.Cu")
		(net "BUS_SW_EN")
	)
	(segment
		(start 48.872394 -176.365662)
		(end 48.872394 -176.365916)
		(width 0.1143)
		(layer "B.Cu")
		(net "BUS_SW_EN")
	)
	(segment
		(start 79.42072 -148.480018)
		(end 79.42072 -149.235922)
		(width 0.1143)
		(layer "B.Cu")
		(net "BUS_SW_EN")
	)
	(segment
		(start 48.872394 -176.365916)
		(end 37.973 -187.26531)
		(width 0.1143)
		(layer "B.Cu")
		(net "BUS_SW_EN")
	)
	(segment
		(start 21.710396 -205.90383)
		(end 19.442938 -208.171288)
		(width 0.1143)
		(layer "B.Cu")
		(net "BUS_SW_EN")
	)
	(segment
		(start 12.13358 -234.184952)
		(end 12.13358 -236.838744)
		(width 0.1143)
		(layer "F.Cu")
		(net "PCIE_MATED#_AB")
	)
	(segment
		(start 27.064716 -234.19308)
		(end 27.064716 -237.10138)
		(width 0.1143)
		(layer "F.Cu")
		(net "PCIE_MATED#_AB")
	)
	(segment
		(start 13.412216 -238.11738)
		(end 13.412216 -238.45393)
		(width 0.1143)
		(layer "F.Cu")
		(net "PCIE_MATED#_AB")
	)
	(segment
		(start 12.142216 -236.84738)
		(end 13.412216 -238.11738)
		(width 0.1143)
		(layer "F.Cu")
		(net "PCIE_MATED#_AB")
	)
	(segment
		(start 27.636216 -237.67288)
		(end 27.636216 -238.45393)
		(width 0.1143)
		(layer "F.Cu")
		(net "PCIE_MATED#_AB")
	)
	(segment
		(start 12.13358 -236.838744)
		(end 12.142216 -236.84738)
		(width 0.1143)
		(layer "F.Cu")
		(net "PCIE_MATED#_AB")
	)
	(segment
		(start 27.064716 -237.10138)
		(end 27.636216 -237.67288)
		(width 0.1143)
		(layer "F.Cu")
		(net "PCIE_MATED#_AB")
	)
	(via
		(at 27.636216 -238.45393)
		(size 0.5588)
		(drill 0.3048)
		(layers "F.Cu" "B.Cu")
		(net "PCIE_MATED#_AB")
	)
	(via
		(at 23.775416 -238.45393)
		(size 0.7112)
		(drill 0.3556)
		(layers "F.Cu" "B.Cu")
		(net "PCIE_MATED#_AB")
	)
	(via
		(at 13.412216 -238.45393)
		(size 0.5588)
		(drill 0.3048)
		(layers "F.Cu" "B.Cu")
		(net "PCIE_MATED#_AB")
	)
	(segment
		(start 23.775416 -238.45393)
		(end 13.412216 -238.45393)
		(width 0.1143)
		(layer "B.Cu")
		(net "PCIE_MATED#_AB")
	)
	(segment
		(start 27.636216 -238.45393)
		(end 23.775416 -238.45393)
		(width 0.1143)
		(layer "B.Cu")
		(net "PCIE_MATED#_AB")
	)
	(segment
		(start 167.0685 -155.8036)
		(end 168.148 -155.8036)
		(width 0.1143)
		(layer "F.Cu")
		(net "EXP_IOC_BMC_SCL_14")
	)
	(segment
		(start 80.796892 -116.105432)
		(end 81.476342 -116.784882)
		(width 0.1143)
		(layer "F.Cu")
		(net "EXP_IOC_BMC_SCL_14")
	)
	(segment
		(start 80.244188 -116.105432)
		(end 80.796892 -116.105432)
		(width 0.1143)
		(layer "F.Cu")
		(net "EXP_IOC_BMC_SCL_14")
	)
	(segment
		(start 168.148 -155.8036)
		(end 168.529 -155.4226)
		(width 0.1143)
		(layer "F.Cu")
		(net "EXP_IOC_BMC_SCL_14")
	)
	(segment
		(start 81.476342 -116.784882)
		(end 81.547462 -116.856002)
		(width 0.1143)
		(layer "F.Cu")
		(net "EXP_IOC_BMC_SCL_14")
	)
	(segment
		(start 76.84897 -120.904)
		(end 76.84897 -119.145304)
		(width 0.1143)
		(layer "F.Cu")
		(net "EXP_IOC_BMC_SCL_14")
	)
	(segment
		(start 168.529 -155.4226)
		(end 168.529 -155.067)
		(width 0.1143)
		(layer "F.Cu")
		(net "EXP_IOC_BMC_SCL_14")
	)
	(segment
		(start 76.84897 -119.145304)
		(end 79.901542 -116.092732)
		(width 0.1143)
		(layer "F.Cu")
		(net "EXP_IOC_BMC_SCL_14")
	)
	(segment
		(start 81.547462 -116.856002)
		(end 84.232242 -116.856002)
		(width 0.1143)
		(layer "F.Cu")
		(net "EXP_IOC_BMC_SCL_14")
	)
	(segment
		(start 80.231488 -116.092732)
		(end 80.244188 -116.105432)
		(width 0.1143)
		(layer "F.Cu")
		(net "EXP_IOC_BMC_SCL_14")
	)
	(segment
		(start 79.901542 -116.092732)
		(end 80.231488 -116.092732)
		(width 0.1143)
		(layer "F.Cu")
		(net "EXP_IOC_BMC_SCL_14")
	)
	(via
		(at 76.84897 -120.904)
		(size 0.5588)
		(drill 0.3048)
		(layers "F.Cu" "B.Cu")
		(net "EXP_IOC_BMC_SCL_14")
	)
	(via
		(at 327.020428 -149.987)
		(size 0.5588)
		(drill 0.3048)
		(layers "F.Cu" "B.Cu")
		(net "EXP_IOC_BMC_SCL_14")
	)
	(via
		(at 328.422 -173.355)
		(size 0.7112)
		(drill 0.3556)
		(layers "F.Cu" "B.Cu")
		(net "EXP_IOC_BMC_SCL_14")
	)
	(via
		(at 168.529 -155.067)
		(size 0.5588)
		(drill 0.3048)
		(layers "F.Cu" "B.Cu")
		(net "EXP_IOC_BMC_SCL_14")
	)
	(segment
		(start 332.105 -173.355)
		(end 332.867 -172.593)
		(width 0.1143)
		(layer "B.Cu")
		(net "EXP_IOC_BMC_SCL_14")
	)
	(segment
		(start 333.950818 -172.652182)
		(end 334.772 -171.831)
		(width 0.1143)
		(layer "B.Cu")
		(net "EXP_IOC_BMC_SCL_14")
	)
	(segment
		(start 326.134476 -173.61535)
		(end 326.191626 -173.6725)
		(width 0.1143)
		(layer "B.Cu")
		(net "EXP_IOC_BMC_SCL_14")
	)
	(segment
		(start 320.074544 -174.625)
		(end 321.312032 -173.387512)
		(width 0.1143)
		(layer "B.Cu")
		(net "EXP_IOC_BMC_SCL_14")
	)
	(segment
		(start 327.5965 -173.6725)
		(end 327.914 -173.355)
		(width 0.1143)
		(layer "B.Cu")
		(net "EXP_IOC_BMC_SCL_14")
	)
	(segment
		(start 326.191626 -173.6725)
		(end 327.5965 -173.6725)
		(width 0.1143)
		(layer "B.Cu")
		(net "EXP_IOC_BMC_SCL_14")
	)
	(segment
		(start 329.4253 -152.229566)
		(end 327.182734 -149.987)
		(width 0.1143)
		(layer "B.Cu")
		(net "EXP_IOC_BMC_SCL_14")
	)
	(segment
		(start 326.107806 -173.61535)
		(end 326.134476 -173.61535)
		(width 0.1143)
		(layer "B.Cu")
		(net "EXP_IOC_BMC_SCL_14")
	)
	(segment
		(start 334.772 -171.831)
		(end 334.772 -168.524936)
		(width 0.1143)
		(layer "B.Cu")
		(net "EXP_IOC_BMC_SCL_14")
	)
	(segment
		(start 321.312032 -173.387512)
		(end 324.800468 -173.387512)
		(width 0.1143)
		(layer "B.Cu")
		(net "EXP_IOC_BMC_SCL_14")
	)
	(segment
		(start 333.502 -172.593)
		(end 333.561182 -172.652182)
		(width 0.1143)
		(layer "B.Cu")
		(net "EXP_IOC_BMC_SCL_14")
	)
	(segment
		(start 324.800468 -173.387512)
		(end 324.831456 -173.4185)
		(width 0.1143)
		(layer "B.Cu")
		(net "EXP_IOC_BMC_SCL_14")
	)
	(segment
		(start 335.290414 -168.006522)
		(end 335.290414 -162.443414)
		(width 0.1143)
		(layer "B.Cu")
		(net "EXP_IOC_BMC_SCL_14")
	)
	(segment
		(start 328.422 -173.355)
		(end 332.105 -173.355)
		(width 0.1143)
		(layer "B.Cu")
		(net "EXP_IOC_BMC_SCL_14")
	)
	(segment
		(start 334.772 -168.524936)
		(end 335.290414 -168.006522)
		(width 0.1143)
		(layer "B.Cu")
		(net "EXP_IOC_BMC_SCL_14")
	)
	(segment
		(start 335.290414 -162.443414)
		(end 329.4253 -156.5783)
		(width 0.1143)
		(layer "B.Cu")
		(net "EXP_IOC_BMC_SCL_14")
	)
	(segment
		(start 333.561182 -172.652182)
		(end 333.950818 -172.652182)
		(width 0.1143)
		(layer "B.Cu")
		(net "EXP_IOC_BMC_SCL_14")
	)
	(segment
		(start 318.4525 -174.625)
		(end 320.074544 -174.625)
		(width 0.1143)
		(layer "B.Cu")
		(net "EXP_IOC_BMC_SCL_14")
	)
	(segment
		(start 327.182734 -149.987)
		(end 327.020428 -149.987)
		(width 0.1143)
		(layer "B.Cu")
		(net "EXP_IOC_BMC_SCL_14")
	)
	(segment
		(start 327.914 -173.355)
		(end 328.422 -173.355)
		(width 0.1143)
		(layer "B.Cu")
		(net "EXP_IOC_BMC_SCL_14")
	)
	(segment
		(start 324.831456 -173.4185)
		(end 325.910956 -173.4185)
		(width 0.1143)
		(layer "B.Cu")
		(net "EXP_IOC_BMC_SCL_14")
	)
	(segment
		(start 329.4253 -156.5783)
		(end 329.4253 -152.229566)
		(width 0.1143)
		(layer "B.Cu")
		(net "EXP_IOC_BMC_SCL_14")
	)
	(segment
		(start 332.867 -172.593)
		(end 333.502 -172.593)
		(width 0.1143)
		(layer "B.Cu")
		(net "EXP_IOC_BMC_SCL_14")
	)
	(segment
		(start 325.910956 -173.4185)
		(end 326.107806 -173.61535)
		(width 0.1143)
		(layer "B.Cu")
		(net "EXP_IOC_BMC_SCL_14")
	)
	(segment
		(start 170.9293 -155.9433)
		(end 170.053 -155.067)
		(width 0.127)
		(layer "In2.Cu")
		(net "EXP_IOC_BMC_SCL_14")
	)
	(segment
		(start 304.173382 -133.171946)
		(end 303.665636 -132.6642)
		(width 0.127)
		(layer "In2.Cu")
		(net "EXP_IOC_BMC_SCL_14")
	)
	(segment
		(start 175.566832 -155.9433)
		(end 170.9293 -155.9433)
		(width 0.127)
		(layer "In2.Cu")
		(net "EXP_IOC_BMC_SCL_14")
	)
	(segment
		(start 176.582832 -154.9273)
		(end 175.566832 -155.9433)
		(width 0.127)
		(layer "In2.Cu")
		(net "EXP_IOC_BMC_SCL_14")
	)
	(segment
		(start 85.34527 -133.73227)
		(end 85.34527 -133.398768)
		(width 0.127)
		(layer "In2.Cu")
		(net "EXP_IOC_BMC_SCL_14")
	)
	(segment
		(start 168.529 -155.067)
		(end 167.64 -155.956)
		(width 0.127)
		(layer "In2.Cu")
		(net "EXP_IOC_BMC_SCL_14")
	)
	(segment
		(start 167.64 -155.956)
		(end 109.855 -155.956)
		(width 0.127)
		(layer "In2.Cu")
		(net "EXP_IOC_BMC_SCL_14")
	)
	(segment
		(start 312.599832 -133.4389)
		(end 312.333132 -133.1722)
		(width 0.127)
		(layer "In2.Cu")
		(net "EXP_IOC_BMC_SCL_14")
	)
	(segment
		(start 77.29347 -126.610618)
		(end 77.29347 -121.3485)
		(width 0.127)
		(layer "In2.Cu")
		(net "EXP_IOC_BMC_SCL_14")
	)
	(segment
		(start 320.339466 -141.178534)
		(end 314.777628 -135.616696)
		(width 0.127)
		(layer "In2.Cu")
		(net "EXP_IOC_BMC_SCL_14")
	)
	(segment
		(start 322.707 -149.987)
		(end 320.339466 -147.619466)
		(width 0.127)
		(layer "In2.Cu")
		(net "EXP_IOC_BMC_SCL_14")
	)
	(segment
		(start 310.21655 -133.171946)
		(end 304.173382 -133.171946)
		(width 0.127)
		(layer "In2.Cu")
		(net "EXP_IOC_BMC_SCL_14")
	)
	(segment
		(start 94.361 -140.462)
		(end 92.202 -140.462)
		(width 0.127)
		(layer "In2.Cu")
		(net "EXP_IOC_BMC_SCL_14")
	)
	(segment
		(start 227.627434 -154.9273)
		(end 176.582832 -154.9273)
		(width 0.127)
		(layer "In2.Cu")
		(net "EXP_IOC_BMC_SCL_14")
	)
	(segment
		(start 88.3793 -136.2583)
		(end 86.422738 -136.2583)
		(width 0.127)
		(layer "In2.Cu")
		(net "EXP_IOC_BMC_SCL_14")
	)
	(segment
		(start 86.422484 -135.267954)
		(end 86.422484 -134.809484)
		(width 0.127)
		(layer "In2.Cu")
		(net "EXP_IOC_BMC_SCL_14")
	)
	(segment
		(start 91.186 -139.065)
		(end 88.3793 -136.2583)
		(width 0.127)
		(layer "In2.Cu")
		(net "EXP_IOC_BMC_SCL_14")
	)
	(segment
		(start 81.994502 -130.048)
		(end 80.730852 -130.048)
		(width 0.127)
		(layer "In2.Cu")
		(net "EXP_IOC_BMC_SCL_14")
	)
	(segment
		(start 92.202 -140.462)
		(end 91.186 -139.446)
		(width 0.127)
		(layer "In2.Cu")
		(net "EXP_IOC_BMC_SCL_14")
	)
	(segment
		(start 287.528 -138.811)
		(end 270.9037 -155.4353)
		(width 0.127)
		(layer "In2.Cu")
		(net "EXP_IOC_BMC_SCL_14")
	)
	(segment
		(start 91.186 -139.446)
		(end 91.186 -139.065)
		(width 0.127)
		(layer "In2.Cu")
		(net "EXP_IOC_BMC_SCL_14")
	)
	(segment
		(start 327.020428 -149.987)
		(end 322.707 -149.987)
		(width 0.127)
		(layer "In2.Cu")
		(net "EXP_IOC_BMC_SCL_14")
	)
	(segment
		(start 109.855 -155.956)
		(end 94.361 -140.462)
		(width 0.127)
		(layer "In2.Cu")
		(net "EXP_IOC_BMC_SCL_14")
	)
	(segment
		(start 310.216804 -133.1722)
		(end 310.21655 -133.171946)
		(width 0.127)
		(layer "In2.Cu")
		(net "EXP_IOC_BMC_SCL_14")
	)
	(segment
		(start 77.29347 -121.3485)
		(end 76.84897 -120.904)
		(width 0.127)
		(layer "In2.Cu")
		(net "EXP_IOC_BMC_SCL_14")
	)
	(segment
		(start 303.665636 -132.6642)
		(end 298.163234 -132.6642)
		(width 0.127)
		(layer "In2.Cu")
		(net "EXP_IOC_BMC_SCL_14")
	)
	(segment
		(start 80.730852 -130.048)
		(end 77.29347 -126.610618)
		(width 0.127)
		(layer "In2.Cu")
		(net "EXP_IOC_BMC_SCL_14")
	)
	(segment
		(start 86.422484 -134.809484)
		(end 85.34527 -133.73227)
		(width 0.127)
		(layer "In2.Cu")
		(net "EXP_IOC_BMC_SCL_14")
	)
	(segment
		(start 314.777628 -135.118094)
		(end 313.098434 -133.4389)
		(width 0.127)
		(layer "In2.Cu")
		(net "EXP_IOC_BMC_SCL_14")
	)
	(segment
		(start 85.34527 -133.398768)
		(end 81.994502 -130.048)
		(width 0.127)
		(layer "In2.Cu")
		(net "EXP_IOC_BMC_SCL_14")
	)
	(segment
		(start 314.777628 -135.616696)
		(end 314.777628 -135.118094)
		(width 0.127)
		(layer "In2.Cu")
		(net "EXP_IOC_BMC_SCL_14")
	)
	(segment
		(start 313.098434 -133.4389)
		(end 312.599832 -133.4389)
		(width 0.127)
		(layer "In2.Cu")
		(net "EXP_IOC_BMC_SCL_14")
	)
	(segment
		(start 86.13267 -135.968232)
		(end 86.13267 -135.557768)
		(width 0.127)
		(layer "In2.Cu")
		(net "EXP_IOC_BMC_SCL_14")
	)
	(segment
		(start 86.13267 -135.557768)
		(end 86.422484 -135.267954)
		(width 0.127)
		(layer "In2.Cu")
		(net "EXP_IOC_BMC_SCL_14")
	)
	(segment
		(start 228.135434 -155.4353)
		(end 227.627434 -154.9273)
		(width 0.127)
		(layer "In2.Cu")
		(net "EXP_IOC_BMC_SCL_14")
	)
	(segment
		(start 292.016434 -138.811)
		(end 287.528 -138.811)
		(width 0.127)
		(layer "In2.Cu")
		(net "EXP_IOC_BMC_SCL_14")
	)
	(segment
		(start 86.422738 -136.2583)
		(end 86.13267 -135.968232)
		(width 0.127)
		(layer "In2.Cu")
		(net "EXP_IOC_BMC_SCL_14")
	)
	(segment
		(start 170.053 -155.067)
		(end 168.529 -155.067)
		(width 0.127)
		(layer "In2.Cu")
		(net "EXP_IOC_BMC_SCL_14")
	)
	(segment
		(start 270.9037 -155.4353)
		(end 228.135434 -155.4353)
		(width 0.127)
		(layer "In2.Cu")
		(net "EXP_IOC_BMC_SCL_14")
	)
	(segment
		(start 320.339466 -147.619466)
		(end 320.339466 -141.178534)
		(width 0.127)
		(layer "In2.Cu")
		(net "EXP_IOC_BMC_SCL_14")
	)
	(segment
		(start 312.333132 -133.1722)
		(end 310.216804 -133.1722)
		(width 0.127)
		(layer "In2.Cu")
		(net "EXP_IOC_BMC_SCL_14")
	)
	(segment
		(start 298.163234 -132.6642)
		(end 292.016434 -138.811)
		(width 0.127)
		(layer "In2.Cu")
		(net "EXP_IOC_BMC_SCL_14")
	)
	(segment
		(start 81.476342 -118.308628)
		(end 81.03997 -118.745)
		(width 0.1143)
		(layer "F.Cu")
		(net "EXP_IOC_BMC_SDA_14")
	)
	(segment
		(start 81.03997 -118.745)
		(end 78.75397 -118.745)
		(width 0.1143)
		(layer "F.Cu")
		(net "EXP_IOC_BMC_SDA_14")
	)
	(segment
		(start 158.369 -154.1526)
		(end 158.115 -154.4066)
		(width 0.1143)
		(layer "F.Cu")
		(net "EXP_IOC_BMC_SDA_14")
	)
	(segment
		(start 159.4485 -154.1526)
		(end 158.369 -154.1526)
		(width 0.1143)
		(layer "F.Cu")
		(net "EXP_IOC_BMC_SDA_14")
	)
	(segment
		(start 158.115 -154.4066)
		(end 158.115 -154.559)
		(width 0.1143)
		(layer "F.Cu")
		(net "EXP_IOC_BMC_SDA_14")
	)
	(segment
		(start 81.897982 -117.506242)
		(end 81.476342 -117.927882)
		(width 0.1143)
		(layer "F.Cu")
		(net "EXP_IOC_BMC_SDA_14")
	)
	(segment
		(start 78.75397 -118.745)
		(end 77.48397 -120.015)
		(width 0.1143)
		(layer "F.Cu")
		(net "EXP_IOC_BMC_SDA_14")
	)
	(segment
		(start 81.476342 -117.927882)
		(end 81.476342 -118.308628)
		(width 0.1143)
		(layer "F.Cu")
		(net "EXP_IOC_BMC_SDA_14")
	)
	(segment
		(start 84.232242 -117.506242)
		(end 81.897982 -117.506242)
		(width 0.1143)
		(layer "F.Cu")
		(net "EXP_IOC_BMC_SDA_14")
	)
	(via
		(at 77.48397 -120.015)
		(size 0.5588)
		(drill 0.3048)
		(layers "F.Cu" "B.Cu")
		(net "EXP_IOC_BMC_SDA_14")
	)
	(via
		(at 158.115 -154.559)
		(size 0.5588)
		(drill 0.3048)
		(layers "F.Cu" "B.Cu")
		(net "EXP_IOC_BMC_SDA_14")
	)
	(via
		(at 328.549 -154.305)
		(size 0.7112)
		(drill 0.3556)
		(layers "F.Cu" "B.Cu")
		(net "EXP_IOC_BMC_SDA_14")
	)
	(via
		(at 327.23709 -150.888192)
		(size 0.5588)
		(drill 0.3048)
		(layers "F.Cu" "B.Cu")
		(net "EXP_IOC_BMC_SDA_14")
	)
	(segment
		(start 331.4573 -172.8597)
		(end 332.775814 -171.541186)
		(width 0.1143)
		(layer "B.Cu")
		(net "EXP_IOC_BMC_SDA_14")
	)
	(segment
		(start 326.313038 -173.12005)
		(end 326.339708 -173.12005)
		(width 0.1143)
		(layer "B.Cu")
		(net "EXP_IOC_BMC_SDA_14")
	)
	(segment
		(start 334.01 -170.763438)
		(end 334.01 -168.586404)
		(width 0.1143)
		(layer "B.Cu")
		(net "EXP_IOC_BMC_SDA_14")
	)
	(segment
		(start 328.726038 -172.8597)
		(end 331.4573 -172.8597)
		(width 0.1143)
		(layer "B.Cu")
		(net "EXP_IOC_BMC_SDA_14")
	)
	(segment
		(start 325.036688 -172.9232)
		(end 326.116188 -172.9232)
		(width 0.1143)
		(layer "B.Cu")
		(net "EXP_IOC_BMC_SDA_14")
	)
	(segment
		(start 328.656188 -172.78985)
		(end 328.726038 -172.8597)
		(width 0.1143)
		(layer "B.Cu")
		(net "EXP_IOC_BMC_SDA_14")
	)
	(segment
		(start 334.795114 -167.80129)
		(end 334.795114 -162.837114)
		(width 0.1143)
		(layer "B.Cu")
		(net "EXP_IOC_BMC_SDA_14")
	)
	(segment
		(start 333.232252 -171.541186)
		(end 334.01 -170.763438)
		(width 0.1143)
		(layer "B.Cu")
		(net "EXP_IOC_BMC_SDA_14")
	)
	(segment
		(start 320.390012 -173.609)
		(end 321.1068 -172.892212)
		(width 0.1143)
		(layer "B.Cu")
		(net "EXP_IOC_BMC_SDA_14")
	)
	(segment
		(start 334.01 -168.586404)
		(end 334.795114 -167.80129)
		(width 0.1143)
		(layer "B.Cu")
		(net "EXP_IOC_BMC_SDA_14")
	)
	(segment
		(start 327.708768 -172.8597)
		(end 328.117962 -172.8597)
		(width 0.1143)
		(layer "B.Cu")
		(net "EXP_IOC_BMC_SDA_14")
	)
	(segment
		(start 318.4525 -173.609)
		(end 320.390012 -173.609)
		(width 0.1143)
		(layer "B.Cu")
		(net "EXP_IOC_BMC_SDA_14")
	)
	(segment
		(start 328.549 -152.053798)
		(end 328.549 -154.305)
		(width 0.1143)
		(layer "B.Cu")
		(net "EXP_IOC_BMC_SDA_14")
	)
	(segment
		(start 327.23709 -150.888192)
		(end 327.383394 -150.888192)
		(width 0.1143)
		(layer "B.Cu")
		(net "EXP_IOC_BMC_SDA_14")
	)
	(segment
		(start 327.391268 -173.1772)
		(end 327.708768 -172.8597)
		(width 0.1143)
		(layer "B.Cu")
		(net "EXP_IOC_BMC_SDA_14")
	)
	(segment
		(start 326.339708 -173.12005)
		(end 326.396858 -173.1772)
		(width 0.1143)
		(layer "B.Cu")
		(net "EXP_IOC_BMC_SDA_14")
	)
	(segment
		(start 332.775814 -171.541186)
		(end 333.232252 -171.541186)
		(width 0.1143)
		(layer "B.Cu")
		(net "EXP_IOC_BMC_SDA_14")
	)
	(segment
		(start 321.1068 -172.892212)
		(end 325.0057 -172.892212)
		(width 0.1143)
		(layer "B.Cu")
		(net "EXP_IOC_BMC_SDA_14")
	)
	(segment
		(start 326.396858 -173.1772)
		(end 327.391268 -173.1772)
		(width 0.1143)
		(layer "B.Cu")
		(net "EXP_IOC_BMC_SDA_14")
	)
	(segment
		(start 325.0057 -172.892212)
		(end 325.036688 -172.9232)
		(width 0.1143)
		(layer "B.Cu")
		(net "EXP_IOC_BMC_SDA_14")
	)
	(segment
		(start 328.549 -156.591)
		(end 328.549 -154.305)
		(width 0.1143)
		(layer "B.Cu")
		(net "EXP_IOC_BMC_SDA_14")
	)
	(segment
		(start 327.383394 -150.888192)
		(end 328.549 -152.053798)
		(width 0.1143)
		(layer "B.Cu")
		(net "EXP_IOC_BMC_SDA_14")
	)
	(segment
		(start 328.117962 -172.8597)
		(end 328.187812 -172.78985)
		(width 0.1143)
		(layer "B.Cu")
		(net "EXP_IOC_BMC_SDA_14")
	)
	(segment
		(start 326.116188 -172.9232)
		(end 326.313038 -173.12005)
		(width 0.1143)
		(layer "B.Cu")
		(net "EXP_IOC_BMC_SDA_14")
	)
	(segment
		(start 328.187812 -172.78985)
		(end 328.656188 -172.78985)
		(width 0.1143)
		(layer "B.Cu")
		(net "EXP_IOC_BMC_SDA_14")
	)
	(segment
		(start 334.795114 -162.837114)
		(end 328.549 -156.591)
		(width 0.1143)
		(layer "B.Cu")
		(net "EXP_IOC_BMC_SDA_14")
	)
	(segment
		(start 227.838 -154.4193)
		(end 228.346 -154.9273)
		(width 0.127)
		(layer "In2.Cu")
		(net "EXP_IOC_BMC_SDA_14")
	)
	(segment
		(start 89.027 -135.632698)
		(end 88.230202 -134.8359)
		(width 0.127)
		(layer "In2.Cu")
		(net "EXP_IOC_BMC_SDA_14")
	)
	(segment
		(start 78.23327 -126.483618)
		(end 78.23327 -126.220982)
		(width 0.127)
		(layer "In2.Cu")
		(net "EXP_IOC_BMC_SDA_14")
	)
	(segment
		(start 303.876202 -132.1562)
		(end 304.383948 -132.663946)
		(width 0.127)
		(layer "In2.Cu")
		(net "EXP_IOC_BMC_SDA_14")
	)
	(segment
		(start 310.42737 -132.6642)
		(end 312.543698 -132.6642)
		(width 0.127)
		(layer "In2.Cu")
		(net "EXP_IOC_BMC_SDA_14")
	)
	(segment
		(start 176.372266 -154.4193)
		(end 227.838 -154.4193)
		(width 0.127)
		(layer "In2.Cu")
		(net "EXP_IOC_BMC_SDA_14")
	)
	(segment
		(start 312.810398 -132.9309)
		(end 313.309 -132.9309)
		(width 0.127)
		(layer "In2.Cu")
		(net "EXP_IOC_BMC_SDA_14")
	)
	(segment
		(start 291.805868 -138.303)
		(end 297.952668 -132.1562)
		(width 0.127)
		(layer "In2.Cu")
		(net "EXP_IOC_BMC_SDA_14")
	)
	(segment
		(start 304.383948 -132.663946)
		(end 310.427116 -132.663946)
		(width 0.127)
		(layer "In2.Cu")
		(net "EXP_IOC_BMC_SDA_14")
	)
	(segment
		(start 315.285628 -135.40613)
		(end 320.847466 -140.967968)
		(width 0.127)
		(layer "In2.Cu")
		(net "EXP_IOC_BMC_SDA_14")
	)
	(segment
		(start 110.109 -155.448)
		(end 94.615 -139.954)
		(width 0.127)
		(layer "In2.Cu")
		(net "EXP_IOC_BMC_SDA_14")
	)
	(segment
		(start 144.907 -155.448)
		(end 110.109 -155.448)
		(width 0.127)
		(layer "In2.Cu")
		(net "EXP_IOC_BMC_SDA_14")
	)
	(segment
		(start 77.864716 -120.395746)
		(end 77.48397 -120.015)
		(width 0.127)
		(layer "In2.Cu")
		(net "EXP_IOC_BMC_SDA_14")
	)
	(segment
		(start 91.948 -139.104116)
		(end 89.027 -136.183116)
		(width 0.127)
		(layer "In2.Cu")
		(net "EXP_IOC_BMC_SDA_14")
	)
	(segment
		(start 81.171034 -129.421382)
		(end 78.23327 -126.483618)
		(width 0.127)
		(layer "In2.Cu")
		(net "EXP_IOC_BMC_SDA_14")
	)
	(segment
		(start 327.515728 -149.733)
		(end 327.515728 -150.609554)
		(width 0.127)
		(layer "In2.Cu")
		(net "EXP_IOC_BMC_SDA_14")
	)
	(segment
		(start 312.543698 -132.6642)
		(end 312.810398 -132.9309)
		(width 0.127)
		(layer "In2.Cu")
		(net "EXP_IOC_BMC_SDA_14")
	)
	(segment
		(start 94.615 -139.954)
		(end 92.456 -139.954)
		(width 0.127)
		(layer "In2.Cu")
		(net "EXP_IOC_BMC_SDA_14")
	)
	(segment
		(start 327.007728 -149.225)
		(end 327.515728 -149.733)
		(width 0.127)
		(layer "In2.Cu")
		(net "EXP_IOC_BMC_SDA_14")
	)
	(segment
		(start 327.515728 -150.609554)
		(end 327.23709 -150.888192)
		(width 0.127)
		(layer "In2.Cu")
		(net "EXP_IOC_BMC_SDA_14")
	)
	(segment
		(start 287.103566 -138.303)
		(end 291.805868 -138.303)
		(width 0.127)
		(layer "In2.Cu")
		(net "EXP_IOC_BMC_SDA_14")
	)
	(segment
		(start 78.23327 -126.220982)
		(end 77.864716 -125.852428)
		(width 0.127)
		(layer "In2.Cu")
		(net "EXP_IOC_BMC_SDA_14")
	)
	(segment
		(start 85.90407 -133.544818)
		(end 85.90407 -133.239002)
		(width 0.127)
		(layer "In2.Cu")
		(net "EXP_IOC_BMC_SDA_14")
	)
	(segment
		(start 145.796 -154.559)
		(end 144.907 -155.448)
		(width 0.127)
		(layer "In2.Cu")
		(net "EXP_IOC_BMC_SDA_14")
	)
	(segment
		(start 228.346 -154.9273)
		(end 270.479266 -154.9273)
		(width 0.127)
		(layer "In2.Cu")
		(net "EXP_IOC_BMC_SDA_14")
	)
	(segment
		(start 158.115 -154.559)
		(end 176.232566 -154.559)
		(width 0.127)
		(layer "In2.Cu")
		(net "EXP_IOC_BMC_SDA_14")
	)
	(segment
		(start 320.847466 -140.967968)
		(end 320.847466 -146.984466)
		(width 0.127)
		(layer "In2.Cu")
		(net "EXP_IOC_BMC_SDA_14")
	)
	(segment
		(start 87.195152 -134.8359)
		(end 85.90407 -133.544818)
		(width 0.127)
		(layer "In2.Cu")
		(net "EXP_IOC_BMC_SDA_14")
	)
	(segment
		(start 270.479266 -154.9273)
		(end 287.103566 -138.303)
		(width 0.127)
		(layer "In2.Cu")
		(net "EXP_IOC_BMC_SDA_14")
	)
	(segment
		(start 323.088 -149.225)
		(end 327.007728 -149.225)
		(width 0.127)
		(layer "In2.Cu")
		(net "EXP_IOC_BMC_SDA_14")
	)
	(segment
		(start 82.08645 -129.421382)
		(end 81.171034 -129.421382)
		(width 0.127)
		(layer "In2.Cu")
		(net "EXP_IOC_BMC_SDA_14")
	)
	(segment
		(start 158.115 -154.559)
		(end 145.796 -154.559)
		(width 0.127)
		(layer "In2.Cu")
		(net "EXP_IOC_BMC_SDA_14")
	)
	(segment
		(start 89.027 -136.183116)
		(end 89.027 -135.632698)
		(width 0.127)
		(layer "In2.Cu")
		(net "EXP_IOC_BMC_SDA_14")
	)
	(segment
		(start 85.90407 -133.239002)
		(end 82.08645 -129.421382)
		(width 0.127)
		(layer "In2.Cu")
		(net "EXP_IOC_BMC_SDA_14")
	)
	(segment
		(start 310.427116 -132.663946)
		(end 310.42737 -132.6642)
		(width 0.127)
		(layer "In2.Cu")
		(net "EXP_IOC_BMC_SDA_14")
	)
	(segment
		(start 313.309 -132.9309)
		(end 315.285628 -134.907528)
		(width 0.127)
		(layer "In2.Cu")
		(net "EXP_IOC_BMC_SDA_14")
	)
	(segment
		(start 297.952668 -132.1562)
		(end 303.876202 -132.1562)
		(width 0.127)
		(layer "In2.Cu")
		(net "EXP_IOC_BMC_SDA_14")
	)
	(segment
		(start 88.230202 -134.8359)
		(end 87.195152 -134.8359)
		(width 0.127)
		(layer "In2.Cu")
		(net "EXP_IOC_BMC_SDA_14")
	)
	(segment
		(start 91.948 -139.446)
		(end 91.948 -139.104116)
		(width 0.127)
		(layer "In2.Cu")
		(net "EXP_IOC_BMC_SDA_14")
	)
	(segment
		(start 92.456 -139.954)
		(end 91.948 -139.446)
		(width 0.127)
		(layer "In2.Cu")
		(net "EXP_IOC_BMC_SDA_14")
	)
	(segment
		(start 320.847466 -146.984466)
		(end 323.088 -149.225)
		(width 0.127)
		(layer "In2.Cu")
		(net "EXP_IOC_BMC_SDA_14")
	)
	(segment
		(start 315.285628 -134.907528)
		(end 315.285628 -135.40613)
		(width 0.127)
		(layer "In2.Cu")
		(net "EXP_IOC_BMC_SDA_14")
	)
	(segment
		(start 176.232566 -154.559)
		(end 176.372266 -154.4193)
		(width 0.127)
		(layer "In2.Cu")
		(net "EXP_IOC_BMC_SDA_14")
	)
	(segment
		(start 77.864716 -125.852428)
		(end 77.864716 -120.395746)
		(width 0.127)
		(layer "In2.Cu")
		(net "EXP_IOC_BMC_SDA_14")
	)
	(segment
		(start 303.911 -189.5729)
		(end 303.911 -189.357)
		(width 0.1143)
		(layer "F.Cu")
		(net "UART COUNT")
	)
	(segment
		(start 301.625 -191.4525)
		(end 300.736 -192.3415)
		(width 0.1143)
		(layer "F.Cu")
		(net "UART COUNT")
	)
	(segment
		(start 302.768 -191.4525)
		(end 302.801528 -190.682372)
		(width 0.1143)
		(layer "F.Cu")
		(net "UART COUNT")
	)
	(segment
		(start 302.801528 -190.682372)
		(end 303.911 -189.5729)
		(width 0.1143)
		(layer "F.Cu")
		(net "UART COUNT")
	)
	(segment
		(start 302.768 -191.4525)
		(end 301.752 -191.4525)
		(width 0.1143)
		(layer "F.Cu")
		(net "UART COUNT")
	)
	(segment
		(start 301.752 -191.4525)
		(end 301.625 -191.4525)
		(width 0.1143)
		(layer "F.Cu")
		(net "UART COUNT")
	)
	(via
		(at 303.911 -189.357)
		(size 0.5588)
		(drill 0.3048)
		(layers "F.Cu" "B.Cu")
		(net "UART COUNT")
	)
	(via
		(at 315.722 -188.722)
		(size 0.5588)
		(drill 0.3048)
		(layers "F.Cu" "B.Cu")
		(net "UART COUNT")
	)
	(via
		(at 310.261 -137.033)
		(size 0.5588)
		(drill 0.3048)
		(layers "F.Cu" "B.Cu")
		(net "UART COUNT")
	)
	(segment
		(start 306.185824 -189.738)
		(end 305.816 -189.368176)
		(width 0.1143)
		(layer "B.Cu")
		(net "UART COUNT")
	)
	(segment
		(start 311.277 -189.738)
		(end 306.185824 -189.738)
		(width 0.1143)
		(layer "B.Cu")
		(net "UART COUNT")
	)
	(segment
		(start 305.816 -189.368176)
		(end 303.922176 -189.368176)
		(width 0.1143)
		(layer "B.Cu")
		(net "UART COUNT")
	)
	(segment
		(start 315.722 -188.722)
		(end 315.075824 -189.368176)
		(width 0.1143)
		(layer "B.Cu")
		(net "UART COUNT")
	)
	(segment
		(start 311.646824 -189.368176)
		(end 311.277 -189.738)
		(width 0.1143)
		(layer "B.Cu")
		(net "UART COUNT")
	)
	(segment
		(start 303.922176 -189.368176)
		(end 303.911 -189.357)
		(width 0.1143)
		(layer "B.Cu")
		(net "UART COUNT")
	)
	(segment
		(start 315.075824 -189.368176)
		(end 311.646824 -189.368176)
		(width 0.1143)
		(layer "B.Cu")
		(net "UART COUNT")
	)
	(segment
		(start 314.7187 -186.357768)
		(end 315.468 -185.608468)
		(width 0.127)
		(layer "In2.Cu")
		(net "UART COUNT")
	)
	(segment
		(start 313.181746 -173.438312)
		(end 313.181746 -173.017688)
		(width 0.127)
		(layer "In2.Cu")
		(net "UART COUNT")
	)
	(segment
		(start 315.341 -176.149)
		(end 313.436 -174.244)
		(width 0.127)
		(layer "In2.Cu")
		(net "UART COUNT")
	)
	(segment
		(start 314.7187 -186.768232)
		(end 314.7187 -186.357768)
		(width 0.127)
		(layer "In2.Cu")
		(net "UART COUNT")
	)
	(segment
		(start 310.388 -140.725906)
		(end 310.388 -137.16)
		(width 0.127)
		(layer "In2.Cu")
		(net "UART COUNT")
	)
	(segment
		(start 315.341 -181.801262)
		(end 315.341 -176.149)
		(width 0.127)
		(layer "In2.Cu")
		(net "UART COUNT")
	)
	(segment
		(start 315.468 -181.928262)
		(end 315.341 -181.801262)
		(width 0.127)
		(layer "In2.Cu")
		(net "UART COUNT")
	)
	(segment
		(start 313.436 -172.763434)
		(end 313.436 -143.773906)
		(width 0.127)
		(layer "In2.Cu")
		(net "UART COUNT")
	)
	(segment
		(start 315.468 -185.608468)
		(end 315.468 -181.928262)
		(width 0.127)
		(layer "In2.Cu")
		(net "UART COUNT")
	)
	(segment
		(start 313.436 -174.244)
		(end 313.436 -173.692566)
		(width 0.127)
		(layer "In2.Cu")
		(net "UART COUNT")
	)
	(segment
		(start 315.722 -188.722)
		(end 314.8203 -187.8203)
		(width 0.127)
		(layer "In2.Cu")
		(net "UART COUNT")
	)
	(segment
		(start 313.181746 -173.017688)
		(end 313.436 -172.763434)
		(width 0.127)
		(layer "In2.Cu")
		(net "UART COUNT")
	)
	(segment
		(start 313.436 -143.773906)
		(end 310.388 -140.725906)
		(width 0.127)
		(layer "In2.Cu")
		(net "UART COUNT")
	)
	(segment
		(start 314.8203 -187.8203)
		(end 314.8203 -186.869832)
		(width 0.127)
		(layer "In2.Cu")
		(net "UART COUNT")
	)
	(segment
		(start 314.8203 -186.869832)
		(end 314.7187 -186.768232)
		(width 0.127)
		(layer "In2.Cu")
		(net "UART COUNT")
	)
	(segment
		(start 313.436 -173.692566)
		(end 313.181746 -173.438312)
		(width 0.127)
		(layer "In2.Cu")
		(net "UART COUNT")
	)
	(segment
		(start 310.388 -137.16)
		(end 310.261 -137.033)
		(width 0.127)
		(layer "In2.Cu")
		(net "UART COUNT")
	)
	(segment
		(start 306.705 -100.391468)
		(end 314.640468 -92.456)
		(width 0.127)
		(layer "In5.Cu")
		(net "UART COUNT")
	)
	(segment
		(start 310.261 -136.652)
		(end 306.705 -133.096)
		(width 0.127)
		(layer "In5.Cu")
		(net "UART COUNT")
	)
	(segment
		(start 306.705 -110.236)
		(end 306.705 -100.391468)
		(width 0.127)
		(layer "In5.Cu")
		(net "UART COUNT")
	)
	(segment
		(start 307.5813 -111.1123)
		(end 306.705 -110.236)
		(width 0.127)
		(layer "In5.Cu")
		(net "UART COUNT")
	)
	(segment
		(start 334.047084 -12.954)
		(end 337.649566 -12.954)
		(width 0.127)
		(layer "In5.Cu")
		(net "UART COUNT")
	)
	(segment
		(start 310.261 -137.033)
		(end 310.261 -136.652)
		(width 0.127)
		(layer "In5.Cu")
		(net "UART COUNT")
	)
	(segment
		(start 321.2592 -89.662)
		(end 323.55917 -89.662)
		(width 0.127)
		(layer "In5.Cu")
		(net "UART COUNT")
	)
	(segment
		(start 314.640468 -92.456)
		(end 318.4652 -92.456)
		(width 0.127)
		(layer "In5.Cu")
		(net "UART COUNT")
	)
	(segment
		(start 337.649566 -12.954)
		(end 342.278462 -8.325104)
		(width 0.127)
		(layer "In5.Cu")
		(net "UART COUNT")
	)
	(segment
		(start 325.755 -87.46617)
		(end 325.755 -21.246084)
		(width 0.127)
		(layer "In5.Cu")
		(net "UART COUNT")
	)
	(segment
		(start 342.810084 -6.326124)
		(end 341.984584 -5.500624)
		(width 0.127)
		(layer "In5.Cu")
		(net "UART COUNT")
	)
	(segment
		(start 318.4652 -92.456)
		(end 321.2592 -89.662)
		(width 0.127)
		(layer "In5.Cu")
		(net "UART COUNT")
	)
	(segment
		(start 342.278462 -8.325104)
		(end 342.326722 -8.325104)
		(width 0.127)
		(layer "In5.Cu")
		(net "UART COUNT")
	)
	(segment
		(start 323.55917 -89.662)
		(end 325.755 -87.46617)
		(width 0.127)
		(layer "In5.Cu")
		(net "UART COUNT")
	)
	(segment
		(start 342.326722 -8.325104)
		(end 342.810084 -7.841742)
		(width 0.127)
		(layer "In5.Cu")
		(net "UART COUNT")
	)
	(segment
		(start 342.810084 -7.841742)
		(end 342.810084 -6.326124)
		(width 0.127)
		(layer "In5.Cu")
		(net "UART COUNT")
	)
	(segment
		(start 325.755 -21.246084)
		(end 334.047084 -12.954)
		(width 0.127)
		(layer "In5.Cu")
		(net "UART COUNT")
	)
	(segment
		(start 306.705 -112.522)
		(end 307.5813 -111.6457)
		(width 0.127)
		(layer "In5.Cu")
		(net "UART COUNT")
	)
	(segment
		(start 307.5813 -111.6457)
		(end 307.5813 -111.1123)
		(width 0.127)
		(layer "In5.Cu")
		(net "UART COUNT")
	)
	(segment
		(start 306.705 -133.096)
		(end 306.705 -112.522)
		(width 0.127)
		(layer "In5.Cu")
		(net "UART COUNT")
	)
	(segment
		(start 74.390758 -53.123592)
		(end 84.12988 -43.38447)
		(width 0.1016)
		(layer "F.Cu")
		(net "IOC_RAID_TX_N5")
	)
	(segment
		(start 18.290286 -115.286028)
		(end 27.04973 -115.286028)
		(width 0.1016)
		(layer "F.Cu")
		(net "IOC_RAID_TX_N5")
	)
	(segment
		(start 74.111866 -69.27596)
		(end 74.111866 -53.796946)
		(width 0.1016)
		(layer "F.Cu")
		(net "IOC_RAID_TX_N5")
	)
	(segment
		(start 14.00048 -102.489762)
		(end 14.00048 -103.916734)
		(width 0.1016)
		(layer "F.Cu")
		(net "IOC_RAID_TX_N5")
	)
	(segment
		(start 29.743654 -114.170206)
		(end 73.74001 -70.17385)
		(width 0.1016)
		(layer "F.Cu")
		(net "IOC_RAID_TX_N5")
	)
	(segment
		(start 13.77188 -104.550972)
		(end 13.77188 -110.767622)
		(width 0.1016)
		(layer "F.Cu")
		(net "IOC_RAID_TX_N5")
	)
	(segment
		(start 84.868766 -43.0784)
		(end 85.849714 -43.0784)
		(width 0.1016)
		(layer "F.Cu")
		(net "IOC_RAID_TX_N5")
	)
	(arc
		(start 14.00048 -103.916734)
		(mid 13.974282 -104.048442)
		(end 13.899642 -104.160066)
		(width 0.1016)
		(layer "F.Cu")
		(net "IOC_RAID_TX_N5")
	)
	(arc
		(start 13.77188 -110.767622)
		(mid 15.09529 -113.962618)
		(end 18.290286 -115.286028)
		(width 0.1016)
		(layer "F.Cu")
		(net "IOC_RAID_TX_N5")
	)
	(arc
		(start 13.899642 -104.160066)
		(mid 13.804599 -104.345338)
		(end 13.77188 -104.550972)
		(width 0.1016)
		(layer "F.Cu")
		(net "IOC_RAID_TX_N5")
	)
	(arc
		(start 27.04973 -115.286028)
		(mid 28.507671 -114.996043)
		(end 29.743654 -114.170206)
		(width 0.1016)
		(layer "F.Cu")
		(net "IOC_RAID_TX_N5")
	)
	(arc
		(start 85.849714 -43.0784)
		(mid 86.04888 -43.038783)
		(end 86.21776 -42.926)
		(width 0.1016)
		(layer "F.Cu")
		(net "IOC_RAID_TX_N5")
	)
	(arc
		(start 73.74001 -70.17385)
		(mid 74.015216 -69.76188)
		(end 74.111866 -69.27596)
		(width 0.1016)
		(layer "F.Cu")
		(net "IOC_RAID_TX_N5")
	)
	(arc
		(start 84.12988 -43.38447)
		(mid 84.468884 -43.157955)
		(end 84.868766 -43.0784)
		(width 0.1016)
		(layer "F.Cu")
		(net "IOC_RAID_TX_N5")
	)
	(arc
		(start 74.111866 -53.796946)
		(mid 74.184336 -53.432523)
		(end 74.390758 -53.123592)
		(width 0.1016)
		(layer "F.Cu")
		(net "IOC_RAID_TX_N5")
	)
	(segment
		(start 16.17091 -104.419908)
		(end 16.17091 -109.20222)
		(width 0.1016)
		(layer "F.Cu")
		(net "IOC_RAID_TX_N6")
	)
	(segment
		(start 72.441562 -52.64785)
		(end 83.439762 -41.64965)
		(width 0.1016)
		(layer "F.Cu")
		(net "IOC_RAID_TX_N6")
	)
	(segment
		(start 16.39951 -102.489762)
		(end 16.39951 -103.867966)
		(width 0.1016)
		(layer "F.Cu")
		(net "IOC_RAID_TX_N6")
	)
	(segment
		(start 20.476718 -113.508028)
		(end 26.28773 -113.508028)
		(width 0.1016)
		(layer "F.Cu")
		(net "IOC_RAID_TX_N6")
	)
	(segment
		(start 72.064626 -68.7832)
		(end 72.064626 -53.557932)
		(width 0.1016)
		(layer "F.Cu")
		(net "IOC_RAID_TX_N6")
	)
	(segment
		(start 84.129626 -41.3639)
		(end 86.00313 -41.3639)
		(width 0.1016)
		(layer "F.Cu")
		(net "IOC_RAID_TX_N6")
	)
	(segment
		(start 28.981654 -112.392206)
		(end 71.69277 -69.68109)
		(width 0.1016)
		(layer "F.Cu")
		(net "IOC_RAID_TX_N6")
	)
	(arc
		(start 83.439762 -41.64965)
		(mid 83.756289 -41.438217)
		(end 84.129626 -41.3639)
		(width 0.1016)
		(layer "F.Cu")
		(net "IOC_RAID_TX_N6")
	)
	(arc
		(start 86.00313 -41.3639)
		(mid 86.119286 -41.340795)
		(end 86.21776 -41.275)
		(width 0.1016)
		(layer "F.Cu")
		(net "IOC_RAID_TX_N6")
	)
	(arc
		(start 72.064626 -53.557932)
		(mid 72.162579 -53.065397)
		(end 72.441562 -52.64785)
		(width 0.1016)
		(layer "F.Cu")
		(net "IOC_RAID_TX_N6")
	)
	(arc
		(start 71.69277 -69.68109)
		(mid 71.967976 -69.26912)
		(end 72.064626 -68.7832)
		(width 0.1016)
		(layer "F.Cu")
		(net "IOC_RAID_TX_N6")
	)
	(arc
		(start 16.17091 -109.20222)
		(mid 17.432052 -112.246886)
		(end 20.476718 -113.508028)
		(width 0.1016)
		(layer "F.Cu")
		(net "IOC_RAID_TX_N6")
	)
	(arc
		(start 16.39951 -103.867966)
		(mid 16.368014 -104.026307)
		(end 16.278352 -104.160574)
		(width 0.1016)
		(layer "F.Cu")
		(net "IOC_RAID_TX_N6")
	)
	(arc
		(start 26.28773 -113.508028)
		(mid 27.745671 -113.218043)
		(end 28.981654 -112.392206)
		(width 0.1016)
		(layer "F.Cu")
		(net "IOC_RAID_TX_N6")
	)
	(arc
		(start 16.278352 -104.160574)
		(mid 16.19885 -104.279557)
		(end 16.17091 -104.419908)
		(width 0.1016)
		(layer "F.Cu")
		(net "IOC_RAID_TX_N6")
	)
	(segment
		(start 72.684132 -52.89042)
		(end 83.682332 -41.89222)
		(width 0.1016)
		(layer "F.Cu")
		(net "IOC_RAID_TX_P6")
	)
	(segment
		(start 29.224478 -112.634522)
		(end 71.935086 -69.923914)
		(width 0.1016)
		(layer "F.Cu")
		(net "IOC_RAID_TX_P6")
	)
	(segment
		(start 20.476718 -113.850928)
		(end 26.287984 -113.850928)
		(width 0.1016)
		(layer "F.Cu")
		(net "IOC_RAID_TX_P6")
	)
	(segment
		(start 84.389468 -41.814496)
		(end 84.401406 -41.82618)
		(width 0.1016)
		(layer "F.Cu")
		(net "IOC_RAID_TX_P6")
	)
	(segment
		(start 84.640166 -41.94556)
		(end 84.944966 -41.94556)
		(width 0.1016)
		(layer "F.Cu")
		(net "IOC_RAID_TX_P6")
	)
	(segment
		(start 85.422486 -41.7068)
		(end 85.727286 -41.7068)
		(width 0.1016)
		(layer "F.Cu")
		(net "IOC_RAID_TX_P6")
	)
	(segment
		(start 72.646286 -55.408322)
		(end 72.646286 -55.103522)
		(width 0.1016)
		(layer "F.Cu")
		(net "IOC_RAID_TX_P6")
	)
	(segment
		(start 15.59941 -102.489762)
		(end 15.59941 -103.825802)
		(width 0.1016)
		(layer "F.Cu")
		(net "IOC_RAID_TX_P6")
	)
	(segment
		(start 72.407526 -68.783454)
		(end 72.407526 -55.885842)
		(width 0.1016)
		(layer "F.Cu")
		(net "IOC_RAID_TX_P6")
	)
	(segment
		(start 15.82801 -104.458516)
		(end 15.82801 -109.20222)
		(width 0.1016)
		(layer "F.Cu")
		(net "IOC_RAID_TX_P6")
	)
	(segment
		(start 72.407526 -54.626002)
		(end 72.407526 -53.558186)
		(width 0.1016)
		(layer "F.Cu")
		(net "IOC_RAID_TX_P6")
	)
	(arc
		(start 72.646286 -55.103522)
		(mid 72.615794 -54.969529)
		(end 72.526906 -54.864762)
		(width 0.1016)
		(layer "F.Cu")
		(net "IOC_RAID_TX_P6")
	)
	(arc
		(start 84.944966 -41.94556)
		(mid 85.078959 -41.915068)
		(end 85.183726 -41.82618)
		(width 0.1016)
		(layer "F.Cu")
		(net "IOC_RAID_TX_P6")
	)
	(arc
		(start 72.526906 -54.864762)
		(mid 72.438112 -54.759948)
		(end 72.407526 -54.626002)
		(width 0.1016)
		(layer "F.Cu")
		(net "IOC_RAID_TX_P6")
	)
	(arc
		(start 83.682332 -41.89222)
		(mid 83.887669 -41.755018)
		(end 84.12988 -41.7068)
		(width 0.1016)
		(layer "F.Cu")
		(net "IOC_RAID_TX_P6")
	)
	(arc
		(start 26.287984 -113.850928)
		(mid 27.87723 -113.534807)
		(end 29.224478 -112.634522)
		(width 0.1016)
		(layer "F.Cu")
		(net "IOC_RAID_TX_P6")
	)
	(arc
		(start 15.765526 -104.226868)
		(mid 15.812143 -104.338544)
		(end 15.82801 -104.458516)
		(width 0.1016)
		(layer "F.Cu")
		(net "IOC_RAID_TX_P6")
	)
	(arc
		(start 15.59941 -103.825802)
		(mid 15.642584 -104.042853)
		(end 15.765526 -104.226868)
		(width 0.1016)
		(layer "F.Cu")
		(net "IOC_RAID_TX_P6")
	)
	(arc
		(start 72.407526 -55.885842)
		(mid 72.438018 -55.751849)
		(end 72.526906 -55.647082)
		(width 0.1016)
		(layer "F.Cu")
		(net "IOC_RAID_TX_P6")
	)
	(arc
		(start 84.12988 -41.7068)
		(mid 84.27038 -41.734841)
		(end 84.389468 -41.814496)
		(width 0.1016)
		(layer "F.Cu")
		(net "IOC_RAID_TX_P6")
	)
	(arc
		(start 84.401406 -41.82618)
		(mid 84.50622 -41.914974)
		(end 84.640166 -41.94556)
		(width 0.1016)
		(layer "F.Cu")
		(net "IOC_RAID_TX_P6")
	)
	(arc
		(start 72.407526 -53.558186)
		(mid 72.479412 -53.19679)
		(end 72.684132 -52.89042)
		(width 0.1016)
		(layer "F.Cu")
		(net "IOC_RAID_TX_P6")
	)
	(arc
		(start 85.727286 -41.7068)
		(mid 85.992744 -41.759603)
		(end 86.21776 -41.91)
		(width 0.1016)
		(layer "F.Cu")
		(net "IOC_RAID_TX_P6")
	)
	(arc
		(start 15.82801 -109.20222)
		(mid 17.189585 -112.489353)
		(end 20.476718 -113.850928)
		(width 0.1016)
		(layer "F.Cu")
		(net "IOC_RAID_TX_P6")
	)
	(arc
		(start 85.183726 -41.82618)
		(mid 85.28854 -41.737386)
		(end 85.422486 -41.7068)
		(width 0.1016)
		(layer "F.Cu")
		(net "IOC_RAID_TX_P6")
	)
	(arc
		(start 72.526906 -55.647082)
		(mid 72.6157 -55.542268)
		(end 72.646286 -55.408322)
		(width 0.1016)
		(layer "F.Cu")
		(net "IOC_RAID_TX_P6")
	)
	(arc
		(start 71.935086 -69.923914)
		(mid 72.284709 -69.400667)
		(end 72.407526 -68.783454)
		(width 0.1016)
		(layer "F.Cu")
		(net "IOC_RAID_TX_P6")
	)
	(segment
		(start 18.57121 -104.456738)
		(end 18.57121 -108.838238)
		(width 0.1016)
		(layer "F.Cu")
		(net "IOC_RAID_TX_N7")
	)
	(segment
		(start 28.092654 -110.614206)
		(end 69.97827 -68.72859)
		(width 0.1016)
		(layer "F.Cu")
		(net "IOC_RAID_TX_N7")
	)
	(segment
		(start 70.49897 -51.80838)
		(end 82.340958 -39.966392)
		(width 0.1016)
		(layer "F.Cu")
		(net "IOC_RAID_TX_N7")
	)
	(segment
		(start 21.463 -111.730028)
		(end 25.39873 -111.730028)
		(width 0.1016)
		(layer "F.Cu")
		(net "IOC_RAID_TX_N7")
	)
	(segment
		(start 70.350126 -67.8307)
		(end 70.350126 -52.16779)
		(width 0.1016)
		(layer "F.Cu")
		(net "IOC_RAID_TX_N7")
	)
	(segment
		(start 82.769456 -39.7891)
		(end 85.819234 -39.7891)
		(width 0.1016)
		(layer "F.Cu")
		(net "IOC_RAID_TX_N7")
	)
	(segment
		(start 18.79981 -102.489762)
		(end 18.79981 -103.904796)
		(width 0.1016)
		(layer "F.Cu")
		(net "IOC_RAID_TX_N7")
	)
	(arc
		(start 25.39873 -111.730028)
		(mid 26.856671 -111.440043)
		(end 28.092654 -110.614206)
		(width 0.1016)
		(layer "F.Cu")
		(net "IOC_RAID_TX_N7")
	)
	(arc
		(start 82.340958 -39.966392)
		(mid 82.53757 -39.835113)
		(end 82.769456 -39.7891)
		(width 0.1016)
		(layer "F.Cu")
		(net "IOC_RAID_TX_N7")
	)
	(arc
		(start 85.819234 -39.7891)
		(mid 86.034924 -39.746197)
		(end 86.21776 -39.624)
		(width 0.1016)
		(layer "F.Cu")
		(net "IOC_RAID_TX_N7")
	)
	(arc
		(start 70.350126 -52.16779)
		(mid 70.388815 -51.97329)
		(end 70.49897 -51.80838)
		(width 0.1016)
		(layer "F.Cu")
		(net "IOC_RAID_TX_N7")
	)
	(arc
		(start 69.97827 -68.72859)
		(mid 70.253476 -68.31662)
		(end 70.350126 -67.8307)
		(width 0.1016)
		(layer "F.Cu")
		(net "IOC_RAID_TX_N7")
	)
	(arc
		(start 18.715482 -104.108504)
		(mid 18.608726 -104.268275)
		(end 18.57121 -104.456738)
		(width 0.1016)
		(layer "F.Cu")
		(net "IOC_RAID_TX_N7")
	)
	(arc
		(start 18.57121 -108.838238)
		(mid 19.418196 -110.883042)
		(end 21.463 -111.730028)
		(width 0.1016)
		(layer "F.Cu")
		(net "IOC_RAID_TX_N7")
	)
	(arc
		(start 18.79981 -103.904796)
		(mid 18.777885 -104.015023)
		(end 18.715482 -104.108504)
		(width 0.1016)
		(layer "F.Cu")
		(net "IOC_RAID_TX_N7")
	)
	(segment
		(start 84.611972 -40.132)
		(end 85.911182 -40.132)
		(width 0.1016)
		(layer "F.Cu")
		(net "IOC_RAID_TX_P7")
	)
	(segment
		(start 18.22831 -104.698292)
		(end 18.22831 -108.838238)
		(width 0.1016)
		(layer "F.Cu")
		(net "IOC_RAID_TX_P7")
	)
	(segment
		(start 78.956408 -44.173902)
		(end 79.1718 -43.958256)
		(width 0.1016)
		(layer "F.Cu")
		(net "IOC_RAID_TX_P7")
	)
	(segment
		(start 17.99971 -102.489762)
		(end 17.99971 -104.14635)
		(width 0.1016)
		(layer "F.Cu")
		(net "IOC_RAID_TX_P7")
	)
	(segment
		(start 70.74154 -52.05095)
		(end 78.449932 -44.342558)
		(width 0.1016)
		(layer "F.Cu")
		(net "IOC_RAID_TX_P7")
	)
	(segment
		(start 28.335478 -110.856522)
		(end 70.220586 -68.971414)
		(width 0.1016)
		(layer "F.Cu")
		(net "IOC_RAID_TX_P7")
	)
	(segment
		(start 83.829652 -40.37076)
		(end 84.134452 -40.37076)
		(width 0.1016)
		(layer "F.Cu")
		(net "IOC_RAID_TX_P7")
	)
	(segment
		(start 82.769456 -40.132)
		(end 83.352132 -40.132)
		(width 0.1016)
		(layer "F.Cu")
		(net "IOC_RAID_TX_P7")
	)
	(segment
		(start 70.693026 -67.830954)
		(end 70.693026 -52.16779)
		(width 0.1016)
		(layer "F.Cu")
		(net "IOC_RAID_TX_P7")
	)
	(segment
		(start 21.463 -112.072928)
		(end 25.398984 -112.072928)
		(width 0.1016)
		(layer "F.Cu")
		(net "IOC_RAID_TX_P7")
	)
	(segment
		(start 79.34071 -43.45178)
		(end 82.583528 -40.208962)
		(width 0.1016)
		(layer "F.Cu")
		(net "IOC_RAID_TX_P7")
	)
	(arc
		(start 70.693026 -52.16779)
		(mid 70.705696 -52.104565)
		(end 70.74154 -52.05095)
		(width 0.1016)
		(layer "F.Cu")
		(net "IOC_RAID_TX_P7")
	)
	(arc
		(start 18.22831 -108.838238)
		(mid 19.175729 -111.125509)
		(end 21.463 -112.072928)
		(width 0.1016)
		(layer "F.Cu")
		(net "IOC_RAID_TX_P7")
	)
	(arc
		(start 82.583528 -40.208962)
		(mid 82.668832 -40.151963)
		(end 82.769456 -40.132)
		(width 0.1016)
		(layer "F.Cu")
		(net "IOC_RAID_TX_P7")
	)
	(arc
		(start 83.590892 -40.25138)
		(mid 83.695706 -40.340174)
		(end 83.829652 -40.37076)
		(width 0.1016)
		(layer "F.Cu")
		(net "IOC_RAID_TX_P7")
	)
	(arc
		(start 79.256382 -43.705018)
		(mid 79.267612 -43.568093)
		(end 79.34071 -43.45178)
		(width 0.1016)
		(layer "F.Cu")
		(net "IOC_RAID_TX_P7")
	)
	(arc
		(start 83.352132 -40.132)
		(mid 83.486125 -40.162492)
		(end 83.590892 -40.25138)
		(width 0.1016)
		(layer "F.Cu")
		(net "IOC_RAID_TX_P7")
	)
	(arc
		(start 78.70317 -44.25823)
		(mid 78.840095 -44.247)
		(end 78.956408 -44.173902)
		(width 0.1016)
		(layer "F.Cu")
		(net "IOC_RAID_TX_P7")
	)
	(arc
		(start 84.134452 -40.37076)
		(mid 84.268445 -40.340268)
		(end 84.373212 -40.25138)
		(width 0.1016)
		(layer "F.Cu")
		(net "IOC_RAID_TX_P7")
	)
	(arc
		(start 79.1718 -43.958256)
		(mid 79.245023 -43.841968)
		(end 79.256382 -43.705018)
		(width 0.1016)
		(layer "F.Cu")
		(net "IOC_RAID_TX_P7")
	)
	(arc
		(start 17.99971 -104.14635)
		(mid 18.033913 -104.3183)
		(end 18.131282 -104.464104)
		(width 0.1016)
		(layer "F.Cu")
		(net "IOC_RAID_TX_P7")
	)
	(arc
		(start 25.398984 -112.072928)
		(mid 26.98823 -111.756807)
		(end 28.335478 -110.856522)
		(width 0.1016)
		(layer "F.Cu")
		(net "IOC_RAID_TX_P7")
	)
	(arc
		(start 84.373212 -40.25138)
		(mid 84.478026 -40.162586)
		(end 84.611972 -40.132)
		(width 0.1016)
		(layer "F.Cu")
		(net "IOC_RAID_TX_P7")
	)
	(arc
		(start 70.220586 -68.971414)
		(mid 70.570209 -68.448167)
		(end 70.693026 -67.830954)
		(width 0.1016)
		(layer "F.Cu")
		(net "IOC_RAID_TX_P7")
	)
	(arc
		(start 78.449932 -44.342558)
		(mid 78.566257 -44.269498)
		(end 78.70317 -44.25823)
		(width 0.1016)
		(layer "F.Cu")
		(net "IOC_RAID_TX_P7")
	)
	(arc
		(start 18.131282 -104.464104)
		(mid 18.203075 -104.57155)
		(end 18.22831 -104.698292)
		(width 0.1016)
		(layer "F.Cu")
		(net "IOC_RAID_TX_P7")
	)
	(arc
		(start 85.911182 -40.132)
		(mid 86.077105 -40.165004)
		(end 86.21776 -40.259)
		(width 0.1016)
		(layer "F.Cu")
		(net "IOC_RAID_TX_P7")
	)
	(segment
		(start 84.868766 -43.4213)
		(end 85.880448 -43.4213)
		(width 0.1016)
		(layer "F.Cu")
		(net "IOC_RAID_TX_P5")
	)
	(segment
		(start 74.693526 -57.005982)
		(end 74.693526 -56.701182)
		(width 0.1016)
		(layer "F.Cu")
		(net "IOC_RAID_TX_P5")
	)
	(segment
		(start 74.454766 -69.276214)
		(end 74.454766 -59.048142)
		(width 0.1016)
		(layer "F.Cu")
		(net "IOC_RAID_TX_P5")
	)
	(segment
		(start 74.454766 -57.788302)
		(end 74.454766 -57.483502)
		(width 0.1016)
		(layer "F.Cu")
		(net "IOC_RAID_TX_P5")
	)
	(segment
		(start 13.20038 -102.489762)
		(end 13.20038 -103.946452)
		(width 0.1016)
		(layer "F.Cu")
		(net "IOC_RAID_TX_P5")
	)
	(segment
		(start 13.42898 -104.953816)
		(end 13.42898 -110.767622)
		(width 0.1016)
		(layer "F.Cu")
		(net "IOC_RAID_TX_P5")
	)
	(segment
		(start 74.454766 -56.223662)
		(end 74.454766 -53.7972)
		(width 0.1016)
		(layer "F.Cu")
		(net "IOC_RAID_TX_P5")
	)
	(segment
		(start 13.42771 -104.495092)
		(end 13.42771 -104.923082)
		(width 0.1016)
		(layer "F.Cu")
		(net "IOC_RAID_TX_P5")
	)
	(segment
		(start 29.986478 -114.412522)
		(end 73.982326 -70.416674)
		(width 0.1016)
		(layer "F.Cu")
		(net "IOC_RAID_TX_P5")
	)
	(segment
		(start 18.290286 -115.628928)
		(end 27.049984 -115.628928)
		(width 0.1016)
		(layer "F.Cu")
		(net "IOC_RAID_TX_P5")
	)
	(segment
		(start 74.693526 -58.570622)
		(end 74.693526 -58.265822)
		(width 0.1016)
		(layer "F.Cu")
		(net "IOC_RAID_TX_P5")
	)
	(segment
		(start 74.633328 -53.366162)
		(end 84.37245 -43.62704)
		(width 0.1016)
		(layer "F.Cu")
		(net "IOC_RAID_TX_P5")
	)
	(arc
		(start 74.454766 -57.483502)
		(mid 74.454659 -57.475628)
		(end 74.454766 -57.467754)
		(width 0.1016)
		(layer "F.Cu")
		(net "IOC_RAID_TX_P5")
	)
	(arc
		(start 84.37245 -43.62704)
		(mid 84.600147 -43.474805)
		(end 84.868766 -43.4213)
		(width 0.1016)
		(layer "F.Cu")
		(net "IOC_RAID_TX_P5")
	)
	(arc
		(start 74.693526 -58.265822)
		(mid 74.663034 -58.131829)
		(end 74.574146 -58.027062)
		(width 0.1016)
		(layer "F.Cu")
		(net "IOC_RAID_TX_P5")
	)
	(arc
		(start 13.20038 -103.946452)
		(mid 13.234235 -104.116652)
		(end 13.330682 -104.260904)
		(width 0.1016)
		(layer "F.Cu")
		(net "IOC_RAID_TX_P5")
	)
	(arc
		(start 85.880448 -43.4213)
		(mid 86.062993 -43.45761)
		(end 86.21776 -43.561)
		(width 0.1016)
		(layer "F.Cu")
		(net "IOC_RAID_TX_P5")
	)
	(arc
		(start 13.42898 -110.767622)
		(mid 14.852824 -114.205084)
		(end 18.290286 -115.628928)
		(width 0.1016)
		(layer "F.Cu")
		(net "IOC_RAID_TX_P5")
	)
	(arc
		(start 74.574146 -57.244742)
		(mid 74.66294 -57.139928)
		(end 74.693526 -57.005982)
		(width 0.1016)
		(layer "F.Cu")
		(net "IOC_RAID_TX_P5")
	)
	(arc
		(start 74.454766 -59.048142)
		(mid 74.485258 -58.914149)
		(end 74.574146 -58.809382)
		(width 0.1016)
		(layer "F.Cu")
		(net "IOC_RAID_TX_P5")
	)
	(arc
		(start 74.574146 -56.462422)
		(mid 74.485352 -56.357608)
		(end 74.454766 -56.223662)
		(width 0.1016)
		(layer "F.Cu")
		(net "IOC_RAID_TX_P5")
	)
	(arc
		(start 74.574146 -58.809382)
		(mid 74.66294 -58.704568)
		(end 74.693526 -58.570622)
		(width 0.1016)
		(layer "F.Cu")
		(net "IOC_RAID_TX_P5")
	)
	(arc
		(start 13.42771 -104.923082)
		(mid 13.428652 -104.938436)
		(end 13.42898 -104.953816)
		(width 0.1016)
		(layer "F.Cu")
		(net "IOC_RAID_TX_P5")
	)
	(arc
		(start 74.454766 -53.7972)
		(mid 74.501169 -53.563916)
		(end 74.633328 -53.366162)
		(width 0.1016)
		(layer "F.Cu")
		(net "IOC_RAID_TX_P5")
	)
	(arc
		(start 74.693526 -56.701182)
		(mid 74.663034 -56.567189)
		(end 74.574146 -56.462422)
		(width 0.1016)
		(layer "F.Cu")
		(net "IOC_RAID_TX_P5")
	)
	(arc
		(start 27.049984 -115.628928)
		(mid 28.63923 -115.312807)
		(end 29.986478 -114.412522)
		(width 0.1016)
		(layer "F.Cu")
		(net "IOC_RAID_TX_P5")
	)
	(arc
		(start 74.574146 -58.027062)
		(mid 74.485352 -57.922248)
		(end 74.454766 -57.788302)
		(width 0.1016)
		(layer "F.Cu")
		(net "IOC_RAID_TX_P5")
	)
	(arc
		(start 13.330682 -104.260904)
		(mid 13.402475 -104.36835)
		(end 13.42771 -104.495092)
		(width 0.1016)
		(layer "F.Cu")
		(net "IOC_RAID_TX_P5")
	)
	(arc
		(start 73.982326 -70.416674)
		(mid 74.331949 -69.893427)
		(end 74.454766 -69.276214)
		(width 0.1016)
		(layer "F.Cu")
		(net "IOC_RAID_TX_P5")
	)
	(arc
		(start 74.454766 -57.467754)
		(mid 74.48882 -57.342527)
		(end 74.574146 -57.244742)
		(width 0.1016)
		(layer "F.Cu")
		(net "IOC_RAID_TX_P5")
	)
	(segment
		(start 80.992472 -49.472088)
		(end 85.141054 -45.323506)
		(width 0.1016)
		(layer "F.Cu")
		(net "IOC_RAID_TX_P4")
	)
	(segment
		(start 76.435966 -69.987414)
		(end 76.435966 -54.389528)
		(width 0.1016)
		(layer "F.Cu")
		(net "IOC_RAID_TX_P4")
	)
	(segment
		(start 10.99058 -104.538526)
		(end 10.99058 -110.756446)
		(width 0.1016)
		(layer "F.Cu")
		(net "IOC_RAID_TX_P4")
	)
	(segment
		(start 78.779878 -51.684682)
		(end 78.99527 -51.46929)
		(width 0.1016)
		(layer "F.Cu")
		(net "IOC_RAID_TX_P4")
	)
	(segment
		(start 17.641062 -117.406928)
		(end 27.964384 -117.406928)
		(width 0.1016)
		(layer "F.Cu")
		(net "IOC_RAID_TX_P4")
	)
	(segment
		(start 30.900878 -116.190522)
		(end 75.963526 -71.127874)
		(width 0.1016)
		(layer "F.Cu")
		(net "IOC_RAID_TX_P4")
	)
	(segment
		(start 76.691236 -53.773324)
		(end 77.8891 -52.57546)
		(width 0.1016)
		(layer "F.Cu")
		(net "IOC_RAID_TX_P4")
	)
	(segment
		(start 10.80008 -102.489762)
		(end 10.80008 -104.078532)
		(width 0.1016)
		(layer "F.Cu")
		(net "IOC_RAID_TX_P4")
	)
	(segment
		(start 80.60817 -50.193956)
		(end 80.823816 -49.978564)
		(width 0.1016)
		(layer "F.Cu")
		(net "IOC_RAID_TX_P4")
	)
	(segment
		(start 79.886302 -50.578258)
		(end 80.101694 -50.362866)
		(width 0.1016)
		(layer "F.Cu")
		(net "IOC_RAID_TX_P4")
	)
	(segment
		(start 78.395576 -52.406804)
		(end 78.610968 -52.191158)
		(width 0.1016)
		(layer "F.Cu")
		(net "IOC_RAID_TX_P4")
	)
	(segment
		(start 79.501746 -51.30038)
		(end 79.717392 -51.084734)
		(width 0.1016)
		(layer "F.Cu")
		(net "IOC_RAID_TX_P4")
	)
	(segment
		(start 85.808566 -45.0469)
		(end 85.819234 -45.0469)
		(width 0.1016)
		(layer "F.Cu")
		(net "IOC_RAID_TX_P4")
	)
	(arc
		(start 77.8891 -52.57546)
		(mid 78.005425 -52.5024)
		(end 78.142338 -52.491132)
		(width 0.1016)
		(layer "F.Cu")
		(net "IOC_RAID_TX_P4")
	)
	(arc
		(start 75.963526 -71.127874)
		(mid 76.313149 -70.604627)
		(end 76.435966 -69.987414)
		(width 0.1016)
		(layer "F.Cu")
		(net "IOC_RAID_TX_P4")
	)
	(arc
		(start 79.80172 -50.831496)
		(mid 79.813084 -50.694548)
		(end 79.886302 -50.578258)
		(width 0.1016)
		(layer "F.Cu")
		(net "IOC_RAID_TX_P4")
	)
	(arc
		(start 80.101694 -50.362866)
		(mid 80.217982 -50.289643)
		(end 80.354932 -50.278284)
		(width 0.1016)
		(layer "F.Cu")
		(net "IOC_RAID_TX_P4")
	)
	(arc
		(start 76.435966 -54.389528)
		(mid 76.502303 -54.056029)
		(end 76.691236 -53.773324)
		(width 0.1016)
		(layer "F.Cu")
		(net "IOC_RAID_TX_P4")
	)
	(arc
		(start 80.908144 -49.725326)
		(mid 80.919374 -49.588401)
		(end 80.992472 -49.472088)
		(width 0.1016)
		(layer "F.Cu")
		(net "IOC_RAID_TX_P4")
	)
	(arc
		(start 78.69555 -51.93792)
		(mid 78.70678 -51.800995)
		(end 78.779878 -51.684682)
		(width 0.1016)
		(layer "F.Cu")
		(net "IOC_RAID_TX_P4")
	)
	(arc
		(start 78.610968 -52.191158)
		(mid 78.684191 -52.07487)
		(end 78.69555 -51.93792)
		(width 0.1016)
		(layer "F.Cu")
		(net "IOC_RAID_TX_P4")
	)
	(arc
		(start 10.99058 -110.756446)
		(mid 12.938461 -115.459047)
		(end 17.641062 -117.406928)
		(width 0.1016)
		(layer "F.Cu")
		(net "IOC_RAID_TX_P4")
	)
	(arc
		(start 10.80008 -104.078532)
		(mid 10.830648 -104.232208)
		(end 10.917682 -104.362504)
		(width 0.1016)
		(layer "F.Cu")
		(net "IOC_RAID_TX_P4")
	)
	(arc
		(start 27.964384 -117.406928)
		(mid 29.55363 -117.090807)
		(end 30.900878 -116.190522)
		(width 0.1016)
		(layer "F.Cu")
		(net "IOC_RAID_TX_P4")
	)
	(arc
		(start 79.248508 -51.384708)
		(mid 79.385433 -51.373478)
		(end 79.501746 -51.30038)
		(width 0.1016)
		(layer "F.Cu")
		(net "IOC_RAID_TX_P4")
	)
	(arc
		(start 79.717392 -51.084734)
		(mid 79.790452 -50.968409)
		(end 79.80172 -50.831496)
		(width 0.1016)
		(layer "F.Cu")
		(net "IOC_RAID_TX_P4")
	)
	(arc
		(start 85.819234 -45.0469)
		(mid 86.034924 -45.089803)
		(end 86.21776 -45.212)
		(width 0.1016)
		(layer "F.Cu")
		(net "IOC_RAID_TX_P4")
	)
	(arc
		(start 85.141054 -45.323506)
		(mid 85.447296 -45.118789)
		(end 85.808566 -45.0469)
		(width 0.1016)
		(layer "F.Cu")
		(net "IOC_RAID_TX_P4")
	)
	(arc
		(start 10.917682 -104.362504)
		(mid 10.971644 -104.443264)
		(end 10.99058 -104.538526)
		(width 0.1016)
		(layer "F.Cu")
		(net "IOC_RAID_TX_P4")
	)
	(arc
		(start 78.99527 -51.46929)
		(mid 79.111558 -51.396067)
		(end 79.248508 -51.384708)
		(width 0.1016)
		(layer "F.Cu")
		(net "IOC_RAID_TX_P4")
	)
	(arc
		(start 80.354932 -50.278284)
		(mid 80.491857 -50.267054)
		(end 80.60817 -50.193956)
		(width 0.1016)
		(layer "F.Cu")
		(net "IOC_RAID_TX_P4")
	)
	(arc
		(start 78.142338 -52.491132)
		(mid 78.279263 -52.479902)
		(end 78.395576 -52.406804)
		(width 0.1016)
		(layer "F.Cu")
		(net "IOC_RAID_TX_P4")
	)
	(arc
		(start 80.823816 -49.978564)
		(mid 80.896876 -49.862239)
		(end 80.908144 -49.725326)
		(width 0.1016)
		(layer "F.Cu")
		(net "IOC_RAID_TX_P4")
	)
	(segment
		(start 11.33348 -104.544876)
		(end 11.33348 -110.756446)
		(width 0.1016)
		(layer "F.Cu")
		(net "IOC_RAID_TX_N4")
	)
	(segment
		(start 30.658054 -115.948206)
		(end 75.72121 -70.88505)
		(width 0.1016)
		(layer "F.Cu")
		(net "IOC_RAID_TX_N4")
	)
	(segment
		(start 76.093066 -69.98716)
		(end 76.093066 -54.389274)
		(width 0.1016)
		(layer "F.Cu")
		(net "IOC_RAID_TX_N4")
	)
	(segment
		(start 85.808566 -44.704)
		(end 85.911182 -44.704)
		(width 0.1016)
		(layer "F.Cu")
		(net "IOC_RAID_TX_N4")
	)
	(segment
		(start 11.60018 -102.489762)
		(end 11.60018 -103.900986)
		(width 0.1016)
		(layer "F.Cu")
		(net "IOC_RAID_TX_N4")
	)
	(segment
		(start 17.641062 -117.064028)
		(end 27.96413 -117.064028)
		(width 0.1016)
		(layer "F.Cu")
		(net "IOC_RAID_TX_N4")
	)
	(segment
		(start 76.448666 -53.530754)
		(end 84.898484 -45.080936)
		(width 0.1016)
		(layer "F.Cu")
		(net "IOC_RAID_TX_N4")
	)
	(arc
		(start 11.451082 -104.260904)
		(mid 11.364027 -104.391191)
		(end 11.33348 -104.544876)
		(width 0.1016)
		(layer "F.Cu")
		(net "IOC_RAID_TX_N4")
	)
	(arc
		(start 11.60018 -103.900986)
		(mid 11.561433 -104.095778)
		(end 11.451082 -104.260904)
		(width 0.1016)
		(layer "F.Cu")
		(net "IOC_RAID_TX_N4")
	)
	(arc
		(start 85.911182 -44.704)
		(mid 86.077105 -44.670996)
		(end 86.21776 -44.577)
		(width 0.1016)
		(layer "F.Cu")
		(net "IOC_RAID_TX_N4")
	)
	(arc
		(start 27.96413 -117.064028)
		(mid 29.422071 -116.774043)
		(end 30.658054 -115.948206)
		(width 0.1016)
		(layer "F.Cu")
		(net "IOC_RAID_TX_N4")
	)
	(arc
		(start 84.898484 -45.080936)
		(mid 85.316033 -44.801939)
		(end 85.808566 -44.704)
		(width 0.1016)
		(layer "F.Cu")
		(net "IOC_RAID_TX_N4")
	)
	(arc
		(start 75.72121 -70.88505)
		(mid 75.996416 -70.47308)
		(end 76.093066 -69.98716)
		(width 0.1016)
		(layer "F.Cu")
		(net "IOC_RAID_TX_N4")
	)
	(arc
		(start 11.33348 -110.756446)
		(mid 13.180928 -115.21658)
		(end 17.641062 -117.064028)
		(width 0.1016)
		(layer "F.Cu")
		(net "IOC_RAID_TX_N4")
	)
	(arc
		(start 76.093066 -54.389274)
		(mid 76.18547 -53.924636)
		(end 76.448666 -53.530754)
		(width 0.1016)
		(layer "F.Cu")
		(net "IOC_RAID_TX_N4")
	)
	(segment
		(start 211.455 -183.134)
		(end 211.455 -155.956)
		(width 0.1143)
		(layer "F.Cu")
		(net "EXP_HB")
	)
	(segment
		(start 212.70595 -183.388)
		(end 211.709 -183.388)
		(width 0.1143)
		(layer "F.Cu")
		(net "EXP_HB")
	)
	(segment
		(start 213.614 -181.737)
		(end 212.979 -182.372)
		(width 0.1143)
		(layer "F.Cu")
		(net "EXP_HB")
	)
	(segment
		(start 213.741 -181.61)
		(end 213.614 -181.737)
		(width 0.1143)
		(layer "F.Cu")
		(net "EXP_HB")
	)
	(segment
		(start 215.2015 -181.61)
		(end 213.741 -181.61)
		(width 0.1143)
		(layer "F.Cu")
		(net "EXP_HB")
	)
	(segment
		(start 211.709 -183.388)
		(end 211.455 -183.134)
		(width 0.1143)
		(layer "F.Cu")
		(net "EXP_HB")
	)
	(segment
		(start 215.3285 -181.737)
		(end 215.2015 -181.61)
		(width 0.1143)
		(layer "F.Cu")
		(net "EXP_HB")
	)
	(segment
		(start 211.455 -155.956)
		(end 211.709 -155.702)
		(width 0.1143)
		(layer "F.Cu")
		(net "EXP_HB")
	)
	(segment
		(start 212.979 -183.11495)
		(end 212.70595 -183.388)
		(width 0.1143)
		(layer "F.Cu")
		(net "EXP_HB")
	)
	(segment
		(start 212.979 -182.372)
		(end 212.979 -183.11495)
		(width 0.1143)
		(layer "F.Cu")
		(net "EXP_HB")
	)
	(segment
		(start 83.74253 -137.1854)
		(end 83.74253 -135.8011)
		(width 0.1143)
		(layer "F.Cu")
		(net "EXP_HB")
	)
	(via
		(at 211.709 -155.702)
		(size 0.5588)
		(drill 0.3048)
		(layers "F.Cu" "B.Cu")
		(net "EXP_HB")
	)
	(via
		(at 213.614 -181.737)
		(size 0.7112)
		(drill 0.3556)
		(layers "F.Cu" "B.Cu")
		(net "EXP_HB")
	)
	(via
		(at 83.74253 -135.8011)
		(size 0.5588)
		(drill 0.3048)
		(layers "F.Cu" "B.Cu")
		(net "EXP_HB")
	)
	(segment
		(start 90.297 -139.383262)
		(end 92.010738 -141.097)
		(width 0.127)
		(layer "In2.Cu")
		(net "EXP_HB")
	)
	(segment
		(start 90.297 -139.142978)
		(end 90.297 -139.383262)
		(width 0.127)
		(layer "In2.Cu")
		(net "EXP_HB")
	)
	(segment
		(start 175.796194 -156.5402)
		(end 176.824894 -155.5115)
		(width 0.127)
		(layer "In2.Cu")
		(net "EXP_HB")
	)
	(segment
		(start 94.169738 -141.097)
		(end 109.612938 -156.5402)
		(width 0.127)
		(layer "In2.Cu")
		(net "EXP_HB")
	)
	(segment
		(start 84.78393 -136.8425)
		(end 87.996522 -136.8425)
		(width 0.127)
		(layer "In2.Cu")
		(net "EXP_HB")
	)
	(segment
		(start 109.612938 -156.5402)
		(end 175.796194 -156.5402)
		(width 0.127)
		(layer "In2.Cu")
		(net "EXP_HB")
	)
	(segment
		(start 211.5185 -155.5115)
		(end 211.709 -155.702)
		(width 0.127)
		(layer "In2.Cu")
		(net "EXP_HB")
	)
	(segment
		(start 87.996522 -136.8425)
		(end 90.297 -139.142978)
		(width 0.127)
		(layer "In2.Cu")
		(net "EXP_HB")
	)
	(segment
		(start 83.74253 -135.8011)
		(end 84.78393 -136.8425)
		(width 0.127)
		(layer "In2.Cu")
		(net "EXP_HB")
	)
	(segment
		(start 176.824894 -155.5115)
		(end 211.5185 -155.5115)
		(width 0.127)
		(layer "In2.Cu")
		(net "EXP_HB")
	)
	(segment
		(start 92.010738 -141.097)
		(end 94.169738 -141.097)
		(width 0.127)
		(layer "In2.Cu")
		(net "EXP_HB")
	)
	(segment
		(start 93.540834 -40.200072)
		(end 93.574362 -40.2336)
		(width 0.1016)
		(layer "F.Cu")
		(net "IOC_SAS_RX_N6")
	)
	(segment
		(start 93.574362 -40.2336)
		(end 93.58376 -40.2336)
		(width 0.1016)
		(layer "F.Cu")
		(net "IOC_SAS_RX_N6")
	)
	(segment
		(start 93.58376 -40.2336)
		(end 93.950028 -40.599868)
		(width 0.1016)
		(layer "F.Cu")
		(net "IOC_SAS_RX_N6")
	)
	(via
		(at 93.540834 -40.200072)
		(size 0.508)
		(drill 0.254)
		(layers "F.Cu" "B.Cu")
		(net "IOC_SAS_RX_N6")
	)
	(segment
		(start 29.582364 -106.6292)
		(end 34.193226 -106.6292)
		(width 0.1016)
		(layer "B.Cu")
		(net "IOC_SAS_RX_N6")
	)
	(segment
		(start 86.995254 -40.118538)
		(end 93.343984 -40.118538)
		(width 0.1016)
		(layer "B.Cu")
		(net "IOC_SAS_RX_N6")
	)
	(segment
		(start 20.163536 -106.39044)
		(end 20.468336 -106.39044)
		(width 0.1016)
		(layer "B.Cu")
		(net "IOC_SAS_RX_N6")
	)
	(segment
		(start 24.075136 -106.6292)
		(end 25.777952 -106.6292)
		(width 0.1016)
		(layer "B.Cu")
		(net "IOC_SAS_RX_N6")
	)
	(segment
		(start 20.945856 -106.6292)
		(end 21.250656 -106.6292)
		(width 0.1016)
		(layer "B.Cu")
		(net "IOC_SAS_RX_N6")
	)
	(segment
		(start 16.572484 -101.339904)
		(end 16.572484 -104.589326)
		(width 0.1016)
		(layer "B.Cu")
		(net "IOC_SAS_RX_N6")
	)
	(segment
		(start 23.292816 -106.39044)
		(end 23.597616 -106.39044)
		(width 0.1016)
		(layer "B.Cu")
		(net "IOC_SAS_RX_N6")
	)
	(segment
		(start 55.418228 -92.663772)
		(end 71.69277 -76.38923)
		(width 0.1016)
		(layer "B.Cu")
		(net "IOC_SAS_RX_N6")
	)
	(segment
		(start 22.510496 -106.6292)
		(end 22.815296 -106.6292)
		(width 0.1016)
		(layer "B.Cu")
		(net "IOC_SAS_RX_N6")
	)
	(segment
		(start 19.381216 -106.6292)
		(end 19.686016 -106.6292)
		(width 0.1016)
		(layer "B.Cu")
		(net "IOC_SAS_RX_N6")
	)
	(segment
		(start 16.884904 -100.845366)
		(end 16.701262 -101.029008)
		(width 0.1016)
		(layer "B.Cu")
		(net "IOC_SAS_RX_N6")
	)
	(segment
		(start 27.037792 -106.6292)
		(end 28.322524 -106.6292)
		(width 0.1016)
		(layer "B.Cu")
		(net "IOC_SAS_RX_N6")
	)
	(segment
		(start 21.728176 -106.39044)
		(end 22.032976 -106.39044)
		(width 0.1016)
		(layer "B.Cu")
		(net "IOC_SAS_RX_N6")
	)
	(segment
		(start 16.992854 -105.603802)
		(end 17.054576 -105.665524)
		(width 0.1016)
		(layer "B.Cu")
		(net "IOC_SAS_RX_N6")
	)
	(segment
		(start 35.091116 -106.257344)
		(end 47.40402 -93.94444)
		(width 0.1016)
		(layer "B.Cu")
		(net "IOC_SAS_RX_N6")
	)
	(segment
		(start 72.52843 -53.85943)
		(end 85.756496 -40.631364)
		(width 0.1016)
		(layer "B.Cu")
		(net "IOC_SAS_RX_N6")
	)
	(segment
		(start 48.54448 -93.472)
		(end 53.467254 -93.472)
		(width 0.1016)
		(layer "B.Cu")
		(net "IOC_SAS_RX_N6")
	)
	(segment
		(start 26.255472 -106.39044)
		(end 26.560272 -106.39044)
		(width 0.1016)
		(layer "B.Cu")
		(net "IOC_SAS_RX_N6")
	)
	(segment
		(start 28.800044 -106.39044)
		(end 29.104844 -106.39044)
		(width 0.1016)
		(layer "B.Cu")
		(net "IOC_SAS_RX_N6")
	)
	(segment
		(start 72.064626 -75.49134)
		(end 72.064626 -54.97957)
		(width 0.1016)
		(layer "B.Cu")
		(net "IOC_SAS_RX_N6")
	)
	(arc
		(start 23.597616 -106.39044)
		(mid 23.731609 -106.420932)
		(end 23.836376 -106.50982)
		(width 0.1016)
		(layer "B.Cu")
		(net "IOC_SAS_RX_N6")
	)
	(arc
		(start 53.467254 -93.472)
		(mid 54.523115 -93.2619)
		(end 55.418228 -92.663772)
		(width 0.1016)
		(layer "B.Cu")
		(net "IOC_SAS_RX_N6")
	)
	(arc
		(start 22.271736 -106.50982)
		(mid 22.37655 -106.598614)
		(end 22.510496 -106.6292)
		(width 0.1016)
		(layer "B.Cu")
		(net "IOC_SAS_RX_N6")
	)
	(arc
		(start 25.777952 -106.6292)
		(mid 25.911945 -106.598708)
		(end 26.016712 -106.50982)
		(width 0.1016)
		(layer "B.Cu")
		(net "IOC_SAS_RX_N6")
	)
	(arc
		(start 26.016712 -106.50982)
		(mid 26.121507 -106.420932)
		(end 26.255472 -106.39044)
		(width 0.1016)
		(layer "B.Cu")
		(net "IOC_SAS_RX_N6")
	)
	(arc
		(start 20.468336 -106.39044)
		(mid 20.602329 -106.420932)
		(end 20.707096 -106.50982)
		(width 0.1016)
		(layer "B.Cu")
		(net "IOC_SAS_RX_N6")
	)
	(arc
		(start 85.756496 -40.631364)
		(mid 86.324859 -40.251719)
		(end 86.995254 -40.118538)
		(width 0.1016)
		(layer "B.Cu")
		(net "IOC_SAS_RX_N6")
	)
	(arc
		(start 19.924776 -106.50982)
		(mid 20.02959 -106.421026)
		(end 20.163536 -106.39044)
		(width 0.1016)
		(layer "B.Cu")
		(net "IOC_SAS_RX_N6")
	)
	(arc
		(start 21.489416 -106.50982)
		(mid 21.59423 -106.421026)
		(end 21.728176 -106.39044)
		(width 0.1016)
		(layer "B.Cu")
		(net "IOC_SAS_RX_N6")
	)
	(arc
		(start 72.064626 -54.97957)
		(mid 72.185114 -54.373367)
		(end 72.52843 -53.85943)
		(width 0.1016)
		(layer "B.Cu")
		(net "IOC_SAS_RX_N6")
	)
	(arc
		(start 16.701262 -101.029008)
		(mid 16.605953 -101.171648)
		(end 16.572484 -101.339904)
		(width 0.1016)
		(layer "B.Cu")
		(net "IOC_SAS_RX_N6")
	)
	(arc
		(start 21.250656 -106.6292)
		(mid 21.384649 -106.598708)
		(end 21.489416 -106.50982)
		(width 0.1016)
		(layer "B.Cu")
		(net "IOC_SAS_RX_N6")
	)
	(arc
		(start 34.193226 -106.6292)
		(mid 34.679151 -106.532561)
		(end 35.091116 -106.257344)
		(width 0.1016)
		(layer "B.Cu")
		(net "IOC_SAS_RX_N6")
	)
	(arc
		(start 22.032976 -106.39044)
		(mid 22.166969 -106.420932)
		(end 22.271736 -106.50982)
		(width 0.1016)
		(layer "B.Cu")
		(net "IOC_SAS_RX_N6")
	)
	(arc
		(start 47.40402 -93.94444)
		(mid 47.927267 -93.594817)
		(end 48.54448 -93.472)
		(width 0.1016)
		(layer "B.Cu")
		(net "IOC_SAS_RX_N6")
	)
	(arc
		(start 28.322524 -106.6292)
		(mid 28.456517 -106.598708)
		(end 28.561284 -106.50982)
		(width 0.1016)
		(layer "B.Cu")
		(net "IOC_SAS_RX_N6")
	)
	(arc
		(start 22.815296 -106.6292)
		(mid 22.949289 -106.598708)
		(end 23.054056 -106.50982)
		(width 0.1016)
		(layer "B.Cu")
		(net "IOC_SAS_RX_N6")
	)
	(arc
		(start 29.343604 -106.50982)
		(mid 29.448418 -106.598614)
		(end 29.582364 -106.6292)
		(width 0.1016)
		(layer "B.Cu")
		(net "IOC_SAS_RX_N6")
	)
	(arc
		(start 23.836376 -106.50982)
		(mid 23.94119 -106.598614)
		(end 24.075136 -106.6292)
		(width 0.1016)
		(layer "B.Cu")
		(net "IOC_SAS_RX_N6")
	)
	(arc
		(start 20.707096 -106.50982)
		(mid 20.81191 -106.598614)
		(end 20.945856 -106.6292)
		(width 0.1016)
		(layer "B.Cu")
		(net "IOC_SAS_RX_N6")
	)
	(arc
		(start 29.104844 -106.39044)
		(mid 29.238837 -106.420932)
		(end 29.343604 -106.50982)
		(width 0.1016)
		(layer "B.Cu")
		(net "IOC_SAS_RX_N6")
	)
	(arc
		(start 26.560272 -106.39044)
		(mid 26.694265 -106.420932)
		(end 26.799032 -106.50982)
		(width 0.1016)
		(layer "B.Cu")
		(net "IOC_SAS_RX_N6")
	)
	(arc
		(start 17.054576 -105.665524)
		(mid 18.122062 -106.378732)
		(end 19.381216 -106.6292)
		(width 0.1016)
		(layer "B.Cu")
		(net "IOC_SAS_RX_N6")
	)
	(arc
		(start 16.572484 -104.589326)
		(mid 16.681788 -105.138364)
		(end 16.992854 -105.603802)
		(width 0.1016)
		(layer "B.Cu")
		(net "IOC_SAS_RX_N6")
	)
	(arc
		(start 26.799032 -106.50982)
		(mid 26.903827 -106.598708)
		(end 27.037792 -106.6292)
		(width 0.1016)
		(layer "B.Cu")
		(net "IOC_SAS_RX_N6")
	)
	(arc
		(start 19.686016 -106.6292)
		(mid 19.820009 -106.598708)
		(end 19.924776 -106.50982)
		(width 0.1016)
		(layer "B.Cu")
		(net "IOC_SAS_RX_N6")
	)
	(arc
		(start 71.69277 -76.38923)
		(mid 71.967976 -75.97726)
		(end 72.064626 -75.49134)
		(width 0.1016)
		(layer "B.Cu")
		(net "IOC_SAS_RX_N6")
	)
	(arc
		(start 93.343984 -40.118538)
		(mid 93.450517 -40.139729)
		(end 93.540834 -40.200072)
		(width 0.1016)
		(layer "B.Cu")
		(net "IOC_SAS_RX_N6")
	)
	(arc
		(start 28.561284 -106.50982)
		(mid 28.666098 -106.421026)
		(end 28.800044 -106.39044)
		(width 0.1016)
		(layer "B.Cu")
		(net "IOC_SAS_RX_N6")
	)
	(arc
		(start 23.054056 -106.50982)
		(mid 23.15887 -106.421026)
		(end 23.292816 -106.39044)
		(width 0.1016)
		(layer "B.Cu")
		(net "IOC_SAS_RX_N6")
	)
	(segment
		(start 298.43476 -173.049692)
		(end 298.826428 -173.44136)
		(width 0.1143)
		(layer "F.Cu")
		(net "BMC_TXD5_R")
	)
	(segment
		(start 298.43476 -173.04004)
		(end 298.43476 -173.049692)
		(width 0.1143)
		(layer "F.Cu")
		(net "BMC_TXD5_R")
	)
	(via
		(at 315.722 -175.641)
		(size 0.7112)
		(drill 0.3556)
		(layers "F.Cu" "B.Cu")
		(net "BMC_TXD5_R")
	)
	(via
		(at 298.826428 -173.44136)
		(size 0.508)
		(drill 0.254)
		(layers "F.Cu" "B.Cu")
		(net "BMC_TXD5_R")
	)
	(segment
		(start 298.826428 -173.44136)
		(end 300.90364 -173.44136)
		(width 0.1143)
		(layer "B.Cu")
		(net "BMC_TXD5_R")
	)
	(segment
		(start 300.90364 -173.44136)
		(end 301.106078 -173.238922)
		(width 0.1143)
		(layer "B.Cu")
		(net "BMC_TXD5_R")
	)
	(segment
		(start 312.547 -175.641)
		(end 315.722 -175.641)
		(width 0.1143)
		(layer "B.Cu")
		(net "BMC_TXD5_R")
	)
	(segment
		(start 301.106078 -173.238922)
		(end 310.144922 -173.238922)
		(width 0.1143)
		(layer "B.Cu")
		(net "BMC_TXD5_R")
	)
	(segment
		(start 310.144922 -173.238922)
		(end 312.547 -175.641)
		(width 0.1143)
		(layer "B.Cu")
		(net "BMC_TXD5_R")
	)
	(segment
		(start 315.722 -175.641)
		(end 317.5635 -175.641)
		(width 0.1143)
		(layer "B.Cu")
		(net "BMC_TXD5_R")
	)
	(segment
		(start 92.981018 -39.454836)
		(end 93.090746 -39.564564)
		(width 0.1016)
		(layer "F.Cu")
		(net "IOC_SAS_RX_P7")
	)
	(segment
		(start 92.74556 -39.3954)
		(end 92.837508 -39.3954)
		(width 0.1016)
		(layer "F.Cu")
		(net "IOC_SAS_RX_P7")
	)
	(segment
		(start 93.150182 -39.708074)
		(end 93.150182 -39.800022)
		(width 0.1016)
		(layer "F.Cu")
		(net "IOC_SAS_RX_P7")
	)
	(via
		(at 92.74556 -39.3954)
		(size 0.508)
		(drill 0.254)
		(layers "F.Cu" "B.Cu")
		(net "IOC_SAS_RX_P7")
	)
	(arc
		(start 93.090746 -39.564564)
		(mid 93.134741 -39.630407)
		(end 93.150182 -39.708074)
		(width 0.1016)
		(layer "F.Cu")
		(net "IOC_SAS_RX_P7")
	)
	(arc
		(start 92.837508 -39.3954)
		(mid 92.915172 -39.410848)
		(end 92.981018 -39.454836)
		(width 0.1016)
		(layer "F.Cu")
		(net "IOC_SAS_RX_P7")
	)
	(segment
		(start 70.693026 -53.884576)
		(end 70.693026 -74.539094)
		(width 0.1016)
		(layer "B.Cu")
		(net "IOC_SAS_RX_P7")
	)
	(segment
		(start 92.13977 -38.909752)
		(end 91.708224 -38.909752)
		(width 0.1016)
		(layer "B.Cu")
		(net "IOC_SAS_RX_P7")
	)
	(segment
		(start 91.419172 -38.6207)
		(end 90.50528 -38.6207)
		(width 0.1016)
		(layer "B.Cu")
		(net "IOC_SAS_RX_P7")
	)
	(segment
		(start 70.220586 -75.679554)
		(end 54.97957 -90.92057)
		(width 0.1016)
		(layer "B.Cu")
		(net "IOC_SAS_RX_P7")
	)
	(segment
		(start 85.920072 -38.412674)
		(end 70.866 -53.467)
		(width 0.1016)
		(layer "B.Cu")
		(net "IOC_SAS_RX_P7")
	)
	(segment
		(start 34.59988 -103.8987)
		(end 27.385264 -103.8987)
		(width 0.1016)
		(layer "B.Cu")
		(net "IOC_SAS_RX_P7")
	)
	(segment
		(start 26.125424 -103.8987)
		(end 25.820624 -103.8987)
		(width 0.1016)
		(layer "B.Cu")
		(net "IOC_SAS_RX_P7")
	)
	(segment
		(start 25.343104 -104.13746)
		(end 25.038304 -104.13746)
		(width 0.1016)
		(layer "B.Cu")
		(net "IOC_SAS_RX_P7")
	)
	(segment
		(start 92.625418 -39.3954)
		(end 92.13977 -38.909752)
		(width 0.1016)
		(layer "B.Cu")
		(net "IOC_SAS_RX_P7")
	)
	(segment
		(start 26.907744 -104.13746)
		(end 26.602944 -104.13746)
		(width 0.1016)
		(layer "B.Cu")
		(net "IOC_SAS_RX_P7")
	)
	(segment
		(start 90.145616 -38.471856)
		(end 89.847674 -38.173914)
		(width 0.1016)
		(layer "B.Cu")
		(net "IOC_SAS_RX_P7")
	)
	(segment
		(start 18.563082 -102.0826)
		(end 18.563082 -101.385624)
		(width 0.1016)
		(layer "B.Cu")
		(net "IOC_SAS_RX_P7")
	)
	(segment
		(start 46.757844 -92.408756)
		(end 35.74034 -103.42626)
		(width 0.1016)
		(layer "B.Cu")
		(net "IOC_SAS_RX_P7")
	)
	(segment
		(start 91.708224 -38.909752)
		(end 91.419172 -38.6207)
		(width 0.1016)
		(layer "B.Cu")
		(net "IOC_SAS_RX_P7")
	)
	(segment
		(start 18.379948 -100.94341)
		(end 18.281904 -100.845366)
		(width 0.1016)
		(layer "B.Cu")
		(net "IOC_SAS_RX_P7")
	)
	(segment
		(start 19.26463 -103.23957)
		(end 18.8849 -102.85984)
		(width 0.1016)
		(layer "B.Cu")
		(net "IOC_SAS_RX_P7")
	)
	(segment
		(start 52.284122 -92.0369)
		(end 47.655734 -92.0369)
		(width 0.1016)
		(layer "B.Cu")
		(net "IOC_SAS_RX_P7")
	)
	(segment
		(start 89.730834 -38.1254)
		(end 86.614 -38.1254)
		(width 0.1016)
		(layer "B.Cu")
		(net "IOC_SAS_RX_P7")
	)
	(segment
		(start 92.74556 -39.3954)
		(end 92.625418 -39.3954)
		(width 0.1016)
		(layer "B.Cu")
		(net "IOC_SAS_RX_P7")
	)
	(segment
		(start 24.560784 -103.8987)
		(end 20.85594 -103.8987)
		(width 0.1016)
		(layer "B.Cu")
		(net "IOC_SAS_RX_P7")
	)
	(arc
		(start 54.97957 -90.92057)
		(mid 53.742873 -91.746812)
		(end 52.284122 -92.0369)
		(width 0.1016)
		(layer "B.Cu")
		(net "IOC_SAS_RX_P7")
	)
	(arc
		(start 47.655734 -92.0369)
		(mid 47.169809 -92.133539)
		(end 46.757844 -92.408756)
		(width 0.1016)
		(layer "B.Cu")
		(net "IOC_SAS_RX_P7")
	)
	(arc
		(start 25.581864 -104.01808)
		(mid 25.47705 -104.106874)
		(end 25.343104 -104.13746)
		(width 0.1016)
		(layer "B.Cu")
		(net "IOC_SAS_RX_P7")
	)
	(arc
		(start 25.820624 -103.8987)
		(mid 25.686631 -103.929192)
		(end 25.581864 -104.01808)
		(width 0.1016)
		(layer "B.Cu")
		(net "IOC_SAS_RX_P7")
	)
	(arc
		(start 20.85594 -103.8987)
		(mid 19.99472 -103.72741)
		(end 19.26463 -103.23957)
		(width 0.1016)
		(layer "B.Cu")
		(net "IOC_SAS_RX_P7")
	)
	(arc
		(start 90.50528 -38.6207)
		(mid 90.310629 -38.582075)
		(end 90.145616 -38.471856)
		(width 0.1016)
		(layer "B.Cu")
		(net "IOC_SAS_RX_P7")
	)
	(arc
		(start 70.693026 -74.539094)
		(mid 70.570251 -75.156324)
		(end 70.220586 -75.679554)
		(width 0.1016)
		(layer "B.Cu")
		(net "IOC_SAS_RX_P7")
	)
	(arc
		(start 26.602944 -104.13746)
		(mid 26.468951 -104.106968)
		(end 26.364184 -104.01808)
		(width 0.1016)
		(layer "B.Cu")
		(net "IOC_SAS_RX_P7")
	)
	(arc
		(start 70.866 -53.467)
		(mid 70.737987 -53.658585)
		(end 70.693026 -53.884576)
		(width 0.1016)
		(layer "B.Cu")
		(net "IOC_SAS_RX_P7")
	)
	(arc
		(start 24.799544 -104.01808)
		(mid 24.69473 -103.929286)
		(end 24.560784 -103.8987)
		(width 0.1016)
		(layer "B.Cu")
		(net "IOC_SAS_RX_P7")
	)
	(arc
		(start 35.74034 -103.42626)
		(mid 35.217093 -103.775883)
		(end 34.59988 -103.8987)
		(width 0.1016)
		(layer "B.Cu")
		(net "IOC_SAS_RX_P7")
	)
	(arc
		(start 89.847674 -38.173914)
		(mid 89.794082 -38.138012)
		(end 89.730834 -38.1254)
		(width 0.1016)
		(layer "B.Cu")
		(net "IOC_SAS_RX_P7")
	)
	(arc
		(start 86.614 -38.1254)
		(mid 86.238457 -38.200007)
		(end 85.920072 -38.412674)
		(width 0.1016)
		(layer "B.Cu")
		(net "IOC_SAS_RX_P7")
	)
	(arc
		(start 18.563082 -101.385624)
		(mid 18.51548 -101.146314)
		(end 18.379948 -100.94341)
		(width 0.1016)
		(layer "B.Cu")
		(net "IOC_SAS_RX_P7")
	)
	(arc
		(start 27.146504 -104.01808)
		(mid 27.04169 -104.106874)
		(end 26.907744 -104.13746)
		(width 0.1016)
		(layer "B.Cu")
		(net "IOC_SAS_RX_P7")
	)
	(arc
		(start 27.385264 -103.8987)
		(mid 27.251271 -103.929192)
		(end 27.146504 -104.01808)
		(width 0.1016)
		(layer "B.Cu")
		(net "IOC_SAS_RX_P7")
	)
	(arc
		(start 18.8849 -102.85984)
		(mid 18.64671 -102.503224)
		(end 18.563082 -102.0826)
		(width 0.1016)
		(layer "B.Cu")
		(net "IOC_SAS_RX_P7")
	)
	(arc
		(start 25.038304 -104.13746)
		(mid 24.904311 -104.106968)
		(end 24.799544 -104.01808)
		(width 0.1016)
		(layer "B.Cu")
		(net "IOC_SAS_RX_P7")
	)
	(arc
		(start 26.364184 -104.01808)
		(mid 26.25937 -103.929286)
		(end 26.125424 -103.8987)
		(width 0.1016)
		(layer "B.Cu")
		(net "IOC_SAS_RX_P7")
	)
	(segment
		(start 93.950028 -39.790624)
		(end 93.556582 -39.397178)
		(width 0.1016)
		(layer "F.Cu")
		(net "IOC_SAS_RX_N7")
	)
	(segment
		(start 93.950028 -39.800022)
		(end 93.950028 -39.790624)
		(width 0.1016)
		(layer "F.Cu")
		(net "IOC_SAS_RX_N7")
	)
	(via
		(at 93.556582 -39.397178)
		(size 0.508)
		(drill 0.254)
		(layers "F.Cu" "B.Cu")
		(net "IOC_SAS_RX_N7")
	)
	(segment
		(start 18.905982 -101.484938)
		(end 18.905982 -102.0826)
		(width 0.1016)
		(layer "B.Cu")
		(net "IOC_SAS_RX_N7")
	)
	(segment
		(start 93.152722 -38.993318)
		(end 93.556582 -39.397178)
		(width 0.0889)
		(layer "B.Cu")
		(net "IOC_SAS_RX_N7")
	)
	(segment
		(start 70.350126 -74.53884)
		(end 70.350126 -53.884322)
		(width 0.1016)
		(layer "B.Cu")
		(net "IOC_SAS_RX_N7")
	)
	(segment
		(start 47.65548 -91.694)
		(end 52.284376 -91.694)
		(width 0.1016)
		(layer "B.Cu")
		(net "IOC_SAS_RX_N7")
	)
	(segment
		(start 35.497516 -103.183944)
		(end 46.51502 -92.16644)
		(width 0.1016)
		(layer "B.Cu")
		(net "IOC_SAS_RX_N7")
	)
	(segment
		(start 92.108528 -38.566852)
		(end 92.534994 -38.993318)
		(width 0.1016)
		(layer "B.Cu")
		(net "IOC_SAS_RX_N7")
	)
	(segment
		(start 19.12747 -102.61727)
		(end 19.5072 -102.997)
		(width 0.1016)
		(layer "B.Cu")
		(net "IOC_SAS_RX_N7")
	)
	(segment
		(start 91.850464 -38.566852)
		(end 92.108528 -38.566852)
		(width 0.1016)
		(layer "B.Cu")
		(net "IOC_SAS_RX_N7")
	)
	(segment
		(start 91.561412 -38.2778)
		(end 91.850464 -38.566852)
		(width 0.1016)
		(layer "B.Cu")
		(net "IOC_SAS_RX_N7")
	)
	(segment
		(start 86.614254 -37.7825)
		(end 89.731088 -37.7825)
		(width 0.1016)
		(layer "B.Cu")
		(net "IOC_SAS_RX_N7")
	)
	(segment
		(start 90.090498 -37.931344)
		(end 90.388186 -38.229032)
		(width 0.1016)
		(layer "B.Cu")
		(net "IOC_SAS_RX_N7")
	)
	(segment
		(start 20.856194 -103.5558)
		(end 34.599626 -103.5558)
		(width 0.1016)
		(layer "B.Cu")
		(net "IOC_SAS_RX_N7")
	)
	(segment
		(start 19.170904 -100.845366)
		(end 18.94586 -101.28758)
		(width 0.1016)
		(layer "B.Cu")
		(net "IOC_SAS_RX_N7")
	)
	(segment
		(start 54.737 -90.678)
		(end 69.97827 -75.43673)
		(width 0.1016)
		(layer "B.Cu")
		(net "IOC_SAS_RX_N7")
	)
	(segment
		(start 18.91157 -101.407976)
		(end 18.905982 -101.47173)
		(width 0.1016)
		(layer "B.Cu")
		(net "IOC_SAS_RX_N7")
	)
	(segment
		(start 70.62343 -53.22443)
		(end 85.677502 -38.170104)
		(width 0.1016)
		(layer "B.Cu")
		(net "IOC_SAS_RX_N7")
	)
	(segment
		(start 92.534994 -38.993318)
		(end 93.152722 -38.993318)
		(width 0.0889)
		(layer "B.Cu")
		(net "IOC_SAS_RX_N7")
	)
	(segment
		(start 90.505026 -38.2778)
		(end 91.561412 -38.2778)
		(width 0.1016)
		(layer "B.Cu")
		(net "IOC_SAS_RX_N7")
	)
	(arc
		(start 69.97827 -75.43673)
		(mid 70.253476 -75.02476)
		(end 70.350126 -74.53884)
		(width 0.1016)
		(layer "B.Cu")
		(net "IOC_SAS_RX_N7")
	)
	(arc
		(start 18.94586 -101.28758)
		(mid 18.922899 -101.346123)
		(end 18.91157 -101.407976)
		(width 0.1016)
		(layer "B.Cu")
		(net "IOC_SAS_RX_N7")
	)
	(arc
		(start 85.677502 -38.170104)
		(mid 86.107318 -37.883126)
		(end 86.614254 -37.7825)
		(width 0.1016)
		(layer "B.Cu")
		(net "IOC_SAS_RX_N7")
	)
	(arc
		(start 18.905982 -102.0826)
		(mid 18.963541 -102.371969)
		(end 19.12747 -102.61727)
		(width 0.1016)
		(layer "B.Cu")
		(net "IOC_SAS_RX_N7")
	)
	(arc
		(start 90.388186 -38.229032)
		(mid 90.441748 -38.26507)
		(end 90.505026 -38.2778)
		(width 0.1016)
		(layer "B.Cu")
		(net "IOC_SAS_RX_N7")
	)
	(arc
		(start 34.599626 -103.5558)
		(mid 35.085551 -103.459161)
		(end 35.497516 -103.183944)
		(width 0.1016)
		(layer "B.Cu")
		(net "IOC_SAS_RX_N7")
	)
	(arc
		(start 18.905982 -101.47173)
		(mid 18.905958 -101.478334)
		(end 18.905982 -101.484938)
		(width 0.1016)
		(layer "B.Cu")
		(net "IOC_SAS_RX_N7")
	)
	(arc
		(start 52.284376 -91.694)
		(mid 53.611721 -91.429899)
		(end 54.737 -90.678)
		(width 0.1016)
		(layer "B.Cu")
		(net "IOC_SAS_RX_N7")
	)
	(arc
		(start 70.350126 -53.884322)
		(mid 70.421146 -53.527189)
		(end 70.62343 -53.22443)
		(width 0.1016)
		(layer "B.Cu")
		(net "IOC_SAS_RX_N7")
	)
	(arc
		(start 89.731088 -37.7825)
		(mid 89.925603 -37.821174)
		(end 90.090498 -37.931344)
		(width 0.1016)
		(layer "B.Cu")
		(net "IOC_SAS_RX_N7")
	)
	(arc
		(start 19.5072 -102.997)
		(mid 20.126124 -103.410552)
		(end 20.856194 -103.5558)
		(width 0.1016)
		(layer "B.Cu")
		(net "IOC_SAS_RX_N7")
	)
	(arc
		(start 46.51502 -92.16644)
		(mid 47.038267 -91.816817)
		(end 47.65548 -91.694)
		(width 0.1016)
		(layer "B.Cu")
		(net "IOC_SAS_RX_N7")
	)
	(segment
		(start 93.159072 -40.599868)
		(end 93.554804 -40.9956)
		(width 0.1016)
		(layer "F.Cu")
		(net "IOC_SAS_RX_P6")
	)
	(segment
		(start 93.150182 -40.599868)
		(end 93.159072 -40.599868)
		(width 0.1016)
		(layer "F.Cu")
		(net "IOC_SAS_RX_P6")
	)
	(via
		(at 93.554804 -40.9956)
		(size 0.508)
		(drill 0.254)
		(layers "F.Cu" "B.Cu")
		(net "IOC_SAS_RX_P6")
	)
	(segment
		(start 16.229584 -101.4095)
		(end 16.229584 -104.58958)
		(width 0.1016)
		(layer "B.Cu")
		(net "IOC_SAS_RX_P6")
	)
	(segment
		(start 48.544734 -93.8149)
		(end 53.467 -93.8149)
		(width 0.1016)
		(layer "B.Cu")
		(net "IOC_SAS_RX_P6")
	)
	(segment
		(start 35.33394 -106.49966)
		(end 47.64659 -94.18701)
		(width 0.1016)
		(layer "B.Cu")
		(net "IOC_SAS_RX_P6")
	)
	(segment
		(start 86.995 -40.461438)
		(end 92.94241 -40.461438)
		(width 0.1016)
		(layer "B.Cu")
		(net "IOC_SAS_RX_P6")
	)
	(segment
		(start 55.660798 -92.906342)
		(end 71.935086 -76.632054)
		(width 0.1016)
		(layer "B.Cu")
		(net "IOC_SAS_RX_P6")
	)
	(segment
		(start 93.250766 -40.5892)
		(end 93.482414 -40.820848)
		(width 0.1016)
		(layer "B.Cu")
		(net "IOC_SAS_RX_P6")
	)
	(segment
		(start 72.771 -54.102)
		(end 85.999066 -40.873934)
		(width 0.1016)
		(layer "B.Cu")
		(net "IOC_SAS_RX_P6")
	)
	(segment
		(start 19.380962 -106.9721)
		(end 34.19348 -106.9721)
		(width 0.1016)
		(layer "B.Cu")
		(net "IOC_SAS_RX_P6")
	)
	(segment
		(start 16.750284 -105.846372)
		(end 16.812006 -105.908094)
		(width 0.1016)
		(layer "B.Cu")
		(net "IOC_SAS_RX_P6")
	)
	(segment
		(start 72.407526 -75.491594)
		(end 72.407526 -54.97957)
		(width 0.1016)
		(layer "B.Cu")
		(net "IOC_SAS_RX_P6")
	)
	(arc
		(start 93.482414 -40.820848)
		(mid 93.535986 -40.901025)
		(end 93.554804 -40.9956)
		(width 0.1016)
		(layer "B.Cu")
		(net "IOC_SAS_RX_P6")
	)
	(arc
		(start 71.935086 -76.632054)
		(mid 72.284709 -76.108807)
		(end 72.407526 -75.491594)
		(width 0.1016)
		(layer "B.Cu")
		(net "IOC_SAS_RX_P6")
	)
	(arc
		(start 16.812006 -105.908094)
		(mid 17.990681 -106.695533)
		(end 19.380962 -106.9721)
		(width 0.1016)
		(layer "B.Cu")
		(net "IOC_SAS_RX_P6")
	)
	(arc
		(start 16.22298 -101.308154)
		(mid 16.22584 -101.334656)
		(end 16.227806 -101.36124)
		(width 0.1016)
		(layer "B.Cu")
		(net "IOC_SAS_RX_P6")
	)
	(arc
		(start 92.94241 -40.461438)
		(mid 93.109305 -40.494636)
		(end 93.250766 -40.5892)
		(width 0.1016)
		(layer "B.Cu")
		(net "IOC_SAS_RX_P6")
	)
	(arc
		(start 16.229584 -104.58958)
		(mid 16.364955 -105.269757)
		(end 16.750284 -105.846372)
		(width 0.1016)
		(layer "B.Cu")
		(net "IOC_SAS_RX_P6")
	)
	(arc
		(start 72.407526 -54.97957)
		(mid 72.501995 -54.504643)
		(end 72.771 -54.102)
		(width 0.1016)
		(layer "B.Cu")
		(net "IOC_SAS_RX_P6")
	)
	(arc
		(start 16.227806 -101.36124)
		(mid 16.229064 -101.385356)
		(end 16.229584 -101.4095)
		(width 0.1016)
		(layer "B.Cu")
		(net "IOC_SAS_RX_P6")
	)
	(arc
		(start 16.22044 -101.290882)
		(mid 16.221757 -101.299511)
		(end 16.22298 -101.308154)
		(width 0.1016)
		(layer "B.Cu")
		(net "IOC_SAS_RX_P6")
	)
	(arc
		(start 15.995904 -100.845366)
		(mid 16.143919 -101.050113)
		(end 16.22044 -101.290882)
		(width 0.1016)
		(layer "B.Cu")
		(net "IOC_SAS_RX_P6")
	)
	(arc
		(start 85.999066 -40.873934)
		(mid 86.456004 -40.568618)
		(end 86.995 -40.461438)
		(width 0.1016)
		(layer "B.Cu")
		(net "IOC_SAS_RX_P6")
	)
	(arc
		(start 34.19348 -106.9721)
		(mid 34.81071 -106.849325)
		(end 35.33394 -106.49966)
		(width 0.1016)
		(layer "B.Cu")
		(net "IOC_SAS_RX_P6")
	)
	(arc
		(start 47.64659 -94.18701)
		(mid 48.058648 -93.911619)
		(end 48.544734 -93.8149)
		(width 0.1016)
		(layer "B.Cu")
		(net "IOC_SAS_RX_P6")
	)
	(arc
		(start 53.467 -93.8149)
		(mid 54.654274 -93.57883)
		(end 55.660798 -92.906342)
		(width 0.1016)
		(layer "B.Cu")
		(net "IOC_SAS_RX_P6")
	)
	(segment
		(start 93.55455 -41.80459)
		(end 93.949774 -42.199814)
		(width 0.1016)
		(layer "F.Cu")
		(net "IOC_SAS_RX_N5")
	)
	(segment
		(start 93.949774 -42.199814)
		(end 93.950028 -42.199814)
		(width 0.1016)
		(layer "F.Cu")
		(net "IOC_SAS_RX_N5")
	)
	(via
		(at 93.55455 -41.80459)
		(size 0.508)
		(drill 0.254)
		(layers "F.Cu" "B.Cu")
		(net "IOC_SAS_RX_N5")
	)
	(segment
		(start 92.579698 -41.396666)
		(end 93.279468 -41.396666)
		(width 0.0889)
		(layer "B.Cu")
		(net "IOC_SAS_RX_N5")
	)
	(segment
		(start 56.4515 -94.4245)
		(end 73.40727 -77.46873)
		(width 0.1016)
		(layer "B.Cu")
		(net "IOC_SAS_RX_N5")
	)
	(segment
		(start 14.915896 -106.475784)
		(end 15.724632 -107.28452)
		(width 0.1016)
		(layer "B.Cu")
		(net "IOC_SAS_RX_N5")
	)
	(segment
		(start 74.205592 -54.85765)
		(end 74.882248 -54.181248)
		(width 0.1016)
		(layer "B.Cu")
		(net "IOC_SAS_RX_N5")
	)
	(segment
		(start 49.33188 -95.25)
		(end 54.458616 -95.25)
		(width 0.1016)
		(layer "B.Cu")
		(net "IOC_SAS_RX_N5")
	)
	(segment
		(start 19.84248 -108.99013)
		(end 34.397696 -108.99013)
		(width 0.1016)
		(layer "B.Cu")
		(net "IOC_SAS_RX_N5")
	)
	(segment
		(start 93.382084 -41.439338)
		(end 93.472 -41.529)
		(width 0.0889)
		(layer "B.Cu")
		(net "IOC_SAS_RX_N5")
	)
	(segment
		(start 14.092682 -101.129592)
		(end 14.092682 -105.190036)
		(width 0.1016)
		(layer "B.Cu")
		(net "IOC_SAS_RX_N5")
	)
	(segment
		(start 14.23543 -100.943156)
		(end 14.193774 -100.985066)
		(width 0.1016)
		(layer "B.Cu")
		(net "IOC_SAS_RX_N5")
	)
	(segment
		(start 35.295586 -108.618274)
		(end 48.19142 -95.72244)
		(width 0.1016)
		(layer "B.Cu")
		(net "IOC_SAS_RX_N5")
	)
	(segment
		(start 73.779126 -76.57084)
		(end 73.779126 -55.88762)
		(width 0.1016)
		(layer "B.Cu")
		(net "IOC_SAS_RX_N5")
	)
	(segment
		(start 74.882248 -54.181248)
		(end 83.806792 -45.256704)
		(width 0.1016)
		(layer "B.Cu")
		(net "IOC_SAS_RX_N5")
	)
	(segment
		(start 86.984332 -42.121582)
		(end 87.01532 -42.090594)
		(width 0.1016)
		(layer "B.Cu")
		(net "IOC_SAS_RX_N5")
	)
	(segment
		(start 14.193774 -100.985066)
		(end 14.123162 -101.055932)
		(width 0.1016)
		(layer "B.Cu")
		(net "IOC_SAS_RX_N5")
	)
	(segment
		(start 92.177616 -41.707054)
		(end 92.423234 -41.461436)
		(width 0.0889)
		(layer "B.Cu")
		(net "IOC_SAS_RX_N5")
	)
	(segment
		(start 83.806792 -45.256704)
		(end 86.984332 -42.121582)
		(width 0.1016)
		(layer "B.Cu")
		(net "IOC_SAS_RX_N5")
	)
	(segment
		(start 14.419834 -105.979468)
		(end 14.915896 -106.475784)
		(width 0.1016)
		(layer "B.Cu")
		(net "IOC_SAS_RX_N5")
	)
	(segment
		(start 87.79002 -41.7703)
		(end 92.024708 -41.7703)
		(width 0.1016)
		(layer "B.Cu")
		(net "IOC_SAS_RX_N5")
	)
	(segment
		(start 93.55455 -41.72839)
		(end 93.55455 -41.80459)
		(width 0.0889)
		(layer "B.Cu")
		(net "IOC_SAS_RX_N5")
	)
	(arc
		(start 87.01532 -42.090594)
		(mid 87.370829 -41.853456)
		(end 87.79002 -41.7703)
		(width 0.1016)
		(layer "B.Cu")
		(net "IOC_SAS_RX_N5")
	)
	(arc
		(start 93.472 -41.529)
		(mid 93.533126 -41.620481)
		(end 93.55455 -41.72839)
		(width 0.0889)
		(layer "B.Cu")
		(net "IOC_SAS_RX_N5")
	)
	(arc
		(start 93.279468 -41.396666)
		(mid 93.335014 -41.407808)
		(end 93.382084 -41.439338)
		(width 0.0889)
		(layer "B.Cu")
		(net "IOC_SAS_RX_N5")
	)
	(arc
		(start 15.724632 -107.28452)
		(mid 17.613931 -108.546846)
		(end 19.84248 -108.99013)
		(width 0.1016)
		(layer "B.Cu")
		(net "IOC_SAS_RX_N5")
	)
	(arc
		(start 54.458616 -95.25)
		(mid 55.537165 -95.035463)
		(end 56.4515 -94.4245)
		(width 0.1016)
		(layer "B.Cu")
		(net "IOC_SAS_RX_N5")
	)
	(arc
		(start 73.779126 -55.88762)
		(mid 73.889908 -55.330212)
		(end 74.205592 -54.85765)
		(width 0.1016)
		(layer "B.Cu")
		(net "IOC_SAS_RX_N5")
	)
	(arc
		(start 92.423234 -41.461436)
		(mid 92.49502 -41.41347)
		(end 92.579698 -41.396666)
		(width 0.0889)
		(layer "B.Cu")
		(net "IOC_SAS_RX_N5")
	)
	(arc
		(start 14.471904 -100.845366)
		(mid 14.343933 -100.870727)
		(end 14.23543 -100.943156)
		(width 0.1016)
		(layer "B.Cu")
		(net "IOC_SAS_RX_N5")
	)
	(arc
		(start 14.092682 -105.190036)
		(mid 14.17776 -105.61728)
		(end 14.419834 -105.979468)
		(width 0.1016)
		(layer "B.Cu")
		(net "IOC_SAS_RX_N5")
	)
	(arc
		(start 34.397696 -108.99013)
		(mid 34.883621 -108.893491)
		(end 35.295586 -108.618274)
		(width 0.1016)
		(layer "B.Cu")
		(net "IOC_SAS_RX_N5")
	)
	(arc
		(start 14.123162 -101.055932)
		(mid 14.100581 -101.089727)
		(end 14.092682 -101.129592)
		(width 0.1016)
		(layer "B.Cu")
		(net "IOC_SAS_RX_N5")
	)
	(arc
		(start 92.024708 -41.7703)
		(mid 92.107441 -41.753861)
		(end 92.177616 -41.707054)
		(width 0.0889)
		(layer "B.Cu")
		(net "IOC_SAS_RX_N5")
	)
	(arc
		(start 73.40727 -77.46873)
		(mid 73.682476 -77.05676)
		(end 73.779126 -76.57084)
		(width 0.1016)
		(layer "B.Cu")
		(net "IOC_SAS_RX_N5")
	)
	(arc
		(start 48.19142 -95.72244)
		(mid 48.714667 -95.372817)
		(end 49.33188 -95.25)
		(width 0.1016)
		(layer "B.Cu")
		(net "IOC_SAS_RX_N5")
	)
	(segment
		(start 92.983304 -41.796716)
		(end 92.750132 -41.796716)
		(width 0.1016)
		(layer "F.Cu")
		(net "IOC_SAS_RX_P5")
	)
	(segment
		(start 93.150182 -42.199814)
		(end 93.150182 -41.963594)
		(width 0.1016)
		(layer "F.Cu")
		(net "IOC_SAS_RX_P5")
	)
	(segment
		(start 93.113098 -41.873932)
		(end 93.072966 -41.8338)
		(width 0.1016)
		(layer "F.Cu")
		(net "IOC_SAS_RX_P5")
	)
	(via
		(at 92.750132 -41.796716)
		(size 0.508)
		(drill 0.254)
		(layers "F.Cu" "B.Cu")
		(net "IOC_SAS_RX_P5")
	)
	(arc
		(start 93.150182 -41.963594)
		(mid 93.140549 -41.915076)
		(end 93.113098 -41.873932)
		(width 0.1016)
		(layer "F.Cu")
		(net "IOC_SAS_RX_P5")
	)
	(arc
		(start 93.072966 -41.8338)
		(mid 93.031815 -41.806367)
		(end 92.983304 -41.796716)
		(width 0.1016)
		(layer "F.Cu")
		(net "IOC_SAS_RX_P5")
	)
	(segment
		(start 69.459094 -82.239866)
		(end 69.674486 -82.02422)
		(width 0.1016)
		(layer "B.Cu")
		(net "IOC_SAS_RX_P5")
	)
	(segment
		(start 14.673326 -106.718354)
		(end 15.482062 -107.52709)
		(width 0.1016)
		(layer "B.Cu")
		(net "IOC_SAS_RX_P5")
	)
	(segment
		(start 49.332134 -95.5929)
		(end 54.45887 -95.5929)
		(width 0.1016)
		(layer "B.Cu")
		(net "IOC_SAS_RX_P5")
	)
	(segment
		(start 74.448162 -55.10022)
		(end 75.124818 -54.423818)
		(width 0.1016)
		(layer "B.Cu")
		(net "IOC_SAS_RX_P5")
	)
	(segment
		(start 13.749782 -101.24821)
		(end 13.749782 -105.19029)
		(width 0.1016)
		(layer "B.Cu")
		(net "IOC_SAS_RX_P5")
	)
	(segment
		(start 14.177264 -106.222038)
		(end 14.673326 -106.718354)
		(width 0.1016)
		(layer "B.Cu")
		(net "IOC_SAS_RX_P5")
	)
	(segment
		(start 72.056244 -79.304896)
		(end 73.649586 -77.711554)
		(width 0.1016)
		(layer "B.Cu")
		(net "IOC_SAS_RX_P5")
	)
	(segment
		(start 70.94982 -80.41132)
		(end 71.165212 -80.195928)
		(width 0.1016)
		(layer "B.Cu")
		(net "IOC_SAS_RX_P5")
	)
	(segment
		(start 35.53841 -108.86059)
		(end 48.43399 -95.96501)
		(width 0.1016)
		(layer "B.Cu")
		(net "IOC_SAS_RX_P5")
	)
	(segment
		(start 19.842226 -109.33303)
		(end 34.39795 -109.33303)
		(width 0.1016)
		(layer "B.Cu")
		(net "IOC_SAS_RX_P5")
	)
	(segment
		(start 87.789766 -42.1132)
		(end 91.9861 -42.1132)
		(width 0.1016)
		(layer "B.Cu")
		(net "IOC_SAS_RX_P5")
	)
	(segment
		(start 71.671688 -80.027018)
		(end 71.887334 -79.811626)
		(width 0.1016)
		(layer "B.Cu")
		(net "IOC_SAS_RX_P5")
	)
	(segment
		(start 56.69407 -94.66707)
		(end 68.952618 -82.408522)
		(width 0.1016)
		(layer "B.Cu")
		(net "IOC_SAS_RX_P5")
	)
	(segment
		(start 84.039456 -45.50918)
		(end 87.225378 -42.36593)
		(width 0.1016)
		(layer "B.Cu")
		(net "IOC_SAS_RX_P5")
	)
	(segment
		(start 75.124818 -54.423818)
		(end 84.039456 -45.50918)
		(width 0.1016)
		(layer "B.Cu")
		(net "IOC_SAS_RX_P5")
	)
	(segment
		(start 87.225378 -42.36593)
		(end 87.25789 -42.333418)
		(width 0.1016)
		(layer "B.Cu")
		(net "IOC_SAS_RX_P5")
	)
	(segment
		(start 69.843396 -81.517744)
		(end 70.059042 -81.302098)
		(width 0.1016)
		(layer "B.Cu")
		(net "IOC_SAS_RX_P5")
	)
	(segment
		(start 70.565518 -81.133442)
		(end 70.78091 -80.917796)
		(width 0.1016)
		(layer "B.Cu")
		(net "IOC_SAS_RX_P5")
	)
	(segment
		(start 74.122026 -76.571094)
		(end 74.122026 -55.88762)
		(width 0.1016)
		(layer "B.Cu")
		(net "IOC_SAS_RX_P5")
	)
	(arc
		(start 68.952618 -82.408522)
		(mid 69.068943 -82.335462)
		(end 69.205856 -82.324194)
		(width 0.1016)
		(layer "B.Cu")
		(net "IOC_SAS_RX_P5")
	)
	(arc
		(start 74.122026 -55.88762)
		(mid 74.206789 -55.461488)
		(end 74.448162 -55.10022)
		(width 0.1016)
		(layer "B.Cu")
		(net "IOC_SAS_RX_P5")
	)
	(arc
		(start 71.41845 -80.111346)
		(mid 71.555375 -80.100116)
		(end 71.671688 -80.027018)
		(width 0.1016)
		(layer "B.Cu")
		(net "IOC_SAS_RX_P5")
	)
	(arc
		(start 15.482062 -107.52709)
		(mid 17.482551 -108.863647)
		(end 19.842226 -109.33303)
		(width 0.1016)
		(layer "B.Cu")
		(net "IOC_SAS_RX_P5")
	)
	(arc
		(start 70.865238 -80.664558)
		(mid 70.876602 -80.52761)
		(end 70.94982 -80.41132)
		(width 0.1016)
		(layer "B.Cu")
		(net "IOC_SAS_RX_P5")
	)
	(arc
		(start 71.887334 -79.811626)
		(mid 71.960434 -79.695182)
		(end 71.971662 -79.558134)
		(width 0.1016)
		(layer "B.Cu")
		(net "IOC_SAS_RX_P5")
	)
	(arc
		(start 70.31228 -81.21777)
		(mid 70.449205 -81.20654)
		(end 70.565518 -81.133442)
		(width 0.1016)
		(layer "B.Cu")
		(net "IOC_SAS_RX_P5")
	)
	(arc
		(start 71.165212 -80.195928)
		(mid 71.2815 -80.122705)
		(end 71.41845 -80.111346)
		(width 0.1016)
		(layer "B.Cu")
		(net "IOC_SAS_RX_P5")
	)
	(arc
		(start 48.43399 -95.96501)
		(mid 48.846048 -95.689619)
		(end 49.332134 -95.5929)
		(width 0.1016)
		(layer "B.Cu")
		(net "IOC_SAS_RX_P5")
	)
	(arc
		(start 91.9861 -42.1132)
		(mid 92.399596 -42.030951)
		(end 92.750132 -41.796716)
		(width 0.1016)
		(layer "B.Cu")
		(net "IOC_SAS_RX_P5")
	)
	(arc
		(start 70.059042 -81.302098)
		(mid 70.175367 -81.229038)
		(end 70.31228 -81.21777)
		(width 0.1016)
		(layer "B.Cu")
		(net "IOC_SAS_RX_P5")
	)
	(arc
		(start 69.205856 -82.324194)
		(mid 69.342781 -82.312964)
		(end 69.459094 -82.239866)
		(width 0.1016)
		(layer "B.Cu")
		(net "IOC_SAS_RX_P5")
	)
	(arc
		(start 69.674486 -82.02422)
		(mid 69.747709 -81.907932)
		(end 69.759068 -81.770982)
		(width 0.1016)
		(layer "B.Cu")
		(net "IOC_SAS_RX_P5")
	)
	(arc
		(start 13.749782 -105.19029)
		(mid 13.860927 -105.748674)
		(end 14.177264 -106.222038)
		(width 0.1016)
		(layer "B.Cu")
		(net "IOC_SAS_RX_P5")
	)
	(arc
		(start 34.39795 -109.33303)
		(mid 35.01518 -109.210255)
		(end 35.53841 -108.86059)
		(width 0.1016)
		(layer "B.Cu")
		(net "IOC_SAS_RX_P5")
	)
	(arc
		(start 69.759068 -81.770982)
		(mid 69.770298 -81.634057)
		(end 69.843396 -81.517744)
		(width 0.1016)
		(layer "B.Cu")
		(net "IOC_SAS_RX_P5")
	)
	(arc
		(start 13.582904 -100.845366)
		(mid 13.706401 -101.030192)
		(end 13.749782 -101.24821)
		(width 0.1016)
		(layer "B.Cu")
		(net "IOC_SAS_RX_P5")
	)
	(arc
		(start 71.971662 -79.558134)
		(mid 71.983026 -79.421186)
		(end 72.056244 -79.304896)
		(width 0.1016)
		(layer "B.Cu")
		(net "IOC_SAS_RX_P5")
	)
	(arc
		(start 70.78091 -80.917796)
		(mid 70.85397 -80.801471)
		(end 70.865238 -80.664558)
		(width 0.1016)
		(layer "B.Cu")
		(net "IOC_SAS_RX_P5")
	)
	(arc
		(start 54.45887 -95.5929)
		(mid 55.668558 -95.352296)
		(end 56.69407 -94.66707)
		(width 0.1016)
		(layer "B.Cu")
		(net "IOC_SAS_RX_P5")
	)
	(arc
		(start 73.649586 -77.711554)
		(mid 73.999209 -77.188307)
		(end 74.122026 -76.571094)
		(width 0.1016)
		(layer "B.Cu")
		(net "IOC_SAS_RX_P5")
	)
	(arc
		(start 87.25789 -42.333418)
		(mid 87.501931 -42.170418)
		(end 87.789766 -42.1132)
		(width 0.1016)
		(layer "B.Cu")
		(net "IOC_SAS_RX_P5")
	)
	(segment
		(start 93.556836 -42.62247)
		(end 93.556836 -42.597324)
		(width 0.1016)
		(layer "F.Cu")
		(net "IOC_SAS_RX_N4")
	)
	(segment
		(start 93.950028 -42.999914)
		(end 93.93428 -42.999914)
		(width 0.1016)
		(layer "F.Cu")
		(net "IOC_SAS_RX_N4")
	)
	(segment
		(start 93.93428 -42.999914)
		(end 93.556836 -42.62247)
		(width 0.1016)
		(layer "F.Cu")
		(net "IOC_SAS_RX_N4")
	)
	(via
		(at 93.556836 -42.597324)
		(size 0.508)
		(drill 0.254)
		(layers "F.Cu" "B.Cu")
		(net "IOC_SAS_RX_N4")
	)
	(segment
		(start 58.3565 -96.0755)
		(end 61.436758 -92.995242)
		(width 0.1016)
		(layer "B.Cu")
		(net "IOC_SAS_RX_N4")
	)
	(segment
		(start 87.122 -44.45)
		(end 87.122 -44.446698)
		(width 0.1016)
		(layer "B.Cu")
		(net "IOC_SAS_RX_N4")
	)
	(segment
		(start 75.565 -78.340966)
		(end 75.565 -56.769)
		(width 0.1016)
		(layer "B.Cu")
		(net "IOC_SAS_RX_N4")
	)
	(segment
		(start 61.605668 -92.488766)
		(end 61.821314 -92.27312)
		(width 0.1016)
		(layer "B.Cu")
		(net "IOC_SAS_RX_N4")
	)
	(segment
		(start 93.432376 -42.721784)
		(end 93.556836 -42.597324)
		(width 0.1016)
		(layer "B.Cu")
		(net "IOC_SAS_RX_N4")
	)
	(segment
		(start 91.186 -42.780966)
		(end 91.286076 -42.68089)
		(width 0.1016)
		(layer "B.Cu")
		(net "IOC_SAS_RX_N4")
	)
	(segment
		(start 66.135504 -88.296496)
		(end 66.35115 -88.08085)
		(width 0.1016)
		(layer "B.Cu")
		(net "IOC_SAS_RX_N4")
	)
	(segment
		(start 88.933528 -42.81678)
		(end 91.100402 -42.81678)
		(width 0.1016)
		(layer "B.Cu")
		(net "IOC_SAS_RX_N4")
	)
	(segment
		(start 36.019486 -110.561374)
		(end 48.95342 -97.62744)
		(width 0.1016)
		(layer "B.Cu")
		(net "IOC_SAS_RX_N4")
	)
	(segment
		(start 87.122 -44.446698)
		(end 88.689688 -42.87901)
		(width 0.1016)
		(layer "B.Cu")
		(net "IOC_SAS_RX_N4")
	)
	(segment
		(start 76.10348 -55.468012)
		(end 76.327 -55.245)
		(width 0.1016)
		(layer "B.Cu")
		(net "IOC_SAS_RX_N4")
	)
	(segment
		(start 12.13739 -106.269028)
		(end 15.469616 -109.601254)
		(width 0.1016)
		(layer "B.Cu")
		(net "IOC_SAS_RX_N4")
	)
	(segment
		(start 67.62623 -86.468204)
		(end 67.841876 -86.252558)
		(width 0.1016)
		(layer "B.Cu")
		(net "IOC_SAS_RX_N4")
	)
	(segment
		(start 18.685256 -110.93323)
		(end 35.121596 -110.93323)
		(width 0.1016)
		(layer "B.Cu")
		(net "IOC_SAS_RX_N4")
	)
	(segment
		(start 11.766804 -101.55047)
		(end 11.766804 -105.37444)
		(width 0.1016)
		(layer "B.Cu")
		(net "IOC_SAS_RX_N4")
	)
	(segment
		(start 75.565 -56.769)
		(end 75.564746 -56.769)
		(width 0.1016)
		(layer "B.Cu")
		(net "IOC_SAS_RX_N4")
	)
	(segment
		(start 76.327 -55.245)
		(end 87.122 -44.45)
		(width 0.1016)
		(layer "B.Cu")
		(net "IOC_SAS_RX_N4")
	)
	(segment
		(start 91.614752 -42.545)
		(end 92.539566 -42.545)
		(width 0.1016)
		(layer "B.Cu")
		(net "IOC_SAS_RX_N4")
	)
	(segment
		(start 65.413382 -88.680798)
		(end 65.629028 -88.465406)
		(width 0.1016)
		(layer "B.Cu")
		(net "IOC_SAS_RX_N4")
	)
	(segment
		(start 68.348352 -86.083648)
		(end 75.193144 -79.238856)
		(width 0.1016)
		(layer "B.Cu")
		(net "IOC_SAS_RX_N4")
	)
	(segment
		(start 62.32779 -92.10421)
		(end 65.244726 -89.187274)
		(width 0.1016)
		(layer "B.Cu")
		(net "IOC_SAS_RX_N4")
	)
	(segment
		(start 66.519806 -87.574374)
		(end 66.735452 -87.358982)
		(width 0.1016)
		(layer "B.Cu")
		(net "IOC_SAS_RX_N4")
	)
	(segment
		(start 67.241928 -87.190072)
		(end 67.45732 -86.97468)
		(width 0.1016)
		(layer "B.Cu")
		(net "IOC_SAS_RX_N4")
	)
	(segment
		(start 50.09388 -97.155)
		(end 55.75046 -97.155)
		(width 0.1016)
		(layer "B.Cu")
		(net "IOC_SAS_RX_N4")
	)
	(arc
		(start 75.564746 -56.769)
		(mid 75.704719 -56.064929)
		(end 76.10348 -55.468012)
		(width 0.1016)
		(layer "B.Cu")
		(net "IOC_SAS_RX_N4")
	)
	(arc
		(start 68.095114 -86.16823)
		(mid 68.232062 -86.156866)
		(end 68.348352 -86.083648)
		(width 0.1016)
		(layer "B.Cu")
		(net "IOC_SAS_RX_N4")
	)
	(arc
		(start 11.773662 -101.43236)
		(mid 11.768475 -101.491313)
		(end 11.766804 -101.55047)
		(width 0.1016)
		(layer "B.Cu")
		(net "IOC_SAS_RX_N4")
	)
	(arc
		(start 67.841876 -86.252558)
		(mid 67.958201 -86.179498)
		(end 68.095114 -86.16823)
		(width 0.1016)
		(layer "B.Cu")
		(net "IOC_SAS_RX_N4")
	)
	(arc
		(start 67.541902 -86.721442)
		(mid 67.553132 -86.584517)
		(end 67.62623 -86.468204)
		(width 0.1016)
		(layer "B.Cu")
		(net "IOC_SAS_RX_N4")
	)
	(arc
		(start 65.244726 -89.187274)
		(mid 65.317786 -89.070949)
		(end 65.329054 -88.934036)
		(width 0.1016)
		(layer "B.Cu")
		(net "IOC_SAS_RX_N4")
	)
	(arc
		(start 66.35115 -88.08085)
		(mid 66.42421 -87.964525)
		(end 66.435478 -87.827612)
		(width 0.1016)
		(layer "B.Cu")
		(net "IOC_SAS_RX_N4")
	)
	(arc
		(start 66.98869 -87.274654)
		(mid 67.125638 -87.26329)
		(end 67.241928 -87.190072)
		(width 0.1016)
		(layer "B.Cu")
		(net "IOC_SAS_RX_N4")
	)
	(arc
		(start 92.539566 -42.545)
		(mid 92.851602 -42.57628)
		(end 93.151198 -42.668952)
		(width 0.1016)
		(layer "B.Cu")
		(net "IOC_SAS_RX_N4")
	)
	(arc
		(start 66.435478 -87.827612)
		(mid 66.446708 -87.690687)
		(end 66.519806 -87.574374)
		(width 0.1016)
		(layer "B.Cu")
		(net "IOC_SAS_RX_N4")
	)
	(arc
		(start 35.121596 -110.93323)
		(mid 35.607521 -110.836591)
		(end 36.019486 -110.561374)
		(width 0.1016)
		(layer "B.Cu")
		(net "IOC_SAS_RX_N4")
	)
	(arc
		(start 61.52134 -92.742004)
		(mid 61.53257 -92.605079)
		(end 61.605668 -92.488766)
		(width 0.1016)
		(layer "B.Cu")
		(net "IOC_SAS_RX_N4")
	)
	(arc
		(start 75.193144 -79.238856)
		(mid 75.46835 -78.826886)
		(end 75.565 -78.340966)
		(width 0.1016)
		(layer "B.Cu")
		(net "IOC_SAS_RX_N4")
	)
	(arc
		(start 12.058904 -100.845366)
		(mid 11.905397 -101.043116)
		(end 11.80592 -101.272848)
		(width 0.1016)
		(layer "B.Cu")
		(net "IOC_SAS_RX_N4")
	)
	(arc
		(start 91.100402 -42.81678)
		(mid 91.146743 -42.807357)
		(end 91.186 -42.780966)
		(width 0.1016)
		(layer "B.Cu")
		(net "IOC_SAS_RX_N4")
	)
	(arc
		(start 91.286076 -42.68089)
		(mid 91.436904 -42.580296)
		(end 91.614752 -42.545)
		(width 0.1016)
		(layer "B.Cu")
		(net "IOC_SAS_RX_N4")
	)
	(arc
		(start 65.629028 -88.465406)
		(mid 65.745316 -88.392183)
		(end 65.882266 -88.380824)
		(width 0.1016)
		(layer "B.Cu")
		(net "IOC_SAS_RX_N4")
	)
	(arc
		(start 88.689688 -42.87901)
		(mid 88.807695 -42.832553)
		(end 88.933528 -42.81678)
		(width 0.1016)
		(layer "B.Cu")
		(net "IOC_SAS_RX_N4")
	)
	(arc
		(start 65.882266 -88.380824)
		(mid 66.019191 -88.369594)
		(end 66.135504 -88.296496)
		(width 0.1016)
		(layer "B.Cu")
		(net "IOC_SAS_RX_N4")
	)
	(arc
		(start 61.821314 -92.27312)
		(mid 61.937639 -92.20006)
		(end 62.074552 -92.188792)
		(width 0.1016)
		(layer "B.Cu")
		(net "IOC_SAS_RX_N4")
	)
	(arc
		(start 11.766804 -105.37444)
		(mid 11.86311 -105.858601)
		(end 12.13739 -106.269028)
		(width 0.1016)
		(layer "B.Cu")
		(net "IOC_SAS_RX_N4")
	)
	(arc
		(start 62.074552 -92.188792)
		(mid 62.2115 -92.177428)
		(end 62.32779 -92.10421)
		(width 0.1016)
		(layer "B.Cu")
		(net "IOC_SAS_RX_N4")
	)
	(arc
		(start 93.298772 -42.74058)
		(mid 93.368729 -42.753519)
		(end 93.432376 -42.721784)
		(width 0.1016)
		(layer "B.Cu")
		(net "IOC_SAS_RX_N4")
	)
	(arc
		(start 11.80592 -101.272848)
		(mid 11.786525 -101.351944)
		(end 11.773662 -101.43236)
		(width 0.1016)
		(layer "B.Cu")
		(net "IOC_SAS_RX_N4")
	)
	(arc
		(start 55.75046 -97.155)
		(mid 57.160855 -96.874455)
		(end 58.3565 -96.0755)
		(width 0.1016)
		(layer "B.Cu")
		(net "IOC_SAS_RX_N4")
	)
	(arc
		(start 15.469616 -109.601254)
		(mid 16.944964 -110.58705)
		(end 18.685256 -110.93323)
		(width 0.1016)
		(layer "B.Cu")
		(net "IOC_SAS_RX_N4")
	)
	(arc
		(start 66.735452 -87.358982)
		(mid 66.851777 -87.285922)
		(end 66.98869 -87.274654)
		(width 0.1016)
		(layer "B.Cu")
		(net "IOC_SAS_RX_N4")
	)
	(arc
		(start 61.436758 -92.995242)
		(mid 61.509981 -92.878954)
		(end 61.52134 -92.742004)
		(width 0.1016)
		(layer "B.Cu")
		(net "IOC_SAS_RX_N4")
	)
	(arc
		(start 67.45732 -86.97468)
		(mid 67.530543 -86.858392)
		(end 67.541902 -86.721442)
		(width 0.1016)
		(layer "B.Cu")
		(net "IOC_SAS_RX_N4")
	)
	(arc
		(start 65.329054 -88.934036)
		(mid 65.340284 -88.797111)
		(end 65.413382 -88.680798)
		(width 0.1016)
		(layer "B.Cu")
		(net "IOC_SAS_RX_N4")
	)
	(arc
		(start 48.95342 -97.62744)
		(mid 49.476667 -97.277817)
		(end 50.09388 -97.155)
		(width 0.1016)
		(layer "B.Cu")
		(net "IOC_SAS_RX_N4")
	)
	(arc
		(start 93.151198 -42.668952)
		(mid 93.22592 -42.702839)
		(end 93.298772 -42.74058)
		(width 0.1016)
		(layer "B.Cu")
		(net "IOC_SAS_RX_N4")
	)
	(segment
		(start 93.150182 -42.999914)
		(end 93.15958 -42.999914)
		(width 0.1016)
		(layer "F.Cu")
		(net "IOC_SAS_RX_P4")
	)
	(segment
		(start 93.15958 -42.999914)
		(end 93.550486 -43.39082)
		(width 0.1016)
		(layer "F.Cu")
		(net "IOC_SAS_RX_P4")
	)
	(via
		(at 93.550486 -43.39082)
		(size 0.508)
		(drill 0.254)
		(layers "F.Cu" "B.Cu")
		(net "IOC_SAS_RX_P4")
	)
	(segment
		(start 91.614752 -42.8879)
		(end 92.539566 -42.8879)
		(width 0.1016)
		(layer "B.Cu")
		(net "IOC_SAS_RX_P4")
	)
	(segment
		(start 87.4649 -44.588938)
		(end 88.887554 -43.166284)
		(width 0.1016)
		(layer "B.Cu")
		(net "IOC_SAS_RX_P4")
	)
	(segment
		(start 91.42857 -43.02379)
		(end 91.5289 -42.92346)
		(width 0.1016)
		(layer "B.Cu")
		(net "IOC_SAS_RX_P4")
	)
	(segment
		(start 93.406722 -43.247056)
		(end 93.550486 -43.39082)
		(width 0.1016)
		(layer "B.Cu")
		(net "IOC_SAS_RX_P4")
	)
	(segment
		(start 58.59907 -96.31807)
		(end 75.43546 -79.48168)
		(width 0.1016)
		(layer "B.Cu")
		(net "IOC_SAS_RX_P4")
	)
	(segment
		(start 76.56957 -55.48757)
		(end 87.4649 -44.59224)
		(width 0.1016)
		(layer "B.Cu")
		(net "IOC_SAS_RX_P4")
	)
	(segment
		(start 88.933528 -43.15968)
		(end 91.100402 -43.15968)
		(width 0.1016)
		(layer "B.Cu")
		(net "IOC_SAS_RX_P4")
	)
	(segment
		(start 11.169904 -100.845366)
		(end 11.379454 -101.05517)
		(width 0.1016)
		(layer "B.Cu")
		(net "IOC_SAS_RX_P4")
	)
	(segment
		(start 50.094134 -97.4979)
		(end 55.750714 -97.4979)
		(width 0.1016)
		(layer "B.Cu")
		(net "IOC_SAS_RX_P4")
	)
	(segment
		(start 76.34605 -55.710836)
		(end 76.56957 -55.48757)
		(width 0.1016)
		(layer "B.Cu")
		(net "IOC_SAS_RX_P4")
	)
	(segment
		(start 11.423904 -101.162104)
		(end 11.423904 -105.37444)
		(width 0.1016)
		(layer "B.Cu")
		(net "IOC_SAS_RX_P4")
	)
	(segment
		(start 75.9079 -78.34122)
		(end 75.9079 -56.769)
		(width 0.1016)
		(layer "B.Cu")
		(net "IOC_SAS_RX_P4")
	)
	(segment
		(start 11.89482 -106.511598)
		(end 15.227046 -109.843824)
		(width 0.1016)
		(layer "B.Cu")
		(net "IOC_SAS_RX_P4")
	)
	(segment
		(start 36.26231 -110.80369)
		(end 49.196244 -97.869756)
		(width 0.1016)
		(layer "B.Cu")
		(net "IOC_SAS_RX_P4")
	)
	(segment
		(start 87.4649 -44.59224)
		(end 87.4649 -44.588938)
		(width 0.1016)
		(layer "B.Cu")
		(net "IOC_SAS_RX_P4")
	)
	(segment
		(start 18.685002 -111.27613)
		(end 35.12185 -111.27613)
		(width 0.1016)
		(layer "B.Cu")
		(net "IOC_SAS_RX_P4")
	)
	(arc
		(start 11.423904 -105.37444)
		(mid 11.546228 -105.989877)
		(end 11.89482 -106.511598)
		(width 0.1016)
		(layer "B.Cu")
		(net "IOC_SAS_RX_P4")
	)
	(arc
		(start 11.379454 -101.05517)
		(mid 11.412319 -101.104217)
		(end 11.423904 -101.162104)
		(width 0.1016)
		(layer "B.Cu")
		(net "IOC_SAS_RX_P4")
	)
	(arc
		(start 92.539566 -42.8879)
		(mid 92.783454 -42.912402)
		(end 93.017594 -42.984928)
		(width 0.1016)
		(layer "B.Cu")
		(net "IOC_SAS_RX_P4")
	)
	(arc
		(start 35.12185 -111.27613)
		(mid 35.73908 -111.153355)
		(end 36.26231 -110.80369)
		(width 0.1016)
		(layer "B.Cu")
		(net "IOC_SAS_RX_P4")
	)
	(arc
		(start 91.5289 -42.92346)
		(mid 91.568289 -42.897141)
		(end 91.614752 -42.8879)
		(width 0.1016)
		(layer "B.Cu")
		(net "IOC_SAS_RX_P4")
	)
	(arc
		(start 88.887554 -43.166284)
		(mid 88.910308 -43.161365)
		(end 88.933528 -43.15968)
		(width 0.1016)
		(layer "B.Cu")
		(net "IOC_SAS_RX_P4")
	)
	(arc
		(start 49.196244 -97.869756)
		(mid 49.608214 -97.59455)
		(end 50.094134 -97.4979)
		(width 0.1016)
		(layer "B.Cu")
		(net "IOC_SAS_RX_P4")
	)
	(arc
		(start 91.100402 -43.15968)
		(mid 91.278004 -43.124371)
		(end 91.42857 -43.02379)
		(width 0.1016)
		(layer "B.Cu")
		(net "IOC_SAS_RX_P4")
	)
	(arc
		(start 55.750714 -97.4979)
		(mid 57.292248 -97.191288)
		(end 58.59907 -96.31807)
		(width 0.1016)
		(layer "B.Cu")
		(net "IOC_SAS_RX_P4")
	)
	(arc
		(start 75.9079 -56.769)
		(mid 76.021717 -56.196332)
		(end 76.34605 -55.710836)
		(width 0.1016)
		(layer "B.Cu")
		(net "IOC_SAS_RX_P4")
	)
	(arc
		(start 15.227046 -109.843824)
		(mid 16.813584 -110.903852)
		(end 18.685002 -111.27613)
		(width 0.1016)
		(layer "B.Cu")
		(net "IOC_SAS_RX_P4")
	)
	(arc
		(start 75.43546 -79.48168)
		(mid 75.785083 -78.958433)
		(end 75.9079 -78.34122)
		(width 0.1016)
		(layer "B.Cu")
		(net "IOC_SAS_RX_P4")
	)
	(arc
		(start 93.017594 -42.984928)
		(mid 93.22481 -43.097211)
		(end 93.406722 -43.247056)
		(width 0.1016)
		(layer "B.Cu")
		(net "IOC_SAS_RX_P4")
	)
	(segment
		(start 291.6301 -168.644824)
		(end 291.234876 -169.040048)
		(width 0.1143)
		(layer "F.Cu")
		(net "BMC_TXD1")
	)
	(segment
		(start 290.322 -160.163002)
		(end 290.322 -159.766)
		(width 0.1143)
		(layer "F.Cu")
		(net "BMC_TXD1")
	)
	(segment
		(start 289.941 -159.766)
		(end 290.322 -159.766)
		(width 0.1143)
		(layer "F.Cu")
		(net "BMC_TXD1")
	)
	(segment
		(start 289.1155 -158.9405)
		(end 289.941 -159.766)
		(width 0.1143)
		(layer "F.Cu")
		(net "BMC_TXD1")
	)
	(segment
		(start 289.920934 -160.564068)
		(end 290.322 -160.163002)
		(width 0.1143)
		(layer "F.Cu")
		(net "BMC_TXD1")
	)
	(segment
		(start 288.925 -158.9405)
		(end 289.1155 -158.9405)
		(width 0.1143)
		(layer "F.Cu")
		(net "BMC_TXD1")
	)
	(via
		(at 290.322 -159.766)
		(size 0.508)
		(drill 0.254)
		(layers "F.Cu" "B.Cu")
		(net "BMC_TXD1")
	)
	(via
		(at 291.6301 -168.644824)
		(size 0.508)
		(drill 0.254)
		(layers "F.Cu" "B.Cu")
		(net "BMC_TXD1")
	)
	(via
		(at 289.920934 -160.564068)
		(size 0.7112)
		(drill 0.3556)
		(layers "F.Cu" "B.Cu")
		(net "BMC_TXD1")
	)
	(segment
		(start 291.338 -160.782)
		(end 291.338 -162.179)
		(width 0.127)
		(layer "In2.Cu")
		(net "BMC_TXD1")
	)
	(segment
		(start 290.322 -159.766)
		(end 291.338 -160.782)
		(width 0.127)
		(layer "In2.Cu")
		(net "BMC_TXD1")
	)
	(segment
		(start 291.338 -162.179)
		(end 291.6301 -162.4711)
		(width 0.127)
		(layer "In2.Cu")
		(net "BMC_TXD1")
	)
	(segment
		(start 291.6301 -162.4711)
		(end 291.6301 -168.644824)
		(width 0.127)
		(layer "In2.Cu")
		(net "BMC_TXD1")
	)
	(segment
		(start 335.407 -211.8995)
		(end 336.6135 -211.8995)
		(width 0.1143)
		(layer "F.Cu")
		(net "BMC_I2C_SDA_10")
	)
	(segment
		(start 117.67947 -67.20967)
		(end 117.1194 -66.6496)
		(width 0.1143)
		(layer "F.Cu")
		(net "BMC_I2C_SDA_10")
	)
	(segment
		(start 94.361 -220.218)
		(end 94.234 -220.091)
		(width 0.1143)
		(layer "F.Cu")
		(net "BMC_I2C_SDA_10")
	)
	(segment
		(start 198.12 -18.6055)
		(end 198.12 -24.765)
		(width 0.1143)
		(layer "F.Cu")
		(net "BMC_I2C_SDA_10")
	)
	(segment
		(start 117.1575 -70.485)
		(end 117.67947 -69.96303)
		(width 0.1143)
		(layer "F.Cu")
		(net "BMC_I2C_SDA_10")
	)
	(segment
		(start 193.6115 -14.097)
		(end 198.12 -18.6055)
		(width 0.1143)
		(layer "F.Cu")
		(net "BMC_I2C_SDA_10")
	)
	(segment
		(start 68.58 -220.98)
		(end 69.215 -220.345)
		(width 0.1143)
		(layer "F.Cu")
		(net "BMC_I2C_SDA_10")
	)
	(segment
		(start 311.80405 -142.360396)
		(end 312.15203 -142.708376)
		(width 0.1143)
		(layer "F.Cu")
		(net "BMC_I2C_SDA_10")
	)
	(segment
		(start 14.928088 -202.629516)
		(end 14.674088 -202.883516)
		(width 0.1143)
		(layer "F.Cu")
		(net "BMC_I2C_SDA_10")
	)
	(segment
		(start 311.80405 -128.097534)
		(end 311.80405 -142.360396)
		(width 0.1143)
		(layer "F.Cu")
		(net "BMC_I2C_SDA_10")
	)
	(segment
		(start 14.968728 -204.471016)
		(end 14.674088 -204.176376)
		(width 0.1143)
		(layer "F.Cu")
		(net "BMC_I2C_SDA_10")
	)
	(segment
		(start 311.785 -128.078484)
		(end 311.80405 -128.097534)
		(width 0.1143)
		(layer "F.Cu")
		(net "BMC_I2C_SDA_10")
	)
	(segment
		(start 63.518796 -208.56575)
		(end 57.88025 -208.56575)
		(width 0.1143)
		(layer "F.Cu")
		(net "BMC_I2C_SDA_10")
	)
	(segment
		(start 290.1315 -67.691)
		(end 291.084 -67.691)
		(width 0.1143)
		(layer "F.Cu")
		(net "BMC_I2C_SDA_10")
	)
	(segment
		(start 35.827716 -204.14488)
		(end 37.034216 -204.14488)
		(width 0.1143)
		(layer "F.Cu")
		(net "BMC_I2C_SDA_10")
	)
	(segment
		(start 312.15203 -155.20797)
		(end 308.102 -159.258)
		(width 0.1143)
		(layer "F.Cu")
		(net "BMC_I2C_SDA_10")
	)
	(segment
		(start 306.578 -205.5495)
		(end 306.578 -209.042)
		(width 0.1143)
		(layer "F.Cu")
		(net "BMC_I2C_SDA_10")
	)
	(segment
		(start 56.896 -210.6295)
		(end 56.896 -209.804)
		(width 0.1143)
		(layer "F.Cu")
		(net "BMC_I2C_SDA_10")
	)
	(segment
		(start 117.67947 -69.96303)
		(end 117.67947 -67.20967)
		(width 0.1143)
		(layer "F.Cu")
		(net "BMC_I2C_SDA_10")
	)
	(segment
		(start 37.034216 -204.14488)
		(end 37.161216 -204.27188)
		(width 0.1143)
		(layer "F.Cu")
		(net "BMC_I2C_SDA_10")
	)
	(segment
		(start 334.518 -216.916)
		(end 334.518 -216.027)
		(width 0.1143)
		(layer "F.Cu")
		(net "BMC_I2C_SDA_10")
	)
	(segment
		(start 300.228 -91.5035)
		(end 300.228 -90.678)
		(width 0.1143)
		(layer "F.Cu")
		(net "BMC_I2C_SDA_10")
	)
	(segment
		(start 94.361 -220.9165)
		(end 94.361 -220.218)
		(width 0.1143)
		(layer "F.Cu")
		(net "BMC_I2C_SDA_10")
	)
	(segment
		(start 291.084 -67.691)
		(end 291.211 -67.818)
		(width 0.1143)
		(layer "F.Cu")
		(net "BMC_I2C_SDA_10")
	)
	(segment
		(start 69.215 -220.345)
		(end 69.215 -214.261954)
		(width 0.1143)
		(layer "F.Cu")
		(net "BMC_I2C_SDA_10")
	)
	(segment
		(start 312.15203 -142.708376)
		(end 312.15203 -155.20797)
		(width 0.1143)
		(layer "F.Cu")
		(net "BMC_I2C_SDA_10")
	)
	(segment
		(start 260.966204 -87.611204)
		(end 260.966204 -88.011)
		(width 0.1143)
		(layer "F.Cu")
		(net "BMC_I2C_SDA_10")
	)
	(segment
		(start 56.896 -209.804)
		(end 56.769 -209.677)
		(width 0.1143)
		(layer "F.Cu")
		(net "BMC_I2C_SDA_10")
	)
	(segment
		(start 117.1194 -66.6496)
		(end 117.1194 -66.0527)
		(width 0.1143)
		(layer "F.Cu")
		(net "BMC_I2C_SDA_10")
	)
	(segment
		(start 14.674088 -202.883516)
		(end 14.674088 -203.582016)
		(width 0.1143)
		(layer "F.Cu")
		(net "BMC_I2C_SDA_10")
	)
	(segment
		(start 14.674088 -204.176376)
		(end 14.674088 -203.582016)
		(width 0.1143)
		(layer "F.Cu")
		(net "BMC_I2C_SDA_10")
	)
	(segment
		(start 69.215 -214.261954)
		(end 63.518796 -208.56575)
		(width 0.1143)
		(layer "F.Cu")
		(net "BMC_I2C_SDA_10")
	)
	(segment
		(start 306.578 -209.042)
		(end 309.499 -211.963)
		(width 0.1143)
		(layer "F.Cu")
		(net "BMC_I2C_SDA_10")
	)
	(segment
		(start 14.968728 -205.258416)
		(end 14.968728 -204.471016)
		(width 0.1143)
		(layer "F.Cu")
		(net "BMC_I2C_SDA_10")
	)
	(segment
		(start 308.102 -159.258)
		(end 308.102 -160.2105)
		(width 0.1143)
		(layer "F.Cu")
		(net "BMC_I2C_SDA_10")
	)
	(segment
		(start 198.12 -24.765)
		(end 260.966204 -87.611204)
		(width 0.1143)
		(layer "F.Cu")
		(net "BMC_I2C_SDA_10")
	)
	(segment
		(start 57.88025 -208.56575)
		(end 56.769 -209.677)
		(width 0.1143)
		(layer "F.Cu")
		(net "BMC_I2C_SDA_10")
	)
	(via
		(at 134.239 -78.74)
		(size 0.5588)
		(drill 0.3048)
		(layers "F.Cu" "B.Cu")
		(net "BMC_I2C_SDA_10")
	)
	(via
		(at 56.769 -209.677)
		(size 0.5588)
		(drill 0.3048)
		(layers "F.Cu" "B.Cu")
		(net "BMC_I2C_SDA_10")
	)
	(via
		(at 100.584 -181.483)
		(size 0.5588)
		(drill 0.3048)
		(layers "F.Cu" "B.Cu")
		(net "BMC_I2C_SDA_10")
	)
	(via
		(at 334.518 -216.027)
		(size 0.5588)
		(drill 0.3048)
		(layers "F.Cu" "B.Cu")
		(net "BMC_I2C_SDA_10")
	)
	(via
		(at 336.6135 -211.8995)
		(size 0.5588)
		(drill 0.3048)
		(layers "F.Cu" "B.Cu")
		(net "BMC_I2C_SDA_10")
	)
	(via
		(at 14.674088 -203.582016)
		(size 0.5588)
		(drill 0.3048)
		(layers "F.Cu" "B.Cu")
		(net "BMC_I2C_SDA_10")
	)
	(via
		(at 328.676 -149.225)
		(size 0.5588)
		(drill 0.3048)
		(layers "F.Cu" "B.Cu")
		(net "BMC_I2C_SDA_10")
	)
	(via
		(at 68.58 -220.98)
		(size 0.5588)
		(drill 0.3048)
		(layers "F.Cu" "B.Cu")
		(net "BMC_I2C_SDA_10")
	)
	(via
		(at 309.499 -211.963)
		(size 0.5588)
		(drill 0.3048)
		(layers "F.Cu" "B.Cu")
		(net "BMC_I2C_SDA_10")
	)
	(via
		(at 37.161216 -204.27188)
		(size 0.5588)
		(drill 0.3048)
		(layers "F.Cu" "B.Cu")
		(net "BMC_I2C_SDA_10")
	)
	(via
		(at 300.228 -90.678)
		(size 0.5588)
		(drill 0.3048)
		(layers "F.Cu" "B.Cu")
		(net "BMC_I2C_SDA_10")
	)
	(via
		(at 291.211 -67.818)
		(size 0.5588)
		(drill 0.3048)
		(layers "F.Cu" "B.Cu")
		(net "BMC_I2C_SDA_10")
	)
	(via
		(at 336.33283 -169.767504)
		(size 0.7112)
		(drill 0.3556)
		(layers "F.Cu" "B.Cu")
		(net "BMC_I2C_SDA_10")
	)
	(via
		(at 260.966204 -88.011)
		(size 0.5588)
		(drill 0.3048)
		(layers "F.Cu" "B.Cu")
		(net "BMC_I2C_SDA_10")
	)
	(via
		(at 28.067 -215.519)
		(size 0.5588)
		(drill 0.3048)
		(layers "F.Cu" "B.Cu")
		(net "BMC_I2C_SDA_10")
	)
	(via
		(at 311.785 -128.078484)
		(size 0.5588)
		(drill 0.3048)
		(layers "F.Cu" "B.Cu")
		(net "BMC_I2C_SDA_10")
	)
	(via
		(at 336.169 -178.308)
		(size 0.5588)
		(drill 0.3048)
		(layers "F.Cu" "B.Cu")
		(net "BMC_I2C_SDA_10")
	)
	(via
		(at 143.31061 -93.812106)
		(size 0.5588)
		(drill 0.3048)
		(layers "F.Cu" "B.Cu")
		(net "BMC_I2C_SDA_10")
	)
	(via
		(at 94.234 -220.091)
		(size 0.5588)
		(drill 0.3048)
		(layers "F.Cu" "B.Cu")
		(net "BMC_I2C_SDA_10")
	)
	(via
		(at 117.1194 -66.0527)
		(size 0.5588)
		(drill 0.3048)
		(layers "F.Cu" "B.Cu")
		(net "BMC_I2C_SDA_10")
	)
	(segment
		(start 143.37792 -93.744796)
		(end 143.37792 -92.380308)
		(width 0.1143)
		(layer "B.Cu")
		(net "BMC_I2C_SDA_10")
	)
	(segment
		(start 100.010468 -181.483)
		(end 100.584 -181.483)
		(width 0.1143)
		(layer "B.Cu")
		(net "BMC_I2C_SDA_10")
	)
	(segment
		(start 142.723616 -94.3991)
		(end 143.31061 -93.812106)
		(width 0.1143)
		(layer "B.Cu")
		(net "BMC_I2C_SDA_10")
	)
	(segment
		(start 134.314946 -78.74)
		(end 134.239 -78.74)
		(width 0.1143)
		(layer "B.Cu")
		(net "BMC_I2C_SDA_10")
	)
	(segment
		(start 30.442916 -211.765896)
		(end 30.442916 -213.143084)
		(width 0.1143)
		(layer "B.Cu")
		(net "BMC_I2C_SDA_10")
	)
	(segment
		(start 297.561 -88.011)
		(end 300.228 -90.678)
		(width 0.1143)
		(layer "B.Cu")
		(net "BMC_I2C_SDA_10")
	)
	(segment
		(start 37.161216 -204.637132)
		(end 30.442662 -211.355686)
		(width 0.1143)
		(layer "B.Cu")
		(net "BMC_I2C_SDA_10")
	)
	(segment
		(start 336.33283 -169.767504)
		(end 336.33283 -160.823656)
		(width 0.1143)
		(layer "B.Cu")
		(net "BMC_I2C_SDA_10")
	)
	(segment
		(start 30.442662 -211.355686)
		(end 30.442662 -211.765642)
		(width 0.1143)
		(layer "B.Cu")
		(net "BMC_I2C_SDA_10")
	)
	(segment
		(start 136.651746 -81.0768)
		(end 134.314946 -78.74)
		(width 0.1143)
		(layer "B.Cu")
		(net "BMC_I2C_SDA_10")
	)
	(segment
		(start 330.49845 -155.49245)
		(end 330.49845 -151.04745)
		(width 0.1143)
		(layer "B.Cu")
		(net "BMC_I2C_SDA_10")
	)
	(segment
		(start 136.804654 -81.0768)
		(end 136.651746 -81.0768)
		(width 0.1143)
		(layer "B.Cu")
		(net "BMC_I2C_SDA_10")
	)
	(segment
		(start 143.31061 -93.812106)
		(end 143.37792 -93.744796)
		(width 0.1143)
		(layer "B.Cu")
		(net "BMC_I2C_SDA_10")
	)
	(segment
		(start 336.169 -171.577)
		(end 336.169 -178.308)
		(width 0.1143)
		(layer "B.Cu")
		(net "BMC_I2C_SDA_10")
	)
	(segment
		(start 143.37792 -92.380308)
		(end 142.437612 -91.44)
		(width 0.1143)
		(layer "B.Cu")
		(net "BMC_I2C_SDA_10")
	)
	(segment
		(start 336.296 -171.45)
		(end 336.169 -171.577)
		(width 0.1143)
		(layer "B.Cu")
		(net "BMC_I2C_SDA_10")
	)
	(segment
		(start 137.06475 -81.08315)
		(end 136.811004 -81.08315)
		(width 0.1143)
		(layer "B.Cu")
		(net "BMC_I2C_SDA_10")
	)
	(segment
		(start 136.811004 -81.08315)
		(end 136.804654 -81.0768)
		(width 0.1143)
		(layer "B.Cu")
		(net "BMC_I2C_SDA_10")
	)
	(segment
		(start 30.442916 -213.143084)
		(end 28.067 -215.519)
		(width 0.1143)
		(layer "B.Cu")
		(net "BMC_I2C_SDA_10")
	)
	(segment
		(start 137.692384 -88.359742)
		(end 137.692384 -81.710784)
		(width 0.1143)
		(layer "B.Cu")
		(net "BMC_I2C_SDA_10")
	)
	(segment
		(start 141.97457 -94.3991)
		(end 142.723616 -94.3991)
		(width 0.1143)
		(layer "B.Cu")
		(net "BMC_I2C_SDA_10")
	)
	(segment
		(start 140.772642 -91.44)
		(end 137.692384 -88.359742)
		(width 0.1143)
		(layer "B.Cu")
		(net "BMC_I2C_SDA_10")
	)
	(segment
		(start 142.437612 -91.44)
		(end 140.772642 -91.44)
		(width 0.1143)
		(layer "B.Cu")
		(net "BMC_I2C_SDA_10")
	)
	(segment
		(start 336.33283 -169.767504)
		(end 336.296 -169.804334)
		(width 0.1143)
		(layer "B.Cu")
		(net "BMC_I2C_SDA_10")
	)
	(segment
		(start 94.234 -220.091)
		(end 97.663 -216.662)
		(width 0.1143)
		(layer "B.Cu")
		(net "BMC_I2C_SDA_10")
	)
	(segment
		(start 37.161216 -204.27188)
		(end 37.161216 -204.637132)
		(width 0.1143)
		(layer "B.Cu")
		(net "BMC_I2C_SDA_10")
	)
	(segment
		(start 30.442662 -211.765642)
		(end 30.442916 -211.765896)
		(width 0.1143)
		(layer "B.Cu")
		(net "BMC_I2C_SDA_10")
	)
	(segment
		(start 331.47 -156.464)
		(end 330.49845 -155.49245)
		(width 0.1143)
		(layer "B.Cu")
		(net "BMC_I2C_SDA_10")
	)
	(segment
		(start 97.663 -216.662)
		(end 97.663 -183.830468)
		(width 0.1143)
		(layer "B.Cu")
		(net "BMC_I2C_SDA_10")
	)
	(segment
		(start 331.973174 -156.464)
		(end 331.47 -156.464)
		(width 0.1143)
		(layer "B.Cu")
		(net "BMC_I2C_SDA_10")
	)
	(segment
		(start 336.33283 -160.823656)
		(end 331.973174 -156.464)
		(width 0.1143)
		(layer "B.Cu")
		(net "BMC_I2C_SDA_10")
	)
	(segment
		(start 260.966204 -88.011)
		(end 297.561 -88.011)
		(width 0.1143)
		(layer "B.Cu")
		(net "BMC_I2C_SDA_10")
	)
	(segment
		(start 336.296 -169.804334)
		(end 336.296 -171.45)
		(width 0.1143)
		(layer "B.Cu")
		(net "BMC_I2C_SDA_10")
	)
	(segment
		(start 137.692384 -81.710784)
		(end 137.06475 -81.08315)
		(width 0.1143)
		(layer "B.Cu")
		(net "BMC_I2C_SDA_10")
	)
	(segment
		(start 330.49845 -151.04745)
		(end 328.676 -149.225)
		(width 0.1143)
		(layer "B.Cu")
		(net "BMC_I2C_SDA_10")
	)
	(segment
		(start 97.663 -183.830468)
		(end 100.010468 -181.483)
		(width 0.1143)
		(layer "B.Cu")
		(net "BMC_I2C_SDA_10")
	)
	(segment
		(start 56.769 -209.677)
		(end 56.007 -208.915)
		(width 0.127)
		(layer "In2.Cu")
		(net "BMC_I2C_SDA_10")
	)
	(segment
		(start 337.1088 -179.2478)
		(end 336.169 -178.308)
		(width 0.127)
		(layer "In2.Cu")
		(net "BMC_I2C_SDA_10")
	)
	(segment
		(start 300.228 -89.491566)
		(end 300.228 -90.678)
		(width 0.127)
		(layer "In2.Cu")
		(net "BMC_I2C_SDA_10")
	)
	(segment
		(start 299.593 -95.213932)
		(end 299.593 -101.219)
		(width 0.127)
		(layer "In2.Cu")
		(net "BMC_I2C_SDA_10")
	)
	(segment
		(start 255.916938 -93.0783)
		(end 233.918506 -93.0783)
		(width 0.127)
		(layer "In2.Cu")
		(net "BMC_I2C_SDA_10")
	)
	(segment
		(start 311.447434 -127.889)
		(end 311.595516 -127.889)
		(width 0.127)
		(layer "In2.Cu")
		(net "BMC_I2C_SDA_10")
	)
	(segment
		(start 337.1088 -213.4362)
		(end 337.1088 -179.2478)
		(width 0.127)
		(layer "In2.Cu")
		(net "BMC_I2C_SDA_10")
	)
	(segment
		(start 80.731868 -220.599)
		(end 82.509868 -222.377)
		(width 0.127)
		(layer "In2.Cu")
		(net "BMC_I2C_SDA_10")
	)
	(segment
		(start 299.593 -101.219)
		(end 298.8437 -101.9683)
		(width 0.127)
		(layer "In2.Cu")
		(net "BMC_I2C_SDA_10")
	)
	(segment
		(start 327.533 -143.680434)
		(end 328.676 -144.823434)
		(width 0.127)
		(layer "In2.Cu")
		(net "BMC_I2C_SDA_10")
	)
	(segment
		(start 291.211 -67.818)
		(end 291.211 -69.215)
		(width 0.127)
		(layer "In2.Cu")
		(net "BMC_I2C_SDA_10")
	)
	(segment
		(start 68.961 -220.599)
		(end 80.731868 -220.599)
		(width 0.127)
		(layer "In2.Cu")
		(net "BMC_I2C_SDA_10")
	)
	(segment
		(start 299.339 -86.741)
		(end 299.339 -88.602566)
		(width 0.127)
		(layer "In2.Cu")
		(net "BMC_I2C_SDA_10")
	)
	(segment
		(start 187.67552 -86.89848)
		(end 183.134 -91.44)
		(width 0.127)
		(layer "In2.Cu")
		(net "BMC_I2C_SDA_10")
	)
	(segment
		(start 292.1 -75.139042)
		(end 292.227 -75.266042)
		(width 0.127)
		(layer "In2.Cu")
		(net "BMC_I2C_SDA_10")
	)
	(segment
		(start 327.533 -140.90396)
		(end 327.533 -143.680434)
		(width 0.127)
		(layer "In2.Cu")
		(net "BMC_I2C_SDA_10")
	)
	(segment
		(start 298.8437 -114.523266)
		(end 307.086 -122.765566)
		(width 0.127)
		(layer "In2.Cu")
		(net "BMC_I2C_SDA_10")
	)
	(segment
		(start 132.159502 -75.543664)
		(end 132.159502 -74.22134)
		(width 0.127)
		(layer "In2.Cu")
		(net "BMC_I2C_SDA_10")
	)
	(segment
		(start 312.76798 -128.078484)
		(end 316.811914 -132.122418)
		(width 0.127)
		(layer "In2.Cu")
		(net "BMC_I2C_SDA_10")
	)
	(segment
		(start 144.960848 -93.599254)
		(end 143.523208 -93.599254)
		(width 0.127)
		(layer "In2.Cu")
		(net "BMC_I2C_SDA_10")
	)
	(segment
		(start 132.159502 -74.22134)
		(end 127.407162 -69.469)
		(width 0.127)
		(layer "In2.Cu")
		(net "BMC_I2C_SDA_10")
	)
	(segment
		(start 183.134 -91.44)
		(end 147.120102 -91.44)
		(width 0.127)
		(layer "In2.Cu")
		(net "BMC_I2C_SDA_10")
	)
	(segment
		(start 260.966204 -88.029034)
		(end 255.916938 -93.0783)
		(width 0.127)
		(layer "In2.Cu")
		(net "BMC_I2C_SDA_10")
	)
	(segment
		(start 328.676 -144.823434)
		(end 328.676 -149.225)
		(width 0.127)
		(layer "In2.Cu")
		(net "BMC_I2C_SDA_10")
	)
	(segment
		(start 127.407162 -69.469)
		(end 121.85777 -69.469)
		(width 0.127)
		(layer "In2.Cu")
		(net "BMC_I2C_SDA_10")
	)
	(segment
		(start 56.007 -208.915)
		(end 46.522132 -208.915)
		(width 0.127)
		(layer "In2.Cu")
		(net "BMC_I2C_SDA_10")
	)
	(segment
		(start 88.475566 -220.091)
		(end 94.234 -220.091)
		(width 0.127)
		(layer "In2.Cu")
		(net "BMC_I2C_SDA_10")
	)
	(segment
		(start 295.402 -79.187548)
		(end 295.402 -82.804)
		(width 0.127)
		(layer "In2.Cu")
		(net "BMC_I2C_SDA_10")
	)
	(segment
		(start 233.918506 -93.0783)
		(end 228.448616 -87.60841)
		(width 0.127)
		(layer "In2.Cu")
		(net "BMC_I2C_SDA_10")
	)
	(segment
		(start 42.077132 -204.47)
		(end 37.359336 -204.47)
		(width 0.127)
		(layer "In2.Cu")
		(net "BMC_I2C_SDA_10")
	)
	(segment
		(start 147.120102 -91.44)
		(end 144.960848 -93.599254)
		(width 0.127)
		(layer "In2.Cu")
		(net "BMC_I2C_SDA_10")
	)
	(segment
		(start 119.13997 -66.7512)
		(end 117.8179 -66.7512)
		(width 0.127)
		(layer "In2.Cu")
		(net "BMC_I2C_SDA_10")
	)
	(segment
		(start 292.1 -70.104)
		(end 292.1 -75.139042)
		(width 0.127)
		(layer "In2.Cu")
		(net "BMC_I2C_SDA_10")
	)
	(segment
		(start 134.239 -77.623162)
		(end 132.159502 -75.543664)
		(width 0.127)
		(layer "In2.Cu")
		(net "BMC_I2C_SDA_10")
	)
	(segment
		(start 46.522132 -208.915)
		(end 42.077132 -204.47)
		(width 0.127)
		(layer "In2.Cu")
		(net "BMC_I2C_SDA_10")
	)
	(segment
		(start 134.239 -78.74)
		(end 134.239 -77.623162)
		(width 0.127)
		(layer "In2.Cu")
		(net "BMC_I2C_SDA_10")
	)
	(segment
		(start 37.359336 -204.47)
		(end 37.161216 -204.27188)
		(width 0.127)
		(layer "In2.Cu")
		(net "BMC_I2C_SDA_10")
	)
	(segment
		(start 218.482164 -87.60841)
		(end 217.772234 -86.89848)
		(width 0.127)
		(layer "In2.Cu")
		(net "BMC_I2C_SDA_10")
	)
	(segment
		(start 87.924132 -220.599)
		(end 87.967566 -220.599)
		(width 0.127)
		(layer "In2.Cu")
		(net "BMC_I2C_SDA_10")
	)
	(segment
		(start 295.402 -82.804)
		(end 299.339 -86.741)
		(width 0.127)
		(layer "In2.Cu")
		(net "BMC_I2C_SDA_10")
	)
	(segment
		(start 307.086 -122.765566)
		(end 307.086 -123.527566)
		(width 0.127)
		(layer "In2.Cu")
		(net "BMC_I2C_SDA_10")
	)
	(segment
		(start 292.227 -75.266042)
		(end 292.227 -76.007468)
		(width 0.127)
		(layer "In2.Cu")
		(net "BMC_I2C_SDA_10")
	)
	(segment
		(start 334.518 -216.027)
		(end 337.1088 -213.4362)
		(width 0.127)
		(layer "In2.Cu")
		(net "BMC_I2C_SDA_10")
	)
	(segment
		(start 298.8437 -101.9683)
		(end 298.8437 -114.523266)
		(width 0.127)
		(layer "In2.Cu")
		(net "BMC_I2C_SDA_10")
	)
	(segment
		(start 82.509868 -222.377)
		(end 86.146132 -222.377)
		(width 0.127)
		(layer "In2.Cu")
		(net "BMC_I2C_SDA_10")
	)
	(segment
		(start 143.523208 -93.599254)
		(end 143.31061 -93.812106)
		(width 0.127)
		(layer "In2.Cu")
		(net "BMC_I2C_SDA_10")
	)
	(segment
		(start 260.966204 -88.011)
		(end 260.966204 -88.029034)
		(width 0.127)
		(layer "In2.Cu")
		(net "BMC_I2C_SDA_10")
	)
	(segment
		(start 291.211 -69.215)
		(end 292.1 -70.104)
		(width 0.127)
		(layer "In2.Cu")
		(net "BMC_I2C_SDA_10")
	)
	(segment
		(start 228.448616 -87.60841)
		(end 218.482164 -87.60841)
		(width 0.127)
		(layer "In2.Cu")
		(net "BMC_I2C_SDA_10")
	)
	(segment
		(start 117.8179 -66.7512)
		(end 117.1194 -66.0527)
		(width 0.127)
		(layer "In2.Cu")
		(net "BMC_I2C_SDA_10")
	)
	(segment
		(start 87.967566 -220.599)
		(end 88.475566 -220.091)
		(width 0.127)
		(layer "In2.Cu")
		(net "BMC_I2C_SDA_10")
	)
	(segment
		(start 311.785 -128.078484)
		(end 312.76798 -128.078484)
		(width 0.127)
		(layer "In2.Cu")
		(net "BMC_I2C_SDA_10")
	)
	(segment
		(start 68.58 -220.98)
		(end 68.961 -220.599)
		(width 0.127)
		(layer "In2.Cu")
		(net "BMC_I2C_SDA_10")
	)
	(segment
		(start 299.339 -88.602566)
		(end 300.228 -89.491566)
		(width 0.127)
		(layer "In2.Cu")
		(net "BMC_I2C_SDA_10")
	)
	(segment
		(start 294.9067 -78.692248)
		(end 295.402 -79.187548)
		(width 0.127)
		(layer "In2.Cu")
		(net "BMC_I2C_SDA_10")
	)
	(segment
		(start 86.146132 -222.377)
		(end 87.924132 -220.599)
		(width 0.127)
		(layer "In2.Cu")
		(net "BMC_I2C_SDA_10")
	)
	(segment
		(start 316.811914 -132.122418)
		(end 318.751458 -132.122418)
		(width 0.127)
		(layer "In2.Cu")
		(net "BMC_I2C_SDA_10")
	)
	(segment
		(start 292.227 -76.007468)
		(end 294.9067 -78.687168)
		(width 0.127)
		(layer "In2.Cu")
		(net "BMC_I2C_SDA_10")
	)
	(segment
		(start 300.228 -90.678)
		(end 300.228 -94.578932)
		(width 0.127)
		(layer "In2.Cu")
		(net "BMC_I2C_SDA_10")
	)
	(segment
		(start 217.772234 -86.89848)
		(end 187.67552 -86.89848)
		(width 0.127)
		(layer "In2.Cu")
		(net "BMC_I2C_SDA_10")
	)
	(segment
		(start 121.85777 -69.469)
		(end 119.13997 -66.7512)
		(width 0.127)
		(layer "In2.Cu")
		(net "BMC_I2C_SDA_10")
	)
	(segment
		(start 311.595516 -127.889)
		(end 311.785 -128.078484)
		(width 0.127)
		(layer "In2.Cu")
		(net "BMC_I2C_SDA_10")
	)
	(segment
		(start 307.086 -123.527566)
		(end 311.447434 -127.889)
		(width 0.127)
		(layer "In2.Cu")
		(net "BMC_I2C_SDA_10")
	)
	(segment
		(start 294.9067 -78.687168)
		(end 294.9067 -78.692248)
		(width 0.127)
		(layer "In2.Cu")
		(net "BMC_I2C_SDA_10")
	)
	(segment
		(start 318.751458 -132.122418)
		(end 327.533 -140.90396)
		(width 0.127)
		(layer "In2.Cu")
		(net "BMC_I2C_SDA_10")
	)
	(segment
		(start 300.228 -94.578932)
		(end 299.593 -95.213932)
		(width 0.127)
		(layer "In2.Cu")
		(net "BMC_I2C_SDA_10")
	)
	(segment
		(start 334.518 -216.027)
		(end 336.6135 -213.9315)
		(width 0.127)
		(layer "In5.Cu")
		(net "BMC_I2C_SDA_10")
	)
	(segment
		(start 149.5933 -147.004532)
		(end 116.632228 -179.965604)
		(width 0.127)
		(layer "In5.Cu")
		(net "BMC_I2C_SDA_10")
	)
	(segment
		(start 143.764 -94.265496)
		(end 143.764 -113.621566)
		(width 0.127)
		(layer "In5.Cu")
		(net "BMC_I2C_SDA_10")
	)
	(segment
		(start 309.499 -212.966554)
		(end 313.689746 -217.1573)
		(width 0.127)
		(layer "In5.Cu")
		(net "BMC_I2C_SDA_10")
	)
	(segment
		(start 24.511 -211.776056)
		(end 17.502124 -204.76718)
		(width 0.127)
		(layer "In5.Cu")
		(net "BMC_I2C_SDA_10")
	)
	(segment
		(start 102.101396 -179.965604)
		(end 100.584 -181.483)
		(width 0.127)
		(layer "In5.Cu")
		(net "BMC_I2C_SDA_10")
	)
	(segment
		(start 143.31061 -93.812106)
		(end 143.764 -94.265496)
		(width 0.127)
		(layer "In5.Cu")
		(net "BMC_I2C_SDA_10")
	)
	(segment
		(start 336.6135 -213.9315)
		(end 336.6135 -211.8995)
		(width 0.127)
		(layer "In5.Cu")
		(net "BMC_I2C_SDA_10")
	)
	(segment
		(start 309.499 -211.963)
		(end 309.499 -212.966554)
		(width 0.127)
		(layer "In5.Cu")
		(net "BMC_I2C_SDA_10")
	)
	(segment
		(start 143.764 -113.621566)
		(end 149.5933 -119.450866)
		(width 0.127)
		(layer "In5.Cu")
		(net "BMC_I2C_SDA_10")
	)
	(segment
		(start 14.674088 -203.718668)
		(end 14.674088 -203.582016)
		(width 0.127)
		(layer "In5.Cu")
		(net "BMC_I2C_SDA_10")
	)
	(segment
		(start 149.5933 -119.450866)
		(end 149.5933 -147.004532)
		(width 0.127)
		(layer "In5.Cu")
		(net "BMC_I2C_SDA_10")
	)
	(segment
		(start 313.689746 -217.1573)
		(end 333.3877 -217.1573)
		(width 0.127)
		(layer "In5.Cu")
		(net "BMC_I2C_SDA_10")
	)
	(segment
		(start 333.3877 -217.1573)
		(end 334.518 -216.027)
		(width 0.127)
		(layer "In5.Cu")
		(net "BMC_I2C_SDA_10")
	)
	(segment
		(start 27.305 -215.519)
		(end 24.511 -212.725)
		(width 0.127)
		(layer "In5.Cu")
		(net "BMC_I2C_SDA_10")
	)
	(segment
		(start 28.067 -215.519)
		(end 27.305 -215.519)
		(width 0.127)
		(layer "In5.Cu")
		(net "BMC_I2C_SDA_10")
	)
	(segment
		(start 17.502124 -204.76718)
		(end 15.7226 -204.76718)
		(width 0.127)
		(layer "In5.Cu")
		(net "BMC_I2C_SDA_10")
	)
	(segment
		(start 15.7226 -204.76718)
		(end 14.674088 -203.718668)
		(width 0.127)
		(layer "In5.Cu")
		(net "BMC_I2C_SDA_10")
	)
	(segment
		(start 116.632228 -179.965604)
		(end 102.101396 -179.965604)
		(width 0.127)
		(layer "In5.Cu")
		(net "BMC_I2C_SDA_10")
	)
	(segment
		(start 24.511 -212.725)
		(end 24.511 -211.776056)
		(width 0.127)
		(layer "In5.Cu")
		(net "BMC_I2C_SDA_10")
	)
	(segment
		(start 15.618968 -208.509616)
		(end 15.618968 -210.733132)
		(width 0.1143)
		(layer "F.Cu")
		(net "BMC_IOEXP_SCL_10")
	)
	(segment
		(start 15.880588 -211.836508)
		(end 15.698216 -212.01888)
		(width 0.1143)
		(layer "F.Cu")
		(net "BMC_IOEXP_SCL_10")
	)
	(segment
		(start 15.618968 -210.733132)
		(end 15.888716 -211.00288)
		(width 0.1143)
		(layer "F.Cu")
		(net "BMC_IOEXP_SCL_10")
	)
	(segment
		(start 24.580088 -180.912008)
		(end 25.350216 -180.14188)
		(width 0.1143)
		(layer "F.Cu")
		(net "BMC_IOEXP_SCL_10")
	)
	(segment
		(start 15.880588 -211.011008)
		(end 15.880588 -211.836508)
		(width 0.1143)
		(layer "F.Cu")
		(net "BMC_IOEXP_SCL_10")
	)
	(segment
		(start 15.618968 -208.509616)
		(end 15.618968 -207.113632)
		(width 0.1143)
		(layer "F.Cu")
		(net "BMC_IOEXP_SCL_10")
	)
	(segment
		(start 14.237716 -221.67088)
		(end 13.208 -221.67088)
		(width 0.1143)
		(layer "F.Cu")
		(net "BMC_IOEXP_SCL_10")
	)
	(segment
		(start 24.580088 -181.420516)
		(end 24.580088 -180.912008)
		(width 0.1143)
		(layer "F.Cu")
		(net "BMC_IOEXP_SCL_10")
	)
	(segment
		(start 15.888716 -211.00288)
		(end 15.880588 -211.011008)
		(width 0.1143)
		(layer "F.Cu")
		(net "BMC_IOEXP_SCL_10")
	)
	(segment
		(start 15.618968 -207.113632)
		(end 15.571216 -207.06588)
		(width 0.1143)
		(layer "F.Cu")
		(net "BMC_IOEXP_SCL_10")
	)
	(via
		(at 15.698216 -212.01888)
		(size 0.5588)
		(drill 0.3048)
		(layers "F.Cu" "B.Cu")
		(net "BMC_IOEXP_SCL_10")
	)
	(via
		(at 25.350216 -184.68848)
		(size 0.7112)
		(drill 0.3556)
		(layers "F.Cu" "B.Cu")
		(net "BMC_IOEXP_SCL_10")
	)
	(via
		(at 13.208 -221.67088)
		(size 0.5588)
		(drill 0.3048)
		(layers "F.Cu" "B.Cu")
		(net "BMC_IOEXP_SCL_10")
	)
	(via
		(at 15.571216 -207.06588)
		(size 0.5588)
		(drill 0.3048)
		(layers "F.Cu" "B.Cu")
		(net "BMC_IOEXP_SCL_10")
	)
	(via
		(at 25.350216 -180.14188)
		(size 0.5588)
		(drill 0.3048)
		(layers "F.Cu" "B.Cu")
		(net "BMC_IOEXP_SCL_10")
	)
	(segment
		(start 25.350216 -184.68848)
		(end 25.350216 -180.14188)
		(width 0.1143)
		(layer "B.Cu")
		(net "BMC_IOEXP_SCL_10")
	)
	(segment
		(start 13.15212 -221.615)
		(end 13.208 -221.67088)
		(width 0.1143)
		(layer "B.Cu")
		(net "BMC_IOEXP_SCL_10")
	)
	(segment
		(start 12.3825 -221.615)
		(end 13.15212 -221.615)
		(width 0.1143)
		(layer "B.Cu")
		(net "BMC_IOEXP_SCL_10")
	)
	(segment
		(start 23.191216 -197.08241)
		(end 23.191216 -193.796412)
		(width 0.1143)
		(layer "B.Cu")
		(net "BMC_IOEXP_SCL_10")
	)
	(segment
		(start 15.571216 -204.70241)
		(end 23.191216 -197.08241)
		(width 0.1143)
		(layer "B.Cu")
		(net "BMC_IOEXP_SCL_10")
	)
	(segment
		(start 15.571216 -207.06588)
		(end 15.571216 -204.70241)
		(width 0.1143)
		(layer "B.Cu")
		(net "BMC_IOEXP_SCL_10")
	)
	(segment
		(start 23.191216 -193.796412)
		(end 25.350216 -191.637412)
		(width 0.1143)
		(layer "B.Cu")
		(net "BMC_IOEXP_SCL_10")
	)
	(segment
		(start 25.350216 -191.637412)
		(end 25.350216 -184.68848)
		(width 0.1143)
		(layer "B.Cu")
		(net "BMC_IOEXP_SCL_10")
	)
	(segment
		(start 13.208 -221.67088)
		(end 13.208 -221.621096)
		(width 0.127)
		(layer "In5.Cu")
		(net "BMC_IOEXP_SCL_10")
	)
	(segment
		(start 13.208 -221.621096)
		(end 15.698216 -219.13088)
		(width 0.127)
		(layer "In5.Cu")
		(net "BMC_IOEXP_SCL_10")
	)
	(segment
		(start 15.698216 -219.13088)
		(end 15.698216 -212.01888)
		(width 0.127)
		(layer "In5.Cu")
		(net "BMC_IOEXP_SCL_10")
	)
	(segment
		(start 197.737476 -145.574512)
		(end 198.976488 -145.574512)
		(width 0.1143)
		(layer "F.Cu")
		(net "BMC_I2C_SDA_9")
	)
	(segment
		(start 201.255376 -144.898872)
		(end 199.652128 -144.898872)
		(width 0.1143)
		(layer "F.Cu")
		(net "BMC_I2C_SDA_9")
	)
	(segment
		(start 198.976488 -145.574512)
		(end 199.652128 -144.898872)
		(width 0.1143)
		(layer "F.Cu")
		(net "BMC_I2C_SDA_9")
	)
	(via
		(at 199.652128 -144.898872)
		(size 0.5588)
		(drill 0.3048)
		(layers "F.Cu" "B.Cu")
		(net "BMC_I2C_SDA_9")
	)
	(via
		(at 308.1274 -130.556)
		(size 0.5588)
		(drill 0.3048)
		(layers "F.Cu" "B.Cu")
		(net "BMC_I2C_SDA_9")
	)
	(via
		(at 310.515 -157.607)
		(size 0.7112)
		(drill 0.3556)
		(layers "F.Cu" "B.Cu")
		(net "BMC_I2C_SDA_9")
	)
	(segment
		(start 310.515 -157.607)
		(end 315.988192 -152.133808)
		(width 0.1143)
		(layer "B.Cu")
		(net "BMC_I2C_SDA_9")
	)
	(segment
		(start 315.988192 -152.133808)
		(end 315.988192 -137.23366)
		(width 0.1143)
		(layer "B.Cu")
		(net "BMC_I2C_SDA_9")
	)
	(segment
		(start 308.102 -160.2105)
		(end 308.102 -160.02)
		(width 0.1143)
		(layer "B.Cu")
		(net "BMC_I2C_SDA_9")
	)
	(segment
		(start 308.102 -160.02)
		(end 310.515 -157.607)
		(width 0.1143)
		(layer "B.Cu")
		(net "BMC_I2C_SDA_9")
	)
	(segment
		(start 310.580532 -131.826)
		(end 309.3974 -131.826)
		(width 0.1143)
		(layer "B.Cu")
		(net "BMC_I2C_SDA_9")
	)
	(segment
		(start 315.988192 -137.23366)
		(end 310.580532 -131.826)
		(width 0.1143)
		(layer "B.Cu")
		(net "BMC_I2C_SDA_9")
	)
	(segment
		(start 309.3974 -131.826)
		(end 308.1274 -130.556)
		(width 0.1143)
		(layer "B.Cu")
		(net "BMC_I2C_SDA_9")
	)
	(segment
		(start 284.820868 -134.493)
		(end 275.054568 -144.2593)
		(width 0.127)
		(layer "In2.Cu")
		(net "BMC_I2C_SDA_9")
	)
	(segment
		(start 275.054568 -144.2593)
		(end 200.2917 -144.2593)
		(width 0.127)
		(layer "In2.Cu")
		(net "BMC_I2C_SDA_9")
	)
	(segment
		(start 308.1274 -130.556)
		(end 307.975 -130.556)
		(width 0.127)
		(layer "In2.Cu")
		(net "BMC_I2C_SDA_9")
	)
	(segment
		(start 307.975 -130.556)
		(end 307.0352 -129.6162)
		(width 0.127)
		(layer "In2.Cu")
		(net "BMC_I2C_SDA_9")
	)
	(segment
		(start 307.0352 -129.6162)
		(end 296.4688 -129.6162)
		(width 0.127)
		(layer "In2.Cu")
		(net "BMC_I2C_SDA_9")
	)
	(segment
		(start 291.592 -134.493)
		(end 284.820868 -134.493)
		(width 0.127)
		(layer "In2.Cu")
		(net "BMC_I2C_SDA_9")
	)
	(segment
		(start 296.4688 -129.6162)
		(end 291.592 -134.493)
		(width 0.127)
		(layer "In2.Cu")
		(net "BMC_I2C_SDA_9")
	)
	(segment
		(start 200.2917 -144.2593)
		(end 199.652128 -144.898872)
		(width 0.127)
		(layer "In2.Cu")
		(net "BMC_I2C_SDA_9")
	)
	(segment
		(start 200.630028 -146.224752)
		(end 199.771 -146.224752)
		(width 0.1143)
		(layer "F.Cu")
		(net "BMC_I2C_SCL_9")
	)
	(segment
		(start 200.812908 -146.041872)
		(end 200.630028 -146.224752)
		(width 0.1143)
		(layer "F.Cu")
		(net "BMC_I2C_SCL_9")
	)
	(segment
		(start 201.255376 -146.041872)
		(end 200.812908 -146.041872)
		(width 0.1143)
		(layer "F.Cu")
		(net "BMC_I2C_SCL_9")
	)
	(segment
		(start 197.737476 -146.224752)
		(end 199.771 -146.224752)
		(width 0.1143)
		(layer "F.Cu")
		(net "BMC_I2C_SCL_9")
	)
	(via
		(at 199.771 -146.224752)
		(size 0.5588)
		(drill 0.3048)
		(layers "F.Cu" "B.Cu")
		(net "BMC_I2C_SCL_9")
	)
	(via
		(at 307.213 -130.556)
		(size 0.5588)
		(drill 0.3048)
		(layers "F.Cu" "B.Cu")
		(net "BMC_I2C_SCL_9")
	)
	(via
		(at 308.102 -158.623)
		(size 0.7112)
		(drill 0.3556)
		(layers "F.Cu" "B.Cu")
		(net "BMC_I2C_SCL_9")
	)
	(segment
		(start 310.515 -132.461)
		(end 315.492892 -137.438892)
		(width 0.1143)
		(layer "B.Cu")
		(net "BMC_I2C_SCL_9")
	)
	(segment
		(start 307.086 -159.639)
		(end 308.102 -158.623)
		(width 0.1143)
		(layer "B.Cu")
		(net "BMC_I2C_SCL_9")
	)
	(segment
		(start 307.213 -130.556)
		(end 309.118 -132.461)
		(width 0.1143)
		(layer "B.Cu")
		(net "BMC_I2C_SCL_9")
	)
	(segment
		(start 315.492892 -151.232108)
		(end 308.102 -158.623)
		(width 0.1143)
		(layer "B.Cu")
		(net "BMC_I2C_SCL_9")
	)
	(segment
		(start 309.118 -132.461)
		(end 310.515 -132.461)
		(width 0.1143)
		(layer "B.Cu")
		(net "BMC_I2C_SCL_9")
	)
	(segment
		(start 315.492892 -137.438892)
		(end 315.492892 -151.232108)
		(width 0.1143)
		(layer "B.Cu")
		(net "BMC_I2C_SCL_9")
	)
	(segment
		(start 307.086 -160.2105)
		(end 307.086 -159.639)
		(width 0.1143)
		(layer "B.Cu")
		(net "BMC_I2C_SCL_9")
	)
	(segment
		(start 307.213 -130.556)
		(end 305.150266 -130.556)
		(width 0.127)
		(layer "In2.Cu")
		(net "BMC_I2C_SCL_9")
	)
	(segment
		(start 201.025252 -144.9705)
		(end 199.771 -146.224752)
		(width 0.127)
		(layer "In2.Cu")
		(net "BMC_I2C_SCL_9")
	)
	(segment
		(start 275.061934 -144.9705)
		(end 201.025252 -144.9705)
		(width 0.127)
		(layer "In2.Cu")
		(net "BMC_I2C_SCL_9")
	)
	(segment
		(start 285.031434 -135.001)
		(end 275.061934 -144.9705)
		(width 0.127)
		(layer "In2.Cu")
		(net "BMC_I2C_SCL_9")
	)
	(segment
		(start 305.150266 -130.556)
		(end 304.718466 -130.1242)
		(width 0.127)
		(layer "In2.Cu")
		(net "BMC_I2C_SCL_9")
	)
	(segment
		(start 304.718466 -130.1242)
		(end 296.7228 -130.1242)
		(width 0.127)
		(layer "In2.Cu")
		(net "BMC_I2C_SCL_9")
	)
	(segment
		(start 291.846 -135.001)
		(end 285.031434 -135.001)
		(width 0.127)
		(layer "In2.Cu")
		(net "BMC_I2C_SCL_9")
	)
	(segment
		(start 296.7228 -130.1242)
		(end 291.846 -135.001)
		(width 0.127)
		(layer "In2.Cu")
		(net "BMC_I2C_SCL_9")
	)
	(segment
		(start 16.51762 -222.94088)
		(end 15.126716 -222.94088)
		(width 0.1143)
		(layer "F.Cu")
		(net "PWR_SCL")
	)
	(segment
		(start 13.158216 -222.30588)
		(end 13.031216 -222.43288)
		(width 0.1143)
		(layer "F.Cu")
		(net "PWR_SCL")
	)
	(segment
		(start 15.126716 -221.67088)
		(end 16.478504 -221.67088)
		(width 0.1143)
		(layer "F.Cu")
		(net "PWR_SCL")
	)
	(segment
		(start 15.126716 -222.94088)
		(end 14.491716 -222.30588)
		(width 0.1143)
		(layer "F.Cu")
		(net "PWR_SCL")
	)
	(segment
		(start 17.133062 -222.325438)
		(end 16.51762 -222.94088)
		(width 0.1143)
		(layer "F.Cu")
		(net "PWR_SCL")
	)
	(segment
		(start 14.491716 -222.30588)
		(end 13.158216 -222.30588)
		(width 0.1143)
		(layer "F.Cu")
		(net "PWR_SCL")
	)
	(segment
		(start 16.478504 -221.67088)
		(end 17.133062 -222.325438)
		(width 0.1143)
		(layer "F.Cu")
		(net "PWR_SCL")
	)
	(via
		(at 13.031216 -222.43288)
		(size 0.7112)
		(drill 0.3556)
		(layers "F.Cu" "B.Cu")
		(net "PWR_SCL")
	)
	(segment
		(start 14.682216 -212.01888)
		(end 14.872716 -211.82838)
		(width 0.1143)
		(layer "F.Cu")
		(net "BMC_IOEXP_SDA_10")
	)
	(segment
		(start 14.968728 -209.573876)
		(end 14.968728 -208.509616)
		(width 0.1143)
		(layer "F.Cu")
		(net "BMC_IOEXP_SDA_10")
	)
	(segment
		(start 14.968728 -208.509616)
		(end 14.968728 -207.606392)
		(width 0.1143)
		(layer "F.Cu")
		(net "BMC_IOEXP_SDA_10")
	)
	(segment
		(start 14.237716 -220.52788)
		(end 13.285216 -220.52788)
		(width 0.1143)
		(layer "F.Cu")
		(net "BMC_IOEXP_SDA_10")
	)
	(segment
		(start 14.872716 -211.00288)
		(end 14.864588 -210.994752)
		(width 0.1143)
		(layer "F.Cu")
		(net "BMC_IOEXP_SDA_10")
	)
	(segment
		(start 23.564088 -180.404008)
		(end 24.080216 -179.88788)
		(width 0.1143)
		(layer "F.Cu")
		(net "BMC_IOEXP_SDA_10")
	)
	(segment
		(start 23.564088 -181.420516)
		(end 23.564088 -180.404008)
		(width 0.1143)
		(layer "F.Cu")
		(net "BMC_IOEXP_SDA_10")
	)
	(segment
		(start 14.864588 -209.678016)
		(end 14.968728 -209.573876)
		(width 0.1143)
		(layer "F.Cu")
		(net "BMC_IOEXP_SDA_10")
	)
	(segment
		(start 14.968728 -207.606392)
		(end 14.555216 -207.19288)
		(width 0.1143)
		(layer "F.Cu")
		(net "BMC_IOEXP_SDA_10")
	)
	(segment
		(start 14.872716 -211.82838)
		(end 14.872716 -211.00288)
		(width 0.1143)
		(layer "F.Cu")
		(net "BMC_IOEXP_SDA_10")
	)
	(segment
		(start 14.864588 -210.994752)
		(end 14.864588 -209.678016)
		(width 0.1143)
		(layer "F.Cu")
		(net "BMC_IOEXP_SDA_10")
	)
	(via
		(at 24.080216 -179.88788)
		(size 0.5588)
		(drill 0.3048)
		(layers "F.Cu" "B.Cu")
		(net "BMC_IOEXP_SDA_10")
	)
	(via
		(at 14.555216 -207.19288)
		(size 0.5588)
		(drill 0.3048)
		(layers "F.Cu" "B.Cu")
		(net "BMC_IOEXP_SDA_10")
	)
	(via
		(at 13.285216 -220.52788)
		(size 0.5588)
		(drill 0.3048)
		(layers "F.Cu" "B.Cu")
		(net "BMC_IOEXP_SDA_10")
	)
	(via
		(at 14.682216 -212.01888)
		(size 0.5588)
		(drill 0.3048)
		(layers "F.Cu" "B.Cu")
		(net "BMC_IOEXP_SDA_10")
	)
	(via
		(at 24.080216 -182.55488)
		(size 0.7112)
		(drill 0.3556)
		(layers "F.Cu" "B.Cu")
		(net "BMC_IOEXP_SDA_10")
	)
	(segment
		(start 15.163038 -203.784708)
		(end 14.555216 -204.39253)
		(width 0.1143)
		(layer "B.Cu")
		(net "BMC_IOEXP_SDA_10")
	)
	(segment
		(start 24.080216 -192.20688)
		(end 22.522434 -193.764662)
		(width 0.1143)
		(layer "B.Cu")
		(net "BMC_IOEXP_SDA_10")
	)
	(segment
		(start 22.522434 -193.764662)
		(end 22.522434 -195.51142)
		(width 0.1143)
		(layer "B.Cu")
		(net "BMC_IOEXP_SDA_10")
	)
	(segment
		(start 24.080216 -182.55488)
		(end 24.080216 -179.88788)
		(width 0.1143)
		(layer "B.Cu")
		(net "BMC_IOEXP_SDA_10")
	)
	(segment
		(start 13.214096 -220.599)
		(end 13.285216 -220.52788)
		(width 0.1143)
		(layer "B.Cu")
		(net "BMC_IOEXP_SDA_10")
	)
	(segment
		(start 15.163038 -202.870816)
		(end 15.163038 -203.784708)
		(width 0.1143)
		(layer "B.Cu")
		(net "BMC_IOEXP_SDA_10")
	)
	(segment
		(start 12.3825 -220.599)
		(end 13.214096 -220.599)
		(width 0.1143)
		(layer "B.Cu")
		(net "BMC_IOEXP_SDA_10")
	)
	(segment
		(start 14.555216 -204.39253)
		(end 14.555216 -207.19288)
		(width 0.1143)
		(layer "B.Cu")
		(net "BMC_IOEXP_SDA_10")
	)
	(segment
		(start 22.522434 -195.51142)
		(end 15.163038 -202.870816)
		(width 0.1143)
		(layer "B.Cu")
		(net "BMC_IOEXP_SDA_10")
	)
	(segment
		(start 24.080216 -182.55488)
		(end 24.080216 -192.20688)
		(width 0.1143)
		(layer "B.Cu")
		(net "BMC_IOEXP_SDA_10")
	)
	(segment
		(start 15.113 -218.700096)
		(end 13.285216 -220.52788)
		(width 0.127)
		(layer "In5.Cu")
		(net "BMC_IOEXP_SDA_10")
	)
	(segment
		(start 14.682216 -212.01888)
		(end 15.113 -212.449664)
		(width 0.127)
		(layer "In5.Cu")
		(net "BMC_IOEXP_SDA_10")
	)
	(segment
		(start 15.113 -212.449664)
		(end 15.113 -218.700096)
		(width 0.127)
		(layer "In5.Cu")
		(net "BMC_IOEXP_SDA_10")
	)
	(segment
		(start 94.361 -221.8055)
		(end 94.361 -223.393)
		(width 0.1143)
		(layer "F.Cu")
		(net "FAULT_SDA")
	)
	(segment
		(start 94.36608 -224.78492)
		(end 93.7006 -224.78492)
		(width 0.1143)
		(layer "F.Cu")
		(net "FAULT_SDA")
	)
	(segment
		(start 94.742 -223.774)
		(end 94.742 -224.409)
		(width 0.1143)
		(layer "F.Cu")
		(net "FAULT_SDA")
	)
	(segment
		(start 92.57792 -224.78492)
		(end 93.7006 -224.78492)
		(width 0.1143)
		(layer "F.Cu")
		(net "FAULT_SDA")
	)
	(segment
		(start 90.1065 -223.139)
		(end 91.313 -223.139)
		(width 0.1143)
		(layer "F.Cu")
		(net "FAULT_SDA")
	)
	(segment
		(start 94.361 -223.393)
		(end 94.742 -223.774)
		(width 0.1143)
		(layer "F.Cu")
		(net "FAULT_SDA")
	)
	(segment
		(start 91.821 -224.028)
		(end 92.57792 -224.78492)
		(width 0.1143)
		(layer "F.Cu")
		(net "FAULT_SDA")
	)
	(segment
		(start 91.821 -223.647)
		(end 91.821 -224.028)
		(width 0.1143)
		(layer "F.Cu")
		(net "FAULT_SDA")
	)
	(segment
		(start 94.742 -224.409)
		(end 94.36608 -224.78492)
		(width 0.1143)
		(layer "F.Cu")
		(net "FAULT_SDA")
	)
	(segment
		(start 91.313 -223.139)
		(end 91.821 -223.647)
		(width 0.1143)
		(layer "F.Cu")
		(net "FAULT_SDA")
	)
	(via
		(at 91.821 -223.647)
		(size 0.7112)
		(drill 0.3556)
		(layers "F.Cu" "B.Cu")
		(net "FAULT_SDA")
	)
	(segment
		(start 234.1245 -15.76324)
		(end 233.68 -16.20774)
		(width 0.1143)
		(layer "F.Cu")
		(net "ENCLO_LED_BLUE_OUT")
	)
	(segment
		(start 235.1405 -15.76324)
		(end 234.1245 -15.76324)
		(width 0.1143)
		(layer "F.Cu")
		(net "ENCLO_LED_BLUE_OUT")
	)
	(segment
		(start 233.8705 -17.907)
		(end 233.68 -17.7165)
		(width 0.1143)
		(layer "F.Cu")
		(net "ENCLO_LED_BLUE_OUT")
	)
	(segment
		(start 233.68 -16.20774)
		(end 233.68 -16.8275)
		(width 0.1143)
		(layer "F.Cu")
		(net "ENCLO_LED_BLUE_OUT")
	)
	(segment
		(start 233.68 -17.7165)
		(end 233.68 -16.8275)
		(width 0.1143)
		(layer "F.Cu")
		(net "ENCLO_LED_BLUE_OUT")
	)
	(via
		(at 233.68 -16.8275)
		(size 0.7112)
		(drill 0.3556)
		(layers "F.Cu" "B.Cu")
		(net "ENCLO_LED_BLUE_OUT")
	)
	(segment
		(start 105.349802 -85.349842)
		(end 104.849676 -84.849716)
		(width 0.4572)
		(layer "F.Cu")
		(net "P1V8_E")
	)
	(segment
		(start 191.008 -146.2405)
		(end 191.008 -147.066)
		(width 0.508)
		(layer "F.Cu")
		(net "P1V8_E")
	)
	(segment
		(start 37.465 -119.7864)
		(end 37.465 -119.9134)
		(width 0.508)
		(layer "F.Cu")
		(net "P1V8_E")
	)
	(segment
		(start 51.25847 -140.44676)
		(end 49.74971 -140.44676)
		(width 0.3556)
		(layer "F.Cu")
		(net "P1V8_E")
	)
	(segment
		(start 91.382342 -117.800882)
		(end 92.117672 -117.800882)
		(width 0.508)
		(layer "F.Cu")
		(net "P1V8_E")
	)
	(segment
		(start 95.45447 -83.947)
		(end 94.12097 -83.947)
		(width 0.508)
		(layer "F.Cu")
		(net "P1V8_E")
	)
	(segment
		(start 105.82021 -88.88476)
		(end 105.82021 -88.88222)
		(width 0.508)
		(layer "F.Cu")
		(net "P1V8_E")
	)
	(segment
		(start 237.75162 -115.99672)
		(end 237.75162 -116.21516)
		(width 0.508)
		(layer "F.Cu")
		(net "P1V8_E")
	)
	(segment
		(start 105.349802 -99.350068)
		(end 104.849676 -99.850194)
		(width 0.4572)
		(layer "F.Cu")
		(net "P1V8_E")
	)
	(segment
		(start 48.14697 -145.65503)
		(end 48.133 -145.669)
		(width 0.508)
		(layer "F.Cu")
		(net "P1V8_E")
	)
	(segment
		(start 95.08363 -75.773788)
		(end 95.08363 -79.00416)
		(width 0.508)
		(layer "F.Cu")
		(net "P1V8_E")
	)
	(segment
		(start 46.6217 -119.5197)
		(end 47.4472 -119.5197)
		(width 0.508)
		(layer "F.Cu")
		(net "P1V8_E")
	)
	(segment
		(start 77.894688 -126.284482)
		(end 77.76337 -126.4158)
		(width 0.508)
		(layer "F.Cu")
		(net "P1V8_E")
	)
	(segment
		(start 245.2624 -120.2944)
		(end 245.2624 -115.77066)
		(width 1.016)
		(layer "F.Cu")
		(net "P1V8_E")
	)
	(segment
		(start 105.349802 -101.350064)
		(end 104.849676 -101.85019)
		(width 0.4572)
		(layer "F.Cu")
		(net "P1V8_E")
	)
	(segment
		(start 105.349802 -103.35006)
		(end 104.849676 -103.850186)
		(width 0.4572)
		(layer "F.Cu")
		(net "P1V8_E")
	)
	(segment
		(start 99.45497 -118.745)
		(end 99.45497 -118.98122)
		(width 0.508)
		(layer "F.Cu")
		(net "P1V8_E")
	)
	(segment
		(start 96.145604 -74.676)
		(end 95.31477 -75.506834)
		(width 0.508)
		(layer "F.Cu")
		(net "P1V8_E")
	)
	(segment
		(start 203.0095 -138.811)
		(end 203.0095 -138.557)
		(width 0.508)
		(layer "F.Cu")
		(net "P1V8_E")
	)
	(segment
		(start 192.024 -139.319)
		(end 190.879222 -139.319)
		(width 0.508)
		(layer "F.Cu")
		(net "P1V8_E")
	)
	(segment
		(start 244.2718 -121.285)
		(end 245.2624 -120.2944)
		(width 1.016)
		(layer "F.Cu")
		(net "P1V8_E")
	)
	(segment
		(start 95.45447 -85.09)
		(end 95.45447 -86.233)
		(width 0.508)
		(layer "F.Cu")
		(net "P1V8_E")
	)
	(segment
		(start 193.167 -123.1265)
		(end 193.167 -124.333)
		(width 0.508)
		(layer "F.Cu")
		(net "P1V8_E")
	)
	(segment
		(start 63.5 -179.6415)
		(end 64.389 -179.6415)
		(width 0.508)
		(layer "F.Cu")
		(net "P1V8_E")
	)
	(segment
		(start 99.32797 -75.37704)
		(end 98.62693 -74.676)
		(width 0.508)
		(layer "F.Cu")
		(net "P1V8_E")
	)
	(segment
		(start 17.842992 -215.388698)
		(end 18.010886 -215.22055)
		(width 0.3048)
		(layer "F.Cu")
		(net "P1V8_E")
	)
	(segment
		(start 105.349802 -87.349838)
		(end 104.849676 -86.849712)
		(width 0.4572)
		(layer "F.Cu")
		(net "P1V8_E")
	)
	(segment
		(start 24.088852 -195.009516)
		(end 24.580088 -195.009516)
		(width 0.381)
		(layer "F.Cu")
		(net "P1V8_E")
	)
	(segment
		(start 191.008 -147.066)
		(end 191.1985 -147.2565)
		(width 0.508)
		(layer "F.Cu")
		(net "P1V8_E")
	)
	(segment
		(start 98.68281 -119.6594)
		(end 98.77679 -119.6594)
		(width 0.508)
		(layer "F.Cu")
		(net "P1V8_E")
	)
	(segment
		(start 95.45447 -93.091)
		(end 95.13697 -93.091)
		(width 0.508)
		(layer "F.Cu")
		(net "P1V8_E")
	)
	(segment
		(start 191.008 -146.1135)
		(end 188.722 -146.1135)
		(width 0.508)
		(layer "F.Cu")
		(net "P1V8_E")
	)
	(segment
		(start 23.710138 -194.501516)
		(end 23.710138 -194.630802)
		(width 0.381)
		(layer "F.Cu")
		(net "P1V8_E")
	)
	(segment
		(start 110.349792 -82.349848)
		(end 110.349792 -81.478882)
		(width 0.4572)
		(layer "F.Cu")
		(net "P1V8_E")
	)
	(segment
		(start 82.43697 -129.6035)
		(end 83.45297 -129.6035)
		(width 0.508)
		(layer "F.Cu")
		(net "P1V8_E")
	)
	(segment
		(start 94.12097 -83.947)
		(end 92.97797 -82.804)
		(width 0.508)
		(layer "F.Cu")
		(net "P1V8_E")
	)
	(segment
		(start 46.99 -135.524748)
		(end 46.226222 -136.288526)
		(width 0.508)
		(layer "F.Cu")
		(net "P1V8_E")
	)
	(segment
		(start 115.350036 -87.349838)
		(end 115.850162 -86.849712)
		(width 0.4572)
		(layer "F.Cu")
		(net "P1V8_E")
	)
	(segment
		(start 82.14233 -130.39852)
		(end 82.14233 -131.5466)
		(width 0.2032)
		(layer "F.Cu")
		(net "P1V8_E")
	)
	(segment
		(start 92.50299 -118.94312)
		(end 92.45981 -118.9863)
		(width 0.508)
		(layer "F.Cu")
		(net "P1V8_E")
	)
	(segment
		(start 15.185898 -170.107356)
		(end 14.04874 -170.107356)
		(width 0.2032)
		(layer "F.Cu")
		(net "P1V8_E")
	)
	(segment
		(start 191.0715 -144.8435)
		(end 191.708278 -144.206722)
		(width 0.508)
		(layer "F.Cu")
		(net "P1V8_E")
	)
	(segment
		(start 23.770336 -211.328)
		(end 19.685 -211.328)
		(width 0.508)
		(layer "F.Cu")
		(net "P1V8_E")
	)
	(segment
		(start 229.743 -20.828)
		(end 239.776 -30.861)
		(width 0.508)
		(layer "F.Cu")
		(net "P1V8_E")
	)
	(segment
		(start 14.04874 -170.107356)
		(end 14.047216 -170.10888)
		(width 0.2032)
		(layer "F.Cu")
		(net "P1V8_E")
	)
	(segment
		(start 105.349802 -93.349826)
		(end 104.849676 -92.8497)
		(width 0.4572)
		(layer "F.Cu")
		(net "P1V8_E")
	)
	(segment
		(start 190.876936 -139.316714)
		(end 190.876936 -137.3124)
		(width 0.508)
		(layer "F.Cu")
		(net "P1V8_E")
	)
	(segment
		(start 114.349784 -84.349844)
		(end 113.849658 -83.849718)
		(width 0.4572)
		(layer "F.Cu")
		(net "P1V8_E")
	)
	(segment
		(start 13.983716 -211.00288)
		(end 13.975588 -210.994752)
		(width 0.508)
		(layer "F.Cu")
		(net "P1V8_E")
	)
	(segment
		(start 81.730342 -122.880882)
		(end 81.76006 -122.9106)
		(width 0.3048)
		(layer "F.Cu")
		(net "P1V8_E")
	)
	(segment
		(start 82.43697 -130.10388)
		(end 82.14233 -130.39852)
		(width 0.2032)
		(layer "F.Cu")
		(net "P1V8_E")
	)
	(segment
		(start 79.444342 -126.284482)
		(end 77.894688 -126.284482)
		(width 0.508)
		(layer "F.Cu")
		(net "P1V8_E")
	)
	(segment
		(start 192.024 -147.2565)
		(end 192.405508 -146.874992)
		(width 0.381)
		(layer "F.Cu")
		(net "P1V8_E")
	)
	(segment
		(start 110.349792 -87.372698)
		(end 109.87659 -87.8459)
		(width 0.381)
		(layer "F.Cu")
		(net "P1V8_E")
	)
	(segment
		(start 46.4312 -119.7102)
		(end 46.6217 -119.5197)
		(width 0.508)
		(layer "F.Cu")
		(net "P1V8_E")
	)
	(segment
		(start 95.26397 -119.03456)
		(end 96.07677 -119.84736)
		(width 0.508)
		(layer "F.Cu")
		(net "P1V8_E")
	)
	(segment
		(start 109.349794 -94.349824)
		(end 108.849668 -93.849698)
		(width 0.4572)
		(layer "F.Cu")
		(net "P1V8_E")
	)
	(segment
		(start 38.6207 -119.3292)
		(end 37.9222 -119.3292)
		(width 0.508)
		(layer "F.Cu")
		(net "P1V8_E")
	)
	(segment
		(start 94.12097 -79.375)
		(end 95.45447 -79.375)
		(width 0.508)
		(layer "F.Cu")
		(net "P1V8_E")
	)
	(segment
		(start 81.98739 -129.6035)
		(end 82.43697 -129.6035)
		(width 0.508)
		(layer "F.Cu")
		(net "P1V8_E")
	)
	(segment
		(start 108.849668 -84.849716)
		(end 109.349794 -85.349842)
		(width 0.4572)
		(layer "F.Cu")
		(net "P1V8_E")
	)
	(segment
		(start 201.45883 -144.206722)
		(end 203.0095 -142.656052)
		(width 0.508)
		(layer "F.Cu")
		(net "P1V8_E")
	)
	(segment
		(start 99.32797 -76.0095)
		(end 99.32797 -75.37704)
		(width 0.508)
		(layer "F.Cu")
		(net "P1V8_E")
	)
	(segment
		(start 105.349802 -97.350072)
		(end 104.849676 -97.850198)
		(width 0.4572)
		(layer "F.Cu")
		(net "P1V8_E")
	)
	(segment
		(start 103.349806 -85.349842)
		(end 102.84968 -84.849716)
		(width 0.4572)
		(layer "F.Cu")
		(net "P1V8_E")
	)
	(segment
		(start 59.563 -108.458)
		(end 59.055 -107.95)
		(width 0.508)
		(layer "F.Cu")
		(net "P1V8_E")
	)
	(segment
		(start 86.20887 -114.25936)
		(end 86.23427 -114.25936)
		(width 0.508)
		(layer "F.Cu")
		(net "P1V8_E")
	)
	(segment
		(start 188.66866 -139.316714)
		(end 190.876936 -139.316714)
		(width 0.508)
		(layer "F.Cu")
		(net "P1V8_E")
	)
	(segment
		(start 60.2615 -108.458)
		(end 59.563 -108.458)
		(width 0.508)
		(layer "F.Cu")
		(net "P1V8_E")
	)
	(segment
		(start 12.777216 -192.77838)
		(end 12.777216 -195.88988)
		(width 0.508)
		(layer "F.Cu")
		(net "P1V8_E")
	)
	(segment
		(start 47.06747 -133.477)
		(end 47.06747 -132.3594)
		(width 0.508)
		(layer "F.Cu")
		(net "P1V8_E")
	)
	(segment
		(start 87.468964 -116.22024)
		(end 87.483442 -116.205762)
		(width 0.3048)
		(layer "F.Cu")
		(net "P1V8_E")
	)
	(segment
		(start 83.45297 -129.6035)
		(end 83.45297 -129.78384)
		(width 0.2032)
		(layer "F.Cu")
		(net "P1V8_E")
	)
	(segment
		(start 31.42488 -214.44712)
		(end 31.115 -214.757)
		(width 0.3048)
		(layer "F.Cu")
		(net "P1V8_E")
	)
	(segment
		(start 17.783302 -216.714578)
		(end 17.783302 -215.69807)
		(width 0.3048)
		(layer "F.Cu")
		(net "P1V8_E")
	)
	(segment
		(start 22.81174 -170.107356)
		(end 22.810216 -170.10888)
		(width 0.2032)
		(layer "F.Cu")
		(net "P1V8_E")
	)
	(segment
		(start 16.769588 -210.994752)
		(end 16.769588 -210.122516)
		(width 0.508)
		(layer "F.Cu")
		(net "P1V8_E")
	)
	(segment
		(start 98.05797 -118.745)
		(end 98.05797 -119.03456)
		(width 0.508)
		(layer "F.Cu")
		(net "P1V8_E")
	)
	(segment
		(start 111.849662 -83.849718)
		(end 112.349788 -84.349844)
		(width 0.4572)
		(layer "F.Cu")
		(net "P1V8_E")
	)
	(segment
		(start 48.14697 -144.8435)
		(end 48.14697 -145.65503)
		(width 0.508)
		(layer "F.Cu")
		(net "P1V8_E")
	)
	(segment
		(start 105.349802 -91.34983)
		(end 104.849676 -90.849704)
		(width 0.4572)
		(layer "F.Cu")
		(net "P1V8_E")
	)
	(segment
		(start 237.6678 -115.9129)
		(end 237.75162 -115.99672)
		(width 0.508)
		(layer "F.Cu")
		(net "P1V8_E")
	)
	(segment
		(start 188.722 -146.1135)
		(end 188.60262 -146.23288)
		(width 0.381)
		(layer "F.Cu")
		(net "P1V8_E")
	)
	(segment
		(start 83.45297 -129.78384)
		(end 82.54238 -130.69443)
		(width 0.2032)
		(layer "F.Cu")
		(net "P1V8_E")
	)
	(segment
		(start 239.776 -35.687)
		(end 240.03 -35.941)
		(width 0.508)
		(layer "F.Cu")
		(net "P1V8_E")
	)
	(segment
		(start 117.350032 -87.349838)
		(end 117.850158 -86.849712)
		(width 0.4572)
		(layer "F.Cu")
		(net "P1V8_E")
	)
	(segment
		(start 23.710138 -194.501516)
		(end 23.710138 -191.020446)
		(width 0.3556)
		(layer "F.Cu")
		(net "P1V8_E")
	)
	(segment
		(start 245.2624 -115.17884)
		(end 244.81155 -114.72799)
		(width 0.3048)
		(layer "F.Cu")
		(net "P1V8_E")
	)
	(segment
		(start 85.43925 -115.02898)
		(end 86.20887 -114.25936)
		(width 0.508)
		(layer "F.Cu")
		(net "P1V8_E")
	)
	(segment
		(start 95.13697 -93.091)
		(end 94.50197 -92.456)
		(width 0.508)
		(layer "F.Cu")
		(net "P1V8_E")
	)
	(segment
		(start 191.0715 -146.177)
		(end 191.008 -146.2405)
		(width 0.508)
		(layer "F.Cu")
		(net "P1V8_E")
	)
	(segment
		(start 86.45017 -116.22024)
		(end 87.468964 -116.22024)
		(width 0.3048)
		(layer "F.Cu")
		(net "P1V8_E")
	)
	(segment
		(start 192.405508 -146.874992)
		(end 194.486276 -146.874992)
		(width 0.3556)
		(layer "F.Cu")
		(net "P1V8_E")
	)
	(segment
		(start 191.0715 -145.034)
		(end 191.0715 -146.177)
		(width 0.508)
		(layer "F.Cu")
		(net "P1V8_E")
	)
	(segment
		(start 87.296752 -129.421382)
		(end 88.143842 -129.421382)
		(width 0.508)
		(layer "F.Cu")
		(net "P1V8_E")
	)
	(segment
		(start 12.777216 -195.88988)
		(end 13.158216 -196.27088)
		(width 0.508)
		(layer "F.Cu")
		(net "P1V8_E")
	)
	(segment
		(start 110.349792 -87.349838)
		(end 110.349792 -87.372698)
		(width 0.381)
		(layer "F.Cu")
		(net "P1V8_E")
	)
	(segment
		(start 92.50299 -118.1862)
		(end 92.50299 -118.94312)
		(width 0.508)
		(layer "F.Cu")
		(net "P1V8_E")
	)
	(segment
		(start 24.580088 -195.009516)
		(end 25.596088 -195.009516)
		(width 0.508)
		(layer "F.Cu")
		(net "P1V8_E")
	)
	(segment
		(start 24.025098 -170.107356)
		(end 22.81174 -170.107356)
		(width 0.2032)
		(layer "F.Cu")
		(net "P1V8_E")
	)
	(segment
		(start 41.402 -179.3875)
		(end 41.402 -180.467)
		(width 0.508)
		(layer "F.Cu")
		(net "P1V8_E")
	)
	(segment
		(start 99.45497 -118.98122)
		(end 98.77679 -119.6594)
		(width 0.508)
		(layer "F.Cu")
		(net "P1V8_E")
	)
	(segment
		(start 105.349802 -107.350052)
		(end 104.849676 -107.850178)
		(width 0.4572)
		(layer "F.Cu")
		(net "P1V8_E")
	)
	(segment
		(start 245.2624 -115.77066)
		(end 245.2624 -115.17884)
		(width 0.3048)
		(layer "F.Cu")
		(net "P1V8_E")
	)
	(segment
		(start 237.6678 -114.9858)
		(end 237.6678 -115.9129)
		(width 0.508)
		(layer "F.Cu")
		(net "P1V8_E")
	)
	(segment
		(start 95.08363 -79.00416)
		(end 95.45447 -79.375)
		(width 0.508)
		(layer "F.Cu")
		(net "P1V8_E")
	)
	(segment
		(start 109.349794 -92.349828)
		(end 108.849668 -91.849702)
		(width 0.4572)
		(layer "F.Cu")
		(net "P1V8_E")
	)
	(segment
		(start 190.879222 -139.319)
		(end 190.876936 -139.316714)
		(width 0.508)
		(layer "F.Cu")
		(net "P1V8_E")
	)
	(segment
		(start 105.349802 -95.350076)
		(end 104.849676 -95.850202)
		(width 0.3048)
		(layer "F.Cu")
		(net "P1V8_E")
	)
	(segment
		(start 111.34979 -87.349838)
		(end 111.290862 -87.29091)
		(width 0.3556)
		(layer "F.Cu")
		(net "P1V8_E")
	)
	(segment
		(start 80.841342 -120.721882)
		(end 80.841342 -121.864882)
		(width 0.508)
		(layer "F.Cu")
		(net "P1V8_E")
	)
	(segment
		(start 98.05797 -119.03456)
		(end 98.68281 -119.6594)
		(width 0.508)
		(layer "F.Cu")
		(net "P1V8_E")
	)
	(segment
		(start 98.62693 -74.676)
		(end 96.145604 -74.676)
		(width 0.508)
		(layer "F.Cu")
		(net "P1V8_E")
	)
	(segment
		(start 80.58277 -130.59918)
		(end 80.99171 -130.59918)
		(width 0.508)
		(layer "F.Cu")
		(net "P1V8_E")
	)
	(segment
		(start 77.740002 -126.392432)
		(end 77.76337 -126.4158)
		(width 0.3048)
		(layer "F.Cu")
		(net "P1V8_E")
	)
	(segment
		(start 118.35003 -84.349844)
		(end 118.850156 -83.849718)
		(width 0.4572)
		(layer "F.Cu")
		(net "P1V8_E")
	)
	(segment
		(start 244.81155 -114.72799)
		(end 243.8527 -114.72799)
		(width 0.3048)
		(layer "F.Cu")
		(net "P1V8_E")
	)
	(segment
		(start 109.349794 -97.350072)
		(end 108.849668 -97.850198)
		(width 0.4572)
		(layer "F.Cu")
		(net "P1V8_E")
	)
	(segment
		(start 239.776 -30.861)
		(end 239.776 -35.687)
		(width 0.508)
		(layer "F.Cu")
		(net "P1V8_E")
	)
	(segment
		(start 106.3498 -90.349832)
		(end 105.849674 -89.849706)
		(width 0.4572)
		(layer "F.Cu")
		(net "P1V8_E")
	)
	(segment
		(start 13.158216 -209.169508)
		(end 13.975588 -209.98688)
		(width 0.508)
		(layer "F.Cu")
		(net "P1V8_E")
	)
	(segment
		(start 86.23427 -116.00434)
		(end 86.45017 -116.22024)
		(width 0.3048)
		(layer "F.Cu")
		(net "P1V8_E")
	)
	(segment
		(start 16.777716 -211.00288)
		(end 16.769588 -210.994752)
		(width 0.508)
		(layer "F.Cu")
		(net "P1V8_E")
	)
	(segment
		(start 82.43697 -129.6035)
		(end 82.43697 -130.10388)
		(width 0.2032)
		(layer "F.Cu")
		(net "P1V8_E")
	)
	(segment
		(start 95.45447 -87.376)
		(end 93.61297 -87.376)
		(width 0.508)
		(layer "F.Cu")
		(net "P1V8_E")
	)
	(segment
		(start 96.66097 -118.745)
		(end 96.66097 -119.26316)
		(width 0.508)
		(layer "F.Cu")
		(net "P1V8_E")
	)
	(segment
		(start 191.0715 -145.034)
		(end 191.0715 -144.8435)
		(width 0.508)
		(layer "F.Cu")
		(net "P1V8_E")
	)
	(segment
		(start 95.31477 -75.506834)
		(end 95.31477 -75.542648)
		(width 0.508)
		(layer "F.Cu")
		(net "P1V8_E")
	)
	(segment
		(start 81.730342 -124.130308)
		(end 81.730342 -122.880882)
		(width 0.508)
		(layer "F.Cu")
		(net "P1V8_E")
	)
	(segment
		(start 109.349794 -88.349836)
		(end 108.849668 -87.84971)
		(width 0.4572)
		(layer "F.Cu")
		(net "P1V8_E")
	)
	(segment
		(start 26.556716 -214.43188)
		(end 26.556716 -214.11438)
		(width 0.508)
		(layer "F.Cu")
		(net "P1V8_E")
	)
	(segment
		(start 188.60262 -146.23288)
		(end 187.0456 -146.23288)
		(width 0.3556)
		(layer "F.Cu")
		(net "P1V8_E")
	)
	(segment
		(start 92.97797 -80.518)
		(end 94.12097 -79.375)
		(width 0.508)
		(layer "F.Cu")
		(net "P1V8_E")
	)
	(segment
		(start 93.23197 -91.186)
		(end 94.50197 -92.456)
		(width 0.508)
		(layer "F.Cu")
		(net "P1V8_E")
	)
	(segment
		(start 80.56753 -125.29312)
		(end 81.730342 -124.130308)
		(width 0.508)
		(layer "F.Cu")
		(net "P1V8_E")
	)
	(segment
		(start 193.421 -137.922)
		(end 192.024 -139.319)
		(width 0.508)
		(layer "F.Cu")
		(net "P1V8_E")
	)
	(segment
		(start 95.31477 -75.542648)
		(end 95.08363 -75.773788)
		(width 0.508)
		(layer "F.Cu")
		(net "P1V8_E")
	)
	(segment
		(start 17.842992 -215.63838)
		(end 17.842992 -215.388698)
		(width 0.3048)
		(layer "F.Cu")
		(net "P1V8_E")
	)
	(segment
		(start 80.99171 -130.59918)
		(end 81.98739 -129.6035)
		(width 0.508)
		(layer "F.Cu")
		(net "P1V8_E")
	)
	(segment
		(start 82.54238 -130.69443)
		(end 82.54238 -131.5466)
		(width 0.2032)
		(layer "F.Cu")
		(net "P1V8_E")
	)
	(segment
		(start 107.349798 -85.349842)
		(end 106.849672 -84.849716)
		(width 0.4572)
		(layer "F.Cu")
		(net "P1V8_E")
	)
	(segment
		(start 47.4472 -119.5197)
		(end 48.4632 -119.5197)
		(width 0.508)
		(layer "F.Cu")
		(net "P1V8_E")
	)
	(segment
		(start 96.66097 -119.26316)
		(end 96.07677 -119.84736)
		(width 0.508)
		(layer "F.Cu")
		(net "P1V8_E")
	)
	(segment
		(start 32.9184 -214.44712)
		(end 31.42488 -214.44712)
		(width 0.3048)
		(layer "F.Cu")
		(net "P1V8_E")
	)
	(segment
		(start 203.0095 -140.589)
		(end 203.0095 -138.811)
		(width 0.508)
		(layer "F.Cu")
		(net "P1V8_E")
	)
	(segment
		(start 93.61297 -87.376)
		(end 93.23197 -87.757)
		(width 0.508)
		(layer "F.Cu")
		(net "P1V8_E")
	)
	(segment
		(start 80.333342 -128.951482)
		(end 81.365852 -128.951482)
		(width 0.508)
		(layer "F.Cu")
		(net "P1V8_E")
	)
	(segment
		(start 26.556716 -214.11438)
		(end 23.770336 -211.328)
		(width 0.508)
		(layer "F.Cu")
		(net "P1V8_E")
	)
	(segment
		(start 109.349794 -90.349832)
		(end 108.849668 -89.849706)
		(width 0.4572)
		(layer "F.Cu")
		(net "P1V8_E")
	)
	(segment
		(start 46.226222 -136.288526)
		(end 46.226222 -136.498584)
		(width 0.508)
		(layer "F.Cu")
		(net "P1V8_E")
	)
	(segment
		(start 105.349802 -89.349834)
		(end 105.355136 -89.349834)
		(width 0.508)
		(layer "F.Cu")
		(net "P1V8_E")
	)
	(segment
		(start 95.45447 -83.947)
		(end 95.45447 -85.09)
		(width 0.508)
		(layer "F.Cu")
		(net "P1V8_E")
	)
	(segment
		(start 92.45981 -118.9863)
		(end 91.35999 -118.9863)
		(width 0.508)
		(layer "F.Cu")
		(net "P1V8_E")
	)
	(segment
		(start 37.9222 -119.3292)
		(end 37.465 -119.7864)
		(width 0.508)
		(layer "F.Cu")
		(net "P1V8_E")
	)
	(segment
		(start 188.599318 -139.247372)
		(end 188.66866 -139.316714)
		(width 0.508)
		(layer "F.Cu")
		(net "P1V8_E")
	)
	(segment
		(start 191.0715 -146.177)
		(end 191.008 -146.1135)
		(width 0.508)
		(layer "F.Cu")
		(net "P1V8_E")
	)
	(segment
		(start 95.45447 -86.233)
		(end 95.45447 -87.376)
		(width 0.508)
		(layer "F.Cu")
		(net "P1V8_E")
	)
	(segment
		(start 16.269208 -209.622136)
		(end 16.769588 -210.122516)
		(width 0.3556)
		(layer "F.Cu")
		(net "P1V8_E")
	)
	(segment
		(start 16.269208 -208.509616)
		(end 16.269208 -209.622136)
		(width 0.3556)
		(layer "F.Cu")
		(net "P1V8_E")
	)
	(segment
		(start 203.0095 -138.557)
		(end 202.3745 -137.922)
		(width 0.508)
		(layer "F.Cu")
		(net "P1V8_E")
	)
	(segment
		(start 94.50197 -92.456)
		(end 95.00997 -91.948)
		(width 0.508)
		(layer "F.Cu")
		(net "P1V8_E")
	)
	(segment
		(start 75.786742 -126.392432)
		(end 77.740002 -126.392432)
		(width 0.3048)
		(layer "F.Cu")
		(net "P1V8_E")
	)
	(segment
		(start 83.233768 -122.444002)
		(end 84.105242 -122.444002)
		(width 0.3048)
		(layer "F.Cu")
		(net "P1V8_E")
	)
	(segment
		(start 110.349792 -96.350074)
		(end 109.849666 -96.8502)
		(width 0.4572)
		(layer "F.Cu")
		(net "P1V8_E")
	)
	(segment
		(start 113.349786 -87.349838)
		(end 112.84966 -86.849712)
		(width 0.4572)
		(layer "F.Cu")
		(net "P1V8_E")
	)
	(segment
		(start 95.26397 -118.745)
		(end 95.26397 -119.03456)
		(width 0.508)
		(layer "F.Cu")
		(net "P1V8_E")
	)
	(segment
		(start 95.00997 -91.948)
		(end 95.45447 -91.948)
		(width 0.508)
		(layer "F.Cu")
		(net "P1V8_E")
	)
	(segment
		(start 105.355136 -89.349834)
		(end 105.82021 -88.88476)
		(width 0.508)
		(layer "F.Cu")
		(net "P1V8_E")
	)
	(segment
		(start 191.708278 -144.206722)
		(end 201.45883 -144.206722)
		(width 0.508)
		(layer "F.Cu")
		(net "P1V8_E")
	)
	(segment
		(start 80.841342 -121.864882)
		(end 75.860148 -121.864882)
		(width 0.508)
		(layer "F.Cu")
		(net "P1V8_E")
	)
	(segment
		(start 88.143842 -129.421382)
		(end 88.325452 -129.602992)
		(width 0.2032)
		(layer "F.Cu")
		(net "P1V8_E")
	)
	(segment
		(start 13.975588 -210.994752)
		(end 13.975588 -209.98688)
		(width 0.508)
		(layer "F.Cu")
		(net "P1V8_E")
	)
	(segment
		(start 95.26397 -110.617)
		(end 95.26397 -112.903)
		(width 0.508)
		(layer "F.Cu")
		(net "P1V8_E")
	)
	(segment
		(start 92.117672 -117.800882)
		(end 92.50299 -118.1862)
		(width 0.508)
		(layer "F.Cu")
		(net "P1V8_E")
	)
	(segment
		(start 93.23197 -87.757)
		(end 93.23197 -91.186)
		(width 0.508)
		(layer "F.Cu")
		(net "P1V8_E")
	)
	(segment
		(start 187.481718 -139.247372)
		(end 188.599318 -139.247372)
		(width 0.508)
		(layer "F.Cu")
		(net "P1V8_E")
	)
	(segment
		(start 52.90947 -138.44524)
		(end 52.90947 -139.36218)
		(width 0.3048)
		(layer "F.Cu")
		(net "P1V8_E")
	)
	(segment
		(start 44.6786 -119.70639)
		(end 46.42739 -119.70639)
		(width 0.3048)
		(layer "F.Cu")
		(net "P1V8_E")
	)
	(segment
		(start 110.40872 -87.29091)
		(end 110.349792 -87.349838)
		(width 0.3556)
		(layer "F.Cu")
		(net "P1V8_E")
	)
	(segment
		(start 92.97797 -82.804)
		(end 92.97797 -80.518)
		(width 0.508)
		(layer "F.Cu")
		(net "P1V8_E")
	)
	(segment
		(start 60.2615 -107.442)
		(end 59.563 -107.442)
		(width 0.508)
		(layer "F.Cu")
		(net "P1V8_E")
	)
	(segment
		(start 23.710138 -194.630802)
		(end 24.088852 -195.009516)
		(width 0.381)
		(layer "F.Cu")
		(net "P1V8_E")
	)
	(segment
		(start 13.158216 -196.27088)
		(end 13.158216 -209.169508)
		(width 0.508)
		(layer "F.Cu")
		(net "P1V8_E")
	)
	(segment
		(start 27.686 -214.43188)
		(end 26.556716 -214.43188)
		(width 0.4064)
		(layer "F.Cu")
		(net "P1V8_E")
	)
	(segment
		(start 191.1985 -147.2565)
		(end 192.024 -147.2565)
		(width 0.508)
		(layer "F.Cu")
		(net "P1V8_E")
	)
	(segment
		(start 203.0095 -140.589)
		(end 203.0095 -142.494)
		(width 0.508)
		(layer "F.Cu")
		(net "P1V8_E")
	)
	(segment
		(start 111.290862 -87.29091)
		(end 110.40872 -87.29091)
		(width 0.3556)
		(layer "F.Cu")
		(net "P1V8_E")
	)
	(segment
		(start 116.350034 -84.349844)
		(end 116.85016 -83.849718)
		(width 0.4572)
		(layer "F.Cu")
		(net "P1V8_E")
	)
	(segment
		(start 202.3745 -137.922)
		(end 193.421 -137.922)
		(width 0.508)
		(layer "F.Cu")
		(net "P1V8_E")
	)
	(segment
		(start 36.449 -179.3875)
		(end 36.449 -180.467)
		(width 0.508)
		(layer "F.Cu")
		(net "P1V8_E")
	)
	(segment
		(start 14.047216 -191.50838)
		(end 12.777216 -192.77838)
		(width 0.508)
		(layer "F.Cu")
		(net "P1V8_E")
	)
	(segment
		(start 95.45447 -91.948)
		(end 95.45447 -90.805)
		(width 0.508)
		(layer "F.Cu")
		(net "P1V8_E")
	)
	(segment
		(start 82.76717 -122.9106)
		(end 83.233768 -122.444002)
		(width 0.3048)
		(layer "F.Cu")
		(net "P1V8_E")
	)
	(segment
		(start 59.563 -107.442)
		(end 59.055 -107.95)
		(width 0.508)
		(layer "F.Cu")
		(net "P1V8_E")
	)
	(segment
		(start 52.774342 -132.380482)
		(end 52.774342 -131.206748)
		(width 0.508)
		(layer "F.Cu")
		(net "P1V8_E")
	)
	(segment
		(start 46.42739 -119.70639)
		(end 46.4312 -119.7102)
		(width 0.3048)
		(layer "F.Cu")
		(net "P1V8_E")
	)
	(segment
		(start 52.90947 -135.27024)
		(end 52.90947 -136.22528)
		(width 0.3048)
		(layer "F.Cu")
		(net "P1V8_E")
	)
	(segment
		(start 17.783302 -215.69807)
		(end 17.842992 -215.63838)
		(width 0.3048)
		(layer "F.Cu")
		(net "P1V8_E")
	)
	(segment
		(start 105.349802 -105.350056)
		(end 104.849676 -105.850182)
		(width 0.4572)
		(layer "F.Cu")
		(net "P1V8_E")
	)
	(segment
		(start 86.23427 -114.25936)
		(end 86.23427 -116.00434)
		(width 0.3048)
		(layer "F.Cu")
		(net "P1V8_E")
	)
	(segment
		(start 81.76006 -122.9106)
		(end 82.76717 -122.9106)
		(width 0.3048)
		(layer "F.Cu")
		(net "P1V8_E")
	)
	(segment
		(start 88.325452 -129.602992)
		(end 88.325452 -131.570476)
		(width 0.2032)
		(layer "F.Cu")
		(net "P1V8_E")
	)
	(segment
		(start 203.0095 -142.656052)
		(end 203.0095 -142.494)
		(width 0.508)
		(layer "F.Cu")
		(net "P1V8_E")
	)
	(via
		(at 78.086966 -84.201)
		(size 0.7112)
		(drill 0.4064)
		(layers "F.Cu" "B.Cu")
		(net "P1V8_E")
	)
	(via
		(at 79.102966 -84.963)
		(size 0.7112)
		(drill 0.4064)
		(layers "F.Cu" "B.Cu")
		(net "P1V8_E")
	)
	(via
		(at 87.296752 -129.421382)
		(size 0.5588)
		(drill 0.3048)
		(layers "F.Cu" "B.Cu")
		(net "P1V8_E")
	)
	(via
		(at 46.355 -139.065)
		(size 0.7112)
		(drill 0.3556)
		(layers "F.Cu" "B.Cu")
		(net "P1V8_E")
	)
	(via
		(at 92.46997 -108.839)
		(size 0.7112)
		(drill 0.4064)
		(layers "F.Cu" "B.Cu")
		(net "P1V8_E")
	)
	(via
		(at 36.449 -180.467)
		(size 0.5588)
		(drill 0.3048)
		(layers "F.Cu" "B.Cu")
		(net "P1V8_E")
	)
	(via
		(at 102.84968 -84.849716)
		(size 0.508)
		(drill 0.254)
		(layers "F.Cu" "B.Cu")
		(net "P1V8_E")
	)
	(via
		(at 257.81 -121.285)
		(size 0.508)
		(drill 0.254)
		(layers "F.Cu" "B.Cu")
		(net "P1V8_E")
	)
	(via
		(at 109.87659 -87.8459)
		(size 0.508)
		(drill 0.254)
		(layers "F.Cu" "B.Cu")
		(net "P1V8_E")
	)
	(via
		(at 106.849672 -84.849716)
		(size 0.508)
		(drill 0.254)
		(layers "F.Cu" "B.Cu")
		(net "P1V8_E")
	)
	(via
		(at 46.99 -135.524748)
		(size 0.5588)
		(drill 0.3048)
		(layers "F.Cu" "B.Cu")
		(net "P1V8_E")
	)
	(via
		(at 190.876936 -137.3124)
		(size 0.5588)
		(drill 0.3048)
		(layers "F.Cu" "B.Cu")
		(net "P1V8_E")
	)
	(via
		(at 117.850158 -86.849712)
		(size 0.508)
		(drill 0.254)
		(layers "F.Cu" "B.Cu")
		(net "P1V8_E")
	)
	(via
		(at 13.975588 -209.98688)
		(size 0.5588)
		(drill 0.3048)
		(layers "F.Cu" "B.Cu")
		(net "P1V8_E")
	)
	(via
		(at 75.860148 -121.864882)
		(size 0.5588)
		(drill 0.3048)
		(layers "F.Cu" "B.Cu")
		(net "P1V8_E")
	)
	(via
		(at 80.56753 -125.29312)
		(size 0.5588)
		(drill 0.3048)
		(layers "F.Cu" "B.Cu")
		(net "P1V8_E")
	)
	(via
		(at 104.849676 -105.850182)
		(size 0.508)
		(drill 0.254)
		(layers "F.Cu" "B.Cu")
		(net "P1V8_E")
	)
	(via
		(at 102.40137 -111.1504)
		(size 0.7112)
		(drill 0.4064)
		(layers "F.Cu" "B.Cu")
		(net "P1V8_E")
	)
	(via
		(at 82.94497 -108.077)
		(size 0.7112)
		(drill 0.3556)
		(layers "F.Cu" "B.Cu")
		(net "P1V8_E")
	)
	(via
		(at 109.849666 -96.8502)
		(size 0.508)
		(drill 0.254)
		(layers "F.Cu" "B.Cu")
		(net "P1V8_E")
	)
	(via
		(at 104.849676 -84.849716)
		(size 0.508)
		(drill 0.254)
		(layers "F.Cu" "B.Cu")
		(net "P1V8_E")
	)
	(via
		(at 91.70797 -109.601)
		(size 0.7112)
		(drill 0.4064)
		(layers "F.Cu" "B.Cu")
		(net "P1V8_E")
	)
	(via
		(at 108.849668 -89.849706)
		(size 0.508)
		(drill 0.254)
		(layers "F.Cu" "B.Cu")
		(net "P1V8_E")
	)
	(via
		(at 49.74971 -140.44676)
		(size 0.5588)
		(drill 0.3048)
		(layers "F.Cu" "B.Cu")
		(net "P1V8_E")
	)
	(via
		(at 37.465 -119.9134)
		(size 0.5588)
		(drill 0.3048)
		(layers "F.Cu" "B.Cu")
		(net "P1V8_E")
	)
	(via
		(at 46.4312 -119.7102)
		(size 0.5588)
		(drill 0.3048)
		(layers "F.Cu" "B.Cu")
		(net "P1V8_E")
	)
	(via
		(at 101.48697 -111.379)
		(size 0.508)
		(drill 0.254)
		(layers "F.Cu" "B.Cu")
		(net "P1V8_E")
	)
	(via
		(at 108.849668 -84.849716)
		(size 0.508)
		(drill 0.254)
		(layers "F.Cu" "B.Cu")
		(net "P1V8_E")
	)
	(via
		(at 98.77679 -119.6594)
		(size 0.5588)
		(drill 0.3048)
		(layers "F.Cu" "B.Cu")
		(net "P1V8_E")
	)
	(via
		(at 77.76337 -126.4158)
		(size 0.508)
		(drill 0.254)
		(layers "F.Cu" "B.Cu")
		(net "P1V8_E")
	)
	(via
		(at 85.43925 -115.02898)
		(size 0.5588)
		(drill 0.3048)
		(layers "F.Cu" "B.Cu")
		(net "P1V8_E")
	)
	(via
		(at 60.071 -145.796)
		(size 0.508)
		(drill 0.254)
		(layers "F.Cu" "B.Cu")
		(net "P1V8_E")
	)
	(via
		(at 104.849676 -97.850198)
		(size 0.508)
		(drill 0.254)
		(layers "F.Cu" "B.Cu")
		(net "P1V8_E")
	)
	(via
		(at 113.849658 -83.849718)
		(size 0.508)
		(drill 0.254)
		(layers "F.Cu" "B.Cu")
		(net "P1V8_E")
	)
	(via
		(at 104.849676 -99.850194)
		(size 0.508)
		(drill 0.254)
		(layers "F.Cu" "B.Cu")
		(net "P1V8_E")
	)
	(via
		(at 118.850156 -83.849718)
		(size 0.508)
		(drill 0.254)
		(layers "F.Cu" "B.Cu")
		(net "P1V8_E")
	)
	(via
		(at 94.50197 -92.456)
		(size 0.5588)
		(drill 0.3048)
		(layers "F.Cu" "B.Cu")
		(net "P1V8_E")
	)
	(via
		(at 108.849668 -87.84971)
		(size 0.508)
		(drill 0.254)
		(layers "F.Cu" "B.Cu")
		(net "P1V8_E")
	)
	(via
		(at 96.07677 -119.84736)
		(size 0.5588)
		(drill 0.3048)
		(layers "F.Cu" "B.Cu")
		(net "P1V8_E")
	)
	(via
		(at 47.06747 -132.3594)
		(size 0.5588)
		(drill 0.3048)
		(layers "F.Cu" "B.Cu")
		(net "P1V8_E")
	)
	(via
		(at 81.365852 -128.951482)
		(size 0.508)
		(drill 0.254)
		(layers "F.Cu" "B.Cu")
		(net "P1V8_E")
	)
	(via
		(at 163.957 -122.174)
		(size 0.7112)
		(drill 0.4064)
		(layers "F.Cu" "B.Cu")
		(net "P1V8_E")
	)
	(via
		(at 90.845894 -110.290864)
		(size 0.7112)
		(drill 0.4064)
		(layers "F.Cu" "B.Cu")
		(net "P1V8_E")
	)
	(via
		(at 104.849676 -107.850178)
		(size 0.508)
		(drill 0.254)
		(layers "F.Cu" "B.Cu")
		(net "P1V8_E")
	)
	(via
		(at 80.58277 -130.59918)
		(size 0.5588)
		(drill 0.3048)
		(layers "F.Cu" "B.Cu")
		(net "P1V8_E")
	)
	(via
		(at 105.849674 -89.849706)
		(size 0.508)
		(drill 0.254)
		(layers "F.Cu" "B.Cu")
		(net "P1V8_E")
	)
	(via
		(at 108.849668 -91.849702)
		(size 0.508)
		(drill 0.254)
		(layers "F.Cu" "B.Cu")
		(net "P1V8_E")
	)
	(via
		(at 64.389 -179.6415)
		(size 0.508)
		(drill 0.254)
		(layers "F.Cu" "B.Cu")
		(net "P1V8_E")
	)
	(via
		(at 52.90947 -139.36218)
		(size 0.5588)
		(drill 0.3048)
		(layers "F.Cu" "B.Cu")
		(net "P1V8_E")
	)
	(via
		(at 193.167 -124.333)
		(size 0.5588)
		(drill 0.3048)
		(layers "F.Cu" "B.Cu")
		(net "P1V8_E")
	)
	(via
		(at 16.769588 -210.122516)
		(size 0.5588)
		(drill 0.3048)
		(layers "F.Cu" "B.Cu")
		(net "P1V8_E")
	)
	(via
		(at 117.9068 -78.190852)
		(size 0.5588)
		(drill 0.3048)
		(layers "F.Cu" "B.Cu")
		(net "P1V8_E")
	)
	(via
		(at 52.774342 -131.206748)
		(size 0.5588)
		(drill 0.3048)
		(layers "F.Cu" "B.Cu")
		(net "P1V8_E")
	)
	(via
		(at 105.82021 -88.88222)
		(size 0.508)
		(drill 0.254)
		(layers "F.Cu" "B.Cu")
		(net "P1V8_E")
	)
	(via
		(at 108.849668 -97.850198)
		(size 0.508)
		(drill 0.254)
		(layers "F.Cu" "B.Cu")
		(net "P1V8_E")
	)
	(via
		(at 104.849676 -95.850202)
		(size 0.508)
		(drill 0.254)
		(layers "F.Cu" "B.Cu")
		(net "P1V8_E")
	)
	(via
		(at 22.810216 -170.10888)
		(size 0.5588)
		(drill 0.3048)
		(layers "F.Cu" "B.Cu")
		(net "P1V8_E")
	)
	(via
		(at 92.45981 -118.9863)
		(size 0.5588)
		(drill 0.3048)
		(layers "F.Cu" "B.Cu")
		(net "P1V8_E")
	)
	(via
		(at 95.26397 -112.903)
		(size 0.5588)
		(drill 0.3048)
		(layers "F.Cu" "B.Cu")
		(net "P1V8_E")
	)
	(via
		(at 104.849676 -101.85019)
		(size 0.508)
		(drill 0.254)
		(layers "F.Cu" "B.Cu")
		(net "P1V8_E")
	)
	(via
		(at 108.849668 -93.849698)
		(size 0.508)
		(drill 0.254)
		(layers "F.Cu" "B.Cu")
		(net "P1V8_E")
	)
	(via
		(at 56.388 -178.689)
		(size 0.7112)
		(drill 0.4064)
		(layers "F.Cu" "B.Cu")
		(net "P1V8_E")
	)
	(via
		(at 240.03 -35.941)
		(size 0.508)
		(drill 0.254)
		(layers "F.Cu" "B.Cu")
		(net "P1V8_E")
	)
	(via
		(at 104.849676 -92.8497)
		(size 0.508)
		(drill 0.254)
		(layers "F.Cu" "B.Cu")
		(net "P1V8_E")
	)
	(via
		(at 237.75162 -116.21516)
		(size 0.5588)
		(drill 0.3048)
		(layers "F.Cu" "B.Cu")
		(net "P1V8_E")
	)
	(via
		(at 52.6034 -178.7144)
		(size 0.7112)
		(drill 0.4064)
		(layers "F.Cu" "B.Cu")
		(net "P1V8_E")
	)
	(via
		(at 23.710138 -194.501516)
		(size 0.5588)
		(drill 0.3048)
		(layers "F.Cu" "B.Cu")
		(net "P1V8_E")
	)
	(via
		(at 112.84966 -86.849712)
		(size 0.508)
		(drill 0.254)
		(layers "F.Cu" "B.Cu")
		(net "P1V8_E")
	)
	(via
		(at 85.979 -100.965)
		(size 0.5588)
		(drill 0.3048)
		(layers "F.Cu" "B.Cu")
		(net "P1V8_E")
	)
	(via
		(at 244.2718 -121.285)
		(size 0.5588)
		(drill 0.3048)
		(layers "F.Cu" "B.Cu")
		(net "P1V8_E")
	)
	(via
		(at 14.047216 -170.10888)
		(size 0.5588)
		(drill 0.3048)
		(layers "F.Cu" "B.Cu")
		(net "P1V8_E")
	)
	(via
		(at 104.849676 -90.849704)
		(size 0.508)
		(drill 0.254)
		(layers "F.Cu" "B.Cu")
		(net "P1V8_E")
	)
	(via
		(at 59.055 -107.95)
		(size 0.5588)
		(drill 0.3048)
		(layers "F.Cu" "B.Cu")
		(net "P1V8_E")
	)
	(via
		(at 115.850162 -86.849712)
		(size 0.508)
		(drill 0.254)
		(layers "F.Cu" "B.Cu")
		(net "P1V8_E")
	)
	(via
		(at 31.115 -214.757)
		(size 0.5588)
		(drill 0.3048)
		(layers "F.Cu" "B.Cu")
		(net "P1V8_E")
	)
	(via
		(at 116.85016 -83.849718)
		(size 0.508)
		(drill 0.254)
		(layers "F.Cu" "B.Cu")
		(net "P1V8_E")
	)
	(via
		(at 78.086966 -85.344)
		(size 0.7112)
		(drill 0.4064)
		(layers "F.Cu" "B.Cu")
		(net "P1V8_E")
	)
	(via
		(at 52.90947 -136.22528)
		(size 0.5588)
		(drill 0.3048)
		(layers "F.Cu" "B.Cu")
		(net "P1V8_E")
	)
	(via
		(at 110.349792 -81.478882)
		(size 0.508)
		(drill 0.254)
		(layers "F.Cu" "B.Cu")
		(net "P1V8_E")
	)
	(via
		(at 48.133 -145.669)
		(size 0.5588)
		(drill 0.3048)
		(layers "F.Cu" "B.Cu")
		(net "P1V8_E")
	)
	(via
		(at 19.685 -211.328)
		(size 0.5588)
		(drill 0.3048)
		(layers "F.Cu" "B.Cu")
		(net "P1V8_E")
	)
	(via
		(at 18.010886 -215.22055)
		(size 0.5588)
		(drill 0.3048)
		(layers "F.Cu" "B.Cu")
		(net "P1V8_E")
	)
	(via
		(at 27.686 -214.43188)
		(size 0.508)
		(drill 0.254)
		(layers "F.Cu" "B.Cu")
		(net "P1V8_E")
	)
	(via
		(at 41.402 -180.467)
		(size 0.5588)
		(drill 0.3048)
		(layers "F.Cu" "B.Cu")
		(net "P1V8_E")
	)
	(via
		(at 111.849662 -83.849718)
		(size 0.508)
		(drill 0.254)
		(layers "F.Cu" "B.Cu")
		(net "P1V8_E")
	)
	(via
		(at 104.849676 -86.849712)
		(size 0.508)
		(drill 0.254)
		(layers "F.Cu" "B.Cu")
		(net "P1V8_E")
	)
	(via
		(at 104.849676 -103.850186)
		(size 0.508)
		(drill 0.254)
		(layers "F.Cu" "B.Cu")
		(net "P1V8_E")
	)
	(segment
		(start 112.78997 -75.8825)
		(end 112.78997 -76.2762)
		(width 0.508)
		(layer "B.Cu")
		(net "P1V8_E")
	)
	(segment
		(start 100.711 -83.6422)
		(end 101.283516 -84.214716)
		(width 0.508)
		(layer "B.Cu")
		(net "P1V8_E")
	)
	(segment
		(start 18.010886 -214.53221)
		(end 18.010886 -215.22055)
		(width 0.508)
		(layer "B.Cu")
		(net "P1V8_E")
	)
	(segment
		(start 102.515162 -82.8294)
		(end 102.37597 -82.8294)
		(width 0.3048)
		(layer "B.Cu")
		(net "P1V8_E")
	)
	(segment
		(start 103.26497 -82.1055)
		(end 103.141018 -82.229452)
		(width 0.3048)
		(layer "B.Cu")
		(net "P1V8_E")
	)
	(segment
		(start 113.57737 -82.931)
		(end 113.74247 -83.0961)
		(width 0.3048)
		(layer "B.Cu")
		(net "P1V8_E")
	)
	(segment
		(start 102.112826 -84.214716)
		(end 102.747826 -84.849716)
		(width 0.508)
		(layer "B.Cu")
		(net "P1V8_E")
	)
	(segment
		(start 118.72087 -78.4098)
		(end 118.176548 -78.4098)
		(width 0.508)
		(layer "B.Cu")
		(net "P1V8_E")
	)
	(segment
		(start 118.176548 -78.4098)
		(end 117.9576 -78.190852)
		(width 0.508)
		(layer "B.Cu")
		(net "P1V8_E")
	)
	(segment
		(start 105.75417 -88.1126)
		(end 105.75417 -88.81618)
		(width 0.3048)
		(layer "B.Cu")
		(net "P1V8_E")
	)
	(segment
		(start 16.515588 -204.736954)
		(end 16.515588 -208.789016)
		(width 0.508)
		(layer "B.Cu")
		(net "P1V8_E")
	)
	(segment
		(start 163.957 -122.174)
		(end 163.957 -127.762)
		(width 0.508)
		(layer "B.Cu")
		(net "P1V8_E")
	)
	(segment
		(start 14.36497 -210.376262)
		(end 16.515842 -210.376262)
		(width 0.508)
		(layer "B.Cu")
		(net "P1V8_E")
	)
	(segment
		(start 115.831874 -86.868)
		(end 115.850162 -86.849712)
		(width 0.3556)
		(layer "B.Cu")
		(net "P1V8_E")
	)
	(segment
		(start 23.710138 -194.501516)
		(end 23.883366 -194.674744)
		(width 0.508)
		(layer "B.Cu")
		(net "P1V8_E")
	)
	(segment
		(start 111.26597 -80.518)
		(end 110.63097 -79.883)
		(width 0.508)
		(layer "B.Cu")
		(net "P1V8_E")
	)
	(segment
		(start 29.718 -187.198)
		(end 36.449 -180.467)
		(width 0.508)
		(layer "B.Cu")
		(net "P1V8_E")
	)
	(segment
		(start 104.09047 -86.0679)
		(end 104.09047 -86.090506)
		(width 0.3048)
		(layer "B.Cu")
		(net "P1V8_E")
	)
	(segment
		(start 163.957 -120.8405)
		(end 163.957 -122.174)
		(width 0.508)
		(layer "B.Cu")
		(net "P1V8_E")
	)
	(segment
		(start 86.36 -100.584)
		(end 85.979 -100.965)
		(width 0.508)
		(layer "B.Cu")
		(net "P1V8_E")
	)
	(segment
		(start 29.718 -189.32017)
		(end 29.718 -187.198)
		(width 0.508)
		(layer "B.Cu")
		(net "P1V8_E")
	)
	(segment
		(start 110.02137 -88.6206)
		(end 110.02137 -87.99068)
		(width 0.3048)
		(layer "B.Cu")
		(net "P1V8_E")
	)
	(segment
		(start 103.141018 -82.229452)
		(end 103.11511 -82.229452)
		(width 0.3048)
		(layer "B.Cu")
		(net "P1V8_E")
	)
	(segment
		(start 15.126716 -170.10888)
		(end 15.126716 -170.477434)
		(width 0.508)
		(layer "B.Cu")
		(net "P1V8_E")
	)
	(segment
		(start 16.515842 -210.376262)
		(end 16.769588 -210.122516)
		(width 0.508)
		(layer "B.Cu")
		(net "P1V8_E")
	)
	(segment
		(start 19.685 -211.328)
		(end 19.685 -211.455)
		(width 0.508)
		(layer "B.Cu")
		(net "P1V8_E")
	)
	(segment
		(start 101.1682 -83.185)
		(end 100.711 -83.6422)
		(width 0.3048)
		(layer "B.Cu")
		(net "P1V8_E")
	)
	(segment
		(start 190.876936 -137.3124)
		(end 193.167 -135.022336)
		(width 0.508)
		(layer "B.Cu")
		(net "P1V8_E")
	)
	(segment
		(start 105.75417 -88.81618)
		(end 105.82021 -88.88222)
		(width 0.3048)
		(layer "B.Cu")
		(net "P1V8_E")
	)
	(segment
		(start 115.10137 -86.868)
		(end 115.831874 -86.868)
		(width 0.3556)
		(layer "B.Cu")
		(net "P1V8_E")
	)
	(segment
		(start 101.99497 -83.185)
		(end 101.1682 -83.185)
		(width 0.3048)
		(layer "B.Cu")
		(net "P1V8_E")
	)
	(segment
		(start 238.38916 -116.21516)
		(end 237.75162 -116.21516)
		(width 1.016)
		(layer "B.Cu")
		(net "P1V8_E")
	)
	(segment
		(start 111.71047 -83.0961)
		(end 111.71047 -83.710526)
		(width 0.3048)
		(layer "B.Cu")
		(net "P1V8_E")
	)
	(segment
		(start 118.82247 -83.0961)
		(end 118.82247 -83.822032)
		(width 0.3048)
		(layer "B.Cu")
		(net "P1V8_E")
	)
	(segment
		(start 117.9576 -78.190852)
		(end 117.9068 -78.190852)
		(width 0.508)
		(layer "B.Cu")
		(net "P1V8_E")
	)
	(segment
		(start 163.957 -127.762)
		(end 173.5074 -137.3124)
		(width 0.508)
		(layer "B.Cu")
		(net "P1V8_E")
	)
	(segment
		(start 13.975588 -209.98688)
		(end 14.36497 -210.376262)
		(width 0.508)
		(layer "B.Cu")
		(net "P1V8_E")
	)
	(segment
		(start 116.640102 -79.016098)
		(end 117.465348 -78.190852)
		(width 0.508)
		(layer "B.Cu")
		(net "P1V8_E")
	)
	(segment
		(start 19.05 -212.09)
		(end 19.05 -213.493096)
		(width 0.508)
		(layer "B.Cu")
		(net "P1V8_E")
	)
	(segment
		(start 102.747826 -84.849716)
		(end 102.84968 -84.849716)
		(width 0.508)
		(layer "B.Cu")
		(net "P1V8_E")
	)
	(segment
		(start 105.58907 -87.9475)
		(end 105.75417 -88.1126)
		(width 0.3048)
		(layer "B.Cu")
		(net "P1V8_E")
	)
	(segment
		(start 116.42217 -79.9084)
		(end 116.640102 -79.690468)
		(width 0.508)
		(layer "B.Cu")
		(net "P1V8_E")
	)
	(segment
		(start 87.1855 -100.584)
		(end 86.36 -100.584)
		(width 0.508)
		(layer "B.Cu")
		(net "P1V8_E")
	)
	(segment
		(start 257.81 -121.285)
		(end 244.2718 -121.285)
		(width 1.016)
		(layer "B.Cu")
		(net "P1V8_E")
	)
	(segment
		(start 21.921216 -170.99788)
		(end 22.810216 -170.10888)
		(width 0.508)
		(layer "B.Cu")
		(net "P1V8_E")
	)
	(segment
		(start 17.793716 -215.43772)
		(end 18.010886 -215.22055)
		(width 0.508)
		(layer "B.Cu")
		(net "P1V8_E")
	)
	(segment
		(start 16.515588 -208.789016)
		(end 16.515588 -209.868516)
		(width 0.508)
		(layer "B.Cu")
		(net "P1V8_E")
	)
	(segment
		(start 118.65737 -82.931)
		(end 118.82247 -83.0961)
		(width 0.3048)
		(layer "B.Cu")
		(net "P1V8_E")
	)
	(segment
		(start 24.016716 -170.10888)
		(end 22.810216 -170.10888)
		(width 0.508)
		(layer "B.Cu")
		(net "P1V8_E")
	)
	(segment
		(start 104.31907 -93.380306)
		(end 104.849676 -92.8497)
		(width 0.2032)
		(layer "B.Cu")
		(net "P1V8_E")
	)
	(segment
		(start 111.71047 -83.710526)
		(end 111.849662 -83.849718)
		(width 0.3048)
		(layer "B.Cu")
		(net "P1V8_E")
	)
	(segment
		(start 173.5074 -137.3124)
		(end 190.876936 -137.3124)
		(width 0.508)
		(layer "B.Cu")
		(net "P1V8_E")
	)
	(segment
		(start 108.084366 -94.615)
		(end 108.849668 -93.849698)
		(width 0.3048)
		(layer "B.Cu")
		(net "P1V8_E")
	)
	(segment
		(start 116.640102 -79.690468)
		(end 116.640102 -79.016098)
		(width 0.508)
		(layer "B.Cu")
		(net "P1V8_E")
	)
	(segment
		(start 111.26597 -81.0895)
		(end 111.26597 -80.518)
		(width 0.508)
		(layer "B.Cu")
		(net "P1V8_E")
	)
	(segment
		(start 24.536654 -194.501516)
		(end 29.718 -189.32017)
		(width 0.508)
		(layer "B.Cu")
		(net "P1V8_E")
	)
	(segment
		(start 101.283516 -84.214716)
		(end 102.112826 -84.214716)
		(width 0.508)
		(layer "B.Cu")
		(net "P1V8_E")
	)
	(segment
		(start 108.02747 -94.615)
		(end 108.084366 -94.615)
		(width 0.3048)
		(layer "B.Cu")
		(net "P1V8_E")
	)
	(segment
		(start 111.72317 -83.1088)
		(end 111.71047 -83.0961)
		(width 0.3048)
		(layer "B.Cu")
		(net "P1V8_E")
	)
	(segment
		(start 116.79047 -82.931)
		(end 116.79047 -83.790028)
		(width 0.3048)
		(layer "B.Cu")
		(net "P1V8_E")
	)
	(segment
		(start 104.31907 -94.488)
		(end 104.31907 -93.380306)
		(width 0.2032)
		(layer "B.Cu")
		(net "P1V8_E")
	)
	(segment
		(start 113.74247 -83.74253)
		(end 113.849658 -83.849718)
		(width 0.3048)
		(layer "B.Cu")
		(net "P1V8_E")
	)
	(segment
		(start 243.459 -121.285)
		(end 238.38916 -116.21516)
		(width 1.016)
		(layer "B.Cu")
		(net "P1V8_E")
	)
	(segment
		(start 110.63097 -79.883)
		(end 108.9025 -79.883)
		(width 0.508)
		(layer "B.Cu")
		(net "P1V8_E")
	)
	(segment
		(start 19.685 -211.455)
		(end 19.05 -212.09)
		(width 0.508)
		(layer "B.Cu")
		(net "P1V8_E")
	)
	(segment
		(start 15.126716 -170.477434)
		(end 15.647162 -170.99788)
		(width 0.508)
		(layer "B.Cu")
		(net "P1V8_E")
	)
	(segment
		(start 104.09047 -86.090506)
		(end 104.849676 -86.849712)
		(width 0.3048)
		(layer "B.Cu")
		(net "P1V8_E")
	)
	(segment
		(start 17.793716 -216.71788)
		(end 17.793716 -215.43772)
		(width 0.508)
		(layer "B.Cu")
		(net "P1V8_E")
	)
	(segment
		(start 193.167 -135.022336)
		(end 193.167 -124.333)
		(width 0.508)
		(layer "B.Cu")
		(net "P1V8_E")
	)
	(segment
		(start 244.2718 -121.285)
		(end 243.459 -121.285)
		(width 1.016)
		(layer "B.Cu")
		(net "P1V8_E")
	)
	(segment
		(start 116.79047 -83.790028)
		(end 116.85016 -83.849718)
		(width 0.3048)
		(layer "B.Cu")
		(net "P1V8_E")
	)
	(segment
		(start 110.349792 -81.478882)
		(end 110.739174 -81.0895)
		(width 0.508)
		(layer "B.Cu")
		(net "P1V8_E")
	)
	(segment
		(start 16.515588 -209.868516)
		(end 16.769588 -210.122516)
		(width 0.508)
		(layer "B.Cu")
		(net "P1V8_E")
	)
	(segment
		(start 102.35057 -82.8294)
		(end 101.99497 -83.185)
		(width 0.3048)
		(layer "B.Cu")
		(net "P1V8_E")
	)
	(segment
		(start 103.11511 -82.229452)
		(end 102.515162 -82.8294)
		(width 0.3048)
		(layer "B.Cu")
		(net "P1V8_E")
	)
	(segment
		(start 102.37597 -82.8294)
		(end 102.35057 -82.8294)
		(width 0.3048)
		(layer "B.Cu")
		(net "P1V8_E")
	)
	(segment
		(start 15.647162 -170.99788)
		(end 21.921216 -170.99788)
		(width 0.508)
		(layer "B.Cu")
		(net "P1V8_E")
	)
	(segment
		(start 14.047216 -170.10888)
		(end 15.126716 -170.10888)
		(width 0.508)
		(layer "B.Cu")
		(net "P1V8_E")
	)
	(segment
		(start 113.74247 -83.0961)
		(end 113.74247 -83.74253)
		(width 0.3048)
		(layer "B.Cu")
		(net "P1V8_E")
	)
	(segment
		(start 112.78997 -76.2762)
		(end 116.42217 -79.9084)
		(width 0.508)
		(layer "B.Cu")
		(net "P1V8_E")
	)
	(segment
		(start 117.465348 -78.190852)
		(end 117.9068 -78.190852)
		(width 0.508)
		(layer "B.Cu")
		(net "P1V8_E")
	)
	(segment
		(start 23.883366 -194.674744)
		(end 23.883366 -197.369176)
		(width 0.508)
		(layer "B.Cu")
		(net "P1V8_E")
	)
	(segment
		(start 23.710138 -194.501516)
		(end 24.536654 -194.501516)
		(width 0.508)
		(layer "B.Cu")
		(net "P1V8_E")
	)
	(segment
		(start 118.82247 -83.822032)
		(end 118.850156 -83.849718)
		(width 0.3048)
		(layer "B.Cu")
		(net "P1V8_E")
	)
	(segment
		(start 19.05 -213.493096)
		(end 18.010886 -214.53221)
		(width 0.508)
		(layer "B.Cu")
		(net "P1V8_E")
	)
	(segment
		(start 110.02137 -87.99068)
		(end 109.87659 -87.8459)
		(width 0.3048)
		(layer "B.Cu")
		(net "P1V8_E")
	)
	(segment
		(start 110.739174 -81.0895)
		(end 111.26597 -81.0895)
		(width 0.508)
		(layer "B.Cu")
		(net "P1V8_E")
	)
	(segment
		(start 23.883366 -197.369176)
		(end 16.515588 -204.736954)
		(width 0.508)
		(layer "B.Cu")
		(net "P1V8_E")
	)
	(segment
		(start 194.056 -125.222)
		(end 193.167 -124.333)
		(width 0.508)
		(layer "In2.Cu")
		(net "P1V8_E")
	)
	(segment
		(start 52.6034 -178.7144)
		(end 43.1546 -178.7144)
		(width 0.508)
		(layer "In2.Cu")
		(net "P1V8_E")
	)
	(segment
		(start 64.389 -179.6415)
		(end 64.1985 -179.832)
		(width 0.508)
		(layer "In2.Cu")
		(net "P1V8_E")
	)
	(segment
		(start 257.81 -121.285)
		(end 257.937 -121.158)
		(width 1.016)
		(layer "In2.Cu")
		(net "P1V8_E")
	)
	(segment
		(start 41.402 -180.467)
		(end 36.449 -180.467)
		(width 0.508)
		(layer "In2.Cu")
		(net "P1V8_E")
	)
	(segment
		(start 240.03 -35.968178)
		(end 240.03 -35.941)
		(width 1.016)
		(layer "In2.Cu")
		(net "P1V8_E")
	)
	(segment
		(start 57.531 -179.832)
		(end 56.388 -178.689)
		(width 0.508)
		(layer "In2.Cu")
		(net "P1V8_E")
	)
	(segment
		(start 266.2936 -107.63885)
		(end 266.2936 -84.117688)
		(width 1.016)
		(layer "In2.Cu")
		(net "P1V8_E")
	)
	(segment
		(start 27.88412 -214.63)
		(end 30.988 -214.63)
		(width 0.508)
		(layer "In2.Cu")
		(net "P1V8_E")
	)
	(segment
		(start 36.449 -180.467)
		(end 33.168336 -180.467)
		(width 0.508)
		(layer "In2.Cu")
		(net "P1V8_E")
	)
	(segment
		(start 64.1985 -179.832)
		(end 57.531 -179.832)
		(width 0.508)
		(layer "In2.Cu")
		(net "P1V8_E")
	)
	(segment
		(start 240.3348 -125.222)
		(end 194.056 -125.222)
		(width 0.508)
		(layer "In2.Cu")
		(net "P1V8_E")
	)
	(segment
		(start 148.8694 -119.6594)
		(end 98.77679 -119.6594)
		(width 1.016)
		(layer "In2.Cu")
		(net "P1V8_E")
	)
	(segment
		(start 27.686 -214.43188)
		(end 27.88412 -214.63)
		(width 0.508)
		(layer "In2.Cu")
		(net "P1V8_E")
	)
	(segment
		(start 257.937 -121.158)
		(end 257.937 -115.99545)
		(width 1.016)
		(layer "In2.Cu")
		(net "P1V8_E")
	)
	(segment
		(start 151.384 -122.174)
		(end 148.8694 -119.6594)
		(width 1.016)
		(layer "In2.Cu")
		(net "P1V8_E")
	)
	(segment
		(start 244.2718 -121.285)
		(end 240.3348 -125.222)
		(width 0.508)
		(layer "In2.Cu")
		(net "P1V8_E")
	)
	(segment
		(start 43.1546 -178.7144)
		(end 41.402 -180.467)
		(width 0.508)
		(layer "In2.Cu")
		(net "P1V8_E")
	)
	(segment
		(start 266.2936 -84.117688)
		(end 252.05944 -69.883528)
		(width 1.016)
		(layer "In2.Cu")
		(net "P1V8_E")
	)
	(segment
		(start 252.05944 -69.883528)
		(end 252.05944 -47.997618)
		(width 1.016)
		(layer "In2.Cu")
		(net "P1V8_E")
	)
	(segment
		(start 252.05944 -47.997618)
		(end 240.03 -35.968178)
		(width 1.016)
		(layer "In2.Cu")
		(net "P1V8_E")
	)
	(segment
		(start 163.957 -122.174)
		(end 151.384 -122.174)
		(width 1.016)
		(layer "In2.Cu")
		(net "P1V8_E")
	)
	(segment
		(start 30.988 -214.63)
		(end 31.115 -214.757)
		(width 0.508)
		(layer "In2.Cu")
		(net "P1V8_E")
	)
	(segment
		(start 33.168336 -180.467)
		(end 22.810216 -170.10888)
		(width 0.508)
		(layer "In2.Cu")
		(net "P1V8_E")
	)
	(segment
		(start 257.937 -115.99545)
		(end 266.2936 -107.63885)
		(width 1.016)
		(layer "In2.Cu")
		(net "P1V8_E")
	)
	(segment
		(start 17.975072 -211.328)
		(end 16.769588 -210.122516)
		(width 0.635)
		(layer "In5.Cu")
		(net "P1V8_E")
	)
	(segment
		(start 19.685 -211.328)
		(end 17.975072 -211.328)
		(width 0.635)
		(layer "In5.Cu")
		(net "P1V8_E")
	)
	(segment
		(start 100.819966 -65.3415)
		(end 100.819966 -66.675)
		(width 0.4572)
		(layer "F.Cu")
		(net "P1V8_C")
	)
	(segment
		(start 111.549942 -53.399944)
		(end 111.549688 -53.399944)
		(width 0.3556)
		(layer "F.Cu")
		(net "P1V8_C")
	)
	(segment
		(start 110.750096 -50.999644)
		(end 111.149892 -50.599848)
		(width 0.3556)
		(layer "F.Cu")
		(net "P1V8_C")
	)
	(segment
		(start 110.217966 -66.3321)
		(end 110.217966 -67.1322)
		(width 0.508)
		(layer "F.Cu")
		(net "P1V8_C")
	)
	(segment
		(start 110.56366 -29.845)
		(end 110.725966 -29.845)
		(width 0.3048)
		(layer "F.Cu")
		(net "P1V8_C")
	)
	(segment
		(start 111.549942 -51.799998)
		(end 111.549688 -51.799998)
		(width 0.3556)
		(layer "F.Cu")
		(net "P1V8_C")
	)
	(segment
		(start 116.713 -27.8765)
		(end 115.57 -27.8765)
		(width 0.508)
		(layer "F.Cu")
		(net "P1V8_C")
	)
	(segment
		(start 110.770416 -29.80055)
		(end 111.452406 -29.80055)
		(width 0.3048)
		(layer "F.Cu")
		(net "P1V8_C")
	)
	(segment
		(start 101.2825 -67.686428)
		(end 101.277166 -67.703954)
		(width 0.508)
		(layer "F.Cu")
		(net "P1V8_C")
	)
	(segment
		(start 114.535966 -29.953966)
		(end 114.535966 -29.972)
		(width 0.508)
		(layer "F.Cu")
		(net "P1V8_C")
	)
	(segment
		(start 106.750104 -53.399944)
		(end 107.1499 -53.79974)
		(width 0.3556)
		(layer "F.Cu")
		(net "P1V8_C")
	)
	(segment
		(start 110.750096 -49.399698)
		(end 111.149892 -48.999902)
		(width 0.3556)
		(layer "F.Cu")
		(net "P1V8_C")
	)
	(segment
		(start 110.750096 -54.199536)
		(end 111.149892 -53.79974)
		(width 0.3556)
		(layer "F.Cu")
		(net "P1V8_C")
	)
	(segment
		(start 93.950028 -53.399944)
		(end 93.950282 -53.399944)
		(width 0.3556)
		(layer "F.Cu")
		(net "P1V8_C")
	)
	(segment
		(start 110.750096 -44.599606)
		(end 111.149892 -44.19981)
		(width 0.3556)
		(layer "F.Cu")
		(net "P1V8_C")
	)
	(segment
		(start 95.549974 -53.399944)
		(end 95.550228 -53.399944)
		(width 0.3556)
		(layer "F.Cu")
		(net "P1V8_C")
	)
	(segment
		(start 92.485718 -46.872906)
		(end 92.358718 -46.999906)
		(width 0.3556)
		(layer "F.Cu")
		(net "P1V8_C")
	)
	(segment
		(start 108.077 -60.071)
		(end 107.569 -59.563)
		(width 0.508)
		(layer "F.Cu")
		(net "P1V8_C")
	)
	(segment
		(start 122.047 -48.514)
		(end 122.047 -46.1772)
		(width 0.508)
		(layer "F.Cu")
		(net "P1V8_C")
	)
	(segment
		(start 111.549942 -50.199798)
		(end 111.149892 -50.599848)
		(width 0.3556)
		(layer "F.Cu")
		(net "P1V8_C")
	)
	(segment
		(start 152.4635 -53.213)
		(end 153.67 -53.213)
		(width 0.508)
		(layer "F.Cu")
		(net "P1V8_C")
	)
	(segment
		(start 93.150182 -46.199806)
		(end 93.10116 -46.199806)
		(width 0.3556)
		(layer "F.Cu")
		(net "P1V8_C")
	)
	(segment
		(start 111.549942 -35.80003)
		(end 111.157512 -35.4076)
		(width 0.2032)
		(layer "F.Cu")
		(net "P1V8_C")
	)
	(segment
		(start 93.150182 -50.999898)
		(end 93.150182 -50.99939)
		(width 0.3556)
		(layer "F.Cu")
		(net "P1V8_C")
	)
	(segment
		(start 118.409466 -45.847)
		(end 118.663466 -45.593)
		(width 0.508)
		(layer "F.Cu")
		(net "P1V8_C")
	)
	(segment
		(start 101.2825 -67.4116)
		(end 101.2825 -67.686428)
		(width 0.508)
		(layer "F.Cu")
		(net "P1V8_C")
	)
	(segment
		(start 165.779196 -147.395692)
		(end 167.056308 -147.395692)
		(width 0.3048)
		(layer "F.Cu")
		(net "P1V8_C")
	)
	(segment
		(start 93.950282 -53.399944)
		(end 94.350078 -53.79974)
		(width 0.3556)
		(layer "F.Cu")
		(net "P1V8_C")
	)
	(segment
		(start 93.10116 -46.199806)
		(end 92.485718 -46.815248)
		(width 0.3556)
		(layer "F.Cu")
		(net "P1V8_C")
	)
	(segment
		(start 101.277166 -67.703954)
		(end 101.277166 -68.013834)
		(width 0.508)
		(layer "F.Cu")
		(net "P1V8_C")
	)
	(segment
		(start 110.750096 -46.199552)
		(end 111.149892 -45.799756)
		(width 0.3556)
		(layer "F.Cu")
		(net "P1V8_C")
	)
	(segment
		(start 114.4905 -29.337)
		(end 114.4905 -29.9085)
		(width 0.508)
		(layer "F.Cu")
		(net "P1V8_C")
	)
	(segment
		(start 249.06478 -50.484278)
		(end 249.047 -50.502058)
		(width 0.508)
		(layer "F.Cu")
		(net "P1V8_C")
	)
	(segment
		(start 103.549958 -53.399944)
		(end 103.549704 -53.399944)
		(width 0.3556)
		(layer "F.Cu")
		(net "P1V8_C")
	)
	(segment
		(start 101.949758 -53.399944)
		(end 101.549962 -53.79974)
		(width 0.3556)
		(layer "F.Cu")
		(net "P1V8_C")
	)
	(segment
		(start 112.3315 -61.976)
		(end 112.268 -62.0395)
		(width 0.3048)
		(layer "F.Cu")
		(net "P1V8_C")
	)
	(segment
		(start 100.4443 -67.050666)
		(end 100.4443 -67.4116)
		(width 0.4572)
		(layer "F.Cu")
		(net "P1V8_C")
	)
	(segment
		(start 97.150174 -47.800006)
		(end 97.150174 -47.800768)
		(width 0.3556)
		(layer "F.Cu")
		(net "P1V8_C")
	)
	(segment
		(start 180.601112 -141.732)
		(end 185.42 -136.913112)
		(width 0.3048)
		(layer "F.Cu")
		(net "P1V8_C")
	)
	(segment
		(start 111.549942 -42.199814)
		(end 111.149892 -42.599864)
		(width 0.3556)
		(layer "F.Cu")
		(net "P1V8_C")
	)
	(segment
		(start 118.663466 -45.593)
		(end 119.234966 -45.593)
		(width 0.508)
		(layer "F.Cu")
		(net "P1V8_C")
	)
	(segment
		(start 110.750096 -44.59986)
		(end 110.750096 -44.599606)
		(width 0.3556)
		(layer "F.Cu")
		(net "P1V8_C")
	)
	(segment
		(start 110.750096 -39.799768)
		(end 111.149892 -39.399972)
		(width 0.3556)
		(layer "F.Cu")
		(net "P1V8_C")
	)
	(segment
		(start 107.569 -59.563)
		(end 106.807 -59.563)
		(width 0.508)
		(layer "F.Cu")
		(net "P1V8_C")
	)
	(segment
		(start 223.647 -121.6025)
		(end 223.4565 -121.6025)
		(width 0.508)
		(layer "F.Cu")
		(net "P1V8_C")
	)
	(segment
		(start 107.931966 -67.2338)
		(end 107.931966 -66.3321)
		(width 0.508)
		(layer "F.Cu")
		(net "P1V8_C")
	)
	(segment
		(start 97.95002 -54.19979)
		(end 97.54997 -53.79974)
		(width 0.3556)
		(layer "F.Cu")
		(net "P1V8_C")
	)
	(segment
		(start 152.4635 -56.642)
		(end 153.543 -56.642)
		(width 0.508)
		(layer "F.Cu")
		(net "P1V8_C")
	)
	(segment
		(start 110.750096 -39.800022)
		(end 110.750096 -39.799768)
		(width 0.3556)
		(layer "F.Cu")
		(net "P1V8_C")
	)
	(segment
		(start 104.760268 -54.61)
		(end 105.539794 -54.61)
		(width 0.2032)
		(layer "F.Cu")
		(net "P1V8_C")
	)
	(segment
		(start 93.150182 -47.790354)
		(end 92.757498 -47.39767)
		(width 0.3556)
		(layer "F.Cu")
		(net "P1V8_C")
	)
	(segment
		(start 110.750096 -41.399968)
		(end 110.750096 -41.399714)
		(width 0.3556)
		(layer "F.Cu")
		(net "P1V8_C")
	)
	(segment
		(start 111.549688 -37.399976)
		(end 111.149892 -37.799772)
		(width 0.3556)
		(layer "F.Cu")
		(net "P1V8_C")
	)
	(segment
		(start 111.549942 -40.599868)
		(end 111.149892 -40.999918)
		(width 0.3556)
		(layer "F.Cu")
		(net "P1V8_C")
	)
	(segment
		(start 101.277166 -68.013834)
		(end 100.7618 -68.5292)
		(width 0.508)
		(layer "F.Cu")
		(net "P1V8_C")
	)
	(segment
		(start 93.155008 -49.399952)
		(end 93.557344 -48.997616)
		(width 0.3048)
		(layer "F.Cu")
		(net "P1V8_C")
	)
	(segment
		(start 102.750112 -54.199536)
		(end 103.149908 -53.79974)
		(width 0.3556)
		(layer "F.Cu")
		(net "P1V8_C")
	)
	(segment
		(start 111.76 -60.96)
		(end 112.3315 -61.5315)
		(width 0.3048)
		(layer "F.Cu")
		(net "P1V8_C")
	)
	(segment
		(start 167.056308 -147.395692)
		(end 172.72 -141.732)
		(width 0.3048)
		(layer "F.Cu")
		(net "P1V8_C")
	)
	(segment
		(start 223.4565 -121.6025)
		(end 223.266 -121.793)
		(width 0.508)
		(layer "F.Cu")
		(net "P1V8_C")
	)
	(segment
		(start 104.7115 -68.2625)
		(end 104.013 -68.961)
		(width 0.381)
		(layer "F.Cu")
		(net "P1V8_C")
	)
	(segment
		(start 108.35005 -35.80003)
		(end 108.350304 -35.80003)
		(width 0.3048)
		(layer "F.Cu")
		(net "P1V8_C")
	)
	(segment
		(start 93.150182 -52.59959)
		(end 93.549978 -52.199794)
		(width 0.3556)
		(layer "F.Cu")
		(net "P1V8_C")
	)
	(segment
		(start 120.523 -50.038)
		(end 122.047 -48.514)
		(width 0.508)
		(layer "F.Cu")
		(net "P1V8_C")
	)
	(segment
		(start 108.350304 -53.399944)
		(end 108.7501 -53.79974)
		(width 0.3556)
		(layer "F.Cu")
		(net "P1V8_C")
	)
	(segment
		(start 109.95025 -35.80003)
		(end 110.3503 -36.20008)
		(width 0.3048)
		(layer "F.Cu")
		(net "P1V8_C")
	)
	(segment
		(start 110.750096 -38.199822)
		(end 110.750096 -38.199568)
		(width 0.3556)
		(layer "F.Cu")
		(net "P1V8_C")
	)
	(segment
		(start 109.949996 -53.399944)
		(end 109.15015 -54.19979)
		(width 0.3556)
		(layer "F.Cu")
		(net "P1V8_C")
	)
	(segment
		(start 118.409466 -42.037)
		(end 119.212106 -42.037)
		(width 0.508)
		(layer "F.Cu")
		(net "P1V8_C")
	)
	(segment
		(start 97.150174 -53.399944)
		(end 97.54997 -53.79974)
		(width 0.3556)
		(layer "F.Cu")
		(net "P1V8_C")
	)
	(segment
		(start 110.750096 -46.199806)
		(end 110.750096 -46.199552)
		(width 0.3556)
		(layer "F.Cu")
		(net "P1V8_C")
	)
	(segment
		(start 92.358718 -46.999906)
		(end 92.350082 -46.999906)
		(width 0.3556)
		(layer "F.Cu")
		(net "P1V8_C")
	)
	(segment
		(start 105.150158 -35.80003)
		(end 105.550208 -36.20008)
		(width 0.3048)
		(layer "F.Cu")
		(net "P1V8_C")
	)
	(segment
		(start 103.549704 -53.399944)
		(end 103.149908 -53.79974)
		(width 0.3556)
		(layer "F.Cu")
		(net "P1V8_C")
	)
	(segment
		(start 110.750096 -49.399952)
		(end 110.750096 -49.399698)
		(width 0.3556)
		(layer "F.Cu")
		(net "P1V8_C")
	)
	(segment
		(start 111.549942 -38.999922)
		(end 111.149892 -39.399972)
		(width 0.3556)
		(layer "F.Cu")
		(net "P1V8_C")
	)
	(segment
		(start 185.42 -136.913112)
		(end 185.42 -136.271)
		(width 0.3048)
		(layer "F.Cu")
		(net "P1V8_C")
	)
	(segment
		(start 114.2365 -27.94)
		(end 114.2365 -29.083)
		(width 0.508)
		(layer "F.Cu")
		(net "P1V8_C")
	)
	(segment
		(start 93.150182 -50.99939)
		(end 93.549978 -50.599594)
		(width 0.3556)
		(layer "F.Cu")
		(net "P1V8_C")
	)
	(segment
		(start 110.750096 -41.399714)
		(end 111.149892 -40.999918)
		(width 0.3556)
		(layer "F.Cu")
		(net "P1V8_C")
	)
	(segment
		(start 100.7618 -68.5292)
		(end 100.7618 -68.9356)
		(width 0.508)
		(layer "F.Cu")
		(net "P1V8_C")
	)
	(segment
		(start 100.819966 -66.675)
		(end 100.4443 -67.050666)
		(width 0.4572)
		(layer "F.Cu")
		(net "P1V8_C")
	)
	(segment
		(start 152.4635 -57.785)
		(end 153.543 -57.785)
		(width 0.508)
		(layer "F.Cu")
		(net "P1V8_C")
	)
	(segment
		(start 92.747846 -47.39767)
		(end 92.757498 -47.39767)
		(width 0.3556)
		(layer "F.Cu")
		(net "P1V8_C")
	)
	(segment
		(start 109.15015 -36.599876)
		(end 108.750354 -36.20008)
		(width 0.3048)
		(layer "F.Cu")
		(net "P1V8_C")
	)
	(segment
		(start 110.342426 -35.4076)
		(end 109.949996 -35.80003)
		(width 0.2032)
		(layer "F.Cu")
		(net "P1V8_C")
	)
	(segment
		(start 111.549942 -48.599852)
		(end 111.149892 -48.999902)
		(width 0.3556)
		(layer "F.Cu")
		(net "P1V8_C")
	)
	(segment
		(start 111.496856 -29.845)
		(end 113.538 -29.845)
		(width 0.3048)
		(layer "F.Cu")
		(net "P1V8_C")
	)
	(segment
		(start 114.2365 -29.083)
		(end 114.4905 -29.337)
		(width 0.508)
		(layer "F.Cu")
		(net "P1V8_C")
	)
	(segment
		(start 110.750096 -36.599876)
		(end 110.3503 -36.20008)
		(width 0.3048)
		(layer "F.Cu")
		(net "P1V8_C")
	)
	(segment
		(start 118.409466 -43.815)
		(end 119.234966 -43.815)
		(width 0.508)
		(layer "F.Cu")
		(net "P1V8_C")
	)
	(segment
		(start 150.578566 -61.9379)
		(end 151.003 -61.9125)
		(width 0.254)
		(layer "F.Cu")
		(net "P1V8_C")
	)
	(segment
		(start 105.950004 -36.599876)
		(end 105.550208 -36.20008)
		(width 0.3048)
		(layer "F.Cu")
		(net "P1V8_C")
	)
	(segment
		(start 101.950012 -53.399944)
		(end 101.949758 -53.399944)
		(width 0.3556)
		(layer "F.Cu")
		(net "P1V8_C")
	)
	(segment
		(start 107.54995 -36.599876)
		(end 107.150154 -36.20008)
		(width 0.3048)
		(layer "F.Cu")
		(net "P1V8_C")
	)
	(segment
		(start 250.00204 -50.484278)
		(end 249.06478 -50.484278)
		(width 0.508)
		(layer "F.Cu")
		(net "P1V8_C")
	)
	(segment
		(start 92.350082 -46.999906)
		(end 92.747846 -47.39767)
		(width 0.3556)
		(layer "F.Cu")
		(net "P1V8_C")
	)
	(segment
		(start 92.485718 -46.815248)
		(end 92.485718 -46.872906)
		(width 0.3556)
		(layer "F.Cu")
		(net "P1V8_C")
	)
	(segment
		(start 110.750096 -52.59959)
		(end 111.149892 -52.199794)
		(width 0.3556)
		(layer "F.Cu")
		(net "P1V8_C")
	)
	(segment
		(start 93.949774 -50.199798)
		(end 93.549978 -50.599594)
		(width 0.3556)
		(layer "F.Cu")
		(net "P1V8_C")
	)
	(segment
		(start 114.2365 -27.94)
		(end 114.2365 -26.924)
		(width 0.508)
		(layer "F.Cu")
		(net "P1V8_C")
	)
	(segment
		(start 111.549942 -46.999906)
		(end 111.149892 -47.399956)
		(width 0.3556)
		(layer "F.Cu")
		(net "P1V8_C")
	)
	(segment
		(start 96.350074 -54.19979)
		(end 95.950024 -53.79974)
		(width 0.3556)
		(layer "F.Cu")
		(net "P1V8_C")
	)
	(segment
		(start 109.15015 -54.19979)
		(end 108.7501 -53.79974)
		(width 0.3556)
		(layer "F.Cu")
		(net "P1V8_C")
	)
	(segment
		(start 110.750096 -38.199568)
		(end 111.149892 -37.799772)
		(width 0.3556)
		(layer "F.Cu")
		(net "P1V8_C")
	)
	(segment
		(start 172.72 -141.732)
		(end 180.601112 -141.732)
		(width 0.3048)
		(layer "F.Cu")
		(net "P1V8_C")
	)
	(segment
		(start 111.76 -60.8965)
		(end 111.76 -60.96)
		(width 0.3048)
		(layer "F.Cu")
		(net "P1V8_C")
	)
	(segment
		(start 108.350304 -35.80003)
		(end 108.750354 -36.20008)
		(width 0.3048)
		(layer "F.Cu")
		(net "P1V8_C")
	)
	(segment
		(start 110.725966 -29.845)
		(end 110.770416 -29.80055)
		(width 0.3048)
		(layer "F.Cu")
		(net "P1V8_C")
	)
	(segment
		(start 251.11964 -50.484278)
		(end 250.00204 -50.484278)
		(width 0.508)
		(layer "F.Cu")
		(net "P1V8_C")
	)
	(segment
		(start 217.19159 -87.60333)
		(end 217.12428 -87.53602)
		(width 0.254)
		(layer "F.Cu")
		(net "P1V8_C")
	)
	(segment
		(start 110.750096 -50.999898)
		(end 110.750096 -50.999644)
		(width 0.3556)
		(layer "F.Cu")
		(net "P1V8_C")
	)
	(segment
		(start 111.549688 -53.399944)
		(end 111.149892 -53.79974)
		(width 0.3556)
		(layer "F.Cu")
		(net "P1V8_C")
	)
	(segment
		(start 112.3315 -61.5315)
		(end 112.3315 -61.976)
		(width 0.3048)
		(layer "F.Cu")
		(net "P1V8_C")
	)
	(segment
		(start 108.1405 -60.071)
		(end 108.077 -60.071)
		(width 0.508)
		(layer "F.Cu")
		(net "P1V8_C")
	)
	(segment
		(start 95.550228 -53.399944)
		(end 95.950024 -53.79974)
		(width 0.3556)
		(layer "F.Cu")
		(net "P1V8_C")
	)
	(segment
		(start 97.150174 -47.800768)
		(end 97.545144 -48.195738)
		(width 0.3556)
		(layer "F.Cu")
		(net "P1V8_C")
	)
	(segment
		(start 115.57 -27.8765)
		(end 114.3 -27.8765)
		(width 0.508)
		(layer "F.Cu")
		(net "P1V8_C")
	)
	(segment
		(start 106.750104 -35.80003)
		(end 107.150154 -36.20008)
		(width 0.3048)
		(layer "F.Cu")
		(net "P1V8_C")
	)
	(segment
		(start 111.549942 -43.800014)
		(end 111.549688 -43.800014)
		(width 0.3556)
		(layer "F.Cu")
		(net "P1V8_C")
	)
	(segment
		(start 105.539794 -54.61)
		(end 105.950004 -54.19979)
		(width 0.2032)
		(layer "F.Cu")
		(net "P1V8_C")
	)
	(segment
		(start 93.949774 -51.799998)
		(end 93.549978 -52.199794)
		(width 0.3556)
		(layer "F.Cu")
		(net "P1V8_C")
	)
	(segment
		(start 108.35005 -53.399944)
		(end 108.350304 -53.399944)
		(width 0.3556)
		(layer "F.Cu")
		(net "P1V8_C")
	)
	(segment
		(start 251.328174 -50.692812)
		(end 253.307596 -50.692812)
		(width 0.508)
		(layer "F.Cu")
		(net "P1V8_C")
	)
	(segment
		(start 262.007096 -54.375812)
		(end 262.007096 -55.492904)
		(width 0.508)
		(layer "F.Cu")
		(net "P1V8_C")
	)
	(segment
		(start 111.157512 -35.4076)
		(end 110.342426 -35.4076)
		(width 0.2032)
		(layer "F.Cu")
		(net "P1V8_C")
	)
	(segment
		(start 93.950028 -50.199798)
		(end 93.949774 -50.199798)
		(width 0.3556)
		(layer "F.Cu")
		(net "P1V8_C")
	)
	(segment
		(start 105.150158 -53.399944)
		(end 105.549954 -53.79974)
		(width 0.3556)
		(layer "F.Cu")
		(net "P1V8_C")
	)
	(segment
		(start 111.452406 -29.80055)
		(end 111.496856 -29.845)
		(width 0.3048)
		(layer "F.Cu")
		(net "P1V8_C")
	)
	(segment
		(start 93.150182 -52.599844)
		(end 93.150182 -52.59959)
		(width 0.3556)
		(layer "F.Cu")
		(net "P1V8_C")
	)
	(segment
		(start 111.379 -62.946788)
		(end 111.379 -63.5)
		(width 0.3048)
		(layer "F.Cu")
		(net "P1V8_C")
	)
	(segment
		(start 93.150182 -49.399952)
		(end 93.155008 -49.399952)
		(width 0.3048)
		(layer "F.Cu")
		(net "P1V8_C")
	)
	(segment
		(start 111.549942 -37.399976)
		(end 111.549688 -37.399976)
		(width 0.3556)
		(layer "F.Cu")
		(net "P1V8_C")
	)
	(segment
		(start 219.00388 -87.60333)
		(end 217.19159 -87.60333)
		(width 0.254)
		(layer "F.Cu")
		(net "P1V8_C")
	)
	(segment
		(start 93.150182 -47.800006)
		(end 93.150182 -47.790354)
		(width 0.3556)
		(layer "F.Cu")
		(net "P1V8_C")
	)
	(segment
		(start 93.150182 -54.19979)
		(end 92.750132 -53.79974)
		(width 0.3556)
		(layer "F.Cu")
		(net "P1V8_C")
	)
	(segment
		(start 112.268 -62.0395)
		(end 112.268 -62.057788)
		(width 0.3048)
		(layer "F.Cu")
		(net "P1V8_C")
	)
	(segment
		(start 105.549954 -53.79974)
		(end 105.950004 -54.19979)
		(width 0.3556)
		(layer "F.Cu")
		(net "P1V8_C")
	)
	(segment
		(start 100.4443 -67.4116)
		(end 101.2825 -67.4116)
		(width 0.4572)
		(layer "F.Cu")
		(net "P1V8_C")
	)
	(segment
		(start 110.750096 -42.999914)
		(end 110.750096 -42.99966)
		(width 0.3556)
		(layer "F.Cu")
		(net "P1V8_C")
	)
	(segment
		(start 104.350058 -54.19979)
		(end 104.760268 -54.61)
		(width 0.2032)
		(layer "F.Cu")
		(net "P1V8_C")
	)
	(segment
		(start 93.55836 -48.99152)
		(end 93.55836 -48.9966)
		(width 0.3048)
		(layer "F.Cu")
		(net "P1V8_C")
	)
	(segment
		(start 114.3 -27.8765)
		(end 114.2365 -27.94)
		(width 0.508)
		(layer "F.Cu")
		(net "P1V8_C")
	)
	(segment
		(start 111.549688 -43.800014)
		(end 111.149892 -44.19981)
		(width 0.3556)
		(layer "F.Cu")
		(net "P1V8_C")
	)
	(segment
		(start 216.03716 -87.79764)
		(end 216.03716 -87.90178)
		(width 0.508)
		(layer "F.Cu")
		(net "P1V8_C")
	)
	(segment
		(start 113.665 -29.972)
		(end 114.535966 -29.972)
		(width 0.3048)
		(layer "F.Cu")
		(net "P1V8_C")
	)
	(segment
		(start 249.047 -50.502058)
		(end 249.04446 -50.502058)
		(width 0.508)
		(layer "F.Cu")
		(net "P1V8_C")
	)
	(segment
		(start 216.29878 -87.53602)
		(end 216.03716 -87.79764)
		(width 0.508)
		(layer "F.Cu")
		(net "P1V8_C")
	)
	(segment
		(start 111.549688 -51.799998)
		(end 111.149892 -52.199794)
		(width 0.3556)
		(layer "F.Cu")
		(net "P1V8_C")
	)
	(segment
		(start 104.775 -68.2625)
		(end 104.7115 -68.2625)
		(width 0.381)
		(layer "F.Cu")
		(net "P1V8_C")
	)
	(segment
		(start 251.11964 -50.484278)
		(end 251.328174 -50.692812)
		(width 0.508)
		(layer "F.Cu")
		(net "P1V8_C")
	)
	(segment
		(start 110.750096 -54.19979)
		(end 110.750096 -54.199536)
		(width 0.3556)
		(layer "F.Cu")
		(net "P1V8_C")
	)
	(segment
		(start 217.12428 -87.53602)
		(end 216.29878 -87.53602)
		(width 0.508)
		(layer "F.Cu")
		(net "P1V8_C")
	)
	(segment
		(start 110.750096 -52.599844)
		(end 110.750096 -52.59959)
		(width 0.3556)
		(layer "F.Cu")
		(net "P1V8_C")
	)
	(segment
		(start 119.212106 -42.037)
		(end 119.234966 -42.05986)
		(width 0.508)
		(layer "F.Cu")
		(net "P1V8_C")
	)
	(segment
		(start 111.549688 -45.39996)
		(end 111.149892 -45.799756)
		(width 0.3556)
		(layer "F.Cu")
		(net "P1V8_C")
	)
	(segment
		(start 94.750128 -54.19979)
		(end 94.350078 -53.79974)
		(width 0.3556)
		(layer "F.Cu")
		(net "P1V8_C")
	)
	(segment
		(start 107.54995 -54.19979)
		(end 107.1499 -53.79974)
		(width 0.3556)
		(layer "F.Cu")
		(net "P1V8_C")
	)
	(segment
		(start 118.3005 -50.038)
		(end 120.523 -50.038)
		(width 0.508)
		(layer "F.Cu")
		(net "P1V8_C")
	)
	(segment
		(start 110.750096 -42.99966)
		(end 111.149892 -42.599864)
		(width 0.3556)
		(layer "F.Cu")
		(net "P1V8_C")
	)
	(segment
		(start 114.4905 -29.9085)
		(end 114.535966 -29.953966)
		(width 0.508)
		(layer "F.Cu")
		(net "P1V8_C")
	)
	(segment
		(start 112.268 -62.057788)
		(end 111.379 -62.946788)
		(width 0.3048)
		(layer "F.Cu")
		(net "P1V8_C")
	)
	(segment
		(start 111.549942 -45.39996)
		(end 111.549688 -45.39996)
		(width 0.3556)
		(layer "F.Cu")
		(net "P1V8_C")
	)
	(segment
		(start 223.266 -121.793)
		(end 222.758 -121.793)
		(width 0.508)
		(layer "F.Cu")
		(net "P1V8_C")
	)
	(segment
		(start 109.949996 -35.80003)
		(end 109.95025 -35.80003)
		(width 0.3048)
		(layer "F.Cu")
		(net "P1V8_C")
	)
	(segment
		(start 149.099016 -61.9379)
		(end 150.578566 -61.9379)
		(width 0.254)
		(layer "F.Cu")
		(net "P1V8_C")
	)
	(segment
		(start 93.950028 -51.799998)
		(end 93.949774 -51.799998)
		(width 0.3556)
		(layer "F.Cu")
		(net "P1V8_C")
	)
	(segment
		(start 93.55836 -48.9966)
		(end 93.557344 -48.997616)
		(width 0.3048)
		(layer "F.Cu")
		(net "P1V8_C")
	)
	(segment
		(start 102.750112 -54.19979)
		(end 102.750112 -54.199536)
		(width 0.3556)
		(layer "F.Cu")
		(net "P1V8_C")
	)
	(segment
		(start 93.950028 -48.599852)
		(end 93.55836 -48.99152)
		(width 0.3048)
		(layer "F.Cu")
		(net "P1V8_C")
	)
	(segment
		(start 113.538 -29.845)
		(end 113.665 -29.972)
		(width 0.3048)
		(layer "F.Cu")
		(net "P1V8_C")
	)
	(via
		(at 111.149892 -52.199794)
		(size 0.508)
		(drill 0.254)
		(layers "F.Cu" "B.Cu")
		(net "P1V8_C")
	)
	(via
		(at 108.7501 -53.79974)
		(size 0.508)
		(drill 0.254)
		(layers "F.Cu" "B.Cu")
		(net "P1V8_C")
	)
	(via
		(at 245.364 -53.213)
		(size 0.7112)
		(drill 0.4064)
		(layers "F.Cu" "B.Cu")
		(net "P1V8_C")
	)
	(via
		(at 244.094 -53.975)
		(size 0.7112)
		(drill 0.4064)
		(layers "F.Cu" "B.Cu")
		(net "P1V8_C")
	)
	(via
		(at 222.22714 -91.48064)
		(size 0.5588)
		(drill 0.3048)
		(layers "F.Cu" "B.Cu")
		(net "P1V8_C")
	)
	(via
		(at 107.1499 -53.79974)
		(size 0.508)
		(drill 0.254)
		(layers "F.Cu" "B.Cu")
		(net "P1V8_C")
	)
	(via
		(at 110.217966 -67.1322)
		(size 0.5588)
		(drill 0.3048)
		(layers "F.Cu" "B.Cu")
		(net "P1V8_C")
	)
	(via
		(at 121.393966 -40.132)
		(size 0.5588)
		(drill 0.3048)
		(layers "F.Cu" "B.Cu")
		(net "P1V8_C")
	)
	(via
		(at 121.231914 -37.465)
		(size 0.5588)
		(drill 0.3048)
		(layers "F.Cu" "B.Cu")
		(net "P1V8_C")
	)
	(via
		(at 89.389966 -67.564)
		(size 0.7112)
		(drill 0.4064)
		(layers "F.Cu" "B.Cu")
		(net "P1V8_C")
	)
	(via
		(at 101.549962 -53.79974)
		(size 0.508)
		(drill 0.254)
		(layers "F.Cu" "B.Cu")
		(net "P1V8_C")
	)
	(via
		(at 80.245966 -64.262)
		(size 0.7112)
		(drill 0.4064)
		(layers "F.Cu" "B.Cu")
		(net "P1V8_C")
	)
	(via
		(at 132.061966 -34.417)
		(size 0.7112)
		(drill 0.4064)
		(layers "F.Cu" "B.Cu")
		(net "P1V8_C")
	)
	(via
		(at 119.70766 -30.063694)
		(size 0.5588)
		(drill 0.3048)
		(layers "F.Cu" "B.Cu")
		(net "P1V8_C")
	)
	(via
		(at 115.583716 -45.58665)
		(size 0.5588)
		(drill 0.3048)
		(layers "F.Cu" "B.Cu")
		(net "P1V8_C")
	)
	(via
		(at 102.87 -69.088)
		(size 0.7112)
		(drill 0.3556)
		(layers "F.Cu" "B.Cu")
		(net "P1V8_C")
	)
	(via
		(at 131.064 -34.036)
		(size 0.7112)
		(drill 0.4064)
		(layers "F.Cu" "B.Cu")
		(net "P1V8_C")
	)
	(via
		(at 93.549978 -52.199794)
		(size 0.508)
		(drill 0.254)
		(layers "F.Cu" "B.Cu")
		(net "P1V8_C")
	)
	(via
		(at 66.675 -52.959)
		(size 0.7112)
		(drill 0.4064)
		(layers "F.Cu" "B.Cu")
		(net "P1V8_C")
	)
	(via
		(at 111.149892 -47.399956)
		(size 0.508)
		(drill 0.254)
		(layers "F.Cu" "B.Cu")
		(net "P1V8_C")
	)
	(via
		(at 92.750132 -53.79974)
		(size 0.508)
		(drill 0.254)
		(layers "F.Cu" "B.Cu")
		(net "P1V8_C")
	)
	(via
		(at 92.757498 -47.39767)
		(size 0.508)
		(drill 0.254)
		(layers "F.Cu" "B.Cu")
		(net "P1V8_C")
	)
	(via
		(at 111.149892 -45.799756)
		(size 0.508)
		(drill 0.254)
		(layers "F.Cu" "B.Cu")
		(net "P1V8_C")
	)
	(via
		(at 262.007096 -55.492904)
		(size 0.5588)
		(drill 0.3048)
		(layers "F.Cu" "B.Cu")
		(net "P1V8_C")
	)
	(via
		(at 104.013 -68.961)
		(size 0.508)
		(drill 0.254)
		(layers "F.Cu" "B.Cu")
		(net "P1V8_C")
	)
	(via
		(at 94.350078 -53.79974)
		(size 0.508)
		(drill 0.254)
		(layers "F.Cu" "B.Cu")
		(net "P1V8_C")
	)
	(via
		(at 103.149908 -53.79974)
		(size 0.508)
		(drill 0.254)
		(layers "F.Cu" "B.Cu")
		(net "P1V8_C")
	)
	(via
		(at 106.807 -59.563)
		(size 0.508)
		(drill 0.254)
		(layers "F.Cu" "B.Cu")
		(net "P1V8_C")
	)
	(via
		(at 107.150154 -36.20008)
		(size 0.508)
		(drill 0.254)
		(layers "F.Cu" "B.Cu")
		(net "P1V8_C")
	)
	(via
		(at 119.234966 -43.815)
		(size 0.508)
		(drill 0.254)
		(layers "F.Cu" "B.Cu")
		(net "P1V8_C")
	)
	(via
		(at 66.421 -51.562)
		(size 0.7112)
		(drill 0.3556)
		(layers "F.Cu" "B.Cu")
		(net "P1V8_C")
	)
	(via
		(at 111.149892 -48.999902)
		(size 0.508)
		(drill 0.254)
		(layers "F.Cu" "B.Cu")
		(net "P1V8_C")
	)
	(via
		(at 268.097 -91.44)
		(size 0.508)
		(drill 0.254)
		(layers "F.Cu" "B.Cu")
		(net "P1V8_C")
	)
	(via
		(at 110.3503 -36.20008)
		(size 0.508)
		(drill 0.254)
		(layers "F.Cu" "B.Cu")
		(net "P1V8_C")
	)
	(via
		(at 77.9018 -67.437)
		(size 0.7112)
		(drill 0.3556)
		(layers "F.Cu" "B.Cu")
		(net "P1V8_C")
	)
	(via
		(at 111.149892 -50.599848)
		(size 0.508)
		(drill 0.254)
		(layers "F.Cu" "B.Cu")
		(net "P1V8_C")
	)
	(via
		(at 111.149892 -42.599864)
		(size 0.508)
		(drill 0.254)
		(layers "F.Cu" "B.Cu")
		(net "P1V8_C")
	)
	(via
		(at 93.557344 -48.997616)
		(size 0.508)
		(drill 0.254)
		(layers "F.Cu" "B.Cu")
		(net "P1V8_C")
	)
	(via
		(at 153.543 -56.642)
		(size 0.508)
		(drill 0.254)
		(layers "F.Cu" "B.Cu")
		(net "P1V8_C")
	)
	(via
		(at 185.42 -136.271)
		(size 0.5588)
		(drill 0.3048)
		(layers "F.Cu" "B.Cu")
		(net "P1V8_C")
	)
	(via
		(at 80.245966 -65.405)
		(size 0.7112)
		(drill 0.4064)
		(layers "F.Cu" "B.Cu")
		(net "P1V8_C")
	)
	(via
		(at 107.931966 -67.2338)
		(size 0.5588)
		(drill 0.3048)
		(layers "F.Cu" "B.Cu")
		(net "P1V8_C")
	)
	(via
		(at 153.543 -57.785)
		(size 0.508)
		(drill 0.254)
		(layers "F.Cu" "B.Cu")
		(net "P1V8_C")
	)
	(via
		(at 111.149892 -39.399972)
		(size 0.508)
		(drill 0.254)
		(layers "F.Cu" "B.Cu")
		(net "P1V8_C")
	)
	(via
		(at 108.750354 -36.20008)
		(size 0.508)
		(drill 0.254)
		(layers "F.Cu" "B.Cu")
		(net "P1V8_C")
	)
	(via
		(at 97.54997 -53.79974)
		(size 0.508)
		(drill 0.254)
		(layers "F.Cu" "B.Cu")
		(net "P1V8_C")
	)
	(via
		(at 95.950024 -53.79974)
		(size 0.508)
		(drill 0.254)
		(layers "F.Cu" "B.Cu")
		(net "P1V8_C")
	)
	(via
		(at 111.149892 -40.999918)
		(size 0.508)
		(drill 0.254)
		(layers "F.Cu" "B.Cu")
		(net "P1V8_C")
	)
	(via
		(at 105.550208 -36.20008)
		(size 0.508)
		(drill 0.254)
		(layers "F.Cu" "B.Cu")
		(net "P1V8_C")
	)
	(via
		(at 78.975966 -65.405)
		(size 0.7112)
		(drill 0.4064)
		(layers "F.Cu" "B.Cu")
		(net "P1V8_C")
	)
	(via
		(at 65.786 -53.594)
		(size 0.7112)
		(drill 0.4064)
		(layers "F.Cu" "B.Cu")
		(net "P1V8_C")
	)
	(via
		(at 121.3866 -39.0144)
		(size 0.5588)
		(drill 0.3048)
		(layers "F.Cu" "B.Cu")
		(net "P1V8_C")
	)
	(via
		(at 120.175274 -42.959274)
		(size 0.508)
		(drill 0.254)
		(layers "F.Cu" "B.Cu")
		(net "P1V8_C")
	)
	(via
		(at 249.04446 -50.502058)
		(size 0.5588)
		(drill 0.3048)
		(layers "F.Cu" "B.Cu")
		(net "P1V8_C")
	)
	(via
		(at 93.549978 -50.599594)
		(size 0.508)
		(drill 0.254)
		(layers "F.Cu" "B.Cu")
		(net "P1V8_C")
	)
	(via
		(at 121.266966 -41.275)
		(size 0.508)
		(drill 0.254)
		(layers "F.Cu" "B.Cu")
		(net "P1V8_C")
	)
	(via
		(at 111.149892 -44.19981)
		(size 0.508)
		(drill 0.254)
		(layers "F.Cu" "B.Cu")
		(net "P1V8_C")
	)
	(via
		(at 216.03716 -87.90178)
		(size 0.5588)
		(drill 0.3048)
		(layers "F.Cu" "B.Cu")
		(net "P1V8_C")
	)
	(via
		(at 105.549954 -53.79974)
		(size 0.508)
		(drill 0.254)
		(layers "F.Cu" "B.Cu")
		(net "P1V8_C")
	)
	(via
		(at 120.8786 -44.1452)
		(size 0.7112)
		(drill 0.3556)
		(layers "F.Cu" "B.Cu")
		(net "P1V8_C")
	)
	(via
		(at 97.545144 -48.195738)
		(size 0.508)
		(drill 0.254)
		(layers "F.Cu" "B.Cu")
		(net "P1V8_C")
	)
	(via
		(at 221.107 -113.792)
		(size 0.5588)
		(drill 0.3048)
		(layers "F.Cu" "B.Cu")
		(net "P1V8_C")
	)
	(via
		(at 111.149892 -53.79974)
		(size 0.508)
		(drill 0.254)
		(layers "F.Cu" "B.Cu")
		(net "P1V8_C")
	)
	(via
		(at 111.149892 -37.799772)
		(size 0.508)
		(drill 0.254)
		(layers "F.Cu" "B.Cu")
		(net "P1V8_C")
	)
	(via
		(at 119.234966 -42.05986)
		(size 0.508)
		(drill 0.254)
		(layers "F.Cu" "B.Cu")
		(net "P1V8_C")
	)
	(via
		(at 122.047 -46.1772)
		(size 0.508)
		(drill 0.254)
		(layers "F.Cu" "B.Cu")
		(net "P1V8_C")
	)
	(via
		(at 114.535966 -29.972)
		(size 0.5588)
		(drill 0.3048)
		(layers "F.Cu" "B.Cu")
		(net "P1V8_C")
	)
	(via
		(at 65.786 -52.324)
		(size 0.7112)
		(drill 0.4064)
		(layers "F.Cu" "B.Cu")
		(net "P1V8_C")
	)
	(via
		(at 222.758 -121.793)
		(size 0.5588)
		(drill 0.3048)
		(layers "F.Cu" "B.Cu")
		(net "P1V8_C")
	)
	(via
		(at 111.379 -63.5)
		(size 0.508)
		(drill 0.254)
		(layers "F.Cu" "B.Cu")
		(net "P1V8_C")
	)
	(via
		(at 100.4443 -67.4116)
		(size 0.5588)
		(drill 0.3048)
		(layers "F.Cu" "B.Cu")
		(net "P1V8_C")
	)
	(via
		(at 119.234966 -45.593)
		(size 0.508)
		(drill 0.254)
		(layers "F.Cu" "B.Cu")
		(net "P1V8_C")
	)
	(via
		(at 153.67 -53.213)
		(size 0.508)
		(drill 0.254)
		(layers "F.Cu" "B.Cu")
		(net "P1V8_C")
	)
	(segment
		(start 89.67216 -53.5305)
		(end 88.52916 -53.5305)
		(width 0.508)
		(layer "B.Cu")
		(net "P1V8_C")
	)
	(segment
		(start 221.107 -118.948454)
		(end 221.107 -113.792)
		(width 0.508)
		(layer "B.Cu")
		(net "P1V8_C")
	)
	(segment
		(start 268.097 -91.44)
		(end 267.97 -91.313)
		(width 0.508)
		(layer "B.Cu")
		(net "P1V8_C")
	)
	(segment
		(start 120.885966 -37.465)
		(end 121.231914 -37.465)
		(width 0.508)
		(layer "B.Cu")
		(net "P1V8_C")
	)
	(segment
		(start 101.119686 -54.96052)
		(end 101.119686 -55.057548)
		(width 0.381)
		(layer "B.Cu")
		(net "P1V8_C")
	)
	(segment
		(start 115.780566 -45.7835)
		(end 115.583716 -45.58665)
		(width 0.508)
		(layer "B.Cu")
		(net "P1V8_C")
	)
	(segment
		(start 86.659466 -53.5305)
		(end 87.357966 -53.5305)
		(width 0.508)
		(layer "B.Cu")
		(net "P1V8_C")
	)
	(segment
		(start 91.637866 -53.5305)
		(end 91.648026 -53.54066)
		(width 0.508)
		(layer "B.Cu")
		(net "P1V8_C")
	)
	(segment
		(start 114.218466 -28.829)
		(end 114.535966 -29.1465)
		(width 0.508)
		(layer "B.Cu")
		(net "P1V8_C")
	)
	(segment
		(start 120.504966 -37.846)
		(end 120.885966 -37.465)
		(width 0.508)
		(layer "B.Cu")
		(net "P1V8_C")
	)
	(segment
		(start 92.818966 -54.737)
		(end 92.818966 -53.868574)
		(width 0.508)
		(layer "B.Cu")
		(net "P1V8_C")
	)
	(segment
		(start 85.67166 -50.165)
		(end 85.643466 -50.193194)
		(width 0.508)
		(layer "B.Cu")
		(net "P1V8_C")
	)
	(segment
		(start 105.633266 -54.52872)
		(end 105.297986 -54.864)
		(width 0.3048)
		(layer "B.Cu")
		(net "P1V8_C")
	)
	(segment
		(start 101.424486 -54.65572)
		(end 101.119686 -54.96052)
		(width 0.381)
		(layer "B.Cu")
		(net "P1V8_C")
	)
	(segment
		(start 94.342966 -53.792628)
		(end 94.350078 -53.79974)
		(width 0.508)
		(layer "B.Cu")
		(net "P1V8_C")
	)
	(segment
		(start 105.297986 -54.933088)
		(end 104.775 -55.456074)
		(width 0.3048)
		(layer "B.Cu")
		(net "P1V8_C")
	)
	(segment
		(start 120.4595 -36.6395)
		(end 121.3485 -35.7505)
		(width 0.381)
		(layer "B.Cu")
		(net "P1V8_C")
	)
	(segment
		(start 93.913706 -54.53126)
		(end 94.350078 -54.094888)
		(width 0.508)
		(layer "B.Cu")
		(net "P1V8_C")
	)
	(segment
		(start 111.251746 -52.09794)
		(end 111.149892 -52.199794)
		(width 0.508)
		(layer "B.Cu")
		(net "P1V8_C")
	)
	(segment
		(start 108.750354 -35.524694)
		(end 108.750354 -36.20008)
		(width 0.508)
		(layer "B.Cu")
		(net "P1V8_C")
	)
	(segment
		(start 93.504766 -50.644806)
		(end 93.549978 -50.599594)
		(width 0.508)
		(layer "B.Cu")
		(net "P1V8_C")
	)
	(segment
		(start 104.775 -56.9595)
		(end 104.9655 -57.15)
		(width 0.3048)
		(layer "B.Cu")
		(net "P1V8_C")
	)
	(segment
		(start 121.836942 -47.283116)
		(end 121.8565 -47.302674)
		(width 0.508)
		(layer "B.Cu")
		(net "P1V8_C")
	)
	(segment
		(start 85.67166 -48.034194)
		(end 85.67166 -49.022)
		(width 0.508)
		(layer "B.Cu")
		(net "P1V8_C")
	)
	(segment
		(start 94.350078 -54.094888)
		(end 94.350078 -53.79974)
		(width 0.508)
		(layer "B.Cu")
		(net "P1V8_C")
	)
	(segment
		(start 114.726466 -46.863)
		(end 114.726466 -45.72)
		(width 0.508)
		(layer "B.Cu")
		(net "P1V8_C")
	)
	(segment
		(start 85.643466 -50.193194)
		(end 85.643466 -51.181)
		(width 0.508)
		(layer "B.Cu")
		(net "P1V8_C")
	)
	(segment
		(start 120.441466 -37.846)
		(end 120.504966 -37.846)
		(width 0.508)
		(layer "B.Cu")
		(net "P1V8_C")
	)
	(segment
		(start 224.70618 -90.48242)
		(end 223.70796 -91.48064)
		(width 0.508)
		(layer "B.Cu")
		(net "P1V8_C")
	)
	(segment
		(start 122.047 -46.1772)
		(end 121.836942 -46.387258)
		(width 0.508)
		(layer "B.Cu")
		(net "P1V8_C")
	)
	(segment
		(start 111.170466 -45.0596)
		(end 111.170466 -45.779182)
		(width 0.508)
		(layer "B.Cu")
		(net "P1V8_C")
	)
	(segment
		(start 223.70796 -91.48064)
		(end 222.22714 -91.48064)
		(width 0.508)
		(layer "B.Cu")
		(net "P1V8_C")
	)
	(segment
		(start 222.758 -120.599454)
		(end 221.107 -118.948454)
		(width 0.508)
		(layer "B.Cu")
		(net "P1V8_C")
	)
	(segment
		(start 107.150154 -36.137596)
		(end 107.150154 -36.20008)
		(width 0.508)
		(layer "B.Cu")
		(net "P1V8_C")
	)
	(segment
		(start 108.7501 -53.79974)
		(end 108.818426 -53.731414)
		(width 0.508)
		(layer "B.Cu")
		(net "P1V8_C")
	)
	(segment
		(start 111.149892 -37.799772)
		(end 110.999524 -37.95014)
		(width 0.3556)
		(layer "B.Cu")
		(net "P1V8_C")
	)
	(segment
		(start 114.726466 -45.72)
		(end 114.726466 -44.577)
		(width 0.508)
		(layer "B.Cu")
		(net "P1V8_C")
	)
	(segment
		(start 120.4595 -36.703)
		(end 120.4595 -36.6395)
		(width 0.381)
		(layer "B.Cu")
		(net "P1V8_C")
	)
	(segment
		(start 119.742966 -31.0515)
		(end 119.679466 -30.988)
		(width 0.508)
		(layer "B.Cu")
		(net "P1V8_C")
	)
	(segment
		(start 93.549978 -52.199794)
		(end 92.781882 -52.96789)
		(width 0.508)
		(layer "B.Cu")
		(net "P1V8_C")
	)
	(segment
		(start 111.193326 -41.8719)
		(end 111.193326 -42.55643)
		(width 0.508)
		(layer "B.Cu")
		(net "P1V8_C")
	)
	(segment
		(start 92.818966 -53.868574)
		(end 92.750132 -53.79974)
		(width 0.508)
		(layer "B.Cu")
		(net "P1V8_C")
	)
	(segment
		(start 87.357966 -53.5305)
		(end 87.357966 -54.737)
		(width 0.508)
		(layer "B.Cu")
		(net "P1V8_C")
	)
	(segment
		(start 102.389686 -54.559962)
		(end 103.149908 -53.79974)
		(width 0.3556)
		(layer "B.Cu")
		(net "P1V8_C")
	)
	(segment
		(start 111.157766 -40.28948)
		(end 111.149892 -40.297354)
		(width 0.508)
		(layer "B.Cu")
		(net "P1V8_C")
	)
	(segment
		(start 120.441466 -38.989)
		(end 121.3612 -38.989)
		(width 0.508)
		(layer "B.Cu")
		(net "P1V8_C")
	)
	(segment
		(start 101.549962 -53.79974)
		(end 101.424486 -53.925216)
		(width 0.508)
		(layer "B.Cu")
		(net "P1V8_C")
	)
	(segment
		(start 120.469914 -36.703)
		(end 120.4595 -36.703)
		(width 0.381)
		(layer "B.Cu")
		(net "P1V8_C")
	)
	(segment
		(start 111.399066 -38.53434)
		(end 111.399066 -39.150798)
		(width 0.508)
		(layer "B.Cu")
		(net "P1V8_C")
	)
	(segment
		(start 102.389686 -54.87162)
		(end 102.389686 -54.559962)
		(width 0.3556)
		(layer "B.Cu")
		(net "P1V8_C")
	)
	(segment
		(start 111.249206 -53.700426)
		(end 111.149892 -53.79974)
		(width 0.508)
		(layer "B.Cu")
		(net "P1V8_C")
	)
	(segment
		(start 259.835904 -55.492904)
		(end 262.007096 -55.492904)
		(width 0.635)
		(layer "B.Cu")
		(net "P1V8_C")
	)
	(segment
		(start 88.52916 -53.5305)
		(end 87.38616 -53.5305)
		(width 0.508)
		(layer "B.Cu")
		(net "P1V8_C")
	)
	(segment
		(start 249.04446 -50.502058)
		(end 249.06224 -50.484278)
		(width 0.635)
		(layer "B.Cu")
		(net "P1V8_C")
	)
	(segment
		(start 105.61066 -36.139628)
		(end 105.550208 -36.20008)
		(width 0.508)
		(layer "B.Cu")
		(net "P1V8_C")
	)
	(segment
		(start 267.97 -91.313)
		(end 237.363 -91.313)
		(width 0.508)
		(layer "B.Cu")
		(net "P1V8_C")
	)
	(segment
		(start 119.679466 -30.091888)
		(end 119.679466 -30.988)
		(width 0.508)
		(layer "B.Cu")
		(net "P1V8_C")
	)
	(segment
		(start 109.8804 -39.0652)
		(end 109.5629 -39.3827)
		(width 0.3556)
		(layer "B.Cu")
		(net "P1V8_C")
	)
	(segment
		(start 111.249206 -53.05298)
		(end 111.249206 -53.700426)
		(width 0.508)
		(layer "B.Cu")
		(net "P1V8_C")
	)
	(segment
		(start 92.755466 -50.644806)
		(end 93.504766 -50.644806)
		(width 0.508)
		(layer "B.Cu")
		(net "P1V8_C")
	)
	(segment
		(start 110.43666 -36.11372)
		(end 110.3503 -36.20008)
		(width 0.508)
		(layer "B.Cu")
		(net "P1V8_C")
	)
	(segment
		(start 92.781882 -52.96789)
		(end 92.781882 -53.76799)
		(width 0.508)
		(layer "B.Cu")
		(net "P1V8_C")
	)
	(segment
		(start 111.193326 -42.55643)
		(end 111.149892 -42.599864)
		(width 0.508)
		(layer "B.Cu")
		(net "P1V8_C")
	)
	(segment
		(start 107.312206 -53.962046)
		(end 107.1499 -53.79974)
		(width 0.508)
		(layer "B.Cu")
		(net "P1V8_C")
	)
	(segment
		(start 105.61066 -35.306)
		(end 105.61066 -36.139628)
		(width 0.508)
		(layer "B.Cu")
		(net "P1V8_C")
	)
	(segment
		(start 108.818426 -53.00218)
		(end 108.818426 -52.98186)
		(width 0.508)
		(layer "B.Cu")
		(net "P1V8_C")
	)
	(segment
		(start 95.869506 -53.880258)
		(end 95.950024 -53.79974)
		(width 0.508)
		(layer "B.Cu")
		(net "P1V8_C")
	)
	(segment
		(start 97.898966 -54.79034)
		(end 97.820226 -54.7116)
		(width 0.508)
		(layer "B.Cu")
		(net "P1V8_C")
	)
	(segment
		(start 121.836942 -46.387258)
		(end 121.836942 -47.283116)
		(width 0.508)
		(layer "B.Cu")
		(net "P1V8_C")
	)
	(segment
		(start 111.221266 -47.328582)
		(end 111.149892 -47.399956)
		(width 0.508)
		(layer "B.Cu")
		(net "P1V8_C")
	)
	(segment
		(start 121.864374 -47.310548)
		(end 121.864374 -48.333914)
		(width 0.508)
		(layer "B.Cu")
		(net "P1V8_C")
	)
	(segment
		(start 111.149892 -44.19981)
		(end 111.170466 -44.179236)
		(width 0.508)
		(layer "B.Cu")
		(net "P1V8_C")
	)
	(segment
		(start 87.357966 -53.5305)
		(end 87.38616 -53.5305)
		(width 0.508)
		(layer "B.Cu")
		(net "P1V8_C")
	)
	(segment
		(start 106.62666 -35.614102)
		(end 107.150154 -36.137596)
		(width 0.508)
		(layer "B.Cu")
		(net "P1V8_C")
	)
	(segment
		(start 111.170466 -45.779182)
		(end 111.149892 -45.799756)
		(width 0.508)
		(layer "B.Cu")
		(net "P1V8_C")
	)
	(segment
		(start 121.3485 -35.7505)
		(end 121.3485 -35.56)
		(width 0.381)
		(layer "B.Cu")
		(net "P1V8_C")
	)
	(segment
		(start 121.231914 -37.465)
		(end 120.469914 -36.703)
		(width 0.381)
		(layer "B.Cu")
		(net "P1V8_C")
	)
	(segment
		(start 108.53166 -35.306)
		(end 108.750354 -35.524694)
		(width 0.508)
		(layer "B.Cu")
		(net "P1V8_C")
	)
	(segment
		(start 101.119686 -55.057548)
		(end 100.057966 -56.119268)
		(width 0.381)
		(layer "B.Cu")
		(net "P1V8_C")
	)
	(segment
		(start 115.418616 -45.72)
		(end 115.551966 -45.58665)
		(width 0.508)
		(layer "B.Cu")
		(net "P1V8_C")
	)
	(segment
		(start 111.170466 -48.1965)
		(end 111.170466 -48.979328)
		(width 0.508)
		(layer "B.Cu")
		(net "P1V8_C")
	)
	(segment
		(start 114.535966 -29.972)
		(end 113.48466 -29.972)
		(width 0.508)
		(layer "B.Cu")
		(net "P1V8_C")
	)
	(segment
		(start 117.329966 -45.7835)
		(end 115.780566 -45.7835)
		(width 0.508)
		(layer "B.Cu")
		(net "P1V8_C")
	)
	(segment
		(start 101.424486 -53.925216)
		(end 101.424486 -54.65572)
		(width 0.508)
		(layer "B.Cu")
		(net "P1V8_C")
	)
	(segment
		(start 105.549954 -53.79974)
		(end 105.549954 -54.345586)
		(width 0.508)
		(layer "B.Cu")
		(net "P1V8_C")
	)
	(segment
		(start 106.62666 -35.306)
		(end 106.62666 -35.614102)
		(width 0.508)
		(layer "B.Cu")
		(net "P1V8_C")
	)
	(segment
		(start 119.70766 -30.063694)
		(end 119.679466 -30.091888)
		(width 0.508)
		(layer "B.Cu")
		(net "P1V8_C")
	)
	(segment
		(start 94.7928 -46.55566)
		(end 94.46895 -46.5455)
		(width 0.508)
		(layer "B.Cu")
		(net "P1V8_C")
	)
	(segment
		(start 94.309946 -50.67046)
		(end 93.620844 -50.67046)
		(width 0.508)
		(layer "B.Cu")
		(net "P1V8_C")
	)
	(segment
		(start 254.827278 -50.484278)
		(end 259.835904 -55.492904)
		(width 0.635)
		(layer "B.Cu")
		(net "P1V8_C")
	)
	(segment
		(start 111.297466 -49.784)
		(end 111.297466 -50.452274)
		(width 0.508)
		(layer "B.Cu")
		(net "P1V8_C")
	)
	(segment
		(start 90.68816 -53.5305)
		(end 91.637866 -53.5305)
		(width 0.508)
		(layer "B.Cu")
		(net "P1V8_C")
	)
	(segment
		(start 85.643466 -51.181)
		(end 85.643466 -52.5145)
		(width 0.508)
		(layer "B.Cu")
		(net "P1V8_C")
	)
	(segment
		(start 111.221266 -46.6852)
		(end 111.221266 -47.328582)
		(width 0.508)
		(layer "B.Cu")
		(net "P1V8_C")
	)
	(segment
		(start 109.5629 -39.3827)
		(end 109.20476 -39.3827)
		(width 0.3556)
		(layer "B.Cu")
		(net "P1V8_C")
	)
	(segment
		(start 93.80601 -47.20844)
		(end 92.946728 -47.20844)
		(width 0.508)
		(layer "B.Cu")
		(net "P1V8_C")
	)
	(segment
		(start 94.46895 -46.5455)
		(end 93.80601 -47.20844)
		(width 0.508)
		(layer "B.Cu")
		(net "P1V8_C")
	)
	(segment
		(start 237.363 -91.313)
		(end 236.53242 -90.48242)
		(width 0.508)
		(layer "B.Cu")
		(net "P1V8_C")
	)
	(segment
		(start 91.648026 -53.54066)
		(end 91.907106 -53.79974)
		(width 0.508)
		(layer "B.Cu")
		(net "P1V8_C")
	)
	(segment
		(start 94.294706 -48.74768)
		(end 94.04477 -48.997616)
		(width 0.508)
		(layer "B.Cu")
		(net "P1V8_C")
	)
	(segment
		(start 114.726466 -45.72)
		(end 115.418616 -45.72)
		(width 0.508)
		(layer "B.Cu")
		(net "P1V8_C")
	)
	(segment
		(start 115.551966 -45.58665)
		(end 115.583716 -45.58665)
		(width 0.508)
		(layer "B.Cu")
		(net "P1V8_C")
	)
	(segment
		(start 93.620844 -50.67046)
		(end 93.549978 -50.599594)
		(width 0.508)
		(layer "B.Cu")
		(net "P1V8_C")
	)
	(segment
		(start 92.686886 -47.468282)
		(end 92.757498 -47.39767)
		(width 0.508)
		(layer "B.Cu")
		(net "P1V8_C")
	)
	(segment
		(start 111.031782 -37.681662)
		(end 111.149892 -37.799772)
		(width 0.508)
		(layer "B.Cu")
		(net "P1V8_C")
	)
	(segment
		(start 105.549954 -54.345586)
		(end 105.633266 -54.52872)
		(width 0.508)
		(layer "B.Cu")
		(net "P1V8_C")
	)
	(segment
		(start 95.739966 -53.0225)
		(end 95.739966 -53.589682)
		(width 0.508)
		(layer "B.Cu")
		(net "P1V8_C")
	)
	(segment
		(start 236.53242 -90.48242)
		(end 224.70618 -90.48242)
		(width 0.508)
		(layer "B.Cu")
		(net "P1V8_C")
	)
	(segment
		(start 104.775 -55.456074)
		(end 104.775 -56.9595)
		(width 0.3048)
		(layer "B.Cu")
		(net "P1V8_C")
	)
	(segment
		(start 85.67166 -49.022)
		(end 85.67166 -50.165)
		(width 0.508)
		(layer "B.Cu")
		(net "P1V8_C")
	)
	(segment
		(start 94.342966 -52.6415)
		(end 94.342966 -53.792628)
		(width 0.508)
		(layer "B.Cu")
		(net "P1V8_C")
	)
	(segment
		(start 108.818426 -52.98186)
		(end 108.833666 -52.96662)
		(width 0.508)
		(layer "B.Cu")
		(net "P1V8_C")
	)
	(segment
		(start 94.04477 -48.997616)
		(end 93.557344 -48.997616)
		(width 0.508)
		(layer "B.Cu")
		(net "P1V8_C")
	)
	(segment
		(start 115.742466 -29.972)
		(end 114.535966 -29.972)
		(width 0.508)
		(layer "B.Cu")
		(net "P1V8_C")
	)
	(segment
		(start 107.566206 -54.5211)
		(end 107.312206 -53.962046)
		(width 0.508)
		(layer "B.Cu")
		(net "P1V8_C")
	)
	(segment
		(start 105.297986 -54.864)
		(end 105.297986 -54.933088)
		(width 0.3048)
		(layer "B.Cu")
		(net "P1V8_C")
	)
	(segment
		(start 111.170466 -43.39844)
		(end 111.149892 -43.377866)
		(width 0.508)
		(layer "B.Cu")
		(net "P1V8_C")
	)
	(segment
		(start 119.742966 -32.0675)
		(end 119.742966 -31.0515)
		(width 0.508)
		(layer "B.Cu")
		(net "P1V8_C")
	)
	(segment
		(start 90.659966 -54.8005)
		(end 90.659966 -53.558694)
		(width 0.508)
		(layer "B.Cu")
		(net "P1V8_C")
	)
	(segment
		(start 110.999524 -37.95014)
		(end 110.10646 -37.95014)
		(width 0.3556)
		(layer "B.Cu")
		(net "P1V8_C")
	)
	(segment
		(start 95.739966 -53.589682)
		(end 95.950024 -53.79974)
		(width 0.508)
		(layer "B.Cu")
		(net "P1V8_C")
	)
	(segment
		(start 108.818426 -53.731414)
		(end 108.818426 -53.00218)
		(width 0.508)
		(layer "B.Cu")
		(net "P1V8_C")
	)
	(segment
		(start 85.643466 -48.006)
		(end 85.67166 -48.034194)
		(width 0.508)
		(layer "B.Cu")
		(net "P1V8_C")
	)
	(segment
		(start 121.3612 -38.989)
		(end 121.3866 -39.0144)
		(width 0.508)
		(layer "B.Cu")
		(net "P1V8_C")
	)
	(segment
		(start 97.898966 -55.8165)
		(end 97.898966 -54.79034)
		(width 0.508)
		(layer "B.Cu")
		(net "P1V8_C")
	)
	(segment
		(start 249.06224 -50.484278)
		(end 254.827278 -50.484278)
		(width 0.635)
		(layer "B.Cu")
		(net "P1V8_C")
	)
	(segment
		(start 110.43666 -35.306)
		(end 110.43666 -36.11372)
		(width 0.508)
		(layer "B.Cu")
		(net "P1V8_C")
	)
	(segment
		(start 111.251746 -51.42992)
		(end 111.251746 -52.09794)
		(width 0.508)
		(layer "B.Cu")
		(net "P1V8_C")
	)
	(segment
		(start 121.8565 -47.302674)
		(end 121.864374 -47.310548)
		(width 0.508)
		(layer "B.Cu")
		(net "P1V8_C")
	)
	(segment
		(start 97.820226 -54.069996)
		(end 97.820226 -54.7116)
		(width 0.508)
		(layer "B.Cu")
		(net "P1V8_C")
	)
	(segment
		(start 96.730566 -48.6029)
		(end 97.137982 -48.6029)
		(width 0.3556)
		(layer "B.Cu")
		(net "P1V8_C")
	)
	(segment
		(start 108.833666 -52.96662)
		(end 108.833666 -52.1208)
		(width 0.508)
		(layer "B.Cu")
		(net "P1V8_C")
	)
	(segment
		(start 92.781882 -53.76799)
		(end 92.750132 -53.79974)
		(width 0.508)
		(layer "B.Cu")
		(net "P1V8_C")
	)
	(segment
		(start 111.031782 -37.008054)
		(end 111.031782 -37.681662)
		(width 0.508)
		(layer "B.Cu")
		(net "P1V8_C")
	)
	(segment
		(start 90.659966 -53.558694)
		(end 90.68816 -53.5305)
		(width 0.508)
		(layer "B.Cu")
		(net "P1V8_C")
	)
	(segment
		(start 111.170466 -48.979328)
		(end 111.149892 -48.999902)
		(width 0.508)
		(layer "B.Cu")
		(net "P1V8_C")
	)
	(segment
		(start 111.149892 -43.377866)
		(end 111.149892 -42.599864)
		(width 0.508)
		(layer "B.Cu")
		(net "P1V8_C")
	)
	(segment
		(start 85.643466 -52.5145)
		(end 86.659466 -53.5305)
		(width 0.508)
		(layer "B.Cu")
		(net "P1V8_C")
	)
	(segment
		(start 222.758 -121.793)
		(end 222.758 -120.599454)
		(width 0.508)
		(layer "B.Cu")
		(net "P1V8_C")
	)
	(segment
		(start 110.10646 -37.95014)
		(end 109.8804 -38.1762)
		(width 0.3556)
		(layer "B.Cu")
		(net "P1V8_C")
	)
	(segment
		(start 100.057966 -56.119268)
		(end 100.057966 -56.1975)
		(width 0.381)
		(layer "B.Cu")
		(net "P1V8_C")
	)
	(segment
		(start 111.297466 -50.452274)
		(end 111.149892 -50.599848)
		(width 0.508)
		(layer "B.Cu")
		(net "P1V8_C")
	)
	(segment
		(start 90.68816 -53.5305)
		(end 89.67216 -53.5305)
		(width 0.508)
		(layer "B.Cu")
		(net "P1V8_C")
	)
	(segment
		(start 111.399066 -39.150798)
		(end 111.149892 -39.399972)
		(width 0.508)
		(layer "B.Cu")
		(net "P1V8_C")
	)
	(segment
		(start 97.137982 -48.6029)
		(end 97.545144 -48.195738)
		(width 0.3556)
		(layer "B.Cu")
		(net "P1V8_C")
	)
	(segment
		(start 91.907106 -53.79974)
		(end 92.750132 -53.79974)
		(width 0.508)
		(layer "B.Cu")
		(net "P1V8_C")
	)
	(segment
		(start 93.913706 -54.71668)
		(end 93.913706 -54.53126)
		(width 0.508)
		(layer "B.Cu")
		(net "P1V8_C")
	)
	(segment
		(start 114.535966 -29.1465)
		(end 114.535966 -29.972)
		(width 0.508)
		(layer "B.Cu")
		(net "P1V8_C")
	)
	(segment
		(start 95.869506 -54.70906)
		(end 95.869506 -53.880258)
		(width 0.508)
		(layer "B.Cu")
		(net "P1V8_C")
	)
	(segment
		(start 111.149892 -40.297354)
		(end 111.149892 -40.999918)
		(width 0.508)
		(layer "B.Cu")
		(net "P1V8_C")
	)
	(segment
		(start 111.170466 -44.179236)
		(end 111.170466 -43.39844)
		(width 0.508)
		(layer "B.Cu")
		(net "P1V8_C")
	)
	(segment
		(start 97.54997 -53.79974)
		(end 97.820226 -54.069996)
		(width 0.508)
		(layer "B.Cu")
		(net "P1V8_C")
	)
	(segment
		(start 109.8804 -38.1762)
		(end 109.8804 -39.0652)
		(width 0.3556)
		(layer "B.Cu")
		(net "P1V8_C")
	)
	(segment
		(start 92.686886 -48.302926)
		(end 92.686886 -47.468282)
		(width 0.508)
		(layer "B.Cu")
		(net "P1V8_C")
	)
	(segment
		(start 92.946728 -47.20844)
		(end 92.757498 -47.39767)
		(width 0.508)
		(layer "B.Cu")
		(net "P1V8_C")
	)
	(segment
		(start 216.3953 -88.25992)
		(end 216.03716 -87.90178)
		(width 0.508)
		(layer "In2.Cu")
		(net "P1V8_C")
	)
	(segment
		(start 192.222374 -122.936)
		(end 185.42 -129.738374)
		(width 0.508)
		(layer "In2.Cu")
		(net "P1V8_C")
	)
	(segment
		(start 197.739 -122.936)
		(end 192.222374 -122.936)
		(width 0.508)
		(layer "In2.Cu")
		(net "P1V8_C")
	)
	(segment
		(start 202.438 -123.317)
		(end 201.041 -121.92)
		(width 0.508)
		(layer "In2.Cu")
		(net "P1V8_C")
	)
	(segment
		(start 198.755 -121.92)
		(end 197.739 -122.936)
		(width 0.508)
		(layer "In2.Cu")
		(net "P1V8_C")
	)
	(segment
		(start 220.4212 -113.1062)
		(end 221.107 -113.792)
		(width 0.508)
		(layer "In2.Cu")
		(net "P1V8_C")
	)
	(segment
		(start 222.504 -121.539)
		(end 212.344 -121.539)
		(width 0.508)
		(layer "In2.Cu")
		(net "P1V8_C")
	)
	(segment
		(start 222.22714 -91.48064)
		(end 220.42628 -91.48064)
		(width 0.508)
		(layer "In2.Cu")
		(net "P1V8_C")
	)
	(segment
		(start 267.462 -83.439)
		(end 259.969 -75.946)
		(width 0.508)
		(layer "In2.Cu")
		(net "P1V8_C")
	)
	(segment
		(start 267.462 -90.297)
		(end 267.462 -83.439)
		(width 0.508)
		(layer "In2.Cu")
		(net "P1V8_C")
	)
	(segment
		(start 217.20556 -88.25992)
		(end 216.3953 -88.25992)
		(width 0.508)
		(layer "In2.Cu")
		(net "P1V8_C")
	)
	(segment
		(start 268.097 -91.44)
		(end 268.097 -90.932)
		(width 0.508)
		(layer "In2.Cu")
		(net "P1V8_C")
	)
	(segment
		(start 222.758 -121.793)
		(end 222.504 -121.539)
		(width 0.508)
		(layer "In2.Cu")
		(net "P1V8_C")
	)
	(segment
		(start 259.969 -75.946)
		(end 259.969 -57.531)
		(width 0.508)
		(layer "In2.Cu")
		(net "P1V8_C")
	)
	(segment
		(start 201.041 -121.92)
		(end 198.755 -121.92)
		(width 0.508)
		(layer "In2.Cu")
		(net "P1V8_C")
	)
	(segment
		(start 222.22714 -91.48064)
		(end 222.22714 -93.30436)
		(width 0.508)
		(layer "In2.Cu")
		(net "P1V8_C")
	)
	(segment
		(start 220.42628 -91.48064)
		(end 217.20556 -88.25992)
		(width 0.508)
		(layer "In2.Cu")
		(net "P1V8_C")
	)
	(segment
		(start 268.097 -90.932)
		(end 267.462 -90.297)
		(width 0.508)
		(layer "In2.Cu")
		(net "P1V8_C")
	)
	(segment
		(start 185.42 -129.738374)
		(end 185.42 -136.271)
		(width 0.508)
		(layer "In2.Cu")
		(net "P1V8_C")
	)
	(segment
		(start 222.22714 -93.30436)
		(end 220.4212 -95.1103)
		(width 0.508)
		(layer "In2.Cu")
		(net "P1V8_C")
	)
	(segment
		(start 212.344 -121.539)
		(end 210.566 -123.317)
		(width 0.508)
		(layer "In2.Cu")
		(net "P1V8_C")
	)
	(segment
		(start 210.566 -123.317)
		(end 202.438 -123.317)
		(width 0.508)
		(layer "In2.Cu")
		(net "P1V8_C")
	)
	(segment
		(start 259.969 -57.531)
		(end 262.007096 -55.492904)
		(width 0.508)
		(layer "In2.Cu")
		(net "P1V8_C")
	)
	(segment
		(start 220.4212 -95.1103)
		(end 220.4212 -113.1062)
		(width 0.508)
		(layer "In2.Cu")
		(net "P1V8_C")
	)
	(segment
		(start 138.450066 -73.75017)
		(end 138.450066 -74.652378)
		(width 0.508)
		(layer "F.Cu")
		(net "P12V_MSB")
	)
	(segment
		(start 222.74276 -80.5815)
		(end 222.97644 -80.34782)
		(width 0.508)
		(layer "F.Cu")
		(net "P12V_MSB")
	)
	(segment
		(start 139.449556 -75.75042)
		(end 139.449556 -76.652628)
		(width 0.508)
		(layer "F.Cu")
		(net "P12V_MSB")
	)
	(segment
		(start 138.547348 -75.75042)
		(end 139.449556 -75.75042)
		(width 0.508)
		(layer "F.Cu")
		(net "P12V_MSB")
	)
	(segment
		(start 222.504 -83.82)
		(end 222.74276 -83.58124)
		(width 0.508)
		(layer "F.Cu")
		(net "P12V_MSB")
	)
	(segment
		(start 139.449556 -75.75042)
		(end 140.351764 -75.75042)
		(width 0.508)
		(layer "F.Cu")
		(net "P12V_MSB")
	)
	(segment
		(start 138.450066 -72.847962)
		(end 138.450066 -73.75017)
		(width 0.508)
		(layer "F.Cu")
		(net "P12V_MSB")
	)
	(segment
		(start 137.547858 -73.75017)
		(end 138.450066 -73.75017)
		(width 0.508)
		(layer "F.Cu")
		(net "P12V_MSB")
	)
	(segment
		(start 222.74276 -83.58124)
		(end 222.74276 -80.5815)
		(width 0.508)
		(layer "F.Cu")
		(net "P12V_MSB")
	)
	(segment
		(start 138.450066 -73.75017)
		(end 139.352274 -73.75017)
		(width 0.508)
		(layer "F.Cu")
		(net "P12V_MSB")
	)
	(segment
		(start 139.449556 -74.848212)
		(end 139.449556 -75.75042)
		(width 0.508)
		(layer "F.Cu")
		(net "P12V_MSB")
	)
	(via
		(at 148.844 -66.675)
		(size 0.7112)
		(drill 0.4064)
		(layers "F.Cu" "B.Cu")
		(net "P12V_MSB")
	)
	(via
		(at 151.257 -64.389)
		(size 0.7112)
		(drill 0.4064)
		(layers "F.Cu" "B.Cu")
		(net "P12V_MSB")
	)
	(via
		(at 222.377 -73.787)
		(size 0.7112)
		(drill 0.4064)
		(layers "F.Cu" "B.Cu")
		(net "P12V_MSB")
	)
	(via
		(at 151.257 -65.532)
		(size 0.7112)
		(drill 0.4064)
		(layers "F.Cu" "B.Cu")
		(net "P12V_MSB")
	)
	(via
		(at 264.0838 -74.7268)
		(size 0.7112)
		(drill 0.4064)
		(layers "F.Cu" "B.Cu")
		(net "P12V_MSB")
	)
	(via
		(at 265.684 -73.66)
		(size 0.7112)
		(drill 0.4064)
		(layers "F.Cu" "B.Cu")
		(net "P12V_MSB")
	)
	(via
		(at 150.114 -65.532)
		(size 0.7112)
		(drill 0.4064)
		(layers "F.Cu" "B.Cu")
		(net "P12V_MSB")
	)
	(via
		(at 223.139 -74.721212)
		(size 0.7112)
		(drill 0.4064)
		(layers "F.Cu" "B.Cu")
		(net "P12V_MSB")
	)
	(via
		(at 150.114 -64.389)
		(size 0.7112)
		(drill 0.4064)
		(layers "F.Cu" "B.Cu")
		(net "P12V_MSB")
	)
	(via
		(at 262.4328 -74.7268)
		(size 0.7112)
		(drill 0.4064)
		(layers "F.Cu" "B.Cu")
		(net "P12V_MSB")
	)
	(via
		(at 264.414 -70.104)
		(size 0.7112)
		(drill 0.3556)
		(layers "F.Cu" "B.Cu")
		(net "P12V_MSB")
	)
	(via
		(at 148.844 -67.818)
		(size 0.7112)
		(drill 0.4064)
		(layers "F.Cu" "B.Cu")
		(net "P12V_MSB")
	)
	(via
		(at 264.033 -73.66)
		(size 0.7112)
		(drill 0.4064)
		(layers "F.Cu" "B.Cu")
		(net "P12V_MSB")
	)
	(via
		(at 262.382 -73.66)
		(size 0.7112)
		(drill 0.4064)
		(layers "F.Cu" "B.Cu")
		(net "P12V_MSB")
	)
	(via
		(at 222.97644 -80.34782)
		(size 0.5588)
		(drill 0.3048)
		(layers "F.Cu" "B.Cu")
		(net "P12V_MSB")
	)
	(via
		(at 150.114 -66.675)
		(size 0.7112)
		(drill 0.4064)
		(layers "F.Cu" "B.Cu")
		(net "P12V_MSB")
	)
	(via
		(at 261.0358 -74.7268)
		(size 0.7112)
		(drill 0.4064)
		(layers "F.Cu" "B.Cu")
		(net "P12V_MSB")
	)
	(via
		(at 260.985 -73.66)
		(size 0.7112)
		(drill 0.4064)
		(layers "F.Cu" "B.Cu")
		(net "P12V_MSB")
	)
	(via
		(at 223.452944 -73.66)
		(size 0.7112)
		(drill 0.4064)
		(layers "F.Cu" "B.Cu")
		(net "P12V_MSB")
	)
	(via
		(at 265.7348 -74.7268)
		(size 0.7112)
		(drill 0.4064)
		(layers "F.Cu" "B.Cu")
		(net "P12V_MSB")
	)
	(segment
		(start 221.449646 -78.24978)
		(end 222.351854 -78.24978)
		(width 0.508)
		(layer "B.Cu")
		(net "P12V_MSB")
	)
	(segment
		(start 219.449396 -78.24978)
		(end 219.449396 -79.151988)
		(width 0.508)
		(layer "B.Cu")
		(net "P12V_MSB")
	)
	(segment
		(start 219.547948 -73.75017)
		(end 220.450156 -73.75017)
		(width 0.508)
		(layer "B.Cu")
		(net "P12V_MSB")
	)
	(segment
		(start 219.449396 -74.848212)
		(end 219.449396 -75.75042)
		(width 0.508)
		(layer "B.Cu")
		(net "P12V_MSB")
	)
	(segment
		(start 220.450156 -72.847962)
		(end 220.450156 -73.75017)
		(width 0.508)
		(layer "B.Cu")
		(net "P12V_MSB")
	)
	(segment
		(start 220.450156 -73.75017)
		(end 220.450156 -74.652378)
		(width 0.508)
		(layer "B.Cu")
		(net "P12V_MSB")
	)
	(segment
		(start 220.450156 -73.75017)
		(end 221.352364 -73.75017)
		(width 0.508)
		(layer "B.Cu")
		(net "P12V_MSB")
	)
	(segment
		(start 220.450156 -79.347822)
		(end 220.450156 -80.25003)
		(width 0.508)
		(layer "B.Cu")
		(net "P12V_MSB")
	)
	(segment
		(start 221.449646 -78.24978)
		(end 221.449646 -79.151988)
		(width 0.508)
		(layer "B.Cu")
		(net "P12V_MSB")
	)
	(segment
		(start 219.449396 -75.75042)
		(end 219.449396 -76.652628)
		(width 0.508)
		(layer "B.Cu")
		(net "P12V_MSB")
	)
	(segment
		(start 218.547188 -78.24978)
		(end 219.449396 -78.24978)
		(width 0.508)
		(layer "B.Cu")
		(net "P12V_MSB")
	)
	(segment
		(start 221.449646 -77.347572)
		(end 221.449646 -78.24978)
		(width 0.508)
		(layer "B.Cu")
		(net "P12V_MSB")
	)
	(segment
		(start 219.449396 -77.347572)
		(end 219.449396 -78.24978)
		(width 0.508)
		(layer "B.Cu")
		(net "P12V_MSB")
	)
	(segment
		(start 219.547948 -80.25003)
		(end 220.450156 -80.25003)
		(width 0.508)
		(layer "B.Cu")
		(net "P12V_MSB")
	)
	(segment
		(start 219.449396 -78.24978)
		(end 220.351604 -78.24978)
		(width 0.508)
		(layer "B.Cu")
		(net "P12V_MSB")
	)
	(segment
		(start 220.450156 -80.25003)
		(end 220.450156 -81.152238)
		(width 0.508)
		(layer "B.Cu")
		(net "P12V_MSB")
	)
	(segment
		(start 220.547438 -78.24978)
		(end 221.449646 -78.24978)
		(width 0.508)
		(layer "B.Cu")
		(net "P12V_MSB")
	)
	(segment
		(start 220.450156 -80.25003)
		(end 221.352364 -80.25003)
		(width 0.508)
		(layer "B.Cu")
		(net "P12V_MSB")
	)
	(segment
		(start 218.547188 -75.75042)
		(end 219.449396 -75.75042)
		(width 0.508)
		(layer "B.Cu")
		(net "P12V_MSB")
	)
	(segment
		(start 219.449396 -75.75042)
		(end 220.351604 -75.75042)
		(width 0.508)
		(layer "B.Cu")
		(net "P12V_MSB")
	)
	(segment
		(start 219.449396 -75.75042)
		(end 219.449396 -76.652628)
		(width 0.508)
		(layer "In2.Cu")
		(net "P12V_MSB")
	)
	(segment
		(start 219.449396 -77.347572)
		(end 219.449396 -78.24978)
		(width 0.508)
		(layer "In2.Cu")
		(net "P12V_MSB")
	)
	(segment
		(start 221.449646 -78.24978)
		(end 222.351854 -78.24978)
		(width 0.508)
		(layer "In2.Cu")
		(net "P12V_MSB")
	)
	(segment
		(start 219.547948 -73.75017)
		(end 220.450156 -73.75017)
		(width 0.508)
		(layer "In2.Cu")
		(net "P12V_MSB")
	)
	(segment
		(start 219.449396 -74.848212)
		(end 219.449396 -75.75042)
		(width 0.508)
		(layer "In2.Cu")
		(net "P12V_MSB")
	)
	(segment
		(start 219.449396 -78.24978)
		(end 220.351604 -78.24978)
		(width 0.508)
		(layer "In2.Cu")
		(net "P12V_MSB")
	)
	(segment
		(start 221.449646 -77.347572)
		(end 221.449646 -78.24978)
		(width 0.508)
		(layer "In2.Cu")
		(net "P12V_MSB")
	)
	(segment
		(start 220.450156 -80.25003)
		(end 220.450156 -81.152238)
		(width 0.508)
		(layer "In2.Cu")
		(net "P12V_MSB")
	)
	(segment
		(start 219.449396 -75.75042)
		(end 220.351604 -75.75042)
		(width 0.508)
		(layer "In2.Cu")
		(net "P12V_MSB")
	)
	(segment
		(start 220.450156 -73.75017)
		(end 221.352364 -73.75017)
		(width 0.508)
		(layer "In2.Cu")
		(net "P12V_MSB")
	)
	(segment
		(start 219.449396 -78.24978)
		(end 219.449396 -79.151988)
		(width 0.508)
		(layer "In2.Cu")
		(net "P12V_MSB")
	)
	(segment
		(start 220.450156 -80.25003)
		(end 221.352364 -80.25003)
		(width 0.508)
		(layer "In2.Cu")
		(net "P12V_MSB")
	)
	(segment
		(start 220.547438 -78.24978)
		(end 221.449646 -78.24978)
		(width 0.508)
		(layer "In2.Cu")
		(net "P12V_MSB")
	)
	(segment
		(start 220.450156 -73.75017)
		(end 220.450156 -74.652378)
		(width 0.508)
		(layer "In2.Cu")
		(net "P12V_MSB")
	)
	(segment
		(start 221.449646 -78.24978)
		(end 221.449646 -79.151988)
		(width 0.508)
		(layer "In2.Cu")
		(net "P12V_MSB")
	)
	(segment
		(start 218.547188 -75.75042)
		(end 219.449396 -75.75042)
		(width 0.508)
		(layer "In2.Cu")
		(net "P12V_MSB")
	)
	(segment
		(start 220.450156 -72.847962)
		(end 220.450156 -73.75017)
		(width 0.508)
		(layer "In2.Cu")
		(net "P12V_MSB")
	)
	(segment
		(start 219.547948 -80.25003)
		(end 220.450156 -80.25003)
		(width 0.508)
		(layer "In2.Cu")
		(net "P12V_MSB")
	)
	(segment
		(start 220.450156 -79.347822)
		(end 220.450156 -80.25003)
		(width 0.508)
		(layer "In2.Cu")
		(net "P12V_MSB")
	)
	(segment
		(start 218.547188 -78.24978)
		(end 219.449396 -78.24978)
		(width 0.508)
		(layer "In2.Cu")
		(net "P12V_MSB")
	)
	(segment
		(start 277.495 -116.2685)
		(end 277.495 -117.221)
		(width 0.1143)
		(layer "F.Cu")
		(net "BMC_1V8_C_EN")
	)
	(via
		(at 254.635 -165.862)
		(size 0.508)
		(drill 0.254)
		(layers "F.Cu" "B.Cu")
		(net "BMC_1V8_C_EN")
	)
	(via
		(at 261.493 -165.862)
		(size 0.7112)
		(drill 0.3556)
		(layers "F.Cu" "B.Cu")
		(net "BMC_1V8_C_EN")
	)
	(via
		(at 277.495 -117.221)
		(size 0.5588)
		(drill 0.3048)
		(layers "F.Cu" "B.Cu")
		(net "BMC_1V8_C_EN")
	)
	(segment
		(start 265.447272 -164.1475)
		(end 263.9695 -164.1475)
		(width 0.1143)
		(layer "B.Cu")
		(net "BMC_1V8_C_EN")
	)
	(segment
		(start 274.403566 -164.485066)
		(end 265.784838 -164.485066)
		(width 0.1143)
		(layer "B.Cu")
		(net "BMC_1V8_C_EN")
	)
	(segment
		(start 254.635 -165.862)
		(end 261.493 -165.862)
		(width 0.1143)
		(layer "B.Cu")
		(net "BMC_1V8_C_EN")
	)
	(segment
		(start 276.2885 -166.37)
		(end 274.403566 -164.485066)
		(width 0.1143)
		(layer "B.Cu")
		(net "BMC_1V8_C_EN")
	)
	(segment
		(start 263.9695 -164.1475)
		(end 262.255 -165.862)
		(width 0.1143)
		(layer "B.Cu")
		(net "BMC_1V8_C_EN")
	)
	(segment
		(start 265.784838 -164.485066)
		(end 265.447272 -164.1475)
		(width 0.1143)
		(layer "B.Cu")
		(net "BMC_1V8_C_EN")
	)
	(segment
		(start 262.255 -165.862)
		(end 261.493 -165.862)
		(width 0.1143)
		(layer "B.Cu")
		(net "BMC_1V8_C_EN")
	)
	(segment
		(start 254.635 -159.258)
		(end 252.095 -156.718)
		(width 0.127)
		(layer "In5.Cu")
		(net "BMC_1V8_C_EN")
	)
	(segment
		(start 252.095 -135.763)
		(end 251.3838 -135.0518)
		(width 0.127)
		(layer "In5.Cu")
		(net "BMC_1V8_C_EN")
	)
	(segment
		(start 251.902468 -127.762)
		(end 266.954 -127.762)
		(width 0.127)
		(layer "In5.Cu")
		(net "BMC_1V8_C_EN")
	)
	(segment
		(start 251.3838 -128.280668)
		(end 251.902468 -127.762)
		(width 0.127)
		(layer "In5.Cu")
		(net "BMC_1V8_C_EN")
	)
	(segment
		(start 254.635 -165.862)
		(end 254.635 -159.258)
		(width 0.127)
		(layer "In5.Cu")
		(net "BMC_1V8_C_EN")
	)
	(segment
		(start 251.3838 -135.0518)
		(end 251.3838 -128.280668)
		(width 0.127)
		(layer "In5.Cu")
		(net "BMC_1V8_C_EN")
	)
	(segment
		(start 266.954 -127.762)
		(end 277.495 -117.221)
		(width 0.127)
		(layer "In5.Cu")
		(net "BMC_1V8_C_EN")
	)
	(segment
		(start 252.095 -156.718)
		(end 252.095 -135.763)
		(width 0.127)
		(layer "In5.Cu")
		(net "BMC_1V8_C_EN")
	)
	(segment
		(start 88.9635 -225.552)
		(end 84.919566 -225.552)
		(width 0.1143)
		(layer "F.Cu")
		(net "HDD_LED_RESET_N")
	)
	(segment
		(start 84.54136 -137.1854)
		(end 84.54136 -138.88339)
		(width 0.1143)
		(layer "F.Cu")
		(net "HDD_LED_RESET_N")
	)
	(segment
		(start 84.54136 -138.88339)
		(end 84.97697 -139.319)
		(width 0.1143)
		(layer "F.Cu")
		(net "HDD_LED_RESET_N")
	)
	(segment
		(start 89.2175 -225.806)
		(end 88.9635 -225.552)
		(width 0.1143)
		(layer "F.Cu")
		(net "HDD_LED_RESET_N")
	)
	(segment
		(start 84.919566 -225.552)
		(end 84.284566 -224.917)
		(width 0.1143)
		(layer "F.Cu")
		(net "HDD_LED_RESET_N")
	)
	(segment
		(start 85.35797 -139.7)
		(end 84.97697 -139.319)
		(width 0.1143)
		(layer "F.Cu")
		(net "HDD_LED_RESET_N")
	)
	(segment
		(start 85.35797 -140.208)
		(end 85.35797 -139.7)
		(width 0.1143)
		(layer "F.Cu")
		(net "HDD_LED_RESET_N")
	)
	(via
		(at 84.284566 -224.917)
		(size 0.5588)
		(drill 0.3048)
		(layers "F.Cu" "B.Cu")
		(net "HDD_LED_RESET_N")
	)
	(via
		(at 85.35797 -140.208)
		(size 0.7112)
		(drill 0.3556)
		(layers "F.Cu" "B.Cu")
		(net "HDD_LED_RESET_N")
	)
	(via
		(at 40.005 -220.345)
		(size 0.5588)
		(drill 0.3048)
		(layers "F.Cu" "B.Cu")
		(net "HDD_LED_RESET_N")
	)
	(via
		(at 84.97697 -139.319)
		(size 0.5588)
		(drill 0.3048)
		(layers "F.Cu" "B.Cu")
		(net "HDD_LED_RESET_N")
	)
	(segment
		(start 40.132 -220.218)
		(end 40.132 -207.137)
		(width 0.1143)
		(layer "B.Cu")
		(net "HDD_LED_RESET_N")
	)
	(segment
		(start 66.5861 -170.965368)
		(end 66.5861 -166.489126)
		(width 0.1143)
		(layer "B.Cu")
		(net "HDD_LED_RESET_N")
	)
	(segment
		(start 59.891168 -177.6603)
		(end 66.5861 -170.965368)
		(width 0.1143)
		(layer "B.Cu")
		(net "HDD_LED_RESET_N")
	)
	(segment
		(start 83.268566 -149.80666)
		(end 83.268566 -146.093434)
		(width 0.1143)
		(layer "B.Cu")
		(net "HDD_LED_RESET_N")
	)
	(segment
		(start 83.268566 -146.093434)
		(end 84.97697 -144.38503)
		(width 0.1143)
		(layer "B.Cu")
		(net "HDD_LED_RESET_N")
	)
	(segment
		(start 40.132 -207.137)
		(end 41.402 -205.867)
		(width 0.1143)
		(layer "B.Cu")
		(net "HDD_LED_RESET_N")
	)
	(segment
		(start 51.996594 -177.6603)
		(end 59.891168 -177.6603)
		(width 0.1143)
		(layer "B.Cu")
		(net "HDD_LED_RESET_N")
	)
	(segment
		(start 40.005 -220.345)
		(end 40.132 -220.218)
		(width 0.1143)
		(layer "B.Cu")
		(net "HDD_LED_RESET_N")
	)
	(segment
		(start 41.402 -205.867)
		(end 41.402 -188.254894)
		(width 0.1143)
		(layer "B.Cu")
		(net "HDD_LED_RESET_N")
	)
	(segment
		(start 41.402 -188.254894)
		(end 51.996594 -177.6603)
		(width 0.1143)
		(layer "B.Cu")
		(net "HDD_LED_RESET_N")
	)
	(segment
		(start 84.97697 -144.38503)
		(end 84.97697 -139.319)
		(width 0.1143)
		(layer "B.Cu")
		(net "HDD_LED_RESET_N")
	)
	(segment
		(start 66.5861 -166.489126)
		(end 83.268566 -149.80666)
		(width 0.1143)
		(layer "B.Cu")
		(net "HDD_LED_RESET_N")
	)
	(segment
		(start 41.148 -221.488)
		(end 55.0926 -221.488)
		(width 0.127)
		(layer "In2.Cu")
		(net "HDD_LED_RESET_N")
	)
	(segment
		(start 83.395566 -224.917)
		(end 84.284566 -224.917)
		(width 0.127)
		(layer "In2.Cu")
		(net "HDD_LED_RESET_N")
	)
	(segment
		(start 55.0926 -221.488)
		(end 55.2323 -221.6277)
		(width 0.127)
		(layer "In2.Cu")
		(net "HDD_LED_RESET_N")
	)
	(segment
		(start 55.2323 -221.6277)
		(end 80.106266 -221.6277)
		(width 0.127)
		(layer "In2.Cu")
		(net "HDD_LED_RESET_N")
	)
	(segment
		(start 40.005 -220.345)
		(end 41.148 -221.488)
		(width 0.127)
		(layer "In2.Cu")
		(net "HDD_LED_RESET_N")
	)
	(segment
		(start 80.106266 -221.6277)
		(end 83.395566 -224.917)
		(width 0.127)
		(layer "In2.Cu")
		(net "HDD_LED_RESET_N")
	)
	(segment
		(start 84.14258 -137.1854)
		(end 84.14258 -139.082272)
		(width 0.1143)
		(layer "F.Cu")
		(net "HDD_PWR_RESET_N")
	)
	(segment
		(start 84.14258 -139.082272)
		(end 84.14512 -139.084812)
		(width 0.1143)
		(layer "F.Cu")
		(net "HDD_PWR_RESET_N")
	)
	(segment
		(start 84.14512 -139.084812)
		(end 84.14512 -139.363704)
		(width 0.1143)
		(layer "F.Cu")
		(net "HDD_PWR_RESET_N")
	)
	(segment
		(start 21.392134 -212.541866)
		(end 21.392134 -212.363812)
		(width 0.1143)
		(layer "F.Cu")
		(net "HDD_PWR_RESET_N")
	)
	(segment
		(start 84.14512 -139.363704)
		(end 84.59597 -139.814554)
		(width 0.1143)
		(layer "F.Cu")
		(net "HDD_PWR_RESET_N")
	)
	(segment
		(start 82.916014 -146.05)
		(end 81.73212 -146.05)
		(width 0.1143)
		(layer "F.Cu")
		(net "HDD_PWR_RESET_N")
	)
	(segment
		(start 84.59597 -139.814554)
		(end 84.59597 -144.370044)
		(width 0.1143)
		(layer "F.Cu")
		(net "HDD_PWR_RESET_N")
	)
	(segment
		(start 84.59597 -144.370044)
		(end 82.916014 -146.05)
		(width 0.1143)
		(layer "F.Cu")
		(net "HDD_PWR_RESET_N")
	)
	(segment
		(start 21.159216 -213.35238)
		(end 21.159216 -212.774784)
		(width 0.1143)
		(layer "F.Cu")
		(net "HDD_PWR_RESET_N")
	)
	(segment
		(start 21.159216 -212.774784)
		(end 21.392134 -212.541866)
		(width 0.1143)
		(layer "F.Cu")
		(net "HDD_PWR_RESET_N")
	)
	(via
		(at 21.392134 -211.144866)
		(size 0.7112)
		(drill 0.3556)
		(layers "F.Cu" "B.Cu")
		(net "HDD_PWR_RESET_N")
	)
	(via
		(at 81.73212 -146.05)
		(size 0.5588)
		(drill 0.3048)
		(layers "F.Cu" "B.Cu")
		(net "HDD_PWR_RESET_N")
	)
	(via
		(at 21.392134 -212.363812)
		(size 0.5588)
		(drill 0.3048)
		(layers "F.Cu" "B.Cu")
		(net "HDD_PWR_RESET_N")
	)
	(segment
		(start 21.392134 -209.602578)
		(end 21.392134 -211.144866)
		(width 0.1143)
		(layer "B.Cu")
		(net "HDD_PWR_RESET_N")
	)
	(segment
		(start 51.393598 -176.1617)
		(end 51.380898 -176.1744)
		(width 0.1143)
		(layer "B.Cu")
		(net "HDD_PWR_RESET_N")
	)
	(segment
		(start 39.688262 -187.867036)
		(end 39.688262 -188.687456)
		(width 0.1143)
		(layer "B.Cu")
		(net "HDD_PWR_RESET_N")
	)
	(segment
		(start 50.510694 -177.044604)
		(end 39.688262 -187.867036)
		(width 0.1143)
		(layer "B.Cu")
		(net "HDD_PWR_RESET_N")
	)
	(segment
		(start 65.1002 -170.349672)
		(end 59.288172 -176.1617)
		(width 0.1143)
		(layer "B.Cu")
		(net "HDD_PWR_RESET_N")
	)
	(segment
		(start 51.380898 -176.1744)
		(end 51.380644 -176.1744)
		(width 0.1143)
		(layer "B.Cu")
		(net "HDD_PWR_RESET_N")
	)
	(segment
		(start 65.1002 -165.87343)
		(end 65.1002 -170.349672)
		(width 0.1143)
		(layer "B.Cu")
		(net "HDD_PWR_RESET_N")
	)
	(segment
		(start 21.392134 -212.363812)
		(end 21.392134 -211.144866)
		(width 0.1143)
		(layer "B.Cu")
		(net "HDD_PWR_RESET_N")
	)
	(segment
		(start 51.380644 -176.1744)
		(end 50.510694 -177.04435)
		(width 0.1143)
		(layer "B.Cu")
		(net "HDD_PWR_RESET_N")
	)
	(segment
		(start 81.73212 -146.05)
		(end 81.73212 -149.24151)
		(width 0.1143)
		(layer "B.Cu")
		(net "HDD_PWR_RESET_N")
	)
	(segment
		(start 50.510694 -177.04435)
		(end 50.510694 -177.044604)
		(width 0.1143)
		(layer "B.Cu")
		(net "HDD_PWR_RESET_N")
	)
	(segment
		(start 59.288172 -176.1617)
		(end 51.393598 -176.1617)
		(width 0.1143)
		(layer "B.Cu")
		(net "HDD_PWR_RESET_N")
	)
	(segment
		(start 39.688516 -191.306196)
		(end 21.392134 -209.602578)
		(width 0.1143)
		(layer "B.Cu")
		(net "HDD_PWR_RESET_N")
	)
	(segment
		(start 39.688262 -188.687456)
		(end 39.688516 -188.68771)
		(width 0.1143)
		(layer "B.Cu")
		(net "HDD_PWR_RESET_N")
	)
	(segment
		(start 39.688516 -188.68771)
		(end 39.688516 -191.306196)
		(width 0.1143)
		(layer "B.Cu")
		(net "HDD_PWR_RESET_N")
	)
	(segment
		(start 81.73212 -149.24151)
		(end 65.1002 -165.87343)
		(width 0.1143)
		(layer "B.Cu")
		(net "HDD_PWR_RESET_N")
	)
	(segment
		(start 288.034984 -180.240178)
		(end 288.675064 -180.240178)
		(width 0.1016)
		(layer "F.Cu")
		(net "EXP_TRAY_ID_BMC")
	)
	(segment
		(start 289.060636 -179.950364)
		(end 289.179 -179.832)
		(width 0.1016)
		(layer "F.Cu")
		(net "EXP_TRAY_ID_BMC")
	)
	(segment
		(start 289.67684 -179.832)
		(end 289.74034 -179.7685)
		(width 0.1016)
		(layer "F.Cu")
		(net "EXP_TRAY_ID_BMC")
	)
	(segment
		(start 267.849096 -181.5084)
		(end 267.372592 -181.031896)
		(width 0.1143)
		(layer "F.Cu")
		(net "EXP_TRAY_ID_BMC")
	)
	(segment
		(start 267.302488 -181.102)
		(end 267.372592 -181.031896)
		(width 0.1143)
		(layer "F.Cu")
		(net "EXP_TRAY_ID_BMC")
	)
	(segment
		(start 288.675064 -180.240178)
		(end 288.964878 -179.950364)
		(width 0.1016)
		(layer "F.Cu")
		(net "EXP_TRAY_ID_BMC")
	)
	(segment
		(start 266.5095 -181.102)
		(end 267.302488 -181.102)
		(width 0.1143)
		(layer "F.Cu")
		(net "EXP_TRAY_ID_BMC")
	)
	(segment
		(start 288.964878 -179.950364)
		(end 289.060636 -179.950364)
		(width 0.1016)
		(layer "F.Cu")
		(net "EXP_TRAY_ID_BMC")
	)
	(segment
		(start 268.0716 -181.5084)
		(end 267.849096 -181.5084)
		(width 0.1143)
		(layer "F.Cu")
		(net "EXP_TRAY_ID_BMC")
	)
	(segment
		(start 289.179 -179.832)
		(end 289.67684 -179.832)
		(width 0.1016)
		(layer "F.Cu")
		(net "EXP_TRAY_ID_BMC")
	)
	(via
		(at 289.74034 -179.7685)
		(size 0.508)
		(drill 0.254)
		(layers "F.Cu" "B.Cu")
		(net "EXP_TRAY_ID_BMC")
	)
	(via
		(at 267.372592 -181.031896)
		(size 0.5588)
		(drill 0.3048)
		(layers "F.Cu" "B.Cu")
		(net "EXP_TRAY_ID_BMC")
	)
	(via
		(at 268.0716 -181.5084)
		(size 0.7112)
		(drill 0.3556)
		(layers "F.Cu" "B.Cu")
		(net "EXP_TRAY_ID_BMC")
	)
	(segment
		(start 287.787588 -179.847494)
		(end 287.42259 -180.212492)
		(width 0.0889)
		(layer "In2.Cu")
		(net "EXP_TRAY_ID_BMC")
	)
	(segment
		(start 273.038824 -181.247796)
		(end 272.62836 -181.247796)
		(width 0.127)
		(layer "In2.Cu")
		(net "EXP_TRAY_ID_BMC")
	)
	(segment
		(start 287.42259 -180.212492)
		(end 287.038034 -180.212492)
		(width 0.0889)
		(layer "In2.Cu")
		(net "EXP_TRAY_ID_BMC")
	)
	(segment
		(start 287.038034 -180.212492)
		(end 287.004252 -180.246274)
		(width 0.0889)
		(layer "In2.Cu")
		(net "EXP_TRAY_ID_BMC")
	)
	(segment
		(start 271.98193 -180.32222)
		(end 268.082268 -180.32222)
		(width 0.127)
		(layer "In2.Cu")
		(net "EXP_TRAY_ID_BMC")
	)
	(segment
		(start 285.148782 -180.32222)
		(end 273.91487 -180.32222)
		(width 0.127)
		(layer "In2.Cu")
		(net "EXP_TRAY_ID_BMC")
	)
	(segment
		(start 273.328892 -180.957728)
		(end 273.038824 -181.247796)
		(width 0.127)
		(layer "In2.Cu")
		(net "EXP_TRAY_ID_BMC")
	)
	(segment
		(start 272.338292 -180.957728)
		(end 272.338292 -180.678582)
		(width 0.127)
		(layer "In2.Cu")
		(net "EXP_TRAY_ID_BMC")
	)
	(segment
		(start 289.277806 -178.6763)
		(end 288.958782 -178.6763)
		(width 0.127)
		(layer "In2.Cu")
		(net "EXP_TRAY_ID_BMC")
	)
	(segment
		(start 285.224728 -180.246274)
		(end 285.148782 -180.32222)
		(width 0.0889)
		(layer "In2.Cu")
		(net "EXP_TRAY_ID_BMC")
	)
	(segment
		(start 288.958782 -178.6763)
		(end 287.787588 -179.847494)
		(width 0.127)
		(layer "In2.Cu")
		(net "EXP_TRAY_ID_BMC")
	)
	(segment
		(start 268.082268 -180.32222)
		(end 267.372592 -181.031896)
		(width 0.127)
		(layer "In2.Cu")
		(net "EXP_TRAY_ID_BMC")
	)
	(segment
		(start 289.74034 -179.138834)
		(end 289.277806 -178.6763)
		(width 0.127)
		(layer "In2.Cu")
		(net "EXP_TRAY_ID_BMC")
	)
	(segment
		(start 273.91487 -180.32222)
		(end 273.328892 -180.908198)
		(width 0.127)
		(layer "In2.Cu")
		(net "EXP_TRAY_ID_BMC")
	)
	(segment
		(start 272.62836 -181.247796)
		(end 272.338292 -180.957728)
		(width 0.127)
		(layer "In2.Cu")
		(net "EXP_TRAY_ID_BMC")
	)
	(segment
		(start 272.338292 -180.678582)
		(end 271.98193 -180.32222)
		(width 0.127)
		(layer "In2.Cu")
		(net "EXP_TRAY_ID_BMC")
	)
	(segment
		(start 287.004252 -180.246274)
		(end 285.224728 -180.246274)
		(width 0.0889)
		(layer "In2.Cu")
		(net "EXP_TRAY_ID_BMC")
	)
	(segment
		(start 289.74034 -179.7685)
		(end 289.74034 -179.138834)
		(width 0.127)
		(layer "In2.Cu")
		(net "EXP_TRAY_ID_BMC")
	)
	(segment
		(start 273.328892 -180.908198)
		(end 273.328892 -180.957728)
		(width 0.127)
		(layer "In2.Cu")
		(net "EXP_TRAY_ID_BMC")
	)
	(segment
		(start 195.706492 -178.689508)
		(end 196.664834 -177.731166)
		(width 0.127)
		(layer "F.Cu")
		(net "INVERTER_G1")
	)
	(segment
		(start 197.484492 -176.911508)
		(end 196.664834 -177.731166)
		(width 0.127)
		(layer "F.Cu")
		(net "INVERTER_G1")
	)
	(segment
		(start 195.706492 -179.782216)
		(end 195.706492 -178.689508)
		(width 0.127)
		(layer "F.Cu")
		(net "INVERTER_G1")
	)
	(segment
		(start 197.484492 -175.959516)
		(end 197.484492 -176.911508)
		(width 0.127)
		(layer "F.Cu")
		(net "INVERTER_G1")
	)
	(via
		(at 196.664834 -177.731166)
		(size 0.7112)
		(drill 0.3556)
		(layers "F.Cu" "B.Cu")
		(net "INVERTER_G1")
	)
	(segment
		(start 203.191872 -195.317872)
		(end 203.835 -195.961)
		(width 0.1143)
		(layer "F.Cu")
		(net "DIVIDER 2_IN")
	)
	(segment
		(start 203.191872 -194.001136)
		(end 203.191872 -195.317872)
		(width 0.1143)
		(layer "F.Cu")
		(net "DIVIDER 2_IN")
	)
	(segment
		(start 206.502 -188.849)
		(end 206.502 -185.7375)
		(width 0.1143)
		(layer "F.Cu")
		(net "DIVIDER 2_IN")
	)
	(segment
		(start 205.486 -195.961)
		(end 206.502 -194.945)
		(width 0.1143)
		(layer "F.Cu")
		(net "DIVIDER 2_IN")
	)
	(segment
		(start 203.835 -195.961)
		(end 205.486 -195.961)
		(width 0.1143)
		(layer "F.Cu")
		(net "DIVIDER 2_IN")
	)
	(segment
		(start 206.502 -194.945)
		(end 206.502 -188.849)
		(width 0.1143)
		(layer "F.Cu")
		(net "DIVIDER 2_IN")
	)
	(segment
		(start 206.502 -185.7375)
		(end 205.74 -184.9755)
		(width 0.1143)
		(layer "F.Cu")
		(net "DIVIDER 2_IN")
	)
	(segment
		(start 205.74 -184.9755)
		(end 204.724 -184.9755)
		(width 0.1143)
		(layer "F.Cu")
		(net "DIVIDER 2_IN")
	)
	(via
		(at 206.502 -188.849)
		(size 0.7112)
		(drill 0.3556)
		(layers "F.Cu" "B.Cu")
		(net "DIVIDER 2_IN")
	)
	(segment
		(start 194.563492 -180.671216)
		(end 195.706492 -180.671216)
		(width 0.127)
		(layer "F.Cu")
		(net "HB_A_OUT")
	)
	(segment
		(start 197.231 -188.921136)
		(end 196.977 -188.667136)
		(width 0.127)
		(layer "F.Cu")
		(net "HB_A_OUT")
	)
	(segment
		(start 196.899784 -180.671216)
		(end 196.977 -180.594)
		(width 0.127)
		(layer "F.Cu")
		(net "HB_A_OUT")
	)
	(segment
		(start 201.921872 -193.031872)
		(end 200.66 -191.77)
		(width 0.127)
		(layer "F.Cu")
		(net "HB_A_OUT")
	)
	(segment
		(start 200.66 -188.929264)
		(end 200.651872 -188.921136)
		(width 0.127)
		(layer "F.Cu")
		(net "HB_A_OUT")
	)
	(segment
		(start 195.706492 -180.671216)
		(end 196.899784 -180.671216)
		(width 0.127)
		(layer "F.Cu")
		(net "HB_A_OUT")
	)
	(segment
		(start 196.977 -180.594)
		(end 196.977 -182.245)
		(width 0.127)
		(layer "F.Cu")
		(net "HB_A_OUT")
	)
	(segment
		(start 200.66 -191.77)
		(end 200.66 -188.929264)
		(width 0.127)
		(layer "F.Cu")
		(net "HB_A_OUT")
	)
	(segment
		(start 196.977 -188.667136)
		(end 196.977 -182.245)
		(width 0.127)
		(layer "F.Cu")
		(net "HB_A_OUT")
	)
	(segment
		(start 200.651872 -188.921136)
		(end 197.231 -188.921136)
		(width 0.127)
		(layer "F.Cu")
		(net "HB_A_OUT")
	)
	(segment
		(start 201.921872 -194.001136)
		(end 201.921872 -193.031872)
		(width 0.127)
		(layer "F.Cu")
		(net "HB_A_OUT")
	)
	(via
		(at 196.977 -182.245)
		(size 0.7112)
		(drill 0.3556)
		(layers "F.Cu" "B.Cu")
		(net "HB_A_OUT")
	)
	(segment
		(start 203.191872 -186.380628)
		(end 203.191872 -187.198)
		(width 0.1143)
		(layer "F.Cu")
		(net "DIVIDER 1_IN")
	)
	(segment
		(start 203.708 -185.8645)
		(end 203.191872 -186.380628)
		(width 0.1143)
		(layer "F.Cu")
		(net "DIVIDER 1_IN")
	)
	(segment
		(start 204.724 -185.8645)
		(end 203.708 -185.8645)
		(width 0.1143)
		(layer "F.Cu")
		(net "DIVIDER 1_IN")
	)
	(segment
		(start 203.191872 -188.921136)
		(end 203.191872 -187.198)
		(width 0.1143)
		(layer "F.Cu")
		(net "DIVIDER 1_IN")
	)
	(via
		(at 203.191872 -187.198)
		(size 0.7112)
		(drill 0.3556)
		(layers "F.Cu" "B.Cu")
		(net "DIVIDER 1_IN")
	)
	(segment
		(start 197.484492 -172.543216)
		(end 197.484492 -174.079916)
		(width 0.127)
		(layer "F.Cu")
		(net "INVERTER_G2")
	)
	(segment
		(start 198.134732 -171.923456)
		(end 198.119492 -171.908216)
		(width 0.127)
		(layer "F.Cu")
		(net "INVERTER_G2")
	)
	(segment
		(start 198.134732 -174.079916)
		(end 198.171816 -174.117)
		(width 0.127)
		(layer "F.Cu")
		(net "INVERTER_G2")
	)
	(segment
		(start 198.171816 -174.117)
		(end 199.517 -174.117)
		(width 0.127)
		(layer "F.Cu")
		(net "INVERTER_G2")
	)
	(segment
		(start 198.134732 -174.079916)
		(end 198.134732 -171.923456)
		(width 0.127)
		(layer "F.Cu")
		(net "INVERTER_G2")
	)
	(segment
		(start 198.119492 -171.908216)
		(end 197.484492 -172.543216)
		(width 0.127)
		(layer "F.Cu")
		(net "INVERTER_G2")
	)
	(via
		(at 199.517 -174.117)
		(size 0.7112)
		(drill 0.3556)
		(layers "F.Cu" "B.Cu")
		(net "INVERTER_G2")
	)
	(segment
		(start 200.7362 -186.1312)
		(end 199.898 -186.1312)
		(width 0.127)
		(layer "F.Cu")
		(net "HB_A_IN")
	)
	(segment
		(start 201.9935 -185.8645)
		(end 201.549 -186.309)
		(width 0.127)
		(layer "F.Cu")
		(net "HB_A_IN")
	)
	(segment
		(start 201.921872 -189.856872)
		(end 201.921872 -188.921136)
		(width 0.127)
		(layer "F.Cu")
		(net "HB_A_IN")
	)
	(segment
		(start 204.47 -192.405)
		(end 201.921872 -189.856872)
		(width 0.127)
		(layer "F.Cu")
		(net "HB_A_IN")
	)
	(segment
		(start 201.549 -186.309)
		(end 201.549 -187.198)
		(width 0.127)
		(layer "F.Cu")
		(net "HB_A_IN")
	)
	(segment
		(start 201.549 -186.309)
		(end 200.914 -186.309)
		(width 0.127)
		(layer "F.Cu")
		(net "HB_A_IN")
	)
	(segment
		(start 201.549 -187.198)
		(end 201.676 -187.325)
		(width 0.127)
		(layer "F.Cu")
		(net "HB_A_IN")
	)
	(segment
		(start 201.921872 -187.570872)
		(end 201.676 -187.325)
		(width 0.127)
		(layer "F.Cu")
		(net "HB_A_IN")
	)
	(segment
		(start 204.47 -193.993008)
		(end 204.47 -192.405)
		(width 0.127)
		(layer "F.Cu")
		(net "HB_A_IN")
	)
	(segment
		(start 202.692 -185.8645)
		(end 201.9935 -185.8645)
		(width 0.127)
		(layer "F.Cu")
		(net "HB_A_IN")
	)
	(segment
		(start 200.914 -186.309)
		(end 200.7362 -186.1312)
		(width 0.127)
		(layer "F.Cu")
		(net "HB_A_IN")
	)
	(segment
		(start 204.461872 -194.001136)
		(end 204.47 -193.993008)
		(width 0.127)
		(layer "F.Cu")
		(net "HB_A_IN")
	)
	(segment
		(start 201.921872 -188.921136)
		(end 201.921872 -187.570872)
		(width 0.127)
		(layer "F.Cu")
		(net "HB_A_IN")
	)
	(via
		(at 201.676 -187.325)
		(size 0.7112)
		(drill 0.3556)
		(layers "F.Cu" "B.Cu")
		(net "HB_A_IN")
	)
	(segment
		(start 292.038532 -169.040048)
		(end 292.438836 -168.639744)
		(width 0.1143)
		(layer "F.Cu")
		(net "HIGH_HEX_3")
	)
	(segment
		(start 292.438836 -168.639744)
		(end 292.443916 -168.639744)
		(width 0.1143)
		(layer "F.Cu")
		(net "HIGH_HEX_3")
	)
	(segment
		(start 292.034976 -169.040048)
		(end 292.038532 -169.040048)
		(width 0.1143)
		(layer "F.Cu")
		(net "HIGH_HEX_3")
	)
	(via
		(at 315.003942 -139.783058)
		(size 0.5588)
		(drill 0.3048)
		(layers "F.Cu" "B.Cu")
		(net "HIGH_HEX_3")
	)
	(via
		(at 292.443916 -168.639744)
		(size 0.508)
		(drill 0.254)
		(layers "F.Cu" "B.Cu")
		(net "HIGH_HEX_3")
	)
	(segment
		(start 296.200068 -139.7381)
		(end 290.201096 -145.737072)
		(width 0.1143)
		(layer "B.Cu")
		(net "HIGH_HEX_3")
	)
	(segment
		(start 287.095438 -152.278588)
		(end 291.90061 -157.08376)
		(width 0.1143)
		(layer "B.Cu")
		(net "HIGH_HEX_3")
	)
	(segment
		(start 291.90061 -157.08376)
		(end 291.90061 -166.405052)
		(width 0.1143)
		(layer "B.Cu")
		(net "HIGH_HEX_3")
	)
	(segment
		(start 309.68315 -139.7381)
		(end 296.200068 -139.7381)
		(width 0.1143)
		(layer "B.Cu")
		(net "HIGH_HEX_3")
	)
	(segment
		(start 290.201096 -147.375372)
		(end 287.095438 -150.48103)
		(width 0.1143)
		(layer "B.Cu")
		(net "HIGH_HEX_3")
	)
	(segment
		(start 292.27145 -168.378886)
		(end 292.27145 -168.467278)
		(width 0.1143)
		(layer "B.Cu")
		(net "HIGH_HEX_3")
	)
	(segment
		(start 291.78885 -167.896286)
		(end 292.27145 -168.378886)
		(width 0.1143)
		(layer "B.Cu")
		(net "HIGH_HEX_3")
	)
	(segment
		(start 290.201096 -145.737072)
		(end 290.201096 -147.375372)
		(width 0.1143)
		(layer "B.Cu")
		(net "HIGH_HEX_3")
	)
	(segment
		(start 315.003942 -139.783058)
		(end 309.728108 -139.783058)
		(width 0.1143)
		(layer "B.Cu")
		(net "HIGH_HEX_3")
	)
	(segment
		(start 287.095438 -150.48103)
		(end 287.095438 -152.278588)
		(width 0.1143)
		(layer "B.Cu")
		(net "HIGH_HEX_3")
	)
	(segment
		(start 292.27145 -168.467278)
		(end 292.443916 -168.639744)
		(width 0.1143)
		(layer "B.Cu")
		(net "HIGH_HEX_3")
	)
	(segment
		(start 291.78885 -166.516812)
		(end 291.78885 -167.896286)
		(width 0.1143)
		(layer "B.Cu")
		(net "HIGH_HEX_3")
	)
	(segment
		(start 291.90061 -166.405052)
		(end 291.78885 -166.516812)
		(width 0.1143)
		(layer "B.Cu")
		(net "HIGH_HEX_3")
	)
	(segment
		(start 309.728108 -139.783058)
		(end 309.68315 -139.7381)
		(width 0.1143)
		(layer "B.Cu")
		(net "HIGH_HEX_3")
	)
	(segment
		(start 315.003942 -139.783058)
		(end 314.452 -139.231116)
		(width 0.127)
		(layer "In5.Cu")
		(net "HIGH_HEX_3")
	)
	(segment
		(start 336.191098 -19.558)
		(end 343.281 -12.468098)
		(width 0.127)
		(layer "In5.Cu")
		(net "HIGH_HEX_3")
	)
	(segment
		(start 311.5691 -124.850652)
		(end 311.5691 -113.19891)
		(width 0.127)
		(layer "In5.Cu")
		(net "HIGH_HEX_3")
	)
	(segment
		(start 317.754 -99.695)
		(end 328.549 -88.9)
		(width 0.127)
		(layer "In5.Cu")
		(net "HIGH_HEX_3")
	)
	(segment
		(start 346.810584 -6.326124)
		(end 345.985084 -5.500624)
		(width 0.127)
		(layer "In5.Cu")
		(net "HIGH_HEX_3")
	)
	(segment
		(start 312.293 -112.47501)
		(end 312.293 -110.617)
		(width 0.127)
		(layer "In5.Cu")
		(net "HIGH_HEX_3")
	)
	(segment
		(start 331.394816 -19.558)
		(end 336.191098 -19.558)
		(width 0.127)
		(layer "In5.Cu")
		(net "HIGH_HEX_3")
	)
	(segment
		(start 329.023218 -21.929598)
		(end 331.394816 -19.558)
		(width 0.127)
		(layer "In5.Cu")
		(net "HIGH_HEX_3")
	)
	(segment
		(start 343.281 -12.468098)
		(end 343.281 -11.710162)
		(width 0.127)
		(layer "In5.Cu")
		(net "HIGH_HEX_3")
	)
	(segment
		(start 317.754 -105.156)
		(end 317.754 -99.695)
		(width 0.127)
		(layer "In5.Cu")
		(net "HIGH_HEX_3")
	)
	(segment
		(start 311.5691 -113.19891)
		(end 312.293 -112.47501)
		(width 0.127)
		(layer "In5.Cu")
		(net "HIGH_HEX_3")
	)
	(segment
		(start 329.023218 -71.70166)
		(end 329.023218 -21.929598)
		(width 0.127)
		(layer "In5.Cu")
		(net "HIGH_HEX_3")
	)
	(segment
		(start 330.0857 -72.764142)
		(end 329.023218 -71.70166)
		(width 0.127)
		(layer "In5.Cu")
		(net "HIGH_HEX_3")
	)
	(segment
		(start 328.549 -88.9)
		(end 328.549 -85.725)
		(width 0.127)
		(layer "In5.Cu")
		(net "HIGH_HEX_3")
	)
	(segment
		(start 330.0857 -84.1883)
		(end 330.0857 -72.764142)
		(width 0.127)
		(layer "In5.Cu")
		(net "HIGH_HEX_3")
	)
	(segment
		(start 328.549 -85.725)
		(end 330.0857 -84.1883)
		(width 0.127)
		(layer "In5.Cu")
		(net "HIGH_HEX_3")
	)
	(segment
		(start 314.452 -139.231116)
		(end 314.452 -127.733552)
		(width 0.127)
		(layer "In5.Cu")
		(net "HIGH_HEX_3")
	)
	(segment
		(start 343.281 -11.710162)
		(end 346.810584 -8.180578)
		(width 0.127)
		(layer "In5.Cu")
		(net "HIGH_HEX_3")
	)
	(segment
		(start 314.452 -127.733552)
		(end 311.5691 -124.850652)
		(width 0.127)
		(layer "In5.Cu")
		(net "HIGH_HEX_3")
	)
	(segment
		(start 312.293 -110.617)
		(end 317.754 -105.156)
		(width 0.127)
		(layer "In5.Cu")
		(net "HIGH_HEX_3")
	)
	(segment
		(start 346.810584 -8.180578)
		(end 346.810584 -6.326124)
		(width 0.127)
		(layer "In5.Cu")
		(net "HIGH_HEX_3")
	)
	(segment
		(start 97.54997 -79.375)
		(end 98.933 -80.75803)
		(width 0.1143)
		(layer "F.Cu")
		(net "JTAG_EXP_TCK")
	)
	(segment
		(start 107.349798 -86.34984)
		(end 106.849672 -85.849714)
		(width 0.1143)
		(layer "F.Cu")
		(net "JTAG_EXP_TCK")
	)
	(segment
		(start 98.18497 -76.8985)
		(end 97.54997 -77.5335)
		(width 0.1143)
		(layer "F.Cu")
		(net "JTAG_EXP_TCK")
	)
	(segment
		(start 97.54997 -77.5335)
		(end 97.54997 -79.121)
		(width 0.1143)
		(layer "F.Cu")
		(net "JTAG_EXP_TCK")
	)
	(segment
		(start 97.54997 -79.121)
		(end 97.54997 -79.375)
		(width 0.1143)
		(layer "F.Cu")
		(net "JTAG_EXP_TCK")
	)
	(segment
		(start 98.933 -80.75803)
		(end 98.933 -81.0641)
		(width 0.1143)
		(layer "F.Cu")
		(net "JTAG_EXP_TCK")
	)
	(via
		(at 98.933 -81.0641)
		(size 0.508)
		(drill 0.254)
		(layers "F.Cu" "B.Cu")
		(net "JTAG_EXP_TCK")
	)
	(via
		(at 106.849672 -85.849714)
		(size 0.508)
		(drill 0.254)
		(layers "F.Cu" "B.Cu")
		(net "JTAG_EXP_TCK")
	)
	(segment
		(start 105.023412 -83.430618)
		(end 105.268776 -83.675982)
		(width 0.127)
		(layer "In2.Cu")
		(net "JTAG_EXP_TCK")
	)
	(segment
		(start 105.812336 -84.405216)
		(end 105.99801 -84.405216)
		(width 0.127)
		(layer "In2.Cu")
		(net "JTAG_EXP_TCK")
	)
	(segment
		(start 105.268776 -83.861656)
		(end 105.812336 -84.405216)
		(width 0.127)
		(layer "In2.Cu")
		(net "JTAG_EXP_TCK")
	)
	(segment
		(start 99.3521 -81.4832)
		(end 100.53066 -81.4832)
		(width 0.127)
		(layer "In2.Cu")
		(net "JTAG_EXP_TCK")
	)
	(segment
		(start 98.933 -81.0641)
		(end 99.3521 -81.4832)
		(width 0.127)
		(layer "In2.Cu")
		(net "JTAG_EXP_TCK")
	)
	(segment
		(start 104.526588 -83.430618)
		(end 105.023412 -83.430618)
		(width 0.127)
		(layer "In2.Cu")
		(net "JTAG_EXP_TCK")
	)
	(segment
		(start 102.562406 -81.6102)
		(end 102.613206 -81.661)
		(width 0.127)
		(layer "In2.Cu")
		(net "JTAG_EXP_TCK")
	)
	(segment
		(start 100.65766 -81.6102)
		(end 102.562406 -81.6102)
		(width 0.127)
		(layer "In2.Cu")
		(net "JTAG_EXP_TCK")
	)
	(segment
		(start 102.613206 -81.661)
		(end 102.75697 -81.661)
		(width 0.127)
		(layer "In2.Cu")
		(net "JTAG_EXP_TCK")
	)
	(segment
		(start 106.294174 -85.071204)
		(end 106.849672 -85.626702)
		(width 0.127)
		(layer "In2.Cu")
		(net "JTAG_EXP_TCK")
	)
	(segment
		(start 106.849672 -85.626702)
		(end 106.849672 -85.849714)
		(width 0.127)
		(layer "In2.Cu")
		(net "JTAG_EXP_TCK")
	)
	(segment
		(start 105.99801 -84.405216)
		(end 106.294174 -84.70138)
		(width 0.127)
		(layer "In2.Cu")
		(net "JTAG_EXP_TCK")
	)
	(segment
		(start 102.75697 -81.661)
		(end 104.526588 -83.430618)
		(width 0.127)
		(layer "In2.Cu")
		(net "JTAG_EXP_TCK")
	)
	(segment
		(start 100.53066 -81.4832)
		(end 100.65766 -81.6102)
		(width 0.127)
		(layer "In2.Cu")
		(net "JTAG_EXP_TCK")
	)
	(segment
		(start 106.294174 -84.70138)
		(end 106.294174 -85.071204)
		(width 0.127)
		(layer "In2.Cu")
		(net "JTAG_EXP_TCK")
	)
	(segment
		(start 105.268776 -83.675982)
		(end 105.268776 -83.861656)
		(width 0.127)
		(layer "In2.Cu")
		(net "JTAG_EXP_TCK")
	)
	(segment
		(start 319.913 -179.705)
		(end 318.4525 -179.705)
		(width 0.1143)
		(layer "F.Cu")
		(net "ADC_P1V8_STBY")
	)
	(segment
		(start 328.82205 -196.19595)
		(end 333.58455 -191.43345)
		(width 0.1143)
		(layer "F.Cu")
		(net "ADC_P1V8_STBY")
	)
	(segment
		(start 329.556872 -213.605872)
		(end 328.82205 -212.87105)
		(width 0.1143)
		(layer "F.Cu")
		(net "ADC_P1V8_STBY")
	)
	(segment
		(start 333.58455 -191.43345)
		(end 333.58455 -187.28055)
		(width 0.1143)
		(layer "F.Cu")
		(net "ADC_P1V8_STBY")
	)
	(segment
		(start 329.556872 -214.257636)
		(end 329.556872 -213.605872)
		(width 0.1143)
		(layer "F.Cu")
		(net "ADC_P1V8_STBY")
	)
	(segment
		(start 326.771 -186.69)
		(end 327.914 -186.69)
		(width 0.1143)
		(layer "F.Cu")
		(net "ADC_P1V8_STBY")
	)
	(segment
		(start 324.358 -182.8165)
		(end 325.374 -182.8165)
		(width 0.1143)
		(layer "F.Cu")
		(net "ADC_P1V8_STBY")
	)
	(segment
		(start 325.374 -182.8165)
		(end 325.374 -185.293)
		(width 0.1143)
		(layer "F.Cu")
		(net "ADC_P1V8_STBY")
	)
	(segment
		(start 323.0245 -182.8165)
		(end 319.913 -179.705)
		(width 0.1143)
		(layer "F.Cu")
		(net "ADC_P1V8_STBY")
	)
	(segment
		(start 332.994 -186.69)
		(end 327.914 -186.69)
		(width 0.1143)
		(layer "F.Cu")
		(net "ADC_P1V8_STBY")
	)
	(segment
		(start 333.58455 -187.28055)
		(end 332.994 -186.69)
		(width 0.1143)
		(layer "F.Cu")
		(net "ADC_P1V8_STBY")
	)
	(segment
		(start 323.342 -182.8165)
		(end 323.0245 -182.8165)
		(width 0.1143)
		(layer "F.Cu")
		(net "ADC_P1V8_STBY")
	)
	(segment
		(start 328.82205 -212.87105)
		(end 328.82205 -196.19595)
		(width 0.1143)
		(layer "F.Cu")
		(net "ADC_P1V8_STBY")
	)
	(segment
		(start 325.374 -185.293)
		(end 326.771 -186.69)
		(width 0.1143)
		(layer "F.Cu")
		(net "ADC_P1V8_STBY")
	)
	(segment
		(start 324.358 -182.8165)
		(end 323.342 -182.8165)
		(width 0.1143)
		(layer "F.Cu")
		(net "ADC_P1V8_STBY")
	)
	(via
		(at 327.914 -186.69)
		(size 0.7112)
		(drill 0.3556)
		(layers "F.Cu" "B.Cu")
		(net "ADC_P1V8_STBY")
	)
	(segment
		(start 96.470216 -29.856176)
		(end 96.470216 -24.527764)
		(width 0.1397)
		(layer "F.Cu")
		(net "PCIE_SAS_CPU_TX_P2")
	)
	(segment
		(start 184.967372 -63.065406)
		(end 184.967372 -63.06566)
		(width 0.1397)
		(layer "F.Cu")
		(net "PCIE_SAS_CPU_TX_P2")
	)
	(segment
		(start 139.7889 -12.340844)
		(end 139.7889 -17.361154)
		(width 0.1397)
		(layer "F.Cu")
		(net "PCIE_SAS_CPU_TX_P2")
	)
	(segment
		(start 186.3725 -63.8175)
		(end 195.231004 -72.676004)
		(width 0.1397)
		(layer "F.Cu")
		(net "PCIE_SAS_CPU_TX_P2")
	)
	(segment
		(start 97.98177 -33.323276)
		(end 97.98177 -32.18307)
		(width 0.1397)
		(layer "F.Cu")
		(net "PCIE_SAS_CPU_TX_P2")
	)
	(segment
		(start 195.797424 -74.323194)
		(end 196.35343 -74.8792)
		(width 0.1397)
		(layer "F.Cu")
		(net "PCIE_SAS_CPU_TX_P2")
	)
	(segment
		(start 140.16101 -18.259044)
		(end 184.967372 -63.065406)
		(width 0.1397)
		(layer "F.Cu")
		(net "PCIE_SAS_CPU_TX_P2")
	)
	(segment
		(start 109.898688 -14.457172)
		(end 117.236748 -7.119112)
		(width 0.1397)
		(layer "F.Cu")
		(net "PCIE_SAS_CPU_TX_P2")
	)
	(segment
		(start 195.63842 -73.660254)
		(end 195.63842 -73.9394)
		(width 0.1397)
		(layer "F.Cu")
		(net "PCIE_SAS_CPU_TX_P2")
	)
	(segment
		(start 106.092244 -14.6431)
		(end 109.449616 -14.6431)
		(width 0.1397)
		(layer "F.Cu")
		(net "PCIE_SAS_CPU_TX_P2")
	)
	(segment
		(start 97.877376 -31.931356)
		(end 96.942656 -30.996636)
		(width 0.1397)
		(layer "F.Cu")
		(net "PCIE_SAS_CPU_TX_P2")
	)
	(segment
		(start 184.967372 -63.06566)
		(end 185.01995 -63.118238)
		(width 0.1397)
		(layer "F.Cu")
		(net "PCIE_SAS_CPU_TX_P2")
	)
	(segment
		(start 135.465058 -7.118858)
		(end 139.1539 -10.8077)
		(width 0.1397)
		(layer "F.Cu")
		(net "PCIE_SAS_CPU_TX_P2")
	)
	(segment
		(start 196.63283 -75.553824)
		(end 196.63283 -76.30922)
		(width 0.1397)
		(layer "F.Cu")
		(net "PCIE_SAS_CPU_TX_P2")
	)
	(segment
		(start 117.92839 -6.8326)
		(end 134.773162 -6.8326)
		(width 0.1397)
		(layer "F.Cu")
		(net "PCIE_SAS_CPU_TX_P2")
	)
	(segment
		(start 96.942656 -23.387304)
		(end 105.400602 -14.929358)
		(width 0.1397)
		(layer "F.Cu")
		(net "PCIE_SAS_CPU_TX_P2")
	)
	(segment
		(start 186.13501 -63.580264)
		(end 186.3725 -63.8175)
		(width 0.1397)
		(layer "F.Cu")
		(net "PCIE_SAS_CPU_TX_P2")
	)
	(via
		(at 196.929502 -77.0255)
		(size 0.5588)
		(drill 0.3048)
		(layers "F.Cu" "B.Cu")
		(net "PCIE_SAS_CPU_TX_P2")
	)
	(arc
		(start 97.95002 -33.399984)
		(mid 97.973536 -33.36479)
		(end 97.98177 -33.323276)
		(width 0.1397)
		(layer "F.Cu")
		(net "PCIE_SAS_CPU_TX_P2")
	)
	(arc
		(start 134.773162 -6.8326)
		(mid 135.147579 -6.906907)
		(end 135.465058 -7.118858)
		(width 0.1397)
		(layer "F.Cu")
		(net "PCIE_SAS_CPU_TX_P2")
	)
	(arc
		(start 96.942656 -30.996636)
		(mid 96.593033 -30.473389)
		(end 96.470216 -29.856176)
		(width 0.1397)
		(layer "F.Cu")
		(net "PCIE_SAS_CPU_TX_P2")
	)
	(arc
		(start 117.236748 -7.119112)
		(mid 117.554062 -6.907026)
		(end 117.92839 -6.8326)
		(width 0.1397)
		(layer "F.Cu")
		(net "PCIE_SAS_CPU_TX_P2")
	)
	(arc
		(start 195.63842 -73.9394)
		(mid 195.679738 -74.14712)
		(end 195.797424 -74.323194)
		(width 0.1397)
		(layer "F.Cu")
		(net "PCIE_SAS_CPU_TX_P2")
	)
	(arc
		(start 185.42 -63.283846)
		(mid 185.806989 -63.360934)
		(end 186.13501 -63.580264)
		(width 0.1397)
		(layer "F.Cu")
		(net "PCIE_SAS_CPU_TX_P2")
	)
	(arc
		(start 195.231004 -72.676004)
		(mid 195.532626 -73.127598)
		(end 195.63842 -73.660254)
		(width 0.1397)
		(layer "F.Cu")
		(net "PCIE_SAS_CPU_TX_P2")
	)
	(arc
		(start 139.7889 -17.361154)
		(mid 139.864522 -17.792298)
		(end 140.082016 -18.172176)
		(width 0.1397)
		(layer "F.Cu")
		(net "PCIE_SAS_CPU_TX_P2")
	)
	(arc
		(start 109.449616 -14.6431)
		(mid 109.69262 -14.594764)
		(end 109.898688 -14.457172)
		(width 0.1397)
		(layer "F.Cu")
		(net "PCIE_SAS_CPU_TX_P2")
	)
	(arc
		(start 97.98177 -32.18307)
		(mid 97.95458 -32.046847)
		(end 97.877376 -31.931356)
		(width 0.1397)
		(layer "F.Cu")
		(net "PCIE_SAS_CPU_TX_P2")
	)
	(arc
		(start 140.082016 -18.172176)
		(mid 140.120511 -18.216521)
		(end 140.16101 -18.259044)
		(width 0.1397)
		(layer "F.Cu")
		(net "PCIE_SAS_CPU_TX_P2")
	)
	(arc
		(start 196.35343 -74.8792)
		(mid 196.560245 -75.18872)
		(end 196.63283 -75.553824)
		(width 0.1397)
		(layer "F.Cu")
		(net "PCIE_SAS_CPU_TX_P2")
	)
	(arc
		(start 185.01995 -63.118238)
		(mid 185.203495 -63.240879)
		(end 185.42 -63.283846)
		(width 0.1397)
		(layer "F.Cu")
		(net "PCIE_SAS_CPU_TX_P2")
	)
	(arc
		(start 139.1539 -10.8077)
		(mid 139.623905 -11.511112)
		(end 139.7889 -12.340844)
		(width 0.1397)
		(layer "F.Cu")
		(net "PCIE_SAS_CPU_TX_P2")
	)
	(arc
		(start 105.400602 -14.929358)
		(mid 105.717945 -14.717409)
		(end 106.092244 -14.6431)
		(width 0.1397)
		(layer "F.Cu")
		(net "PCIE_SAS_CPU_TX_P2")
	)
	(arc
		(start 196.63283 -76.30922)
		(mid 196.709936 -76.69686)
		(end 196.929502 -77.0255)
		(width 0.1397)
		(layer "F.Cu")
		(net "PCIE_SAS_CPU_TX_P2")
	)
	(arc
		(start 96.470216 -24.527764)
		(mid 96.592991 -23.910534)
		(end 96.942656 -23.387304)
		(width 0.1397)
		(layer "F.Cu")
		(net "PCIE_SAS_CPU_TX_P2")
	)
	(segment
		(start 197.450456 -78.24978)
		(end 197.450456 -78.673706)
		(width 0.1397)
		(layer "B.Cu")
		(net "PCIE_SAS_CPU_TX_P2")
	)
	(segment
		(start 196.60489 -78.55331)
		(end 196.60489 -77.44206)
		(width 0.1397)
		(layer "B.Cu")
		(net "PCIE_SAS_CPU_TX_P2")
	)
	(segment
		(start 196.669914 -77.285088)
		(end 196.929502 -77.0255)
		(width 0.1397)
		(layer "B.Cu")
		(net "PCIE_SAS_CPU_TX_P2")
	)
	(segment
		(start 197.090538 -79.033624)
		(end 196.928232 -79.033624)
		(width 0.1397)
		(layer "B.Cu")
		(net "PCIE_SAS_CPU_TX_P2")
	)
	(arc
		(start 196.60489 -77.44206)
		(mid 196.621788 -77.357106)
		(end 196.669914 -77.285088)
		(width 0.1397)
		(layer "B.Cu")
		(net "PCIE_SAS_CPU_TX_P2")
	)
	(arc
		(start 197.450456 -78.673706)
		(mid 197.345038 -78.928206)
		(end 197.090538 -79.033624)
		(width 0.1397)
		(layer "B.Cu")
		(net "PCIE_SAS_CPU_TX_P2")
	)
	(arc
		(start 196.778118 -78.971394)
		(mid 196.649949 -78.779575)
		(end 196.60489 -78.55331)
		(width 0.1397)
		(layer "B.Cu")
		(net "PCIE_SAS_CPU_TX_P2")
	)
	(arc
		(start 196.928232 -79.033624)
		(mid 196.846971 -79.01746)
		(end 196.778118 -78.971394)
		(width 0.1397)
		(layer "B.Cu")
		(net "PCIE_SAS_CPU_TX_P2")
	)
	(segment
		(start 191.4525 -23.91283)
		(end 191.4525 -24.003)
		(width 0.1143)
		(layer "F.Cu")
		(net "RMII_PHY_BMC_RXD1")
	)
	(segment
		(start 267.63345 -119.052086)
		(end 267.63345 -99.65182)
		(width 0.1143)
		(layer "F.Cu")
		(net "RMII_PHY_BMC_RXD1")
	)
	(segment
		(start 302.6029 -157.5181)
		(end 302.6029 -145.029936)
		(width 0.1143)
		(layer "F.Cu")
		(net "RMII_PHY_BMC_RXD1")
	)
	(segment
		(start 268.6304 -134.702042)
		(end 268.6304 -120.049036)
		(width 0.1143)
		(layer "F.Cu")
		(net "RMII_PHY_BMC_RXD1")
	)
	(segment
		(start 195.326 -25.781)
		(end 195.326 -24.9936)
		(width 0.1143)
		(layer "F.Cu")
		(net "RMII_PHY_BMC_RXD1")
	)
	(segment
		(start 261.5057 -93.52407)
		(end 261.5057 -92.045536)
		(width 0.1143)
		(layer "F.Cu")
		(net "RMII_PHY_BMC_RXD1")
	)
	(segment
		(start 195.326 -24.9936)
		(end 193.6242 -23.2918)
		(width 0.1143)
		(layer "F.Cu")
		(net "RMII_PHY_BMC_RXD1")
	)
	(segment
		(start 297.278298 -161.0995)
		(end 299.361098 -159.0167)
		(width 0.1143)
		(layer "F.Cu")
		(net "RMII_PHY_BMC_RXD1")
	)
	(segment
		(start 195.326 -25.865836)
		(end 195.326 -25.781)
		(width 0.1143)
		(layer "F.Cu")
		(net "RMII_PHY_BMC_RXD1")
	)
	(segment
		(start 296.545 -161.0995)
		(end 297.278298 -161.0995)
		(width 0.1143)
		(layer "F.Cu")
		(net "RMII_PHY_BMC_RXD1")
	)
	(segment
		(start 278.892 -142.748)
		(end 276.676358 -142.748)
		(width 0.1143)
		(layer "F.Cu")
		(net "RMII_PHY_BMC_RXD1")
	)
	(segment
		(start 193.6242 -23.2918)
		(end 192.07353 -23.2918)
		(width 0.1143)
		(layer "F.Cu")
		(net "RMII_PHY_BMC_RXD1")
	)
	(segment
		(start 191.4525 -24.003)
		(end 190.3095 -24.003)
		(width 0.1143)
		(layer "F.Cu")
		(net "RMII_PHY_BMC_RXD1")
	)
	(segment
		(start 299.361098 -159.0167)
		(end 301.104046 -159.0167)
		(width 0.1143)
		(layer "F.Cu")
		(net "RMII_PHY_BMC_RXD1")
	)
	(segment
		(start 261.5057 -92.045536)
		(end 195.326 -25.865836)
		(width 0.1143)
		(layer "F.Cu")
		(net "RMII_PHY_BMC_RXD1")
	)
	(segment
		(start 276.676358 -142.748)
		(end 268.6304 -134.702042)
		(width 0.1143)
		(layer "F.Cu")
		(net "RMII_PHY_BMC_RXD1")
	)
	(segment
		(start 301.104046 -159.0167)
		(end 302.6029 -157.5181)
		(width 0.1143)
		(layer "F.Cu")
		(net "RMII_PHY_BMC_RXD1")
	)
	(segment
		(start 267.63345 -99.65182)
		(end 261.5057 -93.52407)
		(width 0.1143)
		(layer "F.Cu")
		(net "RMII_PHY_BMC_RXD1")
	)
	(segment
		(start 192.07353 -23.2918)
		(end 191.4525 -23.91283)
		(width 0.1143)
		(layer "F.Cu")
		(net "RMII_PHY_BMC_RXD1")
	)
	(segment
		(start 300.320964 -142.748)
		(end 287.528 -142.748)
		(width 0.1143)
		(layer "F.Cu")
		(net "RMII_PHY_BMC_RXD1")
	)
	(segment
		(start 268.6304 -120.049036)
		(end 267.63345 -119.052086)
		(width 0.1143)
		(layer "F.Cu")
		(net "RMII_PHY_BMC_RXD1")
	)
	(segment
		(start 302.6029 -145.029936)
		(end 300.320964 -142.748)
		(width 0.1143)
		(layer "F.Cu")
		(net "RMII_PHY_BMC_RXD1")
	)
	(via
		(at 195.326 -25.781)
		(size 0.7112)
		(drill 0.3556)
		(layers "F.Cu" "B.Cu")
		(net "RMII_PHY_BMC_RXD1")
	)
	(via
		(at 287.528 -142.748)
		(size 0.5588)
		(drill 0.3048)
		(layers "F.Cu" "B.Cu")
		(net "RMII_PHY_BMC_RXD1")
	)
	(via
		(at 278.892 -142.748)
		(size 0.5588)
		(drill 0.3048)
		(layers "F.Cu" "B.Cu")
		(net "RMII_PHY_BMC_RXD1")
	)
	(segment
		(start 287.528 -142.748)
		(end 278.892 -142.748)
		(width 0.127)
		(layer "In5.Cu")
		(net "RMII_PHY_BMC_RXD1")
	)
	(segment
		(start 188.858652 -140.598652)
		(end 189.220348 -140.598652)
		(width 0.1143)
		(layer "F.Cu")
		(net "EXP_EEPROM_WP")
	)
	(segment
		(start 190.119 -140.589)
		(end 189.23 -140.589)
		(width 0.1143)
		(layer "F.Cu")
		(net "EXP_EEPROM_WP")
	)
	(segment
		(start 190.876936 -140.586714)
		(end 190.121286 -140.586714)
		(width 0.1143)
		(layer "F.Cu")
		(net "EXP_EEPROM_WP")
	)
	(segment
		(start 190.121286 -140.586714)
		(end 190.119 -140.589)
		(width 0.1143)
		(layer "F.Cu")
		(net "EXP_EEPROM_WP")
	)
	(segment
		(start 188.2775 -140.589)
		(end 188.858652 -140.598652)
		(width 0.1143)
		(layer "F.Cu")
		(net "EXP_EEPROM_WP")
	)
	(segment
		(start 189.220348 -140.598652)
		(end 189.23 -140.589)
		(width 0.1143)
		(layer "F.Cu")
		(net "EXP_EEPROM_WP")
	)
	(via
		(at 189.23 -140.589)
		(size 0.7112)
		(drill 0.3556)
		(layers "F.Cu" "B.Cu")
		(net "EXP_EEPROM_WP")
	)
	(segment
		(start 261.0866 -92.219272)
		(end 197.277228 -28.4099)
		(width 0.1143)
		(layer "F.Cu")
		(net "RMII_PHY_BMC_RXD0")
	)
	(segment
		(start 261.0866 -93.697806)
		(end 261.0866 -92.219272)
		(width 0.1143)
		(layer "F.Cu")
		(net "RMII_PHY_BMC_RXD0")
	)
	(segment
		(start 268.2113 -120.222772)
		(end 267.21435 -119.225822)
		(width 0.1143)
		(layer "F.Cu")
		(net "RMII_PHY_BMC_RXD0")
	)
	(segment
		(start 288.671 -150.495)
		(end 288.671 -150.494746)
		(width 0.1143)
		(layer "F.Cu")
		(net "RMII_PHY_BMC_RXD0")
	)
	(segment
		(start 191.9605 -24.765)
		(end 191.4525 -25.273)
		(width 0.1143)
		(layer "F.Cu")
		(net "RMII_PHY_BMC_RXD0")
	)
	(segment
		(start 288.671 -150.494746)
		(end 281.432254 -143.256)
		(width 0.1143)
		(layer "F.Cu")
		(net "RMII_PHY_BMC_RXD0")
	)
	(segment
		(start 268.2113 -134.875778)
		(end 268.2113 -120.222772)
		(width 0.1143)
		(layer "F.Cu")
		(net "RMII_PHY_BMC_RXD0")
	)
	(segment
		(start 191.4525 -25.273)
		(end 190.3095 -25.273)
		(width 0.1143)
		(layer "F.Cu")
		(net "RMII_PHY_BMC_RXD0")
	)
	(segment
		(start 276.591522 -143.256)
		(end 268.2113 -134.875778)
		(width 0.1143)
		(layer "F.Cu")
		(net "RMII_PHY_BMC_RXD0")
	)
	(segment
		(start 192.786 -24.765)
		(end 191.9605 -24.765)
		(width 0.1143)
		(layer "F.Cu")
		(net "RMII_PHY_BMC_RXD0")
	)
	(segment
		(start 197.277228 -28.4099)
		(end 196.4309 -28.4099)
		(width 0.1143)
		(layer "F.Cu")
		(net "RMII_PHY_BMC_RXD0")
	)
	(segment
		(start 196.4309 -28.4099)
		(end 192.786 -24.765)
		(width 0.1143)
		(layer "F.Cu")
		(net "RMII_PHY_BMC_RXD0")
	)
	(segment
		(start 267.21435 -119.225822)
		(end 267.21435 -99.825556)
		(width 0.1143)
		(layer "F.Cu")
		(net "RMII_PHY_BMC_RXD0")
	)
	(segment
		(start 267.21435 -99.825556)
		(end 261.0866 -93.697806)
		(width 0.1143)
		(layer "F.Cu")
		(net "RMII_PHY_BMC_RXD0")
	)
	(segment
		(start 281.432254 -143.256)
		(end 276.591522 -143.256)
		(width 0.1143)
		(layer "F.Cu")
		(net "RMII_PHY_BMC_RXD0")
	)
	(via
		(at 293.669466 -156.240734)
		(size 0.7112)
		(drill 0.3556)
		(layers "F.Cu" "B.Cu")
		(net "RMII_PHY_BMC_RXD0")
	)
	(via
		(at 288.671 -150.495)
		(size 0.5588)
		(drill 0.3048)
		(layers "F.Cu" "B.Cu")
		(net "RMII_PHY_BMC_RXD0")
	)
	(segment
		(start 288.671 -151.251158)
		(end 293.660576 -156.240734)
		(width 0.1143)
		(layer "B.Cu")
		(net "RMII_PHY_BMC_RXD0")
	)
	(segment
		(start 293.669466 -156.240734)
		(end 293.669466 -156.255466)
		(width 0.1143)
		(layer "B.Cu")
		(net "RMII_PHY_BMC_RXD0")
	)
	(segment
		(start 296.3545 -163.322)
		(end 296.164 -163.7665)
		(width 0.1143)
		(layer "B.Cu")
		(net "RMII_PHY_BMC_RXD0")
	)
	(segment
		(start 288.671 -150.495)
		(end 288.671 -151.251158)
		(width 0.1143)
		(layer "B.Cu")
		(net "RMII_PHY_BMC_RXD0")
	)
	(segment
		(start 295.91 -158.496)
		(end 295.915842 -158.496)
		(width 0.1143)
		(layer "B.Cu")
		(net "RMII_PHY_BMC_RXD0")
	)
	(segment
		(start 295.915842 -158.496)
		(end 296.3545 -158.934658)
		(width 0.1143)
		(layer "B.Cu")
		(net "RMII_PHY_BMC_RXD0")
	)
	(segment
		(start 293.660576 -156.240734)
		(end 293.669466 -156.240734)
		(width 0.1143)
		(layer "B.Cu")
		(net "RMII_PHY_BMC_RXD0")
	)
	(segment
		(start 293.669466 -156.255466)
		(end 295.91 -158.496)
		(width 0.1143)
		(layer "B.Cu")
		(net "RMII_PHY_BMC_RXD0")
	)
	(segment
		(start 296.3545 -158.934658)
		(end 296.3545 -163.322)
		(width 0.1143)
		(layer "B.Cu")
		(net "RMII_PHY_BMC_RXD0")
	)
	(segment
		(start 104.02697 -76.8985)
		(end 104.28097 -77.108812)
		(width 0.1143)
		(layer "F.Cu")
		(net "JTAG_EXP_TMS")
	)
	(segment
		(start 104.405176 -79.847694)
		(end 104.405176 -82.294476)
		(width 0.1143)
		(layer "F.Cu")
		(net "JTAG_EXP_TMS")
	)
	(segment
		(start 104.53497 -77.362812)
		(end 104.53497 -78.613)
		(width 0.1143)
		(layer "F.Cu")
		(net "JTAG_EXP_TMS")
	)
	(segment
		(start 104.28097 -77.108812)
		(end 104.53497 -77.362812)
		(width 0.1143)
		(layer "F.Cu")
		(net "JTAG_EXP_TMS")
	)
	(segment
		(start 104.405176 -82.294476)
		(end 104.349804 -82.349848)
		(width 0.1143)
		(layer "F.Cu")
		(net "JTAG_EXP_TMS")
	)
	(segment
		(start 104.53497 -78.613)
		(end 104.53497 -79.7179)
		(width 0.1143)
		(layer "F.Cu")
		(net "JTAG_EXP_TMS")
	)
	(segment
		(start 104.53497 -79.7179)
		(end 104.405176 -79.847694)
		(width 0.1143)
		(layer "F.Cu")
		(net "JTAG_EXP_TMS")
	)
	(segment
		(start 101.49586 -28.86456)
		(end 101.49586 -27.197558)
		(width 0.1397)
		(layer "B.Cu")
		(net "PCIE_SAS_CPU_RX_P5")
	)
	(segment
		(start 122.85599 -15.367)
		(end 126.57201 -15.367)
		(width 0.1397)
		(layer "B.Cu")
		(net "PCIE_SAS_CPU_RX_P5")
	)
	(segment
		(start 109.034326 -19.659092)
		(end 117.895624 -19.659092)
		(width 0.1397)
		(layer "B.Cu")
		(net "PCIE_SAS_CPU_RX_P5")
	)
	(segment
		(start 100.97516 -31.360618)
		(end 101.067362 -31.268416)
		(width 0.1397)
		(layer "B.Cu")
		(net "PCIE_SAS_CPU_RX_P5")
	)
	(segment
		(start 148.411184 -36.5379)
		(end 152.909524 -36.5379)
		(width 0.1397)
		(layer "B.Cu")
		(net "PCIE_SAS_CPU_RX_P5")
	)
	(segment
		(start 118.344696 -19.473164)
		(end 122.164348 -15.653512)
		(width 0.1397)
		(layer "B.Cu")
		(net "PCIE_SAS_CPU_RX_P5")
	)
	(segment
		(start 101.782372 -26.505916)
		(end 108.342684 -19.945604)
		(width 0.1397)
		(layer "B.Cu")
		(net "PCIE_SAS_CPU_RX_P5")
	)
	(segment
		(start 101.305614 -29.141166)
		(end 101.434646 -29.012134)
		(width 0.1397)
		(layer "B.Cu")
		(net "PCIE_SAS_CPU_RX_P5")
	)
	(segment
		(start 127.263652 -15.653512)
		(end 147.962112 -36.351972)
		(width 0.1397)
		(layer "B.Cu")
		(net "PCIE_SAS_CPU_RX_P5")
	)
	(segment
		(start 153.601166 -36.824412)
		(end 167.10025 -50.323496)
		(width 0.1397)
		(layer "B.Cu")
		(net "PCIE_SAS_CPU_RX_P5")
	)
	(segment
		(start 167.633904 -51.611784)
		(end 167.633904 -75.307698)
		(width 0.1397)
		(layer "B.Cu")
		(net "PCIE_SAS_CPU_RX_P5")
	)
	(segment
		(start 101.14026 -31.092648)
		(end 101.14026 -29.540708)
		(width 0.1397)
		(layer "B.Cu")
		(net "PCIE_SAS_CPU_RX_P5")
	)
	(arc
		(start 167.633904 -75.307698)
		(mid 167.586244 -75.5473)
		(end 167.450516 -75.75042)
		(width 0.1397)
		(layer "B.Cu")
		(net "PCIE_SAS_CPU_RX_P5")
	)
	(arc
		(start 147.962112 -36.351972)
		(mid 148.168148 -36.489641)
		(end 148.411184 -36.5379)
		(width 0.1397)
		(layer "B.Cu")
		(net "PCIE_SAS_CPU_RX_P5")
	)
	(arc
		(start 101.49586 -27.197558)
		(mid 101.570333 -26.823249)
		(end 101.782372 -26.505916)
		(width 0.1397)
		(layer "B.Cu")
		(net "PCIE_SAS_CPU_RX_P5")
	)
	(arc
		(start 152.909524 -36.5379)
		(mid 153.283833 -36.612373)
		(end 153.601166 -36.824412)
		(width 0.1397)
		(layer "B.Cu")
		(net "PCIE_SAS_CPU_RX_P5")
	)
	(arc
		(start 122.164348 -15.653512)
		(mid 122.481662 -15.441426)
		(end 122.85599 -15.367)
		(width 0.1397)
		(layer "B.Cu")
		(net "PCIE_SAS_CPU_RX_P5")
	)
	(arc
		(start 108.342684 -19.945604)
		(mid 108.659998 -19.733518)
		(end 109.034326 -19.659092)
		(width 0.1397)
		(layer "B.Cu")
		(net "PCIE_SAS_CPU_RX_P5")
	)
	(arc
		(start 101.434646 -29.012134)
		(mid 101.47994 -28.944441)
		(end 101.49586 -28.86456)
		(width 0.1397)
		(layer "B.Cu")
		(net "PCIE_SAS_CPU_RX_P5")
	)
	(arc
		(start 167.10025 -50.323496)
		(mid 167.495191 -50.914568)
		(end 167.633904 -51.611784)
		(width 0.1397)
		(layer "B.Cu")
		(net "PCIE_SAS_CPU_RX_P5")
	)
	(arc
		(start 101.14026 -29.540708)
		(mid 101.183177 -29.324478)
		(end 101.305614 -29.141166)
		(width 0.1397)
		(layer "B.Cu")
		(net "PCIE_SAS_CPU_RX_P5")
	)
	(arc
		(start 126.57201 -15.367)
		(mid 126.946319 -15.441473)
		(end 127.263652 -15.653512)
		(width 0.1397)
		(layer "B.Cu")
		(net "PCIE_SAS_CPU_RX_P5")
	)
	(arc
		(start 117.895624 -19.659092)
		(mid 118.138628 -19.610756)
		(end 118.344696 -19.473164)
		(width 0.1397)
		(layer "B.Cu")
		(net "PCIE_SAS_CPU_RX_P5")
	)
	(arc
		(start 101.067362 -31.268416)
		(mid 101.1213 -31.187787)
		(end 101.14026 -31.092648)
		(width 0.1397)
		(layer "B.Cu")
		(net "PCIE_SAS_CPU_RX_P5")
	)
	(segment
		(start 272.566892 -191.847216)
		(end 273.041872 -191.372236)
		(width 0.254)
		(layer "F.Cu")
		(net "P1V8_STBY_PG")
	)
	(segment
		(start 264.668 -35.032696)
		(end 264.53719 -34.901886)
		(width 0.254)
		(layer "F.Cu")
		(net "P1V8_STBY_PG")
	)
	(segment
		(start 272.566892 -192.937892)
		(end 272.566892 -191.847216)
		(width 0.254)
		(layer "F.Cu")
		(net "P1V8_STBY_PG")
	)
	(segment
		(start 277.319232 -213.148672)
		(end 274.717002 -213.148672)
		(width 0.254)
		(layer "F.Cu")
		(net "P1V8_STBY_PG")
	)
	(segment
		(start 264.668 -35.56)
		(end 264.668 -35.032696)
		(width 0.254)
		(layer "F.Cu")
		(net "P1V8_STBY_PG")
	)
	(segment
		(start 280.915872 -215.146636)
		(end 280.915872 -214.465408)
		(width 0.254)
		(layer "F.Cu")
		(net "P1V8_STBY_PG")
	)
	(segment
		(start 281.21864 -214.16264)
		(end 280.90114 -213.84514)
		(width 0.254)
		(layer "F.Cu")
		(net "P1V8_STBY_PG")
	)
	(segment
		(start 274.172426 -194.543426)
		(end 272.566892 -192.937892)
		(width 0.254)
		(layer "F.Cu")
		(net "P1V8_STBY_PG")
	)
	(segment
		(start 280.90114 -213.84514)
		(end 278.0157 -213.84514)
		(width 0.254)
		(layer "F.Cu")
		(net "P1V8_STBY_PG")
	)
	(segment
		(start 264.937748 -35.829748)
		(end 264.668 -35.56)
		(width 0.254)
		(layer "F.Cu")
		(net "P1V8_STBY_PG")
	)
	(segment
		(start 274.172426 -212.604096)
		(end 274.172426 -194.543426)
		(width 0.254)
		(layer "F.Cu")
		(net "P1V8_STBY_PG")
	)
	(segment
		(start 274.717002 -213.148672)
		(end 274.172426 -212.604096)
		(width 0.254)
		(layer "F.Cu")
		(net "P1V8_STBY_PG")
	)
	(segment
		(start 264.937748 -36.992814)
		(end 264.937748 -35.829748)
		(width 0.254)
		(layer "F.Cu")
		(net "P1V8_STBY_PG")
	)
	(segment
		(start 278.0157 -213.84514)
		(end 277.319232 -213.148672)
		(width 0.254)
		(layer "F.Cu")
		(net "P1V8_STBY_PG")
	)
	(segment
		(start 280.915872 -214.465408)
		(end 281.21864 -214.16264)
		(width 0.254)
		(layer "F.Cu")
		(net "P1V8_STBY_PG")
	)
	(via
		(at 300.101 -241.046)
		(size 0.5588)
		(drill 0.3048)
		(layers "F.Cu" "B.Cu")
		(net "P1V8_STBY_PG")
	)
	(via
		(at 319.024 -64.008)
		(size 0.5588)
		(drill 0.3048)
		(layers "F.Cu" "B.Cu")
		(net "P1V8_STBY_PG")
	)
	(via
		(at 271.78 -36.957)
		(size 0.7112)
		(drill 0.3556)
		(layers "F.Cu" "B.Cu")
		(net "P1V8_STBY_PG")
	)
	(via
		(at 322.326 -64.008)
		(size 0.7112)
		(drill 0.3556)
		(layers "F.Cu" "B.Cu")
		(net "P1V8_STBY_PG")
	)
	(via
		(at 264.53719 -34.901886)
		(size 0.5588)
		(drill 0.3048)
		(layers "F.Cu" "B.Cu")
		(net "P1V8_STBY_PG")
	)
	(via
		(at 330.073 -59.944)
		(size 0.5588)
		(drill 0.3048)
		(layers "F.Cu" "B.Cu")
		(net "P1V8_STBY_PG")
	)
	(via
		(at 269.494 -53.721)
		(size 0.5588)
		(drill 0.3048)
		(layers "F.Cu" "B.Cu")
		(net "P1V8_STBY_PG")
	)
	(via
		(at 281.21864 -214.16264)
		(size 0.5588)
		(drill 0.3048)
		(layers "F.Cu" "B.Cu")
		(net "P1V8_STBY_PG")
	)
	(segment
		(start 327.279 -59.944)
		(end 323.215 -64.008)
		(width 0.254)
		(layer "B.Cu")
		(net "P1V8_STBY_PG")
	)
	(segment
		(start 276.225 -36.957)
		(end 271.78 -36.957)
		(width 0.254)
		(layer "B.Cu")
		(net "P1V8_STBY_PG")
	)
	(segment
		(start 296.418 -244.729)
		(end 294.357552 -244.729)
		(width 0.254)
		(layer "B.Cu")
		(net "P1V8_STBY_PG")
	)
	(segment
		(start 323.215 -64.008)
		(end 322.326 -64.008)
		(width 0.254)
		(layer "B.Cu")
		(net "P1V8_STBY_PG")
	)
	(segment
		(start 294.357552 -244.729)
		(end 281.21864 -231.590088)
		(width 0.254)
		(layer "B.Cu")
		(net "P1V8_STBY_PG")
	)
	(segment
		(start 263.9695 -36.957)
		(end 271.78 -36.957)
		(width 0.254)
		(layer "B.Cu")
		(net "P1V8_STBY_PG")
	)
	(segment
		(start 263.9695 -35.814)
		(end 263.9695 -35.469576)
		(width 0.254)
		(layer "B.Cu")
		(net "P1V8_STBY_PG")
	)
	(segment
		(start 300.101 -241.046)
		(end 296.418 -244.729)
		(width 0.254)
		(layer "B.Cu")
		(net "P1V8_STBY_PG")
	)
	(segment
		(start 263.9695 -36.957)
		(end 263.9695 -35.814)
		(width 0.254)
		(layer "B.Cu")
		(net "P1V8_STBY_PG")
	)
	(segment
		(start 319.024 -64.008)
		(end 322.326 -64.008)
		(width 0.254)
		(layer "B.Cu")
		(net "P1V8_STBY_PG")
	)
	(segment
		(start 277.241 -52.959)
		(end 277.241 -37.973)
		(width 0.254)
		(layer "B.Cu")
		(net "P1V8_STBY_PG")
	)
	(segment
		(start 269.494 -53.721)
		(end 270.129 -54.356)
		(width 0.254)
		(layer "B.Cu")
		(net "P1V8_STBY_PG")
	)
	(segment
		(start 277.241 -37.973)
		(end 276.225 -36.957)
		(width 0.254)
		(layer "B.Cu")
		(net "P1V8_STBY_PG")
	)
	(segment
		(start 275.844 -54.356)
		(end 277.241 -52.959)
		(width 0.254)
		(layer "B.Cu")
		(net "P1V8_STBY_PG")
	)
	(segment
		(start 330.073 -59.944)
		(end 327.279 -59.944)
		(width 0.254)
		(layer "B.Cu")
		(net "P1V8_STBY_PG")
	)
	(segment
		(start 263.9695 -35.469576)
		(end 264.53719 -34.901886)
		(width 0.254)
		(layer "B.Cu")
		(net "P1V8_STBY_PG")
	)
	(segment
		(start 281.21864 -231.590088)
		(end 281.21864 -214.16264)
		(width 0.254)
		(layer "B.Cu")
		(net "P1V8_STBY_PG")
	)
	(segment
		(start 270.129 -54.356)
		(end 275.844 -54.356)
		(width 0.254)
		(layer "B.Cu")
		(net "P1V8_STBY_PG")
	)
	(segment
		(start 330.073 -59.944)
		(end 338.286344 -68.157344)
		(width 0.254)
		(layer "In2.Cu")
		(net "P1V8_STBY_PG")
	)
	(segment
		(start 335.8769 -145.65757)
		(end 339.957918 -149.738588)
		(width 0.254)
		(layer "In2.Cu")
		(net "P1V8_STBY_PG")
	)
	(segment
		(start 338.286344 -68.157344)
		(end 338.286344 -77.682344)
		(width 0.254)
		(layer "In2.Cu")
		(net "P1V8_STBY_PG")
	)
	(segment
		(start 339.957918 -149.738588)
		(end 339.957918 -154.08656)
		(width 0.254)
		(layer "In2.Cu")
		(net "P1V8_STBY_PG")
	)
	(segment
		(start 323.7103 -217.4367)
		(end 300.101 -241.046)
		(width 0.254)
		(layer "In2.Cu")
		(net "P1V8_STBY_PG")
	)
	(segment
		(start 339.957918 -154.08656)
		(end 336.7532 -157.291278)
		(width 0.254)
		(layer "In2.Cu")
		(net "P1V8_STBY_PG")
	)
	(segment
		(start 346.561664 -85.957664)
		(end 346.561664 -90.670888)
		(width 0.254)
		(layer "In2.Cu")
		(net "P1V8_STBY_PG")
	)
	(segment
		(start 333.916528 -217.4367)
		(end 323.7103 -217.4367)
		(width 0.254)
		(layer "In2.Cu")
		(net "P1V8_STBY_PG")
	)
	(segment
		(start 336.7532 -178.083972)
		(end 337.6803 -179.011072)
		(width 0.254)
		(layer "In2.Cu")
		(net "P1V8_STBY_PG")
	)
	(segment
		(start 330.3778 -121.5136)
		(end 330.3778 -133.080252)
		(width 0.254)
		(layer "In2.Cu")
		(net "P1V8_STBY_PG")
	)
	(segment
		(start 346.561664 -90.670888)
		(end 330.1492 -107.083352)
		(width 0.254)
		(layer "In2.Cu")
		(net "P1V8_STBY_PG")
	)
	(segment
		(start 330.3778 -133.080252)
		(end 335.8769 -138.579352)
		(width 0.254)
		(layer "In2.Cu")
		(net "P1V8_STBY_PG")
	)
	(segment
		(start 337.6803 -179.011072)
		(end 337.6803 -213.672928)
		(width 0.254)
		(layer "In2.Cu")
		(net "P1V8_STBY_PG")
	)
	(segment
		(start 337.6803 -213.672928)
		(end 333.916528 -217.4367)
		(width 0.254)
		(layer "In2.Cu")
		(net "P1V8_STBY_PG")
	)
	(segment
		(start 330.1492 -121.285)
		(end 330.3778 -121.5136)
		(width 0.254)
		(layer "In2.Cu")
		(net "P1V8_STBY_PG")
	)
	(segment
		(start 330.1492 -107.083352)
		(end 330.1492 -121.285)
		(width 0.254)
		(layer "In2.Cu")
		(net "P1V8_STBY_PG")
	)
	(segment
		(start 338.286344 -77.682344)
		(end 346.561664 -85.957664)
		(width 0.254)
		(layer "In2.Cu")
		(net "P1V8_STBY_PG")
	)
	(segment
		(start 335.8769 -138.579352)
		(end 335.8769 -145.65757)
		(width 0.254)
		(layer "In2.Cu")
		(net "P1V8_STBY_PG")
	)
	(segment
		(start 336.7532 -157.291278)
		(end 336.7532 -178.083972)
		(width 0.254)
		(layer "In2.Cu")
		(net "P1V8_STBY_PG")
	)
	(segment
		(start 304.88382 -64.562228)
		(end 302.246792 -61.9252)
		(width 0.254)
		(layer "In5.Cu")
		(net "P1V8_STBY_PG")
	)
	(segment
		(start 317.373 -64.008)
		(end 316.818772 -64.562228)
		(width 0.254)
		(layer "In5.Cu")
		(net "P1V8_STBY_PG")
	)
	(segment
		(start 301.0408 -61.9252)
		(end 300.863 -62.103)
		(width 0.254)
		(layer "In5.Cu")
		(net "P1V8_STBY_PG")
	)
	(segment
		(start 296.291 -63.246)
		(end 293.751 -63.246)
		(width 0.254)
		(layer "In5.Cu")
		(net "P1V8_STBY_PG")
	)
	(segment
		(start 269.494 -54.60492)
		(end 269.494 -53.721)
		(width 0.254)
		(layer "In5.Cu")
		(net "P1V8_STBY_PG")
	)
	(segment
		(start 276.86508 -61.976)
		(end 269.494 -54.60492)
		(width 0.254)
		(layer "In5.Cu")
		(net "P1V8_STBY_PG")
	)
	(segment
		(start 297.434 -62.103)
		(end 296.291 -63.246)
		(width 0.254)
		(layer "In5.Cu")
		(net "P1V8_STBY_PG")
	)
	(segment
		(start 300.863 -62.103)
		(end 297.434 -62.103)
		(width 0.254)
		(layer "In5.Cu")
		(net "P1V8_STBY_PG")
	)
	(segment
		(start 316.818772 -64.562228)
		(end 304.88382 -64.562228)
		(width 0.254)
		(layer "In5.Cu")
		(net "P1V8_STBY_PG")
	)
	(segment
		(start 319.024 -64.008)
		(end 317.373 -64.008)
		(width 0.254)
		(layer "In5.Cu")
		(net "P1V8_STBY_PG")
	)
	(segment
		(start 292.481 -61.976)
		(end 276.86508 -61.976)
		(width 0.254)
		(layer "In5.Cu")
		(net "P1V8_STBY_PG")
	)
	(segment
		(start 302.246792 -61.9252)
		(end 301.0408 -61.9252)
		(width 0.254)
		(layer "In5.Cu")
		(net "P1V8_STBY_PG")
	)
	(segment
		(start 293.751 -63.246)
		(end 292.481 -61.976)
		(width 0.254)
		(layer "In5.Cu")
		(net "P1V8_STBY_PG")
	)
	(segment
		(start 307.029104 -73.4822)
		(end 305.417474 -73.4822)
		(width 0.1397)
		(layer "F.Cu")
		(net "PCIE_10G_CPU_TX1_P")
	)
	(segment
		(start 308.675024 -73.200006)
		(end 307.467 -73.200006)
		(width 0.1397)
		(layer "F.Cu")
		(net "PCIE_10G_CPU_TX1_P")
	)
	(segment
		(start 303.678336 -72.39)
		(end 303.166272 -72.39)
		(width 0.1397)
		(layer "F.Cu")
		(net "PCIE_10G_CPU_TX1_P")
	)
	(segment
		(start 307.384958 -73.233788)
		(end 307.213 -73.406)
		(width 0.1397)
		(layer "F.Cu")
		(net "PCIE_10G_CPU_TX1_P")
	)
	(segment
		(start 302.52543 -72.65543)
		(end 302.488346 -72.692514)
		(width 0.1397)
		(layer "F.Cu")
		(net "PCIE_10G_CPU_TX1_P")
	)
	(segment
		(start 304.927 -73.279)
		(end 304.292 -72.644)
		(width 0.1397)
		(layer "F.Cu")
		(net "PCIE_10G_CPU_TX1_P")
	)
	(segment
		(start 302.203612 -73.380346)
		(end 301.974758 -73.6092)
		(width 0.1397)
		(layer "F.Cu")
		(net "PCIE_10G_CPU_TX1_P")
	)
	(via
		(at 301.974758 -73.6092)
		(size 0.5588)
		(drill 0.3048)
		(layers "F.Cu" "B.Cu")
		(net "PCIE_10G_CPU_TX1_P")
	)
	(arc
		(start 307.213 -73.406)
		(mid 307.128628 -73.462376)
		(end 307.029104 -73.4822)
		(width 0.1397)
		(layer "F.Cu")
		(net "PCIE_10G_CPU_TX1_P")
	)
	(arc
		(start 302.2981 -73.152254)
		(mid 302.273545 -73.2757)
		(end 302.203612 -73.380346)
		(width 0.1397)
		(layer "F.Cu")
		(net "PCIE_10G_CPU_TX1_P")
	)
	(arc
		(start 307.467 -73.200006)
		(mid 307.422622 -73.20874)
		(end 307.384958 -73.233788)
		(width 0.1397)
		(layer "F.Cu")
		(net "PCIE_10G_CPU_TX1_P")
	)
	(arc
		(start 302.488346 -72.692514)
		(mid 302.347465 -72.903446)
		(end 302.2981 -73.152254)
		(width 0.1397)
		(layer "F.Cu")
		(net "PCIE_10G_CPU_TX1_P")
	)
	(arc
		(start 305.417474 -73.4822)
		(mid 305.152016 -73.429397)
		(end 304.927 -73.279)
		(width 0.1397)
		(layer "F.Cu")
		(net "PCIE_10G_CPU_TX1_P")
	)
	(arc
		(start 303.166272 -72.39)
		(mid 302.819442 -72.458971)
		(end 302.52543 -72.65543)
		(width 0.1397)
		(layer "F.Cu")
		(net "PCIE_10G_CPU_TX1_P")
	)
	(arc
		(start 304.292 -72.644)
		(mid 304.010434 -72.455956)
		(end 303.678336 -72.39)
		(width 0.1397)
		(layer "F.Cu")
		(net "PCIE_10G_CPU_TX1_P")
	)
	(segment
		(start 302.125888 -72.651112)
		(end 302.21047 -72.735948)
		(width 0.127)
		(layer "In5.Cu")
		(net "PCIE_10G_CPU_TX1_P")
	)
	(segment
		(start 152.656794 -66.4464)
		(end 153.718514 -65.384934)
		(width 0.127)
		(layer "In5.Cu")
		(net "PCIE_10G_CPU_TX1_P")
	)
	(segment
		(start 165.15969 -64.81826)
		(end 165.54069 -64.81826)
		(width 0.127)
		(layer "In5.Cu")
		(net "PCIE_10G_CPU_TX1_P")
	)
	(segment
		(start 148.89861 -79.068168)
		(end 148.784818 -79.011526)
		(width 0.127)
		(layer "In5.Cu")
		(net "PCIE_10G_CPU_TX1_P")
	)
	(segment
		(start 163.11753 -64.6684)
		(end 163.49853 -64.6684)
		(width 0.127)
		(layer "In5.Cu")
		(net "PCIE_10G_CPU_TX1_P")
	)
	(segment
		(start 156.589984 -64.81826)
		(end 156.970984 -64.81826)
		(width 0.127)
		(layer "In5.Cu")
		(net "PCIE_10G_CPU_TX1_P")
	)
	(segment
		(start 168.47185 -64.81826)
		(end 168.85285 -64.81826)
		(width 0.127)
		(layer "In5.Cu")
		(net "PCIE_10G_CPU_TX1_P")
	)
	(segment
		(start 164.47897 -64.6684)
		(end 164.85997 -64.6684)
		(width 0.127)
		(layer "In5.Cu")
		(net "PCIE_10G_CPU_TX1_P")
	)
	(segment
		(start 178.308 -64.262)
		(end 229.772464 -64.262)
		(width 0.127)
		(layer "In5.Cu")
		(net "PCIE_10G_CPU_TX1_P")
	)
	(segment
		(start 148.898864 -79.068168)
		(end 148.89861 -79.068168)
		(width 0.127)
		(layer "In5.Cu")
		(net "PCIE_10G_CPU_TX1_P")
	)
	(segment
		(start 157.951424 -64.81826)
		(end 158.332424 -64.81826)
		(width 0.127)
		(layer "In5.Cu")
		(net "PCIE_10G_CPU_TX1_P")
	)
	(segment
		(start 299.3517 -69.876924)
		(end 302.125888 -72.651112)
		(width 0.127)
		(layer "In5.Cu")
		(net "PCIE_10G_CPU_TX1_P")
	)
	(segment
		(start 165.84041 -64.6684)
		(end 168.17213 -64.6684)
		(width 0.127)
		(layer "In5.Cu")
		(net "PCIE_10G_CPU_TX1_P")
	)
	(segment
		(start 159.312864 -64.81826)
		(end 159.693864 -64.81826)
		(width 0.127)
		(layer "In5.Cu")
		(net "PCIE_10G_CPU_TX1_P")
	)
	(segment
		(start 158.632144 -64.6684)
		(end 159.013144 -64.6684)
		(width 0.127)
		(layer "In5.Cu")
		(net "PCIE_10G_CPU_TX1_P")
	)
	(segment
		(start 159.993584 -64.6684)
		(end 162.13709 -64.6684)
		(width 0.127)
		(layer "In5.Cu")
		(net "PCIE_10G_CPU_TX1_P")
	)
	(segment
		(start 149.449536 -78.24978)
		(end 149.069298 -79.011272)
		(width 0.127)
		(layer "In5.Cu")
		(net "PCIE_10G_CPU_TX1_P")
	)
	(segment
		(start 169.15257 -64.6684)
		(end 177.326544 -64.6684)
		(width 0.127)
		(layer "In5.Cu")
		(net "PCIE_10G_CPU_TX1_P")
	)
	(segment
		(start 149.214078 -69.889116)
		(end 152.656794 -66.4464)
		(width 0.127)
		(layer "In5.Cu")
		(net "PCIE_10G_CPU_TX1_P")
	)
	(segment
		(start 302.330358 -73.025)
		(end 302.330358 -73.152)
		(width 0.127)
		(layer "In5.Cu")
		(net "PCIE_10G_CPU_TX1_P")
	)
	(segment
		(start 162.43681 -64.81826)
		(end 162.81781 -64.81826)
		(width 0.127)
		(layer "In5.Cu")
		(net "PCIE_10G_CPU_TX1_P")
	)
	(segment
		(start 148.619972 -78.613508)
		(end 148.619972 -75.770994)
		(width 0.127)
		(layer "In5.Cu")
		(net "PCIE_10G_CPU_TX1_P")
	)
	(segment
		(start 163.79825 -64.81826)
		(end 164.17925 -64.81826)
		(width 0.127)
		(layer "In5.Cu")
		(net "PCIE_10G_CPU_TX1_P")
	)
	(segment
		(start 157.270704 -64.6684)
		(end 157.651704 -64.6684)
		(width 0.127)
		(layer "In5.Cu")
		(net "PCIE_10G_CPU_TX1_P")
	)
	(segment
		(start 148.45157 -72.204326)
		(end 148.45157 -71.729854)
		(width 0.127)
		(layer "In5.Cu")
		(net "PCIE_10G_CPU_TX1_P")
	)
	(segment
		(start 147.760182 -73.182988)
		(end 148.24837 -72.6948)
		(width 0.127)
		(layer "In5.Cu")
		(net "PCIE_10G_CPU_TX1_P")
	)
	(segment
		(start 231.6734 -65.0494)
		(end 235.1405 -68.5165)
		(width 0.127)
		(layer "In5.Cu")
		(net "PCIE_10G_CPU_TX1_P")
	)
	(segment
		(start 302.258476 -73.325482)
		(end 301.974758 -73.6092)
		(width 0.127)
		(layer "In5.Cu")
		(net "PCIE_10G_CPU_TX1_P")
	)
	(segment
		(start 236.88802 -69.2404)
		(end 297.815 -69.2404)
		(width 0.127)
		(layer "In5.Cu")
		(net "PCIE_10G_CPU_TX1_P")
	)
	(segment
		(start 155.448 -64.6684)
		(end 156.290264 -64.6684)
		(width 0.127)
		(layer "In5.Cu")
		(net "PCIE_10G_CPU_TX1_P")
	)
	(segment
		(start 148.314156 -75.032108)
		(end 147.760182 -74.478388)
		(width 0.127)
		(layer "In5.Cu")
		(net "PCIE_10G_CPU_TX1_P")
	)
	(arc
		(start 302.330358 -73.152)
		(mid 302.311681 -73.245897)
		(end 302.258476 -73.325482)
		(width 0.127)
		(layer "In5.Cu")
		(net "PCIE_10G_CPU_TX1_P")
	)
	(arc
		(start 162.96767 -64.74333)
		(mid 163.034415 -64.689506)
		(end 163.11753 -64.6684)
		(width 0.127)
		(layer "In5.Cu")
		(net "PCIE_10G_CPU_TX1_P")
	)
	(arc
		(start 157.120844 -64.74333)
		(mid 157.187589 -64.689506)
		(end 157.270704 -64.6684)
		(width 0.127)
		(layer "In5.Cu")
		(net "PCIE_10G_CPU_TX1_P")
	)
	(arc
		(start 148.784818 -79.011526)
		(mid 148.6628 -78.828914)
		(end 148.619972 -78.613508)
		(width 0.127)
		(layer "In5.Cu")
		(net "PCIE_10G_CPU_TX1_P")
	)
	(arc
		(start 165.54069 -64.81826)
		(mid 165.623805 -64.797177)
		(end 165.69055 -64.74333)
		(width 0.127)
		(layer "In5.Cu")
		(net "PCIE_10G_CPU_TX1_P")
	)
	(arc
		(start 235.1405 -68.5165)
		(mid 235.942268 -69.052254)
		(end 236.88802 -69.2404)
		(width 0.127)
		(layer "In5.Cu")
		(net "PCIE_10G_CPU_TX1_P")
	)
	(arc
		(start 163.49853 -64.6684)
		(mid 163.581645 -64.689483)
		(end 163.64839 -64.74333)
		(width 0.127)
		(layer "In5.Cu")
		(net "PCIE_10G_CPU_TX1_P")
	)
	(arc
		(start 148.619972 -75.770994)
		(mid 148.540532 -75.37115)
		(end 148.314156 -75.032108)
		(width 0.127)
		(layer "In5.Cu")
		(net "PCIE_10G_CPU_TX1_P")
	)
	(arc
		(start 165.00983 -64.74333)
		(mid 165.076575 -64.797154)
		(end 165.15969 -64.81826)
		(width 0.127)
		(layer "In5.Cu")
		(net "PCIE_10G_CPU_TX1_P")
	)
	(arc
		(start 169.00271 -64.74333)
		(mid 169.069455 -64.689506)
		(end 169.15257 -64.6684)
		(width 0.127)
		(layer "In5.Cu")
		(net "PCIE_10G_CPU_TX1_P")
	)
	(arc
		(start 149.069298 -79.011272)
		(mid 148.995884 -79.075001)
		(end 148.898864 -79.068168)
		(width 0.127)
		(layer "In5.Cu")
		(net "PCIE_10G_CPU_TX1_P")
	)
	(arc
		(start 156.290264 -64.6684)
		(mid 156.3734 -64.689464)
		(end 156.440124 -64.74333)
		(width 0.127)
		(layer "In5.Cu")
		(net "PCIE_10G_CPU_TX1_P")
	)
	(arc
		(start 297.815 -69.2404)
		(mid 298.646657 -69.405827)
		(end 299.3517 -69.876924)
		(width 0.127)
		(layer "In5.Cu")
		(net "PCIE_10G_CPU_TX1_P")
	)
	(arc
		(start 168.85285 -64.81826)
		(mid 168.935986 -64.797196)
		(end 169.00271 -64.74333)
		(width 0.127)
		(layer "In5.Cu")
		(net "PCIE_10G_CPU_TX1_P")
	)
	(arc
		(start 177.917602 -64.423544)
		(mid 178.096733 -64.303945)
		(end 178.308 -64.262)
		(width 0.127)
		(layer "In5.Cu")
		(net "PCIE_10G_CPU_TX1_P")
	)
	(arc
		(start 168.17213 -64.6684)
		(mid 168.255266 -64.689464)
		(end 168.32199 -64.74333)
		(width 0.127)
		(layer "In5.Cu")
		(net "PCIE_10G_CPU_TX1_P")
	)
	(arc
		(start 158.482284 -64.74333)
		(mid 158.549029 -64.689506)
		(end 158.632144 -64.6684)
		(width 0.127)
		(layer "In5.Cu")
		(net "PCIE_10G_CPU_TX1_P")
	)
	(arc
		(start 156.970984 -64.81826)
		(mid 157.05412 -64.797196)
		(end 157.120844 -64.74333)
		(width 0.127)
		(layer "In5.Cu")
		(net "PCIE_10G_CPU_TX1_P")
	)
	(arc
		(start 302.21047 -72.735948)
		(mid 302.299166 -72.868551)
		(end 302.330358 -73.025)
		(width 0.127)
		(layer "In5.Cu")
		(net "PCIE_10G_CPU_TX1_P")
	)
	(arc
		(start 153.718514 -65.384934)
		(mid 154.511994 -64.854655)
		(end 155.448 -64.6684)
		(width 0.127)
		(layer "In5.Cu")
		(net "PCIE_10G_CPU_TX1_P")
	)
	(arc
		(start 177.326544 -64.6684)
		(mid 177.646434 -64.60477)
		(end 177.917602 -64.423544)
		(width 0.127)
		(layer "In5.Cu")
		(net "PCIE_10G_CPU_TX1_P")
	)
	(arc
		(start 168.32199 -64.74333)
		(mid 168.388735 -64.797154)
		(end 168.47185 -64.81826)
		(width 0.127)
		(layer "In5.Cu")
		(net "PCIE_10G_CPU_TX1_P")
	)
	(arc
		(start 148.24837 -72.6948)
		(mid 148.398731 -72.469769)
		(end 148.45157 -72.204326)
		(width 0.127)
		(layer "In5.Cu")
		(net "PCIE_10G_CPU_TX1_P")
	)
	(arc
		(start 163.64839 -64.74333)
		(mid 163.715135 -64.797154)
		(end 163.79825 -64.81826)
		(width 0.127)
		(layer "In5.Cu")
		(net "PCIE_10G_CPU_TX1_P")
	)
	(arc
		(start 158.332424 -64.81826)
		(mid 158.41556 -64.797196)
		(end 158.482284 -64.74333)
		(width 0.127)
		(layer "In5.Cu")
		(net "PCIE_10G_CPU_TX1_P")
	)
	(arc
		(start 165.69055 -64.74333)
		(mid 165.757295 -64.689506)
		(end 165.84041 -64.6684)
		(width 0.127)
		(layer "In5.Cu")
		(net "PCIE_10G_CPU_TX1_P")
	)
	(arc
		(start 147.760182 -74.478388)
		(mid 147.491896 -73.830688)
		(end 147.760182 -73.182988)
		(width 0.127)
		(layer "In5.Cu")
		(net "PCIE_10G_CPU_TX1_P")
	)
	(arc
		(start 148.45157 -71.729854)
		(mid 148.649677 -70.73361)
		(end 149.214078 -69.889116)
		(width 0.127)
		(layer "In5.Cu")
		(net "PCIE_10G_CPU_TX1_P")
	)
	(arc
		(start 156.440124 -64.74333)
		(mid 156.506869 -64.797154)
		(end 156.589984 -64.81826)
		(width 0.127)
		(layer "In5.Cu")
		(net "PCIE_10G_CPU_TX1_P")
	)
	(arc
		(start 159.693864 -64.81826)
		(mid 159.777 -64.797196)
		(end 159.843724 -64.74333)
		(width 0.127)
		(layer "In5.Cu")
		(net "PCIE_10G_CPU_TX1_P")
	)
	(arc
		(start 162.13709 -64.6684)
		(mid 162.220205 -64.689483)
		(end 162.28695 -64.74333)
		(width 0.127)
		(layer "In5.Cu")
		(net "PCIE_10G_CPU_TX1_P")
	)
	(arc
		(start 157.801564 -64.74333)
		(mid 157.868309 -64.797154)
		(end 157.951424 -64.81826)
		(width 0.127)
		(layer "In5.Cu")
		(net "PCIE_10G_CPU_TX1_P")
	)
	(arc
		(start 159.843724 -64.74333)
		(mid 159.910469 -64.689506)
		(end 159.993584 -64.6684)
		(width 0.127)
		(layer "In5.Cu")
		(net "PCIE_10G_CPU_TX1_P")
	)
	(arc
		(start 164.17925 -64.81826)
		(mid 164.262365 -64.797177)
		(end 164.32911 -64.74333)
		(width 0.127)
		(layer "In5.Cu")
		(net "PCIE_10G_CPU_TX1_P")
	)
	(arc
		(start 164.85997 -64.6684)
		(mid 164.943085 -64.689483)
		(end 165.00983 -64.74333)
		(width 0.127)
		(layer "In5.Cu")
		(net "PCIE_10G_CPU_TX1_P")
	)
	(arc
		(start 159.163004 -64.74333)
		(mid 159.229749 -64.797154)
		(end 159.312864 -64.81826)
		(width 0.127)
		(layer "In5.Cu")
		(net "PCIE_10G_CPU_TX1_P")
	)
	(arc
		(start 229.772464 -64.262)
		(mid 230.801246 -64.466637)
		(end 231.6734 -65.0494)
		(width 0.127)
		(layer "In5.Cu")
		(net "PCIE_10G_CPU_TX1_P")
	)
	(arc
		(start 164.32911 -64.74333)
		(mid 164.395855 -64.689506)
		(end 164.47897 -64.6684)
		(width 0.127)
		(layer "In5.Cu")
		(net "PCIE_10G_CPU_TX1_P")
	)
	(arc
		(start 162.28695 -64.74333)
		(mid 162.353695 -64.797154)
		(end 162.43681 -64.81826)
		(width 0.127)
		(layer "In5.Cu")
		(net "PCIE_10G_CPU_TX1_P")
	)
	(arc
		(start 162.81781 -64.81826)
		(mid 162.900925 -64.797177)
		(end 162.96767 -64.74333)
		(width 0.127)
		(layer "In5.Cu")
		(net "PCIE_10G_CPU_TX1_P")
	)
	(arc
		(start 157.651704 -64.6684)
		(mid 157.73484 -64.689464)
		(end 157.801564 -64.74333)
		(width 0.127)
		(layer "In5.Cu")
		(net "PCIE_10G_CPU_TX1_P")
	)
	(arc
		(start 159.013144 -64.6684)
		(mid 159.09628 -64.689464)
		(end 159.163004 -64.74333)
		(width 0.127)
		(layer "In5.Cu")
		(net "PCIE_10G_CPU_TX1_P")
	)
	(segment
		(start 289.177222 -175.440086)
		(end 289.523932 -175.786796)
		(width 0.3556)
		(layer "F.Cu")
		(net "P1V26_STBY")
	)
	(segment
		(start 297.634914 -175.440086)
		(end 297.637454 -175.440086)
		(width 0.3556)
		(layer "F.Cu")
		(net "P1V26_STBY")
	)
	(segment
		(start 288.83483 -178.640232)
		(end 288.439606 -178.245008)
		(width 0.3556)
		(layer "F.Cu")
		(net "P1V26_STBY")
	)
	(segment
		(start 276.479 -193.3702)
		(end 277.1775 -194.0687)
		(width 0.635)
		(layer "F.Cu")
		(net "P1V26_STBY")
	)
	(segment
		(start 297.634914 -177.837846)
		(end 298.0309 -177.44186)
		(width 0.3556)
		(layer "F.Cu")
		(net "P1V26_STBY")
	)
	(segment
		(start 297.634914 -178.640232)
		(end 297.634914 -177.840132)
		(width 0.3556)
		(layer "F.Cu")
		(net "P1V26_STBY")
	)
	(segment
		(start 290.056316 -171.851574)
		(end 290.434776 -171.473114)
		(width 0.3556)
		(layer "F.Cu")
		(net "P1V26_STBY")
	)
	(segment
		(start 287.608772 -180.667152)
		(end 287.633918 -180.642006)
		(width 0.3556)
		(layer "F.Cu")
		(net "P1V26_STBY")
	)
	(segment
		(start 287.66008 -182.26532)
		(end 287.66008 -182.255668)
		(width 0.3556)
		(layer "F.Cu")
		(net "P1V26_STBY")
	)
	(segment
		(start 288.83483 -174.64024)
		(end 289.306 -174.16907)
		(width 0.3556)
		(layer "F.Cu")
		(net "P1V26_STBY")
	)
	(segment
		(start 287.234884 -181.040024)
		(end 287.607756 -180.667152)
		(width 0.3556)
		(layer "F.Cu")
		(net "P1V26_STBY")
	)
	(segment
		(start 288.034984 -182.640224)
		(end 287.66008 -182.26532)
		(width 0.3556)
		(layer "F.Cu")
		(net "P1V26_STBY")
	)
	(segment
		(start 292.443408 -180.639212)
		(end 292.044374 -180.240178)
		(width 0.3556)
		(layer "F.Cu")
		(net "P1V26_STBY")
	)
	(segment
		(start 292.034976 -180.240178)
		(end 290.407598 -178.6128)
		(width 0.3556)
		(layer "F.Cu")
		(net "P1V26_STBY")
	)
	(segment
		(start 290.434776 -171.473114)
		(end 290.434776 -171.440094)
		(width 0.3556)
		(layer "F.Cu")
		(net "P1V26_STBY")
	)
	(segment
		(start 292.834822 -180.240178)
		(end 292.834822 -180.247798)
		(width 0.3556)
		(layer "F.Cu")
		(net "P1V26_STBY")
	)
	(segment
		(start 290.467796 -171.440094)
		(end 290.434776 -171.473114)
		(width 0.3556)
		(layer "F.Cu")
		(net "P1V26_STBY")
	)
	(segment
		(start 297.634914 -174.64024)
		(end 297.644312 -174.64024)
		(width 0.3556)
		(layer "F.Cu")
		(net "P1V26_STBY")
	)
	(segment
		(start 297.637454 -175.440086)
		(end 298.040806 -175.036734)
		(width 0.3556)
		(layer "F.Cu")
		(net "P1V26_STBY")
	)
	(segment
		(start 277.1775 -194.2465)
		(end 277.622 -194.691)
		(width 0.635)
		(layer "F.Cu")
		(net "P1V26_STBY")
	)
	(segment
		(start 288.439606 -178.235356)
		(end 288.83483 -177.840132)
		(width 0.3556)
		(layer "F.Cu")
		(net "P1V26_STBY")
	)
	(segment
		(start 297.634914 -177.840132)
		(end 297.634914 -177.837846)
		(width 0.3556)
		(layer "F.Cu")
		(net "P1V26_STBY")
	)
	(segment
		(start 297.644312 -174.64024)
		(end 298.040806 -175.036734)
		(width 0.3556)
		(layer "F.Cu")
		(net "P1V26_STBY")
	)
	(segment
		(start 288.905188 -178.640232)
		(end 288.83483 -178.640232)
		(width 0.3556)
		(layer "F.Cu")
		(net "P1V26_STBY")
	)
	(segment
		(start 288.439606 -178.245008)
		(end 288.439606 -178.235356)
		(width 0.3556)
		(layer "F.Cu")
		(net "P1V26_STBY")
	)
	(segment
		(start 290.407598 -178.6128)
		(end 288.93262 -178.6128)
		(width 0.3556)
		(layer "F.Cu")
		(net "P1V26_STBY")
	)
	(segment
		(start 292.834822 -180.247798)
		(end 292.443408 -180.639212)
		(width 0.3556)
		(layer "F.Cu")
		(net "P1V26_STBY")
	)
	(segment
		(start 288.93262 -178.6128)
		(end 288.905188 -178.640232)
		(width 0.3556)
		(layer "F.Cu")
		(net "P1V26_STBY")
	)
	(segment
		(start 287.66008 -182.255668)
		(end 287.644586 -182.240174)
		(width 0.3556)
		(layer "F.Cu")
		(net "P1V26_STBY")
	)
	(segment
		(start 291.234876 -171.440094)
		(end 290.467796 -171.440094)
		(width 0.3556)
		(layer "F.Cu")
		(net "P1V26_STBY")
	)
	(segment
		(start 292.044374 -180.240178)
		(end 292.034976 -180.240178)
		(width 0.3556)
		(layer "F.Cu")
		(net "P1V26_STBY")
	)
	(segment
		(start 277.1775 -194.0687)
		(end 277.1775 -194.2465)
		(width 0.635)
		(layer "F.Cu")
		(net "P1V26_STBY")
	)
	(segment
		(start 288.83483 -175.440086)
		(end 289.177222 -175.440086)
		(width 0.3556)
		(layer "F.Cu")
		(net "P1V26_STBY")
	)
	(segment
		(start 287.607756 -180.667152)
		(end 287.608772 -180.667152)
		(width 0.3556)
		(layer "F.Cu")
		(net "P1V26_STBY")
	)
	(segment
		(start 289.306 -174.16907)
		(end 289.306 -174.159418)
		(width 0.3556)
		(layer "F.Cu")
		(net "P1V26_STBY")
	)
	(via
		(at 215.9 -198.882)
		(size 0.7112)
		(drill 0.4064)
		(layers "F.Cu" "B.Cu")
		(net "P1V26_STBY")
	)
	(via
		(at 280.035 -193.675)
		(size 0.7112)
		(drill 0.4064)
		(layers "F.Cu" "B.Cu")
		(net "P1V26_STBY")
	)
	(via
		(at 298.0309 -177.44186)
		(size 0.508)
		(drill 0.254)
		(layers "F.Cu" "B.Cu")
		(net "P1V26_STBY")
	)
	(via
		(at 215.9 -197.612)
		(size 0.7112)
		(drill 0.4064)
		(layers "F.Cu" "B.Cu")
		(net "P1V26_STBY")
	)
	(via
		(at 288.439606 -178.235356)
		(size 0.508)
		(drill 0.254)
		(layers "F.Cu" "B.Cu")
		(net "P1V26_STBY")
	)
	(via
		(at 217.043 -198.882)
		(size 0.7112)
		(drill 0.4064)
		(layers "F.Cu" "B.Cu")
		(net "P1V26_STBY")
	)
	(via
		(at 263.017 -210.82)
		(size 0.7112)
		(drill 0.4064)
		(layers "F.Cu" "B.Cu")
		(net "P1V26_STBY")
	)
	(via
		(at 127.254 -222.504)
		(size 0.7112)
		(drill 0.4064)
		(layers "F.Cu" "B.Cu")
		(net "P1V26_STBY")
	)
	(via
		(at 127.127 -219.329)
		(size 0.7112)
		(drill 0.3556)
		(layers "F.Cu" "B.Cu")
		(net "P1V26_STBY")
	)
	(via
		(at 280.035 -194.9196)
		(size 0.7112)
		(drill 0.4064)
		(layers "F.Cu" "B.Cu")
		(net "P1V26_STBY")
	)
	(via
		(at 278.765 -194.9196)
		(size 0.7112)
		(drill 0.4064)
		(layers "F.Cu" "B.Cu")
		(net "P1V26_STBY")
	)
	(via
		(at 264.16 -210.82)
		(size 0.7112)
		(drill 0.4064)
		(layers "F.Cu" "B.Cu")
		(net "P1V26_STBY")
	)
	(via
		(at 154.686 -220.98)
		(size 0.7112)
		(drill 0.4064)
		(layers "F.Cu" "B.Cu")
		(net "P1V26_STBY")
	)
	(via
		(at 267.5636 -209.677)
		(size 0.7112)
		(drill 0.4064)
		(layers "F.Cu" "B.Cu")
		(net "P1V26_STBY")
	)
	(via
		(at 266.446 -209.677)
		(size 0.7112)
		(drill 0.4064)
		(layers "F.Cu" "B.Cu")
		(net "P1V26_STBY")
	)
	(via
		(at 126.746 -224.282)
		(size 0.7112)
		(drill 0.4064)
		(layers "F.Cu" "B.Cu")
		(net "P1V26_STBY")
	)
	(via
		(at 263.017 -209.677)
		(size 0.7112)
		(drill 0.4064)
		(layers "F.Cu" "B.Cu")
		(net "P1V26_STBY")
	)
	(via
		(at 153.162 -197.739)
		(size 0.7112)
		(drill 0.4064)
		(layers "F.Cu" "B.Cu")
		(net "P1V26_STBY")
	)
	(via
		(at 153.162 -199.39)
		(size 0.7112)
		(drill 0.4064)
		(layers "F.Cu" "B.Cu")
		(net "P1V26_STBY")
	)
	(via
		(at 298.040806 -175.036734)
		(size 0.508)
		(drill 0.254)
		(layers "F.Cu" "B.Cu")
		(net "P1V26_STBY")
	)
	(via
		(at 154.813 -197.739)
		(size 0.7112)
		(drill 0.4064)
		(layers "F.Cu" "B.Cu")
		(net "P1V26_STBY")
	)
	(via
		(at 292.443408 -180.639212)
		(size 0.508)
		(drill 0.254)
		(layers "F.Cu" "B.Cu")
		(net "P1V26_STBY")
	)
	(via
		(at 217.043 -197.612)
		(size 0.7112)
		(drill 0.4064)
		(layers "F.Cu" "B.Cu")
		(net "P1V26_STBY")
	)
	(via
		(at 216.9668 -194.2338)
		(size 0.7112)
		(drill 0.3556)
		(layers "F.Cu" "B.Cu")
		(net "P1V26_STBY")
	)
	(via
		(at 125.73 -224.282)
		(size 0.7112)
		(drill 0.4064)
		(layers "F.Cu" "B.Cu")
		(net "P1V26_STBY")
	)
	(via
		(at 287.633918 -180.642006)
		(size 0.508)
		(drill 0.254)
		(layers "F.Cu" "B.Cu")
		(net "P1V26_STBY")
	)
	(via
		(at 289.523932 -175.786796)
		(size 0.508)
		(drill 0.254)
		(layers "F.Cu" "B.Cu")
		(net "P1V26_STBY")
	)
	(via
		(at 287.644586 -182.240174)
		(size 0.508)
		(drill 0.254)
		(layers "F.Cu" "B.Cu")
		(net "P1V26_STBY")
	)
	(via
		(at 265.303 -209.677)
		(size 0.7112)
		(drill 0.4064)
		(layers "F.Cu" "B.Cu")
		(net "P1V26_STBY")
	)
	(via
		(at 277.622 -194.691)
		(size 0.7112)
		(drill 0.4064)
		(layers "F.Cu" "B.Cu")
		(net "P1V26_STBY")
	)
	(via
		(at 154.739594 -222.913194)
		(size 0.7112)
		(drill 0.4064)
		(layers "F.Cu" "B.Cu")
		(net "P1V26_STBY")
	)
	(via
		(at 289.306 -174.159418)
		(size 0.508)
		(drill 0.254)
		(layers "F.Cu" "B.Cu")
		(net "P1V26_STBY")
	)
	(via
		(at 290.056316 -171.851574)
		(size 0.508)
		(drill 0.254)
		(layers "F.Cu" "B.Cu")
		(net "P1V26_STBY")
	)
	(via
		(at 264.16 -209.677)
		(size 0.7112)
		(drill 0.4064)
		(layers "F.Cu" "B.Cu")
		(net "P1V26_STBY")
	)
	(via
		(at 268.224 -203.581)
		(size 0.7112)
		(drill 0.3556)
		(layers "F.Cu" "B.Cu")
		(net "P1V26_STBY")
	)
	(via
		(at 278.765 -193.675)
		(size 0.7112)
		(drill 0.4064)
		(layers "F.Cu" "B.Cu")
		(net "P1V26_STBY")
	)
	(via
		(at 153.416 -222.885)
		(size 0.7112)
		(drill 0.4064)
		(layers "F.Cu" "B.Cu")
		(net "P1V26_STBY")
	)
	(segment
		(start 288.997644 -178.235356)
		(end 288.439606 -178.235356)
		(width 0.508)
		(layer "B.Cu")
		(net "P1V26_STBY")
	)
	(segment
		(start 289.742372 -174.824136)
		(end 289.742372 -175.568356)
		(width 0.508)
		(layer "B.Cu")
		(net "P1V26_STBY")
	)
	(segment
		(start 290.771072 -172.093636)
		(end 290.449254 -171.848018)
		(width 0.3048)
		(layer "B.Cu")
		(net "P1V26_STBY")
	)
	(segment
		(start 289.306 -177.927)
		(end 288.997644 -178.235356)
		(width 0.508)
		(layer "B.Cu")
		(net "P1V26_STBY")
	)
	(segment
		(start 292.354 -179.832)
		(end 292.43528 -179.91328)
		(width 0.6096)
		(layer "B.Cu")
		(net "P1V26_STBY")
	)
	(segment
		(start 290.059872 -171.848018)
		(end 290.056316 -171.851574)
		(width 0.3048)
		(layer "B.Cu")
		(net "P1V26_STBY")
	)
	(segment
		(start 290.449254 -171.848018)
		(end 290.059872 -171.848018)
		(width 0.3048)
		(layer "B.Cu")
		(net "P1V26_STBY")
	)
	(segment
		(start 292.43528 -179.91328)
		(end 292.43528 -180.631084)
		(width 0.6096)
		(layer "B.Cu")
		(net "P1V26_STBY")
	)
	(segment
		(start 292.43528 -180.631084)
		(end 292.443408 -180.639212)
		(width 0.6096)
		(layer "B.Cu")
		(net "P1V26_STBY")
	)
	(segment
		(start 297.235372 -177.872136)
		(end 297.600624 -177.872136)
		(width 0.5588)
		(layer "B.Cu")
		(net "P1V26_STBY")
	)
	(segment
		(start 289.742372 -175.568356)
		(end 289.523932 -175.786796)
		(width 0.508)
		(layer "B.Cu")
		(net "P1V26_STBY")
	)
	(segment
		(start 297.600624 -177.872136)
		(end 298.0309 -177.44186)
		(width 0.5588)
		(layer "B.Cu")
		(net "P1V26_STBY")
	)
	(segment
		(start 297.999404 -175.078136)
		(end 298.040806 -175.036734)
		(width 0.6096)
		(layer "B.Cu")
		(net "P1V26_STBY")
	)
	(segment
		(start 297.235372 -175.078136)
		(end 297.999404 -175.078136)
		(width 0.6096)
		(layer "B.Cu")
		(net "P1V26_STBY")
	)
	(segment
		(start 294.60317 -79.46517)
		(end 294.58793 -79.48041)
		(width 0.1397)
		(layer "F.Cu")
		(net "CLK_100M_CLKBUFF_ENET1_DP")
	)
	(segment
		(start 294.71112 -74.364342)
		(end 294.71112 -79.204566)
		(width 0.1397)
		(layer "F.Cu")
		(net "CLK_100M_CLKBUFF_ENET1_DP")
	)
	(segment
		(start 300.063916 -67.865244)
		(end 295.52138 -72.40778)
		(width 0.1397)
		(layer "F.Cu")
		(net "CLK_100M_CLKBUFF_ENET1_DP")
	)
	(segment
		(start 293.718488 -79.519018)
		(end 293.6494 -79.44993)
		(width 0.1397)
		(layer "F.Cu")
		(net "CLK_100M_CLKBUFF_ENET1_DP")
	)
	(segment
		(start 301.908464 -67.47129)
		(end 301.0154 -67.47129)
		(width 0.1397)
		(layer "F.Cu")
		(net "CLK_100M_CLKBUFF_ENET1_DP")
	)
	(via
		(at 293.6494 -79.44993)
		(size 0.5588)
		(drill 0.3048)
		(layers "F.Cu" "B.Cu")
		(net "CLK_100M_CLKBUFF_ENET1_DP")
	)
	(arc
		(start 294.58793 -79.48041)
		(mid 294.367094 -79.627968)
		(end 294.1066 -79.6798)
		(width 0.1397)
		(layer "F.Cu")
		(net "CLK_100M_CLKBUFF_ENET1_DP")
	)
	(arc
		(start 294.1066 -79.6798)
		(mid 293.896547 -79.638018)
		(end 293.718488 -79.519018)
		(width 0.1397)
		(layer "F.Cu")
		(net "CLK_100M_CLKBUFF_ENET1_DP")
	)
	(arc
		(start 302.874172 -67.07124)
		(mid 302.431101 -67.36729)
		(end 301.908464 -67.47129)
		(width 0.1397)
		(layer "F.Cu")
		(net "CLK_100M_CLKBUFF_ENET1_DP")
	)
	(arc
		(start 294.71112 -79.204566)
		(mid 294.683065 -79.345606)
		(end 294.60317 -79.46517)
		(width 0.1397)
		(layer "F.Cu")
		(net "CLK_100M_CLKBUFF_ENET1_DP")
	)
	(arc
		(start 295.52138 -72.40778)
		(mid 294.921654 -73.305473)
		(end 294.71112 -74.364342)
		(width 0.1397)
		(layer "F.Cu")
		(net "CLK_100M_CLKBUFF_ENET1_DP")
	)
	(arc
		(start 301.0154 -67.47129)
		(mid 300.500455 -67.573607)
		(end 300.063916 -67.865244)
		(width 0.1397)
		(layer "F.Cu")
		(net "CLK_100M_CLKBUFF_ENET1_DP")
	)
	(segment
		(start 187.2488 -74.137012)
		(end 187.2488 -73.6346)
		(width 0.127)
		(layer "In5.Cu")
		(net "CLK_100M_CLKBUFF_ENET1_DP")
	)
	(segment
		(start 186.32932 -78.366874)
		(end 186.32932 -75.54849)
		(width 0.127)
		(layer "In5.Cu")
		(net "CLK_100M_CLKBUFF_ENET1_DP")
	)
	(segment
		(start 185.74639 -79.16545)
		(end 186.17692 -78.73492)
		(width 0.127)
		(layer "In5.Cu")
		(net "CLK_100M_CLKBUFF_ENET1_DP")
	)
	(segment
		(start 185.411364 -79.2226)
		(end 185.608468 -79.2226)
		(width 0.127)
		(layer "In5.Cu")
		(net "CLK_100M_CLKBUFF_ENET1_DP")
	)
	(segment
		(start 188.453522 -72.5424)
		(end 225.19894 -72.5424)
		(width 0.127)
		(layer "In5.Cu")
		(net "CLK_100M_CLKBUFF_ENET1_DP")
	)
	(segment
		(start 233.842052 -79.7306)
		(end 293.116 -79.7306)
		(width 0.127)
		(layer "In5.Cu")
		(net "CLK_100M_CLKBUFF_ENET1_DP")
	)
	(segment
		(start 293.547292 -79.551784)
		(end 293.6494 -79.44993)
		(width 0.127)
		(layer "In5.Cu")
		(net "CLK_100M_CLKBUFF_ENET1_DP")
	)
	(segment
		(start 185.450226 -78.24978)
		(end 185.166 -78.534006)
		(width 0.127)
		(layer "In5.Cu")
		(net "CLK_100M_CLKBUFF_ENET1_DP")
	)
	(segment
		(start 187.462414 -73.118726)
		(end 187.74537 -72.83577)
		(width 0.127)
		(layer "In5.Cu")
		(net "CLK_100M_CLKBUFF_ENET1_DP")
	)
	(segment
		(start 186.55665 -74.99985)
		(end 187.12815 -74.42835)
		(width 0.127)
		(layer "In5.Cu")
		(net "CLK_100M_CLKBUFF_ENET1_DP")
	)
	(segment
		(start 226.203002 -72.958198)
		(end 232.362502 -79.117698)
		(width 0.127)
		(layer "In5.Cu")
		(net "CLK_100M_CLKBUFF_ENET1_DP")
	)
	(arc
		(start 185.608468 -79.2226)
		(mid 185.683119 -79.207751)
		(end 185.74639 -79.16545)
		(width 0.127)
		(layer "In5.Cu")
		(net "CLK_100M_CLKBUFF_ENET1_DP")
	)
	(arc
		(start 185.166 -78.534006)
		(mid 185.044377 -78.82754)
		(end 185.166 -79.121)
		(width 0.127)
		(layer "In5.Cu")
		(net "CLK_100M_CLKBUFF_ENET1_DP")
	)
	(arc
		(start 186.32932 -75.54849)
		(mid 186.388455 -75.251579)
		(end 186.55665 -74.99985)
		(width 0.127)
		(layer "In5.Cu")
		(net "CLK_100M_CLKBUFF_ENET1_DP")
	)
	(arc
		(start 185.166 -79.121)
		(mid 185.278574 -79.19622)
		(end 185.411364 -79.2226)
		(width 0.127)
		(layer "In5.Cu")
		(net "CLK_100M_CLKBUFF_ENET1_DP")
	)
	(arc
		(start 225.19894 -72.5424)
		(mid 225.742351 -72.650397)
		(end 226.203002 -72.958198)
		(width 0.127)
		(layer "In5.Cu")
		(net "CLK_100M_CLKBUFF_ENET1_DP")
	)
	(arc
		(start 187.12815 -74.42835)
		(mid 187.217434 -74.294682)
		(end 187.2488 -74.137012)
		(width 0.127)
		(layer "In5.Cu")
		(net "CLK_100M_CLKBUFF_ENET1_DP")
	)
	(arc
		(start 186.17692 -78.73492)
		(mid 186.289749 -78.566059)
		(end 186.32932 -78.366874)
		(width 0.127)
		(layer "In5.Cu")
		(net "CLK_100M_CLKBUFF_ENET1_DP")
	)
	(arc
		(start 293.116 -79.7306)
		(mid 293.349425 -79.684075)
		(end 293.547292 -79.551784)
		(width 0.127)
		(layer "In5.Cu")
		(net "CLK_100M_CLKBUFF_ENET1_DP")
	)
	(arc
		(start 187.74537 -72.83577)
		(mid 188.070272 -72.618648)
		(end 188.453522 -72.5424)
		(width 0.127)
		(layer "In5.Cu")
		(net "CLK_100M_CLKBUFF_ENET1_DP")
	)
	(arc
		(start 187.2488 -73.6346)
		(mid 187.304314 -73.355423)
		(end 187.462414 -73.118726)
		(width 0.127)
		(layer "In5.Cu")
		(net "CLK_100M_CLKBUFF_ENET1_DP")
	)
	(arc
		(start 232.362502 -79.117698)
		(mid 233.041325 -79.571273)
		(end 233.842052 -79.7306)
		(width 0.127)
		(layer "In5.Cu")
		(net "CLK_100M_CLKBUFF_ENET1_DP")
	)
	(segment
		(start 275.336 -190.017146)
		(end 273.532854 -190.017146)
		(width 0.1143)
		(layer "F.Cu")
		(net "BMC0_SRST_N")
	)
	(segment
		(start 286.434784 -181.840124)
		(end 286.425386 -181.840124)
		(width 0.1143)
		(layer "F.Cu")
		(net "BMC0_SRST_N")
	)
	(segment
		(start 273.066764 -190.483236)
		(end 273.041872 -190.483236)
		(width 0.1143)
		(layer "F.Cu")
		(net "BMC0_SRST_N")
	)
	(segment
		(start 273.041872 -190.483236)
		(end 273.031712 -190.493396)
		(width 0.1143)
		(layer "F.Cu")
		(net "BMC0_SRST_N")
	)
	(segment
		(start 273.031712 -190.493396)
		(end 271.901412 -190.493396)
		(width 0.1143)
		(layer "F.Cu")
		(net "BMC0_SRST_N")
	)
	(segment
		(start 273.532854 -190.017146)
		(end 273.066764 -190.483236)
		(width 0.1143)
		(layer "F.Cu")
		(net "BMC0_SRST_N")
	)
	(segment
		(start 286.425386 -181.840124)
		(end 286.034734 -181.449472)
		(width 0.1143)
		(layer "F.Cu")
		(net "BMC0_SRST_N")
	)
	(via
		(at 277.86965 -188.595)
		(size 0.7112)
		(drill 0.3556)
		(layers "F.Cu" "B.Cu")
		(net "BMC0_SRST_N")
	)
	(via
		(at 275.336 -190.017146)
		(size 0.5588)
		(drill 0.3048)
		(layers "F.Cu" "B.Cu")
		(net "BMC0_SRST_N")
	)
	(via
		(at 286.034734 -181.449472)
		(size 0.508)
		(drill 0.254)
		(layers "F.Cu" "B.Cu")
		(net "BMC0_SRST_N")
	)
	(segment
		(start 285.163006 -182.3212)
		(end 278.889206 -188.595)
		(width 0.1143)
		(layer "B.Cu")
		(net "BMC0_SRST_N")
	)
	(segment
		(start 286.034734 -181.449472)
		(end 285.684976 -181.79923)
		(width 0.1143)
		(layer "B.Cu")
		(net "BMC0_SRST_N")
	)
	(segment
		(start 285.684976 -181.79923)
		(end 285.684976 -181.802024)
		(width 0.1143)
		(layer "B.Cu")
		(net "BMC0_SRST_N")
	)
	(segment
		(start 277.86965 -188.595)
		(end 276.707346 -188.595)
		(width 0.1143)
		(layer "B.Cu")
		(net "BMC0_SRST_N")
	)
	(segment
		(start 276.707346 -188.595)
		(end 275.336 -189.966346)
		(width 0.1143)
		(layer "B.Cu")
		(net "BMC0_SRST_N")
	)
	(segment
		(start 278.889206 -188.595)
		(end 277.86965 -188.595)
		(width 0.1143)
		(layer "B.Cu")
		(net "BMC0_SRST_N")
	)
	(segment
		(start 285.684976 -181.802024)
		(end 285.1658 -182.3212)
		(width 0.1143)
		(layer "B.Cu")
		(net "BMC0_SRST_N")
	)
	(segment
		(start 285.1658 -182.3212)
		(end 285.163006 -182.3212)
		(width 0.1143)
		(layer "B.Cu")
		(net "BMC0_SRST_N")
	)
	(segment
		(start 275.336 -189.966346)
		(end 275.336 -190.017146)
		(width 0.1143)
		(layer "B.Cu")
		(net "BMC0_SRST_N")
	)
	(segment
		(start 306.99837 -73.8251)
		(end 305.41722 -73.8251)
		(width 0.1397)
		(layer "F.Cu")
		(net "PCIE_10G_CPU_TX1_N")
	)
	(segment
		(start 302.741076 -73.393554)
		(end 302.956722 -73.6092)
		(width 0.1397)
		(layer "F.Cu")
		(net "PCIE_10G_CPU_TX1_N")
	)
	(segment
		(start 303.678336 -72.7329)
		(end 303.166526 -72.7329)
		(width 0.1397)
		(layer "F.Cu")
		(net "PCIE_10G_CPU_TX1_N")
	)
	(segment
		(start 302.768 -72.898)
		(end 302.730916 -72.935084)
		(width 0.1397)
		(layer "F.Cu")
		(net "PCIE_10G_CPU_TX1_N")
	)
	(segment
		(start 308.675024 -74.000106)
		(end 307.420772 -74.000106)
		(width 0.1397)
		(layer "F.Cu")
		(net "PCIE_10G_CPU_TX1_N")
	)
	(segment
		(start 304.68443 -73.52157)
		(end 304.04943 -72.88657)
		(width 0.1397)
		(layer "F.Cu")
		(net "PCIE_10G_CPU_TX1_N")
	)
	(via
		(at 302.956722 -73.6092)
		(size 0.5588)
		(drill 0.3048)
		(layers "F.Cu" "B.Cu")
		(net "PCIE_10G_CPU_TX1_N")
	)
	(arc
		(start 304.04943 -72.88657)
		(mid 303.879171 -72.772806)
		(end 303.678336 -72.7329)
		(width 0.1397)
		(layer "F.Cu")
		(net "PCIE_10G_CPU_TX1_N")
	)
	(arc
		(start 307.213 -73.914)
		(mid 307.114527 -73.848202)
		(end 306.99837 -73.8251)
		(width 0.1397)
		(layer "F.Cu")
		(net "PCIE_10G_CPU_TX1_N")
	)
	(arc
		(start 302.730916 -72.935084)
		(mid 302.664364 -73.034592)
		(end 302.641 -73.152)
		(width 0.1397)
		(layer "F.Cu")
		(net "PCIE_10G_CPU_TX1_N")
	)
	(arc
		(start 307.420772 -74.000106)
		(mid 307.30831 -73.977736)
		(end 307.213 -73.914)
		(width 0.1397)
		(layer "F.Cu")
		(net "PCIE_10G_CPU_TX1_N")
	)
	(arc
		(start 303.166526 -72.7329)
		(mid 302.950836 -72.775803)
		(end 302.768 -72.898)
		(width 0.1397)
		(layer "F.Cu")
		(net "PCIE_10G_CPU_TX1_N")
	)
	(arc
		(start 302.641 -73.152)
		(mid 302.667005 -73.282736)
		(end 302.741076 -73.393554)
		(width 0.1397)
		(layer "F.Cu")
		(net "PCIE_10G_CPU_TX1_N")
	)
	(arc
		(start 305.41722 -73.8251)
		(mid 305.020623 -73.74623)
		(end 304.68443 -73.52157)
		(width 0.1397)
		(layer "F.Cu")
		(net "PCIE_10G_CPU_TX1_N")
	)
	(segment
		(start 231.871012 -64.851788)
		(end 235.338112 -68.318888)
		(width 0.127)
		(layer "In5.Cu")
		(net "PCIE_10G_CPU_TX1_N")
	)
	(segment
		(start 299.549312 -69.679312)
		(end 302.408336 -72.538336)
		(width 0.127)
		(layer "In5.Cu")
		(net "PCIE_10G_CPU_TX1_N")
	)
	(segment
		(start 149.016466 -69.691504)
		(end 152.459182 -66.248788)
		(width 0.127)
		(layer "In5.Cu")
		(net "PCIE_10G_CPU_TX1_N")
	)
	(segment
		(start 148.17217 -72.204072)
		(end 148.17217 -71.7296)
		(width 0.127)
		(layer "In5.Cu")
		(net "PCIE_10G_CPU_TX1_N")
	)
	(segment
		(start 178.308 -63.982346)
		(end 178.308 -63.9826)
		(width 0.127)
		(layer "In5.Cu")
		(net "PCIE_10G_CPU_TX1_N")
	)
	(segment
		(start 147.56257 -72.985376)
		(end 148.050758 -72.497188)
		(width 0.127)
		(layer "In5.Cu")
		(net "PCIE_10G_CPU_TX1_N")
	)
	(segment
		(start 302.609758 -73.024746)
		(end 302.609758 -73.152)
		(width 0.127)
		(layer "In5.Cu")
		(net "PCIE_10G_CPU_TX1_N")
	)
	(segment
		(start 155.447746 -64.389)
		(end 177.32629 -64.389)
		(width 0.127)
		(layer "In5.Cu")
		(net "PCIE_10G_CPU_TX1_N")
	)
	(segment
		(start 148.7678 -79.315564)
		(end 148.623528 -79.243682)
		(width 0.127)
		(layer "In5.Cu")
		(net "PCIE_10G_CPU_TX1_N")
	)
	(segment
		(start 302.687736 -73.340214)
		(end 302.956722 -73.6092)
		(width 0.127)
		(layer "In5.Cu")
		(net "PCIE_10G_CPU_TX1_N")
	)
	(segment
		(start 178.308 -63.9826)
		(end 229.772718 -63.9826)
		(width 0.127)
		(layer "In5.Cu")
		(net "PCIE_10G_CPU_TX1_N")
	)
	(segment
		(start 148.773388 -79.318104)
		(end 148.7678 -79.315564)
		(width 0.127)
		(layer "In5.Cu")
		(net "PCIE_10G_CPU_TX1_N")
	)
	(segment
		(start 152.459182 -66.248788)
		(end 153.520902 -65.187322)
		(width 0.127)
		(layer "In5.Cu")
		(net "PCIE_10G_CPU_TX1_N")
	)
	(segment
		(start 148.773642 -79.318104)
		(end 148.773388 -79.318104)
		(width 0.127)
		(layer "In5.Cu")
		(net "PCIE_10G_CPU_TX1_N")
	)
	(segment
		(start 148.340572 -78.613254)
		(end 148.340572 -75.770994)
		(width 0.127)
		(layer "In5.Cu")
		(net "PCIE_10G_CPU_TX1_N")
	)
	(segment
		(start 236.888274 -68.961)
		(end 297.815 -68.961)
		(width 0.127)
		(layer "In5.Cu")
		(net "PCIE_10G_CPU_TX1_N")
	)
	(segment
		(start 148.450046 -80.25003)
		(end 148.830538 -79.488538)
		(width 0.127)
		(layer "In5.Cu")
		(net "PCIE_10G_CPU_TX1_N")
	)
	(segment
		(start 148.116544 -75.22972)
		(end 147.56257 -74.676)
		(width 0.127)
		(layer "In5.Cu")
		(net "PCIE_10G_CPU_TX1_N")
	)
	(arc
		(start 148.623528 -79.243682)
		(mid 148.414424 -78.958816)
		(end 148.340572 -78.613254)
		(width 0.127)
		(layer "In5.Cu")
		(net "PCIE_10G_CPU_TX1_N")
	)
	(arc
		(start 177.71999 -64.225932)
		(mid 177.989771 -64.04567)
		(end 178.308 -63.982346)
		(width 0.127)
		(layer "In5.Cu")
		(net "PCIE_10G_CPU_TX1_N")
	)
	(arc
		(start 148.050758 -72.497188)
		(mid 148.14067 -72.362719)
		(end 148.17217 -72.204072)
		(width 0.127)
		(layer "In5.Cu")
		(net "PCIE_10G_CPU_TX1_N")
	)
	(arc
		(start 148.340572 -75.770994)
		(mid 148.2824 -75.478072)
		(end 148.116544 -75.22972)
		(width 0.127)
		(layer "In5.Cu")
		(net "PCIE_10G_CPU_TX1_N")
	)
	(arc
		(start 147.56257 -74.676)
		(mid 147.21243 -73.830688)
		(end 147.56257 -72.985376)
		(width 0.127)
		(layer "In5.Cu")
		(net "PCIE_10G_CPU_TX1_N")
	)
	(arc
		(start 177.32629 -64.389)
		(mid 177.539342 -64.346604)
		(end 177.71999 -64.225932)
		(width 0.127)
		(layer "In5.Cu")
		(net "PCIE_10G_CPU_TX1_N")
	)
	(arc
		(start 153.520902 -65.187322)
		(mid 154.404945 -64.596594)
		(end 155.447746 -64.389)
		(width 0.127)
		(layer "In5.Cu")
		(net "PCIE_10G_CPU_TX1_N")
	)
	(arc
		(start 235.338112 -68.318888)
		(mid 236.049332 -68.79411)
		(end 236.888274 -68.961)
		(width 0.127)
		(layer "In5.Cu")
		(net "PCIE_10G_CPU_TX1_N")
	)
	(arc
		(start 302.408336 -72.538336)
		(mid 302.557427 -72.761516)
		(end 302.609758 -73.024746)
		(width 0.127)
		(layer "In5.Cu")
		(net "PCIE_10G_CPU_TX1_N")
	)
	(arc
		(start 148.17217 -71.7296)
		(mid 148.391594 -70.626571)
		(end 149.016466 -69.691504)
		(width 0.127)
		(layer "In5.Cu")
		(net "PCIE_10G_CPU_TX1_N")
	)
	(arc
		(start 229.772718 -63.9826)
		(mid 230.908285 -64.208554)
		(end 231.871012 -64.851788)
		(width 0.127)
		(layer "In5.Cu")
		(net "PCIE_10G_CPU_TX1_N")
	)
	(arc
		(start 297.815 -68.961)
		(mid 298.753593 -69.14768)
		(end 299.549312 -69.679312)
		(width 0.127)
		(layer "In5.Cu")
		(net "PCIE_10G_CPU_TX1_N")
	)
	(arc
		(start 148.830538 -79.488538)
		(mid 148.837297 -79.391593)
		(end 148.773642 -79.318104)
		(width 0.127)
		(layer "In5.Cu")
		(net "PCIE_10G_CPU_TX1_N")
	)
	(arc
		(start 302.609758 -73.152)
		(mid 302.630021 -73.253867)
		(end 302.687736 -73.340214)
		(width 0.127)
		(layer "In5.Cu")
		(net "PCIE_10G_CPU_TX1_N")
	)
	(segment
		(start 109.03458 -20.001992)
		(end 117.895878 -20.001992)
		(width 0.1397)
		(layer "B.Cu")
		(net "PCIE_SAS_CPU_RX_N5")
	)
	(segment
		(start 148.41093 -36.8808)
		(end 152.90927 -36.8808)
		(width 0.1397)
		(layer "B.Cu")
		(net "PCIE_SAS_CPU_RX_N5")
	)
	(segment
		(start 166.37 -73.829926)
		(end 166.449756 -73.75017)
		(width 0.1397)
		(layer "B.Cu")
		(net "PCIE_SAS_CPU_RX_N5")
	)
	(segment
		(start 167.291004 -51.612038)
		(end 167.291004 -74.165206)
		(width 0.1397)
		(layer "B.Cu")
		(net "PCIE_SAS_CPU_RX_N5")
	)
	(segment
		(start 122.856244 -15.7099)
		(end 126.571756 -15.7099)
		(width 0.1397)
		(layer "B.Cu")
		(net "PCIE_SAS_CPU_RX_N5")
	)
	(segment
		(start 166.497 -74.549)
		(end 166.37 -74.422)
		(width 0.1397)
		(layer "B.Cu")
		(net "PCIE_SAS_CPU_RX_N5")
	)
	(segment
		(start 101.48316 -31.157672)
		(end 101.48316 -29.540708)
		(width 0.1397)
		(layer "B.Cu")
		(net "PCIE_SAS_CPU_RX_N5")
	)
	(segment
		(start 127.020828 -15.895828)
		(end 147.719288 -36.594288)
		(width 0.1397)
		(layer "B.Cu")
		(net "PCIE_SAS_CPU_RX_N5")
	)
	(segment
		(start 153.358342 -37.066728)
		(end 166.85768 -50.566066)
		(width 0.1397)
		(layer "B.Cu")
		(net "PCIE_SAS_CPU_RX_N5")
	)
	(segment
		(start 118.58752 -19.71548)
		(end 122.407172 -15.895828)
		(width 0.1397)
		(layer "B.Cu")
		(net "PCIE_SAS_CPU_RX_N5")
	)
	(segment
		(start 101.548184 -29.383736)
		(end 101.677216 -29.254704)
		(width 0.1397)
		(layer "B.Cu")
		(net "PCIE_SAS_CPU_RX_N5")
	)
	(segment
		(start 102.024688 -26.74874)
		(end 108.585508 -20.18792)
		(width 0.1397)
		(layer "B.Cu")
		(net "PCIE_SAS_CPU_RX_N5")
	)
	(segment
		(start 101.61016 -31.360618)
		(end 101.537008 -31.287466)
		(width 0.1397)
		(layer "B.Cu")
		(net "PCIE_SAS_CPU_RX_N5")
	)
	(segment
		(start 101.83876 -28.864814)
		(end 101.83876 -27.197812)
		(width 0.1397)
		(layer "B.Cu")
		(net "PCIE_SAS_CPU_RX_N5")
	)
	(arc
		(start 167.291004 -74.165206)
		(mid 167.249686 -74.372926)
		(end 167.132 -74.549)
		(width 0.1397)
		(layer "B.Cu")
		(net "PCIE_SAS_CPU_RX_N5")
	)
	(arc
		(start 101.537008 -31.287466)
		(mid 101.497164 -31.22793)
		(end 101.48316 -31.157672)
		(width 0.1397)
		(layer "B.Cu")
		(net "PCIE_SAS_CPU_RX_N5")
	)
	(arc
		(start 167.132 -74.549)
		(mid 166.8145 -74.680513)
		(end 166.497 -74.549)
		(width 0.1397)
		(layer "B.Cu")
		(net "PCIE_SAS_CPU_RX_N5")
	)
	(arc
		(start 101.83876 -27.197812)
		(mid 101.887096 -26.954808)
		(end 102.024688 -26.74874)
		(width 0.1397)
		(layer "B.Cu")
		(net "PCIE_SAS_CPU_RX_N5")
	)
	(arc
		(start 126.571756 -15.7099)
		(mid 126.81476 -15.758236)
		(end 127.020828 -15.895828)
		(width 0.1397)
		(layer "B.Cu")
		(net "PCIE_SAS_CPU_RX_N5")
	)
	(arc
		(start 117.895878 -20.001992)
		(mid 118.270187 -19.927519)
		(end 118.58752 -19.71548)
		(width 0.1397)
		(layer "B.Cu")
		(net "PCIE_SAS_CPU_RX_N5")
	)
	(arc
		(start 152.90927 -36.8808)
		(mid 153.152274 -36.929136)
		(end 153.358342 -37.066728)
		(width 0.1397)
		(layer "B.Cu")
		(net "PCIE_SAS_CPU_RX_N5")
	)
	(arc
		(start 166.85768 -50.566066)
		(mid 167.17839 -51.045948)
		(end 167.291004 -51.612038)
		(width 0.1397)
		(layer "B.Cu")
		(net "PCIE_SAS_CPU_RX_N5")
	)
	(arc
		(start 166.37 -74.422)
		(mid 166.247504 -74.126)
		(end 166.37 -73.829926)
		(width 0.1397)
		(layer "B.Cu")
		(net "PCIE_SAS_CPU_RX_N5")
	)
	(arc
		(start 101.677216 -29.254704)
		(mid 101.796742 -29.075821)
		(end 101.83876 -28.864814)
		(width 0.1397)
		(layer "B.Cu")
		(net "PCIE_SAS_CPU_RX_N5")
	)
	(arc
		(start 147.719288 -36.594288)
		(mid 148.036602 -36.806374)
		(end 148.41093 -36.8808)
		(width 0.1397)
		(layer "B.Cu")
		(net "PCIE_SAS_CPU_RX_N5")
	)
	(arc
		(start 122.407172 -15.895828)
		(mid 122.613208 -15.758159)
		(end 122.856244 -15.7099)
		(width 0.1397)
		(layer "B.Cu")
		(net "PCIE_SAS_CPU_RX_N5")
	)
	(arc
		(start 108.585508 -20.18792)
		(mid 108.791544 -20.050251)
		(end 109.03458 -20.001992)
		(width 0.1397)
		(layer "B.Cu")
		(net "PCIE_SAS_CPU_RX_N5")
	)
	(arc
		(start 101.48316 -29.540708)
		(mid 101.500058 -29.455754)
		(end 101.548184 -29.383736)
		(width 0.1397)
		(layer "B.Cu")
		(net "PCIE_SAS_CPU_RX_N5")
	)
	(segment
		(start 288.5694 -195.951856)
		(end 288.536126 -195.98513)
		(width 0.1143)
		(layer "F.Cu")
		(net "PD_ZQ")
	)
	(segment
		(start 290.377372 -192.984628)
		(end 289.941 -193.421)
		(width 0.1143)
		(layer "F.Cu")
		(net "PD_ZQ")
	)
	(segment
		(start 288.536126 -195.98513)
		(end 288.536126 -196.301614)
		(width 0.1143)
		(layer "F.Cu")
		(net "PD_ZQ")
	)
	(segment
		(start 288.536126 -196.301614)
		(end 288.898076 -196.663564)
		(width 0.1143)
		(layer "F.Cu")
		(net "PD_ZQ")
	)
	(segment
		(start 288.5694 -194.7926)
		(end 288.5694 -195.951856)
		(width 0.1143)
		(layer "F.Cu")
		(net "PD_ZQ")
	)
	(segment
		(start 290.377372 -192.306956)
		(end 290.377372 -192.984628)
		(width 0.1143)
		(layer "F.Cu")
		(net "PD_ZQ")
	)
	(segment
		(start 289.941 -193.421)
		(end 288.5694 -194.7926)
		(width 0.1143)
		(layer "F.Cu")
		(net "PD_ZQ")
	)
	(segment
		(start 288.898076 -196.663564)
		(end 288.898076 -196.93509)
		(width 0.1143)
		(layer "F.Cu")
		(net "PD_ZQ")
	)
	(via
		(at 289.941 -193.421)
		(size 0.7112)
		(drill 0.3556)
		(layers "F.Cu" "B.Cu")
		(net "PD_ZQ")
	)
	(segment
		(start 314.350654 -81.240884)
		(end 314.497466 -81.387696)
		(width 0.1397)
		(layer "F.Cu")
		(net "PCIE_10G_CPU_RX3_P")
	)
	(segment
		(start 316.028832 -81.6991)
		(end 317.754 -81.6991)
		(width 0.1397)
		(layer "F.Cu")
		(net "PCIE_10G_CPU_RX3_P")
	)
	(segment
		(start 313.125104 -81.19999)
		(end 314.251848 -81.19999)
		(width 0.1397)
		(layer "F.Cu")
		(net "PCIE_10G_CPU_RX3_P")
	)
	(segment
		(start 318.199262 -81.514696)
		(end 318.306958 -81.407)
		(width 0.1397)
		(layer "F.Cu")
		(net "PCIE_10G_CPU_RX3_P")
	)
	(segment
		(start 314.596272 -81.42859)
		(end 315.375798 -81.42859)
		(width 0.1397)
		(layer "F.Cu")
		(net "PCIE_10G_CPU_RX3_P")
	)
	(via
		(at 318.306958 -81.407)
		(size 0.5588)
		(drill 0.3048)
		(layers "F.Cu" "B.Cu")
		(net "PCIE_10G_CPU_RX3_P")
	)
	(arc
		(start 314.251848 -81.19999)
		(mid 314.305309 -81.210624)
		(end 314.350654 -81.240884)
		(width 0.1397)
		(layer "F.Cu")
		(net "PCIE_10G_CPU_RX3_P")
	)
	(arc
		(start 314.497466 -81.387696)
		(mid 314.542799 -81.417986)
		(end 314.596272 -81.42859)
		(width 0.1397)
		(layer "F.Cu")
		(net "PCIE_10G_CPU_RX3_P")
	)
	(arc
		(start 317.754 -81.6991)
		(mid 317.994963 -81.65117)
		(end 318.199262 -81.514696)
		(width 0.1397)
		(layer "F.Cu")
		(net "PCIE_10G_CPU_RX3_P")
	)
	(arc
		(start 315.375798 -81.42859)
		(mid 315.694439 -81.491954)
		(end 315.96457 -81.67243)
		(width 0.1397)
		(layer "F.Cu")
		(net "PCIE_10G_CPU_RX3_P")
	)
	(arc
		(start 315.96457 -81.67243)
		(mid 315.994039 -81.692184)
		(end 316.028832 -81.6991)
		(width 0.1397)
		(layer "F.Cu")
		(net "PCIE_10G_CPU_RX3_P")
	)
	(segment
		(start 145.5166 -82.002122)
		(end 146.089878 -82.575654)
		(width 0.127)
		(layer "In5.Cu")
		(net "PCIE_10G_CPU_RX3_P")
	)
	(segment
		(start 317.082932 -81.7372)
		(end 317.85814 -81.7372)
		(width 0.127)
		(layer "In5.Cu")
		(net "PCIE_10G_CPU_RX3_P")
	)
	(segment
		(start 178.952906 -85.09)
		(end 299.971968 -85.09)
		(width 0.127)
		(layer "In5.Cu")
		(net "PCIE_10G_CPU_RX3_P")
	)
	(segment
		(start 143.397986 -74.777092)
		(end 143.369792 -74.749152)
		(width 0.127)
		(layer "In5.Cu")
		(net "PCIE_10G_CPU_RX3_P")
	)
	(segment
		(start 150.565866 -85.146134)
		(end 150.66264 -85.243416)
		(width 0.127)
		(layer "In5.Cu")
		(net "PCIE_10G_CPU_RX3_P")
	)
	(segment
		(start 142.86357 -74.7776)
		(end 142.71117 -74.93)
		(width 0.127)
		(layer "In5.Cu")
		(net "PCIE_10G_CPU_RX3_P")
	)
	(segment
		(start 141.69517 -79.7052)
		(end 141.661134 -79.73949)
		(width 0.127)
		(layer "In5.Cu")
		(net "PCIE_10G_CPU_RX3_P")
	)
	(segment
		(start 142.55877 -75.298046)
		(end 142.55877 -78.5114)
		(width 0.127)
		(layer "In5.Cu")
		(net "PCIE_10G_CPU_RX3_P")
	)
	(segment
		(start 148.787866 -83.368134)
		(end 150.565866 -85.146134)
		(width 0.127)
		(layer "In5.Cu")
		(net "PCIE_10G_CPU_RX3_P")
	)
	(segment
		(start 178.340004 -85.503004)
		(end 178.611784 -85.231224)
		(width 0.127)
		(layer "In5.Cu")
		(net "PCIE_10G_CPU_RX3_P")
	)
	(segment
		(start 141.51737 -80.0862)
		(end 141.51737 -80.264)
		(width 0.127)
		(layer "In5.Cu")
		(net "PCIE_10G_CPU_RX3_P")
	)
	(segment
		(start 142.63497 -81.3816)
		(end 144.018 -81.3816)
		(width 0.127)
		(layer "In5.Cu")
		(net "PCIE_10G_CPU_RX3_P")
	)
	(segment
		(start 151.792686 -85.6996)
		(end 177.865278 -85.6996)
		(width 0.127)
		(layer "In5.Cu")
		(net "PCIE_10G_CPU_RX3_P")
	)
	(segment
		(start 142.325344 -79.075026)
		(end 141.69517 -79.7052)
		(width 0.127)
		(layer "In5.Cu")
		(net "PCIE_10G_CPU_RX3_P")
	)
	(segment
		(start 318.059308 -81.653888)
		(end 318.306958 -81.407)
		(width 0.127)
		(layer "In5.Cu")
		(net "PCIE_10G_CPU_RX3_P")
	)
	(segment
		(start 147.193 -83.0326)
		(end 147.977606 -83.0326)
		(width 0.127)
		(layer "In5.Cu")
		(net "PCIE_10G_CPU_RX3_P")
	)
	(segment
		(start 144.018 -81.3816)
		(end 144.018 -81.381346)
		(width 0.127)
		(layer "In5.Cu")
		(net "PCIE_10G_CPU_RX3_P")
	)
	(segment
		(start 314.156852 -84.160106)
		(end 316.224158 -82.0928)
		(width 0.127)
		(layer "In5.Cu")
		(net "PCIE_10G_CPU_RX3_P")
	)
	(segment
		(start 300.332648 -84.940648)
		(end 300.367446 -84.90585)
		(width 0.127)
		(layer "In5.Cu")
		(net "PCIE_10G_CPU_RX3_P")
	)
	(segment
		(start 143.51 -75.60564)
		(end 143.51 -74.93)
		(width 0.127)
		(layer "In5.Cu")
		(net "PCIE_10G_CPU_RX3_P")
	)
	(segment
		(start 143.481044 -74.86015)
		(end 143.397986 -74.777092)
		(width 0.127)
		(layer "In5.Cu")
		(net "PCIE_10G_CPU_RX3_P")
	)
	(segment
		(start 300.99 -84.64804)
		(end 312.9788 -84.64804)
		(width 0.127)
		(layer "In5.Cu")
		(net "PCIE_10G_CPU_RX3_P")
	)
	(arc
		(start 143.450056 -75.75042)
		(mid 143.49444 -75.683994)
		(end 143.51 -75.60564)
		(width 0.127)
		(layer "In5.Cu")
		(net "PCIE_10G_CPU_RX3_P")
	)
	(arc
		(start 141.661134 -79.73949)
		(mid 141.554763 -79.898547)
		(end 141.51737 -80.0862)
		(width 0.127)
		(layer "In5.Cu")
		(net "PCIE_10G_CPU_RX3_P")
	)
	(arc
		(start 299.971968 -85.09)
		(mid 300.167149 -85.051176)
		(end 300.332648 -84.940648)
		(width 0.127)
		(layer "In5.Cu")
		(net "PCIE_10G_CPU_RX3_P")
	)
	(arc
		(start 144.018 -81.381346)
		(mid 144.82905 -81.542674)
		(end 145.5166 -82.002122)
		(width 0.127)
		(layer "In5.Cu")
		(net "PCIE_10G_CPU_RX3_P")
	)
	(arc
		(start 151.765 -85.699854)
		(mid 151.778844 -85.699788)
		(end 151.792686 -85.6996)
		(width 0.127)
		(layer "In5.Cu")
		(net "PCIE_10G_CPU_RX3_P")
	)
	(arc
		(start 317.85814 -81.7372)
		(mid 317.967006 -81.715545)
		(end 318.059308 -81.653888)
		(width 0.127)
		(layer "In5.Cu")
		(net "PCIE_10G_CPU_RX3_P")
	)
	(arc
		(start 178.611784 -85.231224)
		(mid 178.768306 -85.126702)
		(end 178.952906 -85.09)
		(width 0.127)
		(layer "In5.Cu")
		(net "PCIE_10G_CPU_RX3_P")
	)
	(arc
		(start 316.224158 -82.0928)
		(mid 316.618182 -81.829615)
		(end 317.082932 -81.7372)
		(width 0.127)
		(layer "In5.Cu")
		(net "PCIE_10G_CPU_RX3_P")
	)
	(arc
		(start 143.51 -74.93)
		(mid 143.502479 -74.892189)
		(end 143.481044 -74.86015)
		(width 0.127)
		(layer "In5.Cu")
		(net "PCIE_10G_CPU_RX3_P")
	)
	(arc
		(start 147.977606 -83.0326)
		(mid 148.416082 -83.119818)
		(end 148.787866 -83.368134)
		(width 0.127)
		(layer "In5.Cu")
		(net "PCIE_10G_CPU_RX3_P")
	)
	(arc
		(start 312.9788 -84.64804)
		(mid 313.616345 -84.521224)
		(end 314.156852 -84.160106)
		(width 0.127)
		(layer "In5.Cu")
		(net "PCIE_10G_CPU_RX3_P")
	)
	(arc
		(start 150.66264 -85.243416)
		(mid 151.168436 -85.581222)
		(end 151.765 -85.699854)
		(width 0.127)
		(layer "In5.Cu")
		(net "PCIE_10G_CPU_RX3_P")
	)
	(arc
		(start 142.55877 -78.5114)
		(mid 142.498098 -78.816419)
		(end 142.325344 -79.075026)
		(width 0.127)
		(layer "In5.Cu")
		(net "PCIE_10G_CPU_RX3_P")
	)
	(arc
		(start 300.367446 -84.90585)
		(mid 300.65309 -84.715052)
		(end 300.99 -84.64804)
		(width 0.127)
		(layer "In5.Cu")
		(net "PCIE_10G_CPU_RX3_P")
	)
	(arc
		(start 177.865278 -85.6996)
		(mid 178.122182 -85.648499)
		(end 178.340004 -85.503004)
		(width 0.127)
		(layer "In5.Cu")
		(net "PCIE_10G_CPU_RX3_P")
	)
	(arc
		(start 143.1163 -74.643996)
		(mid 142.979859 -74.691741)
		(end 142.86357 -74.7776)
		(width 0.127)
		(layer "In5.Cu")
		(net "PCIE_10G_CPU_RX3_P")
	)
	(arc
		(start 146.089878 -82.575654)
		(mid 146.595995 -82.91383)
		(end 147.193 -83.0326)
		(width 0.127)
		(layer "In5.Cu")
		(net "PCIE_10G_CPU_RX3_P")
	)
	(arc
		(start 142.71117 -74.93)
		(mid 142.598341 -75.098861)
		(end 142.55877 -75.298046)
		(width 0.127)
		(layer "In5.Cu")
		(net "PCIE_10G_CPU_RX3_P")
	)
	(arc
		(start 143.369792 -74.749152)
		(mid 143.253504 -74.671358)
		(end 143.1163 -74.643996)
		(width 0.127)
		(layer "In5.Cu")
		(net "PCIE_10G_CPU_RX3_P")
	)
	(arc
		(start 141.51737 -80.264)
		(mid 141.844707 -81.054263)
		(end 142.63497 -81.3816)
		(width 0.127)
		(layer "In5.Cu")
		(net "PCIE_10G_CPU_RX3_P")
	)
	(segment
		(start 286.839914 -174.24527)
		(end 286.839406 -174.24527)
		(width 0.1143)
		(layer "F.Cu")
		(net "PD_PERST_N")
	)
	(segment
		(start 287.234884 -174.64024)
		(end 286.839914 -174.24527)
		(width 0.1143)
		(layer "F.Cu")
		(net "PD_PERST_N")
	)
	(via
		(at 286.839406 -174.24527)
		(size 0.508)
		(drill 0.254)
		(layers "F.Cu" "B.Cu")
		(net "PD_PERST_N")
	)
	(via
		(at 288.473896 -175.885856)
		(size 0.7112)
		(drill 0.3556)
		(layers "F.Cu" "B.Cu")
		(net "PD_PERST_N")
	)
	(segment
		(start 287.550352 -174.971456)
		(end 288.346896 -175.768)
		(width 0.1143)
		(layer "B.Cu")
		(net "PD_PERST_N")
	)
	(segment
		(start 286.839406 -174.24527)
		(end 286.841692 -174.247556)
		(width 0.1143)
		(layer "B.Cu")
		(net "PD_PERST_N")
	)
	(segment
		(start 286.841692 -174.262796)
		(end 287.550352 -174.971456)
		(width 0.1143)
		(layer "B.Cu")
		(net "PD_PERST_N")
	)
	(segment
		(start 288.35604 -175.768)
		(end 288.473896 -175.885856)
		(width 0.1143)
		(layer "B.Cu")
		(net "PD_PERST_N")
	)
	(segment
		(start 286.841692 -174.247556)
		(end 286.841692 -174.262796)
		(width 0.1143)
		(layer "B.Cu")
		(net "PD_PERST_N")
	)
	(segment
		(start 288.346896 -175.768)
		(end 288.35604 -175.768)
		(width 0.1143)
		(layer "B.Cu")
		(net "PD_PERST_N")
	)
	(segment
		(start 331.645006 -133.753352)
		(end 331.5716 -133.6802)
		(width 0.1397)
		(layer "B.Cu")
		(net "USB_P0_DP")
	)
	(segment
		(start 306.76723 -116.67109)
		(end 306.756308 -116.660422)
		(width 0.1397)
		(layer "B.Cu")
		(net "USB_P0_DP")
	)
	(segment
		(start 331.5716 -133.6802)
		(end 325.953374 -128.061974)
		(width 0.1397)
		(layer "B.Cu")
		(net "USB_P0_DP")
	)
	(segment
		(start 338.4296 -134.1755)
		(end 332.6638 -134.1755)
		(width 0.1397)
		(layer "B.Cu")
		(net "USB_P0_DP")
	)
	(segment
		(start 338.6836 -133.6294)
		(end 338.6836 -133.9215)
		(width 0.1397)
		(layer "B.Cu")
		(net "USB_P0_DP")
	)
	(segment
		(start 261.681468 -113.7031)
		(end 240.025682 -113.7031)
		(width 0.1397)
		(layer "B.Cu")
		(net "USB_P0_DP")
	)
	(segment
		(start 263.80567 -114.98453)
		(end 263.11987 -114.29873)
		(width 0.1397)
		(layer "B.Cu")
		(net "USB_P0_DP")
	)
	(segment
		(start 229.4382 -107.569)
		(end 221.91726 -107.569)
		(width 0.1397)
		(layer "B.Cu")
		(net "USB_P0_DP")
	)
	(segment
		(start 220.06306 -105.7148)
		(end 220.06306 -96.087438)
		(width 0.1397)
		(layer "B.Cu")
		(net "USB_P0_DP")
	)
	(segment
		(start 239.014 -113.284)
		(end 237.6297 -111.8997)
		(width 0.1397)
		(layer "B.Cu")
		(net "USB_P0_DP")
	)
	(segment
		(start 339.348318 -133.353048)
		(end 338.959952 -133.353048)
		(width 0.1397)
		(layer "B.Cu")
		(net "USB_P0_DP")
	)
	(segment
		(start 339.348318 -133.353048)
		(end 339.475318 -133.353048)
		(width 0.1397)
		(layer "B.Cu")
		(net "USB_P0_DP")
	)
	(segment
		(start 213.4997 -88.019128)
		(end 213.4997 -78.369922)
		(width 0.1397)
		(layer "B.Cu")
		(net "USB_P0_DP")
	)
	(segment
		(start 324.0024 -127.254)
		(end 318.213994 -127.254)
		(width 0.1397)
		(layer "B.Cu")
		(net "USB_P0_DP")
	)
	(segment
		(start 219.63253 -95.04807)
		(end 214.13343 -89.54897)
		(width 0.1397)
		(layer "B.Cu")
		(net "USB_P0_DP")
	)
	(segment
		(start 233.8197 -110.8837)
		(end 231.259126 -108.323126)
		(width 0.1397)
		(layer "B.Cu")
		(net "USB_P0_DP")
	)
	(segment
		(start 236.295946 -111.34725)
		(end 234.938824 -111.34725)
		(width 0.1397)
		(layer "B.Cu")
		(net "USB_P0_DP")
	)
	(segment
		(start 304.520854 -115.7351)
		(end 265.617706 -115.7351)
		(width 0.1397)
		(layer "B.Cu")
		(net "USB_P0_DP")
	)
	(segment
		(start 316.73927 -126.64313)
		(end 306.76723 -116.67109)
		(width 0.1397)
		(layer "B.Cu")
		(net "USB_P0_DP")
	)
	(arc
		(start 221.91726 -107.569)
		(mid 220.606143 -107.025917)
		(end 220.06306 -105.7148)
		(width 0.1397)
		(layer "B.Cu")
		(net "USB_P0_DP")
	)
	(arc
		(start 338.6836 -133.9215)
		(mid 338.609205 -134.101105)
		(end 338.4296 -134.1755)
		(width 0.1397)
		(layer "B.Cu")
		(net "USB_P0_DP")
	)
	(arc
		(start 332.6638 -134.1755)
		(mid 332.112429 -134.065732)
		(end 331.645006 -133.753352)
		(width 0.1397)
		(layer "B.Cu")
		(net "USB_P0_DP")
	)
	(arc
		(start 265.617706 -115.7351)
		(mid 264.637039 -115.540033)
		(end 263.80567 -114.98453)
		(width 0.1397)
		(layer "B.Cu")
		(net "USB_P0_DP")
	)
	(arc
		(start 237.6297 -111.8997)
		(mid 237.017754 -111.490874)
		(end 236.295946 -111.34725)
		(width 0.1397)
		(layer "B.Cu")
		(net "USB_P0_DP")
	)
	(arc
		(start 263.11987 -114.29873)
		(mid 262.459911 -113.857852)
		(end 261.681468 -113.7031)
		(width 0.1397)
		(layer "B.Cu")
		(net "USB_P0_DP")
	)
	(arc
		(start 240.025682 -113.7031)
		(mid 239.478145 -113.594188)
		(end 239.014 -113.284)
		(width 0.1397)
		(layer "B.Cu")
		(net "USB_P0_DP")
	)
	(arc
		(start 214.13343 -89.54897)
		(mid 213.664437 -88.847073)
		(end 213.4997 -88.019128)
		(width 0.1397)
		(layer "B.Cu")
		(net "USB_P0_DP")
	)
	(arc
		(start 325.953374 -128.061974)
		(mid 325.058244 -127.463961)
		(end 324.0024 -127.254)
		(width 0.1397)
		(layer "B.Cu")
		(net "USB_P0_DP")
	)
	(arc
		(start 306.756308 -116.660422)
		(mid 305.730532 -115.975622)
		(end 304.520854 -115.7351)
		(width 0.1397)
		(layer "B.Cu")
		(net "USB_P0_DP")
	)
	(arc
		(start 220.06306 -96.087438)
		(mid 219.951103 -95.524972)
		(end 219.63253 -95.04807)
		(width 0.1397)
		(layer "B.Cu")
		(net "USB_P0_DP")
	)
	(arc
		(start 213.4997 -78.369922)
		(mid 213.486765 -78.304894)
		(end 213.449916 -78.24978)
		(width 0.1397)
		(layer "B.Cu")
		(net "USB_P0_DP")
	)
	(arc
		(start 338.959952 -133.353048)
		(mid 338.764542 -133.43399)
		(end 338.6836 -133.6294)
		(width 0.1397)
		(layer "B.Cu")
		(net "USB_P0_DP")
	)
	(arc
		(start 234.938824 -111.34725)
		(mid 234.333161 -111.226776)
		(end 233.8197 -110.8837)
		(width 0.1397)
		(layer "B.Cu")
		(net "USB_P0_DP")
	)
	(arc
		(start 318.213994 -127.254)
		(mid 317.415872 -127.095244)
		(end 316.73927 -126.64313)
		(width 0.1397)
		(layer "B.Cu")
		(net "USB_P0_DP")
	)
	(arc
		(start 231.259126 -108.323126)
		(mid 230.423663 -107.76498)
		(end 229.4382 -107.569)
		(width 0.1397)
		(layer "B.Cu")
		(net "USB_P0_DP")
	)
	(segment
		(start 272.546572 -56.921146)
		(end 272.546572 -57.526428)
		(width 0.254)
		(layer "F.Cu")
		(net "P3V3_EN_G")
	)
	(segment
		(start 270.819372 -57.730136)
		(end 271.255236 -58.166)
		(width 0.254)
		(layer "F.Cu")
		(net "P3V3_EN_G")
	)
	(segment
		(start 272.546572 -57.526428)
		(end 271.907 -58.166)
		(width 0.254)
		(layer "F.Cu")
		(net "P3V3_EN_G")
	)
	(segment
		(start 271.255236 -58.166)
		(end 271.907 -58.166)
		(width 0.254)
		(layer "F.Cu")
		(net "P3V3_EN_G")
	)
	(via
		(at 271.907 -58.166)
		(size 0.7112)
		(drill 0.3556)
		(layers "F.Cu" "B.Cu")
		(net "P3V3_EN_G")
	)
	(segment
		(start 297.24858 -181.434232)
		(end 297.242992 -181.43982)
		(width 0.1143)
		(layer "F.Cu")
		(net "HB0_R_IN0")
	)
	(segment
		(start 297.24858 -181.426358)
		(end 297.24858 -181.434232)
		(width 0.1143)
		(layer "F.Cu")
		(net "HB0_R_IN0")
	)
	(segment
		(start 297.634914 -181.040024)
		(end 297.24858 -181.426358)
		(width 0.1143)
		(layer "F.Cu")
		(net "HB0_R_IN0")
	)
	(via
		(at 308.991 -186.69)
		(size 0.7112)
		(drill 0.3556)
		(layers "F.Cu" "B.Cu")
		(net "HB0_R_IN0")
	)
	(via
		(at 297.242992 -181.43982)
		(size 0.508)
		(drill 0.254)
		(layers "F.Cu" "B.Cu")
		(net "HB0_R_IN0")
	)
	(segment
		(start 297.63085 -181.827678)
		(end 297.242992 -181.43982)
		(width 0.0889)
		(layer "B.Cu")
		(net "HB0_R_IN0")
	)
	(segment
		(start 297.630596 -182.411116)
		(end 297.630596 -182.08752)
		(width 0.0889)
		(layer "B.Cu")
		(net "HB0_R_IN0")
	)
	(segment
		(start 306.578 -187.071)
		(end 305.689 -186.182)
		(width 0.1143)
		(layer "B.Cu")
		(net "HB0_R_IN0")
	)
	(segment
		(start 300.01845 -185.97245)
		(end 300.01845 -185.87847)
		(width 0.1143)
		(layer "B.Cu")
		(net "HB0_R_IN0")
	)
	(segment
		(start 297.386248 -182.992268)
		(end 297.386248 -182.655464)
		(width 0.0889)
		(layer "B.Cu")
		(net "HB0_R_IN0")
	)
	(segment
		(start 297.63085 -182.087266)
		(end 297.63085 -181.827678)
		(width 0.0889)
		(layer "B.Cu")
		(net "HB0_R_IN0")
	)
	(segment
		(start 300.01845 -185.87847)
		(end 297.386248 -183.246268)
		(width 0.1143)
		(layer "B.Cu")
		(net "HB0_R_IN0")
	)
	(segment
		(start 297.386248 -182.655464)
		(end 297.630596 -182.411116)
		(width 0.0889)
		(layer "B.Cu")
		(net "HB0_R_IN0")
	)
	(segment
		(start 305.689 -186.182)
		(end 300.228 -186.182)
		(width 0.1143)
		(layer "B.Cu")
		(net "HB0_R_IN0")
	)
	(segment
		(start 309.118 -186.817)
		(end 308.991 -186.69)
		(width 0.1143)
		(layer "B.Cu")
		(net "HB0_R_IN0")
	)
	(segment
		(start 307.975 -187.071)
		(end 306.578 -187.071)
		(width 0.1143)
		(layer "B.Cu")
		(net "HB0_R_IN0")
	)
	(segment
		(start 300.228 -186.182)
		(end 300.01845 -185.97245)
		(width 0.1143)
		(layer "B.Cu")
		(net "HB0_R_IN0")
	)
	(segment
		(start 308.991 -186.69)
		(end 308.356 -186.69)
		(width 0.1143)
		(layer "B.Cu")
		(net "HB0_R_IN0")
	)
	(segment
		(start 308.356 -186.69)
		(end 307.975 -187.071)
		(width 0.1143)
		(layer "B.Cu")
		(net "HB0_R_IN0")
	)
	(segment
		(start 310.4515 -186.817)
		(end 309.118 -186.817)
		(width 0.1143)
		(layer "B.Cu")
		(net "HB0_R_IN0")
	)
	(segment
		(start 297.630596 -182.08752)
		(end 297.63085 -182.087266)
		(width 0.0889)
		(layer "B.Cu")
		(net "HB0_R_IN0")
	)
	(segment
		(start 297.386248 -183.246268)
		(end 297.386248 -182.992268)
		(width 0.1143)
		(layer "B.Cu")
		(net "HB0_R_IN0")
	)
	(segment
		(start 314.706 -166.878)
		(end 312.674 -168.91)
		(width 0.1143)
		(layer "F.Cu")
		(net "BMC0_SMB6_DAT")
	)
	(segment
		(start 299.23486 -171.440094)
		(end 299.62602 -171.048934)
		(width 0.1143)
		(layer "F.Cu")
		(net "BMC0_SMB6_DAT")
	)
	(segment
		(start 312.674 -168.91)
		(end 312.547 -169.037)
		(width 0.1143)
		(layer "F.Cu")
		(net "BMC0_SMB6_DAT")
	)
	(segment
		(start 299.62602 -171.048934)
		(end 299.634148 -171.048934)
		(width 0.1143)
		(layer "F.Cu")
		(net "BMC0_SMB6_DAT")
	)
	(segment
		(start 317.5635 -166.878)
		(end 314.706 -166.878)
		(width 0.1143)
		(layer "F.Cu")
		(net "BMC0_SMB6_DAT")
	)
	(segment
		(start 312.547 -169.037)
		(end 304.165 -169.037)
		(width 0.1143)
		(layer "F.Cu")
		(net "BMC0_SMB6_DAT")
	)
	(via
		(at 304.165 -169.037)
		(size 0.5588)
		(drill 0.3048)
		(layers "F.Cu" "B.Cu")
		(net "BMC0_SMB6_DAT")
	)
	(via
		(at 312.674 -168.91)
		(size 0.7112)
		(drill 0.3556)
		(layers "F.Cu" "B.Cu")
		(net "BMC0_SMB6_DAT")
	)
	(via
		(at 299.634148 -171.048934)
		(size 0.508)
		(drill 0.254)
		(layers "F.Cu" "B.Cu")
		(net "BMC0_SMB6_DAT")
	)
	(segment
		(start 302.514 -170.688)
		(end 304.165 -169.037)
		(width 0.127)
		(layer "In2.Cu")
		(net "BMC0_SMB6_DAT")
	)
	(segment
		(start 299.634148 -171.048934)
		(end 299.995082 -170.688)
		(width 0.127)
		(layer "In2.Cu")
		(net "BMC0_SMB6_DAT")
	)
	(segment
		(start 299.995082 -170.688)
		(end 302.514 -170.688)
		(width 0.127)
		(layer "In2.Cu")
		(net "BMC0_SMB6_DAT")
	)
	(segment
		(start 338.6582 -135.1534)
		(end 338.6582 -134.789672)
		(width 0.1397)
		(layer "B.Cu")
		(net "USB_P0_DN")
	)
	(segment
		(start 213.1568 -84.737702)
		(end 213.1568 -84.318602)
		(width 0.1397)
		(layer "B.Cu")
		(net "USB_P0_DN")
	)
	(segment
		(start 212.95614 -83.917282)
		(end 212.95614 -83.498182)
		(width 0.1397)
		(layer "B.Cu")
		(net "USB_P0_DN")
	)
	(segment
		(start 219.72016 -99.118674)
		(end 219.72016 -96.087692)
		(width 0.1397)
		(layer "B.Cu")
		(net "USB_P0_DN")
	)
	(segment
		(start 219.72016 -100.759514)
		(end 219.72016 -100.340414)
		(width 0.1397)
		(layer "B.Cu")
		(net "USB_P0_DN")
	)
	(segment
		(start 316.4967 -126.8857)
		(end 306.5272 -116.9162)
		(width 0.1397)
		(layer "B.Cu")
		(net "USB_P0_DN")
	)
	(segment
		(start 213.1568 -88.019382)
		(end 213.1568 -87.600282)
		(width 0.1397)
		(layer "B.Cu")
		(net "USB_P0_DN")
	)
	(segment
		(start 263.5631 -115.2271)
		(end 262.8773 -114.5413)
		(width 0.1397)
		(layer "B.Cu")
		(net "USB_P0_DN")
	)
	(segment
		(start 219.72016 -105.7148)
		(end 219.72016 -103.622094)
		(width 0.1397)
		(layer "B.Cu")
		(net "USB_P0_DN")
	)
	(segment
		(start 306.5272 -116.9162)
		(end 306.515008 -116.904262)
		(width 0.1397)
		(layer "B.Cu")
		(net "USB_P0_DN")
	)
	(segment
		(start 338.386928 -134.5184)
		(end 332.663546 -134.5184)
		(width 0.1397)
		(layer "B.Cu")
		(net "USB_P0_DN")
	)
	(segment
		(start 339.348318 -135.385048)
		(end 338.889848 -135.385048)
		(width 0.1397)
		(layer "B.Cu")
		(net "USB_P0_DN")
	)
	(segment
		(start 229.4382 -107.9119)
		(end 221.91726 -107.9119)
		(width 0.1397)
		(layer "B.Cu")
		(net "USB_P0_DN")
	)
	(segment
		(start 219.38996 -95.29064)
		(end 213.89086 -89.79154)
		(width 0.1397)
		(layer "B.Cu")
		(net "USB_P0_DN")
	)
	(segment
		(start 212.95614 -82.276442)
		(end 212.95614 -81.857342)
		(width 0.1397)
		(layer "B.Cu")
		(net "USB_P0_DN")
	)
	(segment
		(start 213.1568 -83.096862)
		(end 213.1568 -82.677762)
		(width 0.1397)
		(layer "B.Cu")
		(net "USB_P0_DN")
	)
	(segment
		(start 339.348318 -135.385048)
		(end 339.475318 -135.385048)
		(width 0.1397)
		(layer "B.Cu")
		(net "USB_P0_DN")
	)
	(segment
		(start 212.95614 -87.198962)
		(end 212.95614 -86.779862)
		(width 0.1397)
		(layer "B.Cu")
		(net "USB_P0_DN")
	)
	(segment
		(start 238.77143 -113.52657)
		(end 237.38713 -112.14227)
		(width 0.1397)
		(layer "B.Cu")
		(net "USB_P0_DN")
	)
	(segment
		(start 304.5206 -116.078)
		(end 265.617706 -116.078)
		(width 0.1397)
		(layer "B.Cu")
		(net "USB_P0_DN")
	)
	(segment
		(start 219.5195 -99.939094)
		(end 219.5195 -99.519994)
		(width 0.1397)
		(layer "B.Cu")
		(net "USB_P0_DN")
	)
	(segment
		(start 331.40269 -133.996176)
		(end 331.329538 -133.923278)
		(width 0.1397)
		(layer "B.Cu")
		(net "USB_P0_DN")
	)
	(segment
		(start 212.95614 -85.558122)
		(end 212.95614 -85.139022)
		(width 0.1397)
		(layer "B.Cu")
		(net "USB_P0_DN")
	)
	(segment
		(start 219.5195 -101.579934)
		(end 219.5195 -101.160834)
		(width 0.1397)
		(layer "B.Cu")
		(net "USB_P0_DN")
	)
	(segment
		(start 236.295692 -111.69015)
		(end 234.938824 -111.69015)
		(width 0.1397)
		(layer "B.Cu")
		(net "USB_P0_DN")
	)
	(segment
		(start 212.705442 -80.25003)
		(end 212.450426 -80.25003)
		(width 0.1397)
		(layer "B.Cu")
		(net "USB_P0_DN")
	)
	(segment
		(start 219.5195 -103.220774)
		(end 219.5195 -102.801674)
		(width 0.1397)
		(layer "B.Cu")
		(net "USB_P0_DN")
	)
	(segment
		(start 261.681468 -114.046)
		(end 240.025428 -114.046)
		(width 0.1397)
		(layer "B.Cu")
		(net "USB_P0_DN")
	)
	(segment
		(start 324.0024 -127.5969)
		(end 318.21374 -127.5969)
		(width 0.1397)
		(layer "B.Cu")
		(net "USB_P0_DN")
	)
	(segment
		(start 233.57713 -111.12627)
		(end 231.016556 -108.565696)
		(width 0.1397)
		(layer "B.Cu")
		(net "USB_P0_DN")
	)
	(segment
		(start 213.1568 -86.378542)
		(end 213.1568 -85.959442)
		(width 0.1397)
		(layer "B.Cu")
		(net "USB_P0_DN")
	)
	(segment
		(start 331.329538 -133.923278)
		(end 325.710804 -128.304544)
		(width 0.1397)
		(layer "B.Cu")
		(net "USB_P0_DN")
	)
	(segment
		(start 213.1568 -81.455768)
		(end 213.1568 -80.701388)
		(width 0.1397)
		(layer "B.Cu")
		(net "USB_P0_DN")
	)
	(segment
		(start 219.72016 -102.400354)
		(end 219.72016 -101.981254)
		(width 0.1397)
		(layer "B.Cu")
		(net "USB_P0_DN")
	)
	(arc
		(start 213.05647 -84.938362)
		(mid 213.13023 -84.849836)
		(end 213.1568 -84.737702)
		(width 0.1397)
		(layer "B.Cu")
		(net "USB_P0_DN")
	)
	(arc
		(start 219.72016 -103.622094)
		(mid 219.693636 -103.509937)
		(end 219.61983 -103.421434)
		(width 0.1397)
		(layer "B.Cu")
		(net "USB_P0_DN")
	)
	(arc
		(start 240.025428 -114.046)
		(mid 239.346806 -113.910938)
		(end 238.77143 -113.52657)
		(width 0.1397)
		(layer "B.Cu")
		(net "USB_P0_DN")
	)
	(arc
		(start 221.91726 -107.9119)
		(mid 220.363676 -107.268384)
		(end 219.72016 -105.7148)
		(width 0.1397)
		(layer "B.Cu")
		(net "USB_P0_DN")
	)
	(arc
		(start 265.617706 -116.078)
		(mid 264.505763 -115.856914)
		(end 263.5631 -115.2271)
		(width 0.1397)
		(layer "B.Cu")
		(net "USB_P0_DN")
	)
	(arc
		(start 237.38713 -112.14227)
		(mid 236.886374 -111.807676)
		(end 236.295692 -111.69015)
		(width 0.1397)
		(layer "B.Cu")
		(net "USB_P0_DN")
	)
	(arc
		(start 338.889848 -135.385048)
		(mid 338.726048 -135.3172)
		(end 338.6582 -135.1534)
		(width 0.1397)
		(layer "B.Cu")
		(net "USB_P0_DN")
	)
	(arc
		(start 213.05647 -81.656682)
		(mid 213.130287 -81.568043)
		(end 213.1568 -81.455768)
		(width 0.1397)
		(layer "B.Cu")
		(net "USB_P0_DN")
	)
	(arc
		(start 213.89086 -89.79154)
		(mid 213.347553 -88.978468)
		(end 213.1568 -88.019382)
		(width 0.1397)
		(layer "B.Cu")
		(net "USB_P0_DN")
	)
	(arc
		(start 219.72016 -100.340414)
		(mid 219.693636 -100.228257)
		(end 219.61983 -100.139754)
		(width 0.1397)
		(layer "B.Cu")
		(net "USB_P0_DN")
	)
	(arc
		(start 219.61983 -99.319334)
		(mid 219.69359 -99.230808)
		(end 219.72016 -99.118674)
		(width 0.1397)
		(layer "B.Cu")
		(net "USB_P0_DN")
	)
	(arc
		(start 262.8773 -114.5413)
		(mid 262.328648 -114.174702)
		(end 261.681468 -114.046)
		(width 0.1397)
		(layer "B.Cu")
		(net "USB_P0_DN")
	)
	(arc
		(start 234.938824 -111.69015)
		(mid 234.201885 -111.543657)
		(end 233.57713 -111.12627)
		(width 0.1397)
		(layer "B.Cu")
		(net "USB_P0_DN")
	)
	(arc
		(start 212.95614 -81.857342)
		(mid 212.982664 -81.745185)
		(end 213.05647 -81.656682)
		(width 0.1397)
		(layer "B.Cu")
		(net "USB_P0_DN")
	)
	(arc
		(start 212.95614 -86.779862)
		(mid 212.982664 -86.667705)
		(end 213.05647 -86.579202)
		(width 0.1397)
		(layer "B.Cu")
		(net "USB_P0_DN")
	)
	(arc
		(start 213.1568 -87.600282)
		(mid 213.130276 -87.488125)
		(end 213.05647 -87.399622)
		(width 0.1397)
		(layer "B.Cu")
		(net "USB_P0_DN")
	)
	(arc
		(start 213.1568 -84.318602)
		(mid 213.130276 -84.206445)
		(end 213.05647 -84.117942)
		(width 0.1397)
		(layer "B.Cu")
		(net "USB_P0_DN")
	)
	(arc
		(start 231.016556 -108.565696)
		(mid 230.2924 -108.081831)
		(end 229.4382 -107.9119)
		(width 0.1397)
		(layer "B.Cu")
		(net "USB_P0_DN")
	)
	(arc
		(start 213.05647 -84.117942)
		(mid 212.98271 -84.029416)
		(end 212.95614 -83.917282)
		(width 0.1397)
		(layer "B.Cu")
		(net "USB_P0_DN")
	)
	(arc
		(start 338.6582 -134.789672)
		(mid 338.578746 -134.597854)
		(end 338.386928 -134.5184)
		(width 0.1397)
		(layer "B.Cu")
		(net "USB_P0_DN")
	)
	(arc
		(start 213.1568 -80.701388)
		(mid 213.153007 -80.643501)
		(end 213.141814 -80.58658)
		(width 0.1397)
		(layer "B.Cu")
		(net "USB_P0_DN")
	)
	(arc
		(start 219.61983 -100.960174)
		(mid 219.69359 -100.871648)
		(end 219.72016 -100.759514)
		(width 0.1397)
		(layer "B.Cu")
		(net "USB_P0_DN")
	)
	(arc
		(start 213.05647 -86.579202)
		(mid 213.13023 -86.490676)
		(end 213.1568 -86.378542)
		(width 0.1397)
		(layer "B.Cu")
		(net "USB_P0_DN")
	)
	(arc
		(start 306.515008 -116.904262)
		(mid 305.599981 -116.292767)
		(end 304.5206 -116.078)
		(width 0.1397)
		(layer "B.Cu")
		(net "USB_P0_DN")
	)
	(arc
		(start 213.05647 -85.758782)
		(mid 212.98271 -85.670256)
		(end 212.95614 -85.558122)
		(width 0.1397)
		(layer "B.Cu")
		(net "USB_P0_DN")
	)
	(arc
		(start 213.05647 -83.297522)
		(mid 213.13023 -83.208996)
		(end 213.1568 -83.096862)
		(width 0.1397)
		(layer "B.Cu")
		(net "USB_P0_DN")
	)
	(arc
		(start 213.1568 -82.677762)
		(mid 213.130276 -82.565605)
		(end 213.05647 -82.477102)
		(width 0.1397)
		(layer "B.Cu")
		(net "USB_P0_DN")
	)
	(arc
		(start 219.5195 -102.801674)
		(mid 219.546024 -102.689517)
		(end 219.61983 -102.601014)
		(width 0.1397)
		(layer "B.Cu")
		(net "USB_P0_DN")
	)
	(arc
		(start 219.61983 -102.601014)
		(mid 219.69359 -102.512488)
		(end 219.72016 -102.400354)
		(width 0.1397)
		(layer "B.Cu")
		(net "USB_P0_DN")
	)
	(arc
		(start 213.141814 -80.58658)
		(mid 212.980997 -80.343905)
		(end 212.705442 -80.25003)
		(width 0.1397)
		(layer "B.Cu")
		(net "USB_P0_DN")
	)
	(arc
		(start 213.1568 -85.959442)
		(mid 213.130276 -85.847285)
		(end 213.05647 -85.758782)
		(width 0.1397)
		(layer "B.Cu")
		(net "USB_P0_DN")
	)
	(arc
		(start 219.61983 -103.421434)
		(mid 219.54607 -103.332908)
		(end 219.5195 -103.220774)
		(width 0.1397)
		(layer "B.Cu")
		(net "USB_P0_DN")
	)
	(arc
		(start 212.95614 -83.498182)
		(mid 212.982664 -83.386025)
		(end 213.05647 -83.297522)
		(width 0.1397)
		(layer "B.Cu")
		(net "USB_P0_DN")
	)
	(arc
		(start 219.72016 -96.087692)
		(mid 219.634353 -95.656311)
		(end 219.38996 -95.29064)
		(width 0.1397)
		(layer "B.Cu")
		(net "USB_P0_DN")
	)
	(arc
		(start 219.72016 -101.981254)
		(mid 219.693636 -101.869097)
		(end 219.61983 -101.780594)
		(width 0.1397)
		(layer "B.Cu")
		(net "USB_P0_DN")
	)
	(arc
		(start 318.21374 -127.5969)
		(mid 317.284479 -127.412076)
		(end 316.4967 -126.8857)
		(width 0.1397)
		(layer "B.Cu")
		(net "USB_P0_DN")
	)
	(arc
		(start 213.05647 -87.399622)
		(mid 212.98271 -87.311096)
		(end 212.95614 -87.198962)
		(width 0.1397)
		(layer "B.Cu")
		(net "USB_P0_DN")
	)
	(arc
		(start 212.95614 -85.139022)
		(mid 212.982664 -85.026865)
		(end 213.05647 -84.938362)
		(width 0.1397)
		(layer "B.Cu")
		(net "USB_P0_DN")
	)
	(arc
		(start 219.5195 -101.160834)
		(mid 219.546024 -101.048677)
		(end 219.61983 -100.960174)
		(width 0.1397)
		(layer "B.Cu")
		(net "USB_P0_DN")
	)
	(arc
		(start 219.61983 -101.780594)
		(mid 219.54607 -101.692068)
		(end 219.5195 -101.579934)
		(width 0.1397)
		(layer "B.Cu")
		(net "USB_P0_DN")
	)
	(arc
		(start 332.663546 -134.5184)
		(mid 331.981202 -134.382633)
		(end 331.40269 -133.996176)
		(width 0.1397)
		(layer "B.Cu")
		(net "USB_P0_DN")
	)
	(arc
		(start 213.05647 -82.477102)
		(mid 212.98271 -82.388576)
		(end 212.95614 -82.276442)
		(width 0.1397)
		(layer "B.Cu")
		(net "USB_P0_DN")
	)
	(arc
		(start 219.5195 -99.519994)
		(mid 219.546024 -99.407837)
		(end 219.61983 -99.319334)
		(width 0.1397)
		(layer "B.Cu")
		(net "USB_P0_DN")
	)
	(arc
		(start 219.61983 -100.139754)
		(mid 219.54607 -100.051228)
		(end 219.5195 -99.939094)
		(width 0.1397)
		(layer "B.Cu")
		(net "USB_P0_DN")
	)
	(arc
		(start 325.710804 -128.304544)
		(mid 324.926982 -127.780811)
		(end 324.0024 -127.5969)
		(width 0.1397)
		(layer "B.Cu")
		(net "USB_P0_DN")
	)
	(segment
		(start 68.326 -232.664)
		(end 68.326 -234.061)
		(width 0.508)
		(layer "F.Cu")
		(net "GND")
	)
	(segment
		(start 105.950258 -53.399944)
		(end 105.950004 -53.399944)
		(width 0.3556)
		(layer "F.Cu")
		(net "GND")
	)
	(segment
		(start 123.35002 -102.350062)
		(end 123.850146 -102.850188)
		(width 0.4572)
		(layer "F.Cu")
		(net "GND")
	)
	(segment
		(start 84.627466 -61.341)
		(end 83.801966 -61.341)
		(width 0.508)
		(layer "F.Cu")
		(net "GND")
	)
	(segment
		(start 299.23486 -177.840132)
		(end 298.829984 -177.435256)
		(width 0.3556)
		(layer "F.Cu")
		(net "GND")
	)
	(segment
		(start 52.239164 -187.809886)
		(end 53.369972 -187.809886)
		(width 0.508)
		(layer "F.Cu")
		(net "GND")
	)
	(segment
		(start 128.71577 -88.392)
		(end 128.673606 -88.349836)
		(width 0.3048)
		(layer "F.Cu")
		(net "GND")
	)
	(segment
		(start 121.900442 -77.948282)
		(end 121.540524 -78.3082)
		(width 0.508)
		(layer "F.Cu")
		(net "GND")
	)
	(segment
		(start 108.35005 -36.599876)
		(end 107.950254 -36.20008)
		(width 0.3048)
		(layer "F.Cu")
		(net "GND")
	)
	(segment
		(start 200.669652 -142.503652)
		(end 200.914 -142.748)
		(width 0.508)
		(layer "F.Cu")
		(net "GND")
	)
	(segment
		(start 105.150158 -36.599876)
		(end 104.750362 -36.20008)
		(width 0.3048)
		(layer "F.Cu")
		(net "GND")
	)
	(segment
		(start 114.349784 -90.349832)
		(end 113.849658 -89.849706)
		(width 0.508)
		(layer "F.Cu")
		(net "GND")
	)
	(segment
		(start 198.8185 -216.13876)
		(end 198.8185 -214.8205)
		(width 0.381)
		(layer "F.Cu")
		(net "GND")
	)
	(segment
		(start 238.1758 -113.9698)
		(end 237.236 -113.9698)
		(width 0.508)
		(layer "F.Cu")
		(net "GND")
	)
	(segment
		(start 333.468218 -151.234648)
		(end 332.439518 -151.234648)
		(width 0.508)
		(layer "F.Cu")
		(net "GND")
	)
	(segment
		(start 261.8994 -39.37)
		(end 262.636 -39.37)
		(width 0.508)
		(layer "F.Cu")
		(net "GND")
	)
	(segment
		(start 292.097968 -196.93509)
		(end 292.10127 -196.93509)
		(width 0.3556)
		(layer "F.Cu")
		(net "GND")
	)
	(segment
		(start 34.6075 -78.74)
		(end 34.6075 -79.248)
		(width 0.508)
		(layer "F.Cu")
		(net "GND")
	)
	(segment
		(start 92.78874 -45.033946)
		(end 92.757244 -45.00245)
		(width 0.254)
		(layer "F.Cu")
		(net "GND")
	)
	(segment
		(start 112.85093 -72.06996)
		(end 112.84077 -72.0598)
		(width 0.3048)
		(layer "F.Cu")
		(net "GND")
	)
	(segment
		(start 317.2206 -198.755)
		(end 317.2333 -198.7423)
		(width 0.3048)
		(layer "F.Cu")
		(net "GND")
	)
	(segment
		(start 49.67097 -133.731)
		(end 48.10379 -133.731)
		(width 0.3048)
		(layer "F.Cu")
		(net "GND")
	)
	(segment
		(start 152.4635 -52.07)
		(end 153.543 -52.07)
		(width 0.508)
		(layer "F.Cu")
		(net "GND")
	)
	(segment
		(start 186.309 -49.149)
		(end 186.309 -50.02911)
		(width 0.3048)
		(layer "F.Cu")
		(net "GND")
	)
	(segment
		(start 48.10379 -133.731)
		(end 48.09617 -133.72338)
		(width 0.3048)
		(layer "F.Cu")
		(net "GND")
	)
	(segment
		(start 108.35005 -54.199536)
		(end 108.35005 -54.19979)
		(width 0.3556)
		(layer "F.Cu")
		(net "GND")
	)
	(segment
		(start 258.15036 -130.4544)
		(end 258.15036 -131.91236)
		(width 0.3556)
		(layer "F.Cu")
		(net "GND")
	)
	(segment
		(start 91.549982 -33.399984)
		(end 91.549982 -34.19983)
		(width 0.3048)
		(layer "F.Cu")
		(net "GND")
	)
	(segment
		(start 279.527 -196.215)
		(end 278.892 -196.85)
		(width 0.508)
		(layer "F.Cu")
		(net "GND")
	)
	(segment
		(start 124.350018 -95.350076)
		(end 124.850144 -95.850202)
		(width 0.4572)
		(layer "F.Cu")
		(net "GND")
	)
	(segment
		(start 196.799962 -256.25044)
		(end 196.799962 -253.822962)
		(width 0.508)
		(layer "F.Cu")
		(net "GND")
	)
	(segment
		(start 293.698168 -202.535028)
		(end 293.707312 -202.535028)
		(width 0.3556)
		(layer "F.Cu")
		(net "GND")
	)
	(segment
		(start 279.527 -198.247)
		(end 279.527 -198.501)
		(width 0.508)
		(layer "F.Cu")
		(net "GND")
	)
	(segment
		(start 84.999322 -256.25044)
		(end 84.999322 -253.35611)
		(width 0.508)
		(layer "F.Cu")
		(net "GND")
	)
	(segment
		(start 322.190872 -120.768872)
		(end 322.58 -121.158)
		(width 0.508)
		(layer "F.Cu")
		(net "GND")
	)
	(segment
		(start 285.627318 -171.440094)
		(end 285.226252 -171.84116)
		(width 0.3556)
		(layer "F.Cu")
		(net "GND")
	)
	(segment
		(start 306.578 -85.200236)
		(end 306.324 -84.946236)
		(width 0.508)
		(layer "F.Cu")
		(net "GND")
	)
	(segment
		(start 38.6207 -117.817646)
		(end 38.6207 -118.1862)
		(width 0.508)
		(layer "F.Cu")
		(net "GND")
	)
	(segment
		(start 223.040194 -176.558194)
		(end 223.139 -176.657)
		(width 0.381)
		(layer "F.Cu")
		(net "GND")
	)
	(segment
		(start 167.259 -112.849152)
		(end 167.459152 -112.649)
		(width 0.508)
		(layer "F.Cu")
		(net "GND")
	)
	(segment
		(start 101.999542 -256.25044)
		(end 101.999542 -252.621542)
		(width 0.508)
		(layer "F.Cu")
		(net "GND")
	)
	(segment
		(start 314.325 -77.199998)
		(end 314.706 -76.818998)
		(width 0.508)
		(layer "F.Cu")
		(net "GND")
	)
	(segment
		(start 178.997864 -38.616636)
		(end 178.997864 -39.75608)
		(width 0.508)
		(layer "F.Cu")
		(net "GND")
	)
	(segment
		(start 314.52312 -92.40012)
		(end 314.833 -92.71)
		(width 0.508)
		(layer "F.Cu")
		(net "GND")
	)
	(segment
		(start 45.98797 -142.494)
		(end 45.86097 -142.367)
		(width 0.3048)
		(layer "F.Cu")
		(net "GND")
	)
	(segment
		(start 94.750128 -36.599876)
		(end 94.350332 -36.20008)
		(width 0.3048)
		(layer "F.Cu")
		(net "GND")
	)
	(segment
		(start 187.015628 -138.358372)
		(end 186.563 -138.811)
		(width 0.508)
		(layer "F.Cu")
		(net "GND")
	)
	(segment
		(start 145.034 -38.4175)
		(end 144.9705 -38.4175)
		(width 0.508)
		(layer "F.Cu")
		(net "GND")
	)
	(segment
		(start 95.45447 -89.662)
		(end 94.37497 -89.662)
		(width 0.508)
		(layer "F.Cu")
		(net "GND")
	)
	(segment
		(start 126.350014 -107.350052)
		(end 126.85014 -107.850178)
		(width 0.3048)
		(layer "F.Cu")
		(net "GND")
	)
	(segment
		(start 12.40028 -107.424982)
		(end 12.40028 -104.75849)
		(width 0.508)
		(layer "F.Cu")
		(net "GND")
	)
	(segment
		(start 104.350566 -36.599876)
		(end 104.350058 -36.599876)
		(width 0.3048)
		(layer "F.Cu")
		(net "GND")
	)
	(segment
		(start 171.46397 -66.7385)
		(end 171.46397 -66.421)
		(width 0.508)
		(layer "F.Cu")
		(net "GND")
	)
	(segment
		(start 292.862 -150.495)
		(end 293.37 -151.003)
		(width 0.508)
		(layer "F.Cu")
		(net "GND")
	)
	(segment
		(start 130.999992 -253.38278)
		(end 130.474212 -252.857)
		(width 0.508)
		(layer "F.Cu")
		(net "GND")
	)
	(segment
		(start 254.59436 -132.03936)
		(end 254.635 -132.08)
		(width 0.3556)
		(layer "F.Cu")
		(net "GND")
	)
	(segment
		(start 121.85015 -83.849718)
		(end 121.350024 -84.349844)
		(width 0.508)
		(layer "F.Cu")
		(net "GND")
	)
	(segment
		(start 101.950012 -34.19983)
		(end 101.95433 -34.19983)
		(width 0.3048)
		(layer "F.Cu")
		(net "GND")
	)
	(segment
		(start 325.809864 -172.030136)
		(end 325.698104 -172.141896)
		(width 0.3048)
		(layer "F.Cu")
		(net "GND")
	)
	(segment
		(start 183.007 -121.6025)
		(end 183.896 -121.6025)
		(width 0.381)
		(layer "F.Cu")
		(net "GND")
	)
	(segment
		(start 119.350028 -104.350058)
		(end 119.850154 -104.850184)
		(width 0.4572)
		(layer "F.Cu")
		(net "GND")
	)
	(segment
		(start 296.492168 -202.14082)
		(end 296.50182 -202.14082)
		(width 0.3556)
		(layer "F.Cu")
		(net "GND")
	)
	(segment
		(start 80.579722 -114.394742)
		(end 78.251812 -114.394742)
		(width 0.508)
		(layer "F.Cu")
		(net "GND")
	)
	(segment
		(start 24.825198 -175.746156)
		(end 24.825198 -177.457862)
		(width 0.2032)
		(layer "F.Cu")
		(net "GND")
	)
	(segment
		(start 333.468218 -155.552648)
		(end 331.525118 -155.552648)
		(width 0.508)
		(layer "F.Cu")
		(net "GND")
	)
	(segment
		(start 301.51578 -197.358)
		(end 301.51578 -197.78472)
		(width 0.508)
		(layer "F.Cu")
		(net "GND")
	)
	(segment
		(start 97.859088 -34.99993)
		(end 97.751392 -34.892234)
		(width 0.3048)
		(layer "F.Cu")
		(net "GND")
	)
	(segment
		(start 126.350014 -103.35006)
		(end 126.85014 -103.850186)
		(width 0.4572)
		(layer "F.Cu")
		(net "GND")
	)
	(segment
		(start 129.58953 -86.34984)
		(end 129.90957 -86.0298)
		(width 0.4572)
		(layer "F.Cu")
		(net "GND")
	)
	(segment
		(start 200.800462 -256.25044)
		(end 200.800462 -253.251462)
		(width 0.508)
		(layer "F.Cu")
		(net "GND")
	)
	(segment
		(start 52.6288 -208.3308)
		(end 51.943 -207.645)
		(width 0.508)
		(layer "F.Cu")
		(net "GND")
	)
	(segment
		(start 11.43 -238.040164)
		(end 11.43 -239.522)
		(width 0.508)
		(layer "F.Cu")
		(net "GND")
	)
	(segment
		(start 24.765 -238.865664)
		(end 24.842216 -238.94288)
		(width 0.508)
		(layer "F.Cu")
		(net "GND")
	)
	(segment
		(start 8.522716 -213.8553)
		(end 9.145016 -213.233)
		(width 0.381)
		(layer "F.Cu")
		(net "GND")
	)
	(segment
		(start 68.000372 -250.799092)
		(end 66.38544 -249.18416)
		(width 0.508)
		(layer "F.Cu")
		(net "GND")
	)
	(segment
		(start 116.350034 -98.35007)
		(end 116.85016 -98.850196)
		(width 0.4572)
		(layer "F.Cu")
		(net "GND")
	)
	(segment
		(start 269.24 -51.693064)
		(end 269.24 -52.705)
		(width 0.4064)
		(layer "F.Cu")
		(net "GND")
	)
	(segment
		(start 305.415188 -62.992)
		(end 305.288188 -63.119)
		(width 0.508)
		(layer "F.Cu")
		(net "GND")
	)
	(segment
		(start 105.559098 -45.80001)
		(end 105.950004 -46.190916)
		(width 0.3556)
		(layer "F.Cu")
		(net "GND")
	)
	(segment
		(start 95.957898 -37.798248)
		(end 95.559626 -37.399976)
		(width 0.3556)
		(layer "F.Cu")
		(net "GND")
	)
	(segment
		(start 110.349792 -91.349576)
		(end 110.849664 -90.849704)
		(width 0.4572)
		(layer "F.Cu")
		(net "GND")
	)
	(segment
		(start 124.350018 -99.350068)
		(end 124.850144 -99.850194)
		(width 0.4572)
		(layer "F.Cu")
		(net "GND")
	)
	(segment
		(start 182.799482 -254.080518)
		(end 183.642 -253.238)
		(width 0.508)
		(layer "F.Cu")
		(net "GND")
	)
	(segment
		(start 90.507058 -50.999898)
		(end 90.05316 -50.546)
		(width 0.3048)
		(layer "F.Cu")
		(net "GND")
	)
	(segment
		(start 14.800072 -107.424982)
		(end 14.700758 -107.325668)
		(width 0.508)
		(layer "F.Cu")
		(net "GND")
	)
	(segment
		(start 308.5465 -186.817)
		(end 307.975 -186.817)
		(width 0.508)
		(layer "F.Cu")
		(net "GND")
	)
	(segment
		(start 108.349796 -107.350052)
		(end 108.349796 -108.834174)
		(width 0.3048)
		(layer "F.Cu")
		(net "GND")
	)
	(segment
		(start 16.079216 -181.47538)
		(end 16.079216 -179.50688)
		(width 0.508)
		(layer "F.Cu")
		(net "GND")
	)
	(segment
		(start 321.056 -215.42375)
		(end 321.056 -216.662)
		(width 0.508)
		(layer "F.Cu")
		(net "GND")
	)
	(segment
		(start 327.787 -168.926764)
		(end 328.024236 -169.164)
		(width 0.508)
		(layer "F.Cu")
		(net "GND")
	)
	(segment
		(start 193.6115 -17.145)
		(end 193.6115 -18.034)
		(width 0.508)
		(layer "F.Cu")
		(net "GND")
	)
	(segment
		(start 313.125104 -92.40012)
		(end 314.52312 -92.40012)
		(width 0.508)
		(layer "F.Cu")
		(net "GND")
	)
	(segment
		(start 92.724732 -130.302762)
		(end 92.46997 -130.048)
		(width 0.2032)
		(layer "F.Cu")
		(net "GND")
	)
	(segment
		(start 32.424116 -79.462884)
		(end 31.623 -80.264)
		(width 0.508)
		(layer "F.Cu")
		(net "GND")
	)
	(segment
		(start 103.349806 -84.349844)
		(end 102.84968 -83.849718)
		(width 0.4572)
		(layer "F.Cu")
		(net "GND")
	)
	(segment
		(start 97.751392 -34.892234)
		(end 97.33026 -34.892234)
		(width 0.3048)
		(layer "F.Cu")
		(net "GND")
	)
	(segment
		(start 121.350024 -92.349828)
		(end 121.85015 -91.849702)
		(width 0.4572)
		(layer "F.Cu")
		(net "GND")
	)
	(segment
		(start 58.449972 -186.679078)
		(end 58.449972 -187.809886)
		(width 0.508)
		(layer "F.Cu")
		(net "GND")
	)
	(segment
		(start 15.985998 -177.127662)
		(end 16.333216 -177.47488)
		(width 0.2032)
		(layer "F.Cu")
		(net "GND")
	)
	(segment
		(start 200.279 -183.769)
		(end 201.676 -183.769)
		(width 0.508)
		(layer "F.Cu")
		(net "GND")
	)
	(segment
		(start 108.000292 -252.653292)
		(end 107.95 -252.603)
		(width 0.508)
		(layer "F.Cu")
		(net "GND")
	)
	(segment
		(start 124.350018 -93.349826)
		(end 124.224796 -93.349826)
		(width 0.2032)
		(layer "F.Cu")
		(net "GND")
	)
	(segment
		(start 88.725502 -131.570476)
		(end 88.725502 -132.357368)
		(width 0.2032)
		(layer "F.Cu")
		(net "GND")
	)
	(segment
		(start 45.654722 -142.160752)
		(end 45.86097 -142.367)
		(width 0.508)
		(layer "F.Cu")
		(net "GND")
	)
	(segment
		(start 313.82716 -213.5759)
		(end 312.5851 -213.5759)
		(width 0.3048)
		(layer "F.Cu")
		(net "GND")
	)
	(segment
		(start 19.59991 -102.489762)
		(end 19.59991 -104.79786)
		(width 0.3556)
		(layer "F.Cu")
		(net "GND")
	)
	(segment
		(start 120.350026 -96.350074)
		(end 120.850152 -96.8502)
		(width 0.4572)
		(layer "F.Cu")
		(net "GND")
	)
	(segment
		(start 85.09 -237.871)
		(end 86.233 -237.871)
		(width 0.508)
		(layer "F.Cu")
		(net "GND")
	)
	(segment
		(start 120.35028 -86.34984)
		(end 120.350026 -86.34984)
		(width 0.3048)
		(layer "F.Cu")
		(net "GND")
	)
	(segment
		(start 108.349796 -108.834174)
		(end 107.58297 -109.601)
		(width 0.3048)
		(layer "F.Cu")
		(net "GND")
	)
	(segment
		(start 99.149916 -42.59961)
		(end 99.549966 -42.99966)
		(width 0.3556)
		(layer "F.Cu")
		(net "GND")
	)
	(segment
		(start 293.698168 -201.74458)
		(end 294.097964 -202.144376)
		(width 0.3556)
		(layer "F.Cu")
		(net "GND")
	)
	(segment
		(start 323.259958 -88.650064)
		(end 324.352666 -88.650064)
		(width 0.508)
		(layer "F.Cu")
		(net "GND")
	)
	(segment
		(start 223.74225 -156.329888)
		(end 222.987362 -155.575)
		(width 0.508)
		(layer "F.Cu")
		(net "GND")
	)
	(segment
		(start 66.38544 -249.18416)
		(end 66.339212 -249.18416)
		(width 0.508)
		(layer "F.Cu")
		(net "GND")
	)
	(segment
		(start 118.35003 -89.349834)
		(end 118.850156 -88.849708)
		(width 0.508)
		(layer "F.Cu")
		(net "GND")
	)
	(segment
		(start 81.000092 -256.25044)
		(end 81.000092 -253.29388)
		(width 0.508)
		(layer "F.Cu")
		(net "GND")
	)
	(segment
		(start 54.779164 -187.809886)
		(end 55.909972 -187.809886)
		(width 0.508)
		(layer "F.Cu")
		(net "GND")
	)
	(segment
		(start 86.000082 -253.64313)
		(end 86.659212 -252.984)
		(width 0.508)
		(layer "F.Cu")
		(net "GND")
	)
	(segment
		(start 284.78861 -195.580254)
		(end 284.78861 -195.563744)
		(width 0.3556)
		(layer "F.Cu")
		(net "GND")
	)
	(segment
		(start 274.240752 -191.384936)
		(end 274.240752 -192.230248)
		(width 0.508)
		(layer "F.Cu")
		(net "GND")
	)
	(segment
		(start 103.949754 -44.19981)
		(end 104.349804 -44.59986)
		(width 0.3556)
		(layer "F.Cu")
		(net "GND")
	)
	(segment
		(start 95.45447 -95.377)
		(end 95.45447 -94.234)
		(width 0.508)
		(layer "F.Cu")
		(net "GND")
	)
	(segment
		(start 94.37497 -89.662)
		(end 94.12097 -89.408)
		(width 0.508)
		(layer "F.Cu")
		(net "GND")
	)
	(segment
		(start 121.350024 -90.349832)
		(end 120.850152 -90.849704)
		(width 0.508)
		(layer "F.Cu")
		(net "GND")
	)
	(segment
		(start 40.999918 -81.079086)
		(end 40.618918 -81.460086)
		(width 0.3048)
		(layer "F.Cu")
		(net "GND")
	)
	(segment
		(start 314.389008 -54.799992)
		(end 314.833 -54.356)
		(width 0.508)
		(layer "F.Cu")
		(net "GND")
	)
	(segment
		(start 40.999918 -79.590138)
		(end 40.999918 -81.079086)
		(width 0.3048)
		(layer "F.Cu")
		(net "GND")
	)
	(segment
		(start 291.3126 -153.7716)
		(end 292.1 -154.559)
		(width 0.508)
		(layer "F.Cu")
		(net "GND")
	)
	(segment
		(start 211.489798 -102.650798)
		(end 211.455 -102.616)
		(width 0.3048)
		(layer "F.Cu")
		(net "GND")
	)
	(segment
		(start 148.999702 -253.09449)
		(end 148.508212 -252.603)
		(width 0.508)
		(layer "F.Cu")
		(net "GND")
	)
	(segment
		(start 88.999822 -253.41961)
		(end 88.564212 -252.984)
		(width 0.508)
		(layer "F.Cu")
		(net "GND")
	)
	(segment
		(start 55.909972 -186.679078)
		(end 55.909972 -187.809886)
		(width 0.508)
		(layer "F.Cu")
		(net "GND")
	)
	(segment
		(start 118.35003 -98.35007)
		(end 118.850156 -98.850196)
		(width 0.4572)
		(layer "F.Cu")
		(net "GND")
	)
	(segment
		(start 103.385366 -62.3316)
		(end 104.121966 -62.3316)
		(width 0.3048)
		(layer "F.Cu")
		(net "GND")
	)
	(segment
		(start 86.54161 -130.57505)
		(end 86.14156 -130.175)
		(width 0.2032)
		(layer "F.Cu")
		(net "GND")
	)
	(segment
		(start 288.034984 -183.44007)
		(end 288.030666 -183.44007)
		(width 0.3556)
		(layer "F.Cu")
		(net "GND")
	)
	(segment
		(start 110.349792 -98.35007)
		(end 109.849666 -98.850196)
		(width 0.4572)
		(layer "F.Cu")
		(net "GND")
	)
	(segment
		(start 118.35003 -94.349824)
		(end 118.850156 -93.849698)
		(width 0.4572)
		(layer "F.Cu")
		(net "GND")
	)
	(segment
		(start 199.898 -184.2008)
		(end 199.9742 -184.0738)
		(width 0.508)
		(layer "F.Cu")
		(net "GND")
	)
	(segment
		(start 116.205 -30.0355)
		(end 116.205 -30.734)
		(width 0.508)
		(layer "F.Cu")
		(net "GND")
	)
	(segment
		(start 278.4475 -192.2145)
		(end 278.13 -192.532)
		(width 0.508)
		(layer "F.Cu")
		(net "GND")
	)
	(segment
		(start 111.34979 -89.349834)
		(end 111.849662 -89.849706)
		(width 0.4572)
		(layer "F.Cu")
		(net "GND")
	)
	(segment
		(start 278.384 -208.494376)
		(end 279.019 -209.129376)
		(width 0.508)
		(layer "F.Cu")
		(net "GND")
	)
	(segment
		(start 105.150158 -43.800014)
		(end 105.549954 -44.19981)
		(width 0.3556)
		(layer "F.Cu")
		(net "GND")
	)
	(segment
		(start 279.273 -197.231)
		(end 278.892 -196.85)
		(width 0.508)
		(layer "F.Cu")
		(net "GND")
	)
	(segment
		(start 204.5335 -218.567)
		(end 204.5335 -217.424)
		(width 0.508)
		(layer "F.Cu")
		(net "GND")
	)
	(segment
		(start 290.498022 -201.735182)
		(end 290.495482 -201.735182)
		(width 0.3556)
		(layer "F.Cu")
		(net "GND")
	)
	(segment
		(start 166.249858 -9.863328)
		(end 166.249858 -11.210036)
		(width 0.508)
		(layer "F.Cu")
		(net "GND")
	)
	(segment
		(start 201.799952 -253.742952)
		(end 201.799952 -256.25044)
		(width 0.508)
		(layer "F.Cu")
		(net "GND")
	)
	(segment
		(start 45.80001 -79.590138)
		(end 45.80001 -81.587086)
		(width 0.3048)
		(layer "F.Cu")
		(net "GND")
	)
	(segment
		(start 108.349796 -101.350064)
		(end 107.84967 -101.85019)
		(width 0.4572)
		(layer "F.Cu")
		(net "GND")
	)
	(segment
		(start 120.000522 -256.25044)
		(end 120.000522 -253.29769)
		(width 0.508)
		(layer "F.Cu")
		(net "GND")
	)
	(segment
		(start 279.527 -198.501)
		(end 278.765 -199.263)
		(width 0.508)
		(layer "F.Cu")
		(net "GND")
	)
	(segment
		(start 171.154344 -27.399996)
		(end 170.191176 -27.399996)
		(width 0.508)
		(layer "F.Cu")
		(net "GND")
	)
	(segment
		(start 270.891 -45.9232)
		(end 270.891 -47.117)
		(width 0.508)
		(layer "F.Cu")
		(net "GND")
	)
	(segment
		(start 118.850156 -88.849708)
		(end 119.350028 -88.349836)
		(width 0.508)
		(layer "F.Cu")
		(net "GND")
	)
	(segment
		(start 282.058872 -215.146636)
		(end 282.897072 -215.146636)
		(width 0.508)
		(layer "F.Cu")
		(net "GND")
	)
	(segment
		(start 273.7485 -159.385)
		(end 272.923 -159.385)
		(width 0.508)
		(layer "F.Cu")
		(net "GND")
	)
	(segment
		(start 187.3885 -140.589)
		(end 186.553348 -140.598652)
		(width 0.508)
		(layer "F.Cu")
		(net "GND")
	)
	(segment
		(start 109.15015 -35.80003)
		(end 109.5502 -36.20008)
		(width 0.3048)
		(layer "F.Cu")
		(net "GND")
	)
	(segment
		(start 110.86719 -104.832658)
		(end 110.86719 -105.82783)
		(width 0.3048)
		(layer "F.Cu")
		(net "GND")
	)
	(segment
		(start 308.675024 -69.200014)
		(end 307.071268 -69.200014)
		(width 0.508)
		(layer "F.Cu")
		(net "GND")
	)
	(segment
		(start 90.750136 -50.999898)
		(end 90.507058 -50.999898)
		(width 0.3048)
		(layer "F.Cu")
		(net "GND")
	)
	(segment
		(start 224.028 -83.82)
		(end 224.356676 -83.491324)
		(width 0.508)
		(layer "F.Cu")
		(net "GND")
	)
	(segment
		(start 118.35003 -92.349828)
		(end 118.850156 -91.849702)
		(width 0.4572)
		(layer "F.Cu")
		(net "GND")
	)
	(segment
		(start 52.599844 -77.08011)
		(end 52.599844 -75.544172)
		(width 0.3048)
		(layer "F.Cu")
		(net "GND")
	)
	(segment
		(start 293.634922 -169.835322)
		(end 293.241984 -169.442384)
		(width 0.3556)
		(layer "F.Cu")
		(net "GND")
	)
	(segment
		(start 124.224796 -93.349826)
		(end 123.83897 -92.964)
		(width 0.2032)
		(layer "F.Cu")
		(net "GND")
	)
	(segment
		(start 137.599166 -63.177166)
		(end 137.668 -63.246)
		(width 0.254)
		(layer "F.Cu")
		(net "GND")
	)
	(segment
		(start 183.642 -253.238)
		(end 183.642 -253.111)
		(width 0.508)
		(layer "F.Cu")
		(net "GND")
	)
	(segment
		(start 19.762216 -195.57238)
		(end 19.762216 -196.52488)
		(width 0.508)
		(layer "F.Cu")
		(net "GND")
	)
	(segment
		(start 93.549978 -49.799748)
		(end 93.949774 -49.399952)
		(width 0.3556)
		(layer "F.Cu")
		(net "GND")
	)
	(segment
		(start 91.549982 -46.999906)
		(end 91.55938 -46.999906)
		(width 0.254)
		(layer "F.Cu")
		(net "GND")
	)
	(segment
		(start 92.350082 -39.800022)
		(end 91.950286 -39.400226)
		(width 0.3048)
		(layer "F.Cu")
		(net "GND")
	)
	(segment
		(start 25.604216 -202.87488)
		(end 25.350216 -203.12888)
		(width 0.3048)
		(layer "F.Cu")
		(net "GND")
	)
	(segment
		(start 91.549982 -45.39996)
		(end 91.45905 -45.39996)
		(width 0.3048)
		(layer "F.Cu")
		(net "GND")
	)
	(segment
		(start 91.952318 -46.59757)
		(end 91.952318 -46.606968)
		(width 0.254)
		(layer "F.Cu")
		(net "GND")
	)
	(segment
		(start 127.350012 -84.349844)
		(end 128.402842 -84.349844)
		(width 0.4572)
		(layer "F.Cu")
		(net "GND")
	)
	(segment
		(start 285.94558 -191.3255)
		(end 286.05734 -191.21374)
		(width 0.508)
		(layer "F.Cu")
		(net "GND")
	)
	(segment
		(start 64.939164 -185.269886)
		(end 66.069972 -185.269886)
		(width 0.508)
		(layer "F.Cu")
		(net "GND")
	)
	(segment
		(start 90.778076 -33.399984)
		(end 91.549982 -33.399984)
		(width 0.3048)
		(layer "F.Cu")
		(net "GND")
	)
	(segment
		(start 100.350066 -48.599852)
		(end 100.749862 -48.999648)
		(width 0.3556)
		(layer "F.Cu")
		(net "GND")
	)
	(segment
		(start 75.786742 -128.392682)
		(end 77.361288 -128.392682)
		(width 0.3048)
		(layer "F.Cu")
		(net "GND")
	)
	(segment
		(start 286.49803 -196.135244)
		(end 286.49803 -195.57238)
		(width 0.3556)
		(layer "F.Cu")
		(net "GND")
	)
	(segment
		(start 308.675024 -68.400168)
		(end 307.392578 -68.400168)
		(width 0.508)
		(layer "F.Cu")
		(net "GND")
	)
	(segment
		(start 182.38597 -66.7385)
		(end 182.38597 -65.532)
		(width 0.508)
		(layer "F.Cu")
		(net "GND")
	)
	(segment
		(start 27.090116 -202.87488)
		(end 25.604216 -202.87488)
		(width 0.3048)
		(layer "F.Cu")
		(net "GND")
	)
	(segment
		(start 113.349786 -97.350072)
		(end 112.84966 -97.850198)
		(width 0.4572)
		(layer "F.Cu")
		(net "GND")
	)
	(segment
		(start 68.609972 -184.139078)
		(end 68.609972 -185.269886)
		(width 0.508)
		(layer "F.Cu")
		(net "GND")
	)
	(segment
		(start 91.55938 -46.999906)
		(end 91.952318 -46.606968)
		(width 0.254)
		(layer "F.Cu")
		(net "GND")
	)
	(segment
		(start 90.750136 -45.39996)
		(end 90.5002 -45.39996)
		(width 0.3048)
		(layer "F.Cu")
		(net "GND")
	)
	(segment
		(start 93.150182 -34.19983)
		(end 93.549978 -33.800034)
		(width 0.3048)
		(layer "F.Cu")
		(net "GND")
	)
	(segment
		(start 309.97398 -152.30602)
		(end 308.737 -153.543)
		(width 0.508)
		(layer "F.Cu")
		(net "GND")
	)
	(segment
		(start 121.350024 -83.349846)
		(end 121.350278 -83.349846)
		(width 0.508)
		(layer "F.Cu")
		(net "GND")
	)
	(segment
		(start 118.999762 -253.57455)
		(end 118.409212 -252.984)
		(width 0.508)
		(layer "F.Cu")
		(net "GND")
	)
	(segment
		(start 98.131376 -34.893504)
		(end 98.02495 -34.99993)
		(width 0.3048)
		(layer "F.Cu")
		(net "GND")
	)
	(segment
		(start 279.8445 -197.231)
		(end 279.273 -197.231)
		(width 0.508)
		(layer "F.Cu")
		(net "GND")
	)
	(segment
		(start 308.37124 -219.0115)
		(end 309.1815 -219.0115)
		(width 0.381)
		(layer "F.Cu")
		(net "GND")
	)
	(segment
		(start 185.995564 -198.941436)
		(end 185.792872 -198.941436)
		(width 0.508)
		(layer "F.Cu")
		(net "GND")
	)
	(segment
		(start 190.69812 -33.089088)
		(end 190.732664 -33.089088)
		(width 0.508)
		(layer "F.Cu")
		(net "GND")
	)
	(segment
		(start 58.449972 -184.139078)
		(end 58.449972 -185.269886)
		(width 0.508)
		(layer "F.Cu")
		(net "GND")
	)
	(segment
		(start 112.349788 -99.350068)
		(end 112.349534 -99.350068)
		(width 0.4572)
		(layer "F.Cu")
		(net "GND")
	)
	(segment
		(start 114.349784 -98.35007)
		(end 113.849658 -98.850196)
		(width 0.4572)
		(layer "F.Cu")
		(net "GND")
	)
	(segment
		(start 114.349784 -89.349834)
		(end 113.849658 -88.849708)
		(width 0.508)
		(layer "F.Cu")
		(net "GND")
	)
	(segment
		(start 48.289972 -187.809886)
		(end 48.289972 -188.940694)
		(width 0.508)
		(layer "F.Cu")
		(net "GND")
	)
	(segment
		(start 181.36997 -66.7385)
		(end 181.36997 -65.659)
		(width 0.508)
		(layer "F.Cu")
		(net "GND")
	)
	(segment
		(start 105.159048 -45.39996)
		(end 105.150158 -45.39996)
		(width 0.3556)
		(layer "F.Cu")
		(net "GND")
	)
	(segment
		(start 86.54161 -137.1854)
		(end 86.54161 -138.64336)
		(width 0.2032)
		(layer "F.Cu")
		(net "GND")
	)
	(segment
		(start 299.23486 -177.040032)
		(end 299.225208 -177.040032)
		(width 0.3556)
		(layer "F.Cu")
		(net "GND")
	)
	(segment
		(start 199.205596 -122.320812)
		(end 199.205596 -123.513596)
		(width 0.508)
		(layer "F.Cu")
		(net "GND")
	)
	(segment
		(start 87.26297 -131.694936)
		(end 87.26297 -131.318)
		(width 0.2032)
		(layer "F.Cu")
		(net "GND")
	)
	(segment
		(start 285.1912 -191.3255)
		(end 285.94558 -191.3255)
		(width 0.508)
		(layer "F.Cu")
		(net "GND")
	)
	(segment
		(start 123.000262 -256.25044)
		(end 123.000262 -253.38405)
		(width 0.508)
		(layer "F.Cu")
		(net "GND")
	)
	(segment
		(start 221.6658 -117.2845)
		(end 222.1103 -117.729)
		(width 0.508)
		(layer "F.Cu")
		(net "GND")
	)
	(segment
		(start 265.675872 -45.868336)
		(end 265.675872 -47.117)
		(width 0.508)
		(layer "F.Cu")
		(net "GND")
	)
	(segment
		(start 90.5002 -45.39996)
		(end 90.18016 -45.72)
		(width 0.3048)
		(layer "F.Cu")
		(net "GND")
	)
	(segment
		(start 164.90315 -11.210036)
		(end 166.249858 -11.210036)
		(width 0.508)
		(layer "F.Cu")
		(net "GND")
	)
	(segment
		(start 291.211 -157.353)
		(end 291.338 -157.226)
		(width 0.381)
		(layer "F.Cu")
		(net "GND")
	)
	(segment
		(start 58.449972 -187.809886)
		(end 58.449972 -188.940694)
		(width 0.508)
		(layer "F.Cu")
		(net "GND")
	)
	(segment
		(start 76.537566 -85.344)
		(end 75.673966 -85.344)
		(width 0.3048)
		(layer "F.Cu")
		(net "GND")
	)
	(segment
		(start 308.5465 -185.674)
		(end 308.102 -185.674)
		(width 0.508)
		(layer "F.Cu")
		(net "GND")
	)
	(segment
		(start 59.591956 -226.383088)
		(end 59.591956 -227.428044)
		(width 0.2032)
		(layer "F.Cu")
		(net "GND")
	)
	(segment
		(start 239.08004 -94.36989)
		(end 238.24311 -94.36989)
		(width 0.508)
		(layer "F.Cu")
		(net "GND")
	)
	(segment
		(start 38.93185 -175.32985)
		(end 38.989 -175.32985)
		(width 0.508)
		(layer "F.Cu")
		(net "GND")
	)
	(segment
		(start 313.125104 -82.80019)
		(end 314.579 -82.80019)
		(width 0.508)
		(layer "F.Cu")
		(net "GND")
	)
	(segment
		(start 86.621366 -66.7004)
		(end 87.326216 -66.7004)
		(width 0.508)
		(layer "F.Cu")
		(net "GND")
	)
	(segment
		(start 268.4018 -45.466)
		(end 268.901164 -44.966636)
		(width 0.508)
		(layer "F.Cu")
		(net "GND")
	)
	(segment
		(start 24.425148 -168.802812)
		(end 24.207216 -168.58488)
		(width 0.2032)
		(layer "F.Cu")
		(net "GND")
	)
	(segment
		(start 94.750128 -53.399944)
		(end 95.149924 -53.79974)
		(width 0.3556)
		(layer "F.Cu")
		(net "GND")
	)
	(segment
		(start 107.0356 -62.5856)
		(end 106.788966 -62.5856)
		(width 0.508)
		(layer "F.Cu")
		(net "GND")
	)
	(segment
		(start 272.923 -160.401)
		(end 272.542 -160.782)
		(width 0.508)
		(layer "F.Cu")
		(net "GND")
	)
	(segment
		(start 50.3555 -203.99375)
		(end 48.73625 -203.99375)
		(width 0.508)
		(layer "F.Cu")
		(net "GND")
	)
	(segment
		(start 119.350028 -88.349836)
		(end 119.350028 -88.068404)
		(width 0.3048)
		(layer "F.Cu")
		(net "GND")
	)
	(segment
		(start 135.000492 -256.25044)
		(end 135.000492 -253.21641)
		(width 0.508)
		(layer "F.Cu")
		(net "GND")
	)
	(segment
		(start 109.349794 -82.349848)
		(end 109.352842 -82.3468)
		(width 0.4572)
		(layer "F.Cu")
		(net "GND")
	)
	(segment
		(start 107.44327 -72.9488)
		(end 107.31627 -72.8218)
		(width 0.508)
		(layer "F.Cu")
		(net "GND")
	)
	(segment
		(start 313.125104 -93.20022)
		(end 314.59678 -93.20022)
		(width 0.508)
		(layer "F.Cu")
		(net "GND")
	)
	(segment
		(start 255.905 -123.825)
		(end 255.905 -123.317)
		(width 0.3048)
		(layer "F.Cu")
		(net "GND")
	)
	(segment
		(start 171.226988 -33.066228)
		(end 170.448224 -33.066228)
		(width 0.508)
		(layer "F.Cu")
		(net "GND")
	)
	(segment
		(start 121.540524 -78.3082)
		(end 120.58777 -78.3082)
		(width 0.508)
		(layer "F.Cu")
		(net "GND")
	)
	(segment
		(start 122.350022 -82.349594)
		(end 121.915428 -81.915)
		(width 0.508)
		(layer "F.Cu")
		(net "GND")
	)
	(segment
		(start 347.374718 -141.989048)
		(end 347.882718 -141.481048)
		(width 0.508)
		(layer "F.Cu")
		(net "GND")
	)
	(segment
		(start 290.1315 -70.739)
		(end 290.703 -70.739)
		(width 0.508)
		(layer "F.Cu")
		(net "GND")
	)
	(segment
		(start 272.034 -18.062448)
		(end 272.034 -18.034)
		(width 0.508)
		(layer "F.Cu")
		(net "GND")
	)
	(segment
		(start 292.735 -210.058)
		(end 294.12946 -210.058)
		(width 0.508)
		(layer "F.Cu")
		(net "GND")
	)
	(segment
		(start 284.835854 -172.231558)
		(end 285.226252 -171.84116)
		(width 0.3556)
		(layer "F.Cu")
		(net "GND")
	)
	(segment
		(start 336.071718 -158.029148)
		(end 336.071718 -159.108648)
		(width 0.508)
		(layer "F.Cu")
		(net "GND")
	)
	(segment
		(start 306.89423 -62.992)
		(end 305.415188 -62.992)
		(width 0.508)
		(layer "F.Cu")
		(net "GND")
	)
	(segment
		(start 349.964248 -150.853648)
		(end 350.2152 -151.1046)
		(width 0.508)
		(layer "F.Cu")
		(net "GND")
	)
	(segment
		(start 313.125104 -64.400176)
		(end 314.186824 -64.400176)
		(width 0.508)
		(layer "F.Cu")
		(net "GND")
	)
	(segment
		(start 217.805 -164.9095)
		(end 218.7575 -164.9095)
		(width 0.508)
		(layer "F.Cu")
		(net "GND")
	)
	(segment
		(start 303.67986 -94.97314)
		(end 304.038 -94.615)
		(width 0.3048)
		(layer "F.Cu")
		(net "GND")
	)
	(segment
		(start 75.786742 -137.892282)
		(end 77.462888 -137.892282)
		(width 0.3048)
		(layer "F.Cu")
		(net "GND")
	)
	(segment
		(start 103.959152 -45.80001)
		(end 103.559102 -45.39996)
		(width 0.3556)
		(layer "F.Cu")
		(net "GND")
	)
	(segment
		(start 308.675024 -50.8)
		(end 307.467 -50.8)
		(width 0.508)
		(layer "F.Cu")
		(net "GND")
	)
	(segment
		(start 42.38625 -172.28439)
		(end 42.38625 -171.0055)
		(width 0.508)
		(layer "F.Cu")
		(net "GND")
	)
	(segment
		(start 100.47097 -75.057)
		(end 101.18979 -74.33818)
		(width 0.508)
		(layer "F.Cu")
		(net "GND")
	)
	(segment
		(start 284.834838 -169.840148)
		(end 284.834838 -169.843196)
		(width 0.3556)
		(layer "F.Cu")
		(net "GND")
	)
	(segment
		(start 159.5755 -146.05)
		(end 159.5755 -144.8308)
		(width 0.508)
		(layer "F.Cu")
		(net "GND")
	)
	(segment
		(start 14.700758 -107.325668)
		(end 14.700758 -104.871012)
		(width 0.508)
		(layer "F.Cu")
		(net "GND")
	)
	(segment
		(start 331.343 -211.8995)
		(end 331.343 -212.852)
		(width 0.508)
		(layer "F.Cu")
		(net "GND")
	)
	(segment
		(start 123.35002 -107.350052)
		(end 123.850146 -107.850178)
		(width 0.4572)
		(layer "F.Cu")
		(net "GND")
	)
	(segment
		(start 107.349798 -101.350064)
		(end 106.849672 -101.85019)
		(width 0.4572)
		(layer "F.Cu")
		(net "GND")
	)
	(segment
		(start 120.350026 -86.104222)
		(end 120.383554 -86.070694)
		(width 0.3048)
		(layer "F.Cu")
		(net "GND")
	)
	(segment
		(start 179.886864 -33.056068)
		(end 179.102004 -33.056068)
		(width 0.3048)
		(layer "F.Cu")
		(net "GND")
	)
	(segment
		(start 337.684872 -167.623236)
		(end 337.684872 -169.282872)
		(width 0.3048)
		(layer "F.Cu")
		(net "GND")
	)
	(segment
		(start 104.756966 -34.59734)
		(end 104.747568 -34.59734)
		(width 0.3048)
		(layer "F.Cu")
		(net "GND")
	)
	(segment
		(start 219.7735 -168.92524)
		(end 221.107 -168.92524)
		(width 0.3048)
		(layer "F.Cu")
		(net "GND")
	)
	(segment
		(start 68.707 -54.5465)
		(end 68.707 -55.2704)
		(width 0.508)
		(layer "F.Cu")
		(net "GND")
	)
	(segment
		(start 104.750108 -53.79974)
		(end 104.350312 -53.399944)
		(width 0.3556)
		(layer "F.Cu")
		(net "GND")
	)
	(segment
		(start 106.349546 -103.35006)
		(end 105.849674 -102.850188)
		(width 0.4064)
		(layer "F.Cu")
		(net "GND")
	)
	(segment
		(start 172.47997 -65.913)
		(end 172.22597 -65.659)
		(width 0.508)
		(layer "F.Cu")
		(net "GND")
	)
	(segment
		(start 290.123372 -71.700136)
		(end 291.0332 -71.700136)
		(width 0.508)
		(layer "F.Cu")
		(net "GND")
	)
	(segment
		(start 112.349534 -99.350068)
		(end 111.849662 -98.850196)
		(width 0.4572)
		(layer "F.Cu")
		(net "GND")
	)
	(segment
		(start 68.999862 -256.00914)
		(end 68.999862 -250.31065)
		(width 0.508)
		(layer "F.Cu")
		(net "GND")
	)
	(segment
		(start 82.43697 -128.7145)
		(end 83.45297 -128.7145)
		(width 0.508)
		(layer "F.Cu")
		(net "GND")
	)
	(segment
		(start 105.559098 -45.80001)
		(end 105.159048 -45.39996)
		(width 0.3556)
		(layer "F.Cu")
		(net "GND")
	)
	(segment
		(start 308.675024 -66.000122)
		(end 305.392836 -66.000122)
		(width 0.508)
		(layer "F.Cu")
		(net "GND")
	)
	(segment
		(start 125.76937 -81.026)
		(end 125.36297 -81.4324)
		(width 0.508)
		(layer "F.Cu")
		(net "GND")
	)
	(segment
		(start 148.67001 -9.863328)
		(end 148.67001 -11.210036)
		(width 0.508)
		(layer "F.Cu")
		(net "GND")
	)
	(segment
		(start 284.618684 -173.84014)
		(end 284.48 -173.701456)
		(width 0.3556)
		(layer "F.Cu")
		(net "GND")
	)
	(segment
		(start 192.024 -148.1455)
		(end 192.5955 -148.1455)
		(width 0.381)
		(layer "F.Cu")
		(net "GND")
	)
	(segment
		(start 116.000022 -253.23419)
		(end 116.250212 -252.984)
		(width 0.508)
		(layer "F.Cu")
		(net "GND")
	)
	(segment
		(start 99.159568 -47.399956)
		(end 98.759518 -46.999906)
		(width 0.3556)
		(layer "F.Cu")
		(net "GND")
	)
	(segment
		(start 80.167226 -24.4602)
		(end 80.294226 -24.4602)
		(width 0.508)
		(layer "F.Cu")
		(net "GND")
	)
	(segment
		(start 308.675024 -91.60002)
		(end 307.37302 -91.60002)
		(width 0.508)
		(layer "F.Cu")
		(net "GND")
	)
	(segment
		(start 174.743872 -193.035936)
		(end 174.743872 -191.842136)
		(width 0.508)
		(layer "F.Cu")
		(net "GND")
	)
	(segment
		(start 184.031128 -16.628364)
		(end 185.157364 -16.628364)
		(width 0.508)
		(layer "F.Cu")
		(net "GND")
	)
	(segment
		(start 182.6768 -51.7652)
		(end 182.6768 -51.308)
		(width 0.508)
		(layer "F.Cu")
		(net "GND")
	)
	(segment
		(start 172.47997 -66.7385)
		(end 172.47997 -65.913)
		(width 0.508)
		(layer "F.Cu")
		(net "GND")
	)
	(segment
		(start 109.349794 -101.350064)
		(end 108.849668 -101.85019)
		(width 0.4572)
		(layer "F.Cu")
		(net "GND")
	)
	(segment
		(start 254.9525 -117.96776)
		(end 254.23876 -117.96776)
		(width 0.3048)
		(layer "F.Cu")
		(net "GND")
	)
	(segment
		(start 252.603 -137.2235)
		(end 252.603 -138.1252)
		(width 0.508)
		(layer "F.Cu")
		(net "GND")
	)
	(segment
		(start 258.15036 -131.91236)
		(end 258.191 -131.953)
		(width 0.3556)
		(layer "F.Cu")
		(net "GND")
	)
	(segment
		(start 292.097968 -202.535028)
		(end 292.097968 -202.598528)
		(width 0.3556)
		(layer "F.Cu")
		(net "GND")
	)
	(segment
		(start 313.125104 -77.199998)
		(end 314.325 -77.199998)
		(width 0.508)
		(layer "F.Cu")
		(net "GND")
	)
	(segment
		(start 135.000492 -253.21641)
		(end 134.641082 -252.857)
		(width 0.508)
		(layer "F.Cu")
		(net "GND")
	)
	(segment
		(start 290.89096 -197.33768)
		(end 290.89731 -197.34403)
		(width 0.3556)
		(layer "F.Cu")
		(net "GND")
	)
	(segment
		(start 174.51197 -66.7385)
		(end 174.51197 -65.659)
		(width 0.508)
		(layer "F.Cu")
		(net "GND")
	)
	(segment
		(start 219.992448 -22.828504)
		(end 219.992448 -21.749004)
		(width 0.508)
		(layer "F.Cu")
		(net "GND")
	)
	(segment
		(start 84.709 -241.2619)
		(end 84.709 -242.316)
		(width 0.508)
		(layer "F.Cu")
		(net "GND")
	)
	(segment
		(start 86.000082 -256.25044)
		(end 86.000082 -253.64313)
		(width 0.508)
		(layer "F.Cu")
		(net "GND")
	)
	(segment
		(start 84.963 -32.0294)
		(end 85.4964 -32.0294)
		(width 0.254)
		(layer "F.Cu")
		(net "GND")
	)
	(segment
		(start 67.691 -54.5465)
		(end 67.691 -55.372)
		(width 0.508)
		(layer "F.Cu")
		(net "GND")
	)
	(segment
		(start 292.354 -150.495)
		(end 292.862 -150.495)
		(width 0.508)
		(layer "F.Cu")
		(net "GND")
	)
	(segment
		(start 177.854864 -38.616636)
		(end 177.854864 -39.717472)
		(width 0.508)
		(layer "F.Cu")
		(net "GND")
	)
	(segment
		(start 115.349782 -89.349834)
		(end 114.349784 -90.349832)
		(width 0.3048)
		(layer "F.Cu")
		(net "GND")
	)
	(segment
		(start 110.349792 -92.349828)
		(end 109.849666 -91.849702)
		(width 0.4572)
		(layer "F.Cu")
		(net "GND")
	)
	(segment
		(start 54.59984 -79.590138)
		(end 54.59984 -81.545176)
		(width 0.3048)
		(layer "F.Cu")
		(net "GND")
	)
	(segment
		(start 192.3415 -25.273)
		(end 192.3415 -26.1747)
		(width 0.508)
		(layer "F.Cu")
		(net "GND")
	)
	(segment
		(start 292.034976 -167.440356)
		(end 292.439598 -167.844978)
		(width 0.3556)
		(layer "F.Cu")
		(net "GND")
	)
	(segment
		(start 93.950028 -34.19983)
		(end 93.949774 -34.19983)
		(width 0.3048)
		(layer "F.Cu")
		(net "GND")
	)
	(segment
		(start 187.72886 -145.58264)
		(end 187.0456 -145.58264)
		(width 0.3556)
		(layer "F.Cu")
		(net "GND")
	)
	(segment
		(start 281.423872 -63.699136)
		(end 280.107136 -63.699136)
		(width 0.508)
		(layer "F.Cu")
		(net "GND")
	)
	(segment
		(start 17.59966 -99.980242)
		(end 17.59966 -97.75571)
		(width 0.3556)
		(layer "F.Cu")
		(net "GND")
	)
	(segment
		(start 307.398166 -94.800166)
		(end 306.832 -94.234)
		(width 0.508)
		(layer "F.Cu")
		(net "GND")
	)
	(segment
		(start 92.350082 -35.800284)
		(end 91.950286 -36.20008)
		(width 0.3048)
		(layer "F.Cu")
		(net "GND")
	)
	(segment
		(start 291.0332 -71.0692)
		(end 291.0332 -71.700136)
		(width 0.508)
		(layer "F.Cu")
		(net "GND")
	)
	(segment
		(start 184.903872 -192.527936)
		(end 186.250072 -192.527936)
		(width 0.508)
		(layer "F.Cu")
		(net "GND")
	)
	(segment
		(start 284.834838 -171.449746)
		(end 285.226252 -171.84116)
		(width 0.3556)
		(layer "F.Cu")
		(net "GND")
	)
	(segment
		(start 332.431136 -199.588628)
		(end 332.431136 -199.462136)
		(width 0.508)
		(layer "F.Cu")
		(net "GND")
	)
	(segment
		(start 215.773 -110.8075)
		(end 216.8525 -110.8075)
		(width 0.508)
		(layer "F.Cu")
		(net "GND")
	)
	(segment
		(start 38.47084 -174.86884)
		(end 38.93185 -175.32985)
		(width 0.508)
		(layer "F.Cu")
		(net "GND")
	)
	(segment
		(start 80.841342 -122.880882)
		(end 76.228448 -122.880882)
		(width 0.508)
		(layer "F.Cu")
		(net "GND")
	)
	(segment
		(start 192.5955 -148.1455)
		(end 193.215768 -147.525232)
		(width 0.381)
		(layer "F.Cu")
		(net "GND")
	)
	(segment
		(start 198.890636 -168.664636)
		(end 199.517 -169.291)
		(width 0.508)
		(layer "F.Cu")
		(net "GND")
	)
	(segment
		(start 126.70917 -76.2508)
		(end 126.70917 -76.924154)
		(width 0.508)
		(layer "F.Cu")
		(net "GND")
	)
	(segment
		(start 331.665072 -110.435136)
		(end 332.939136 -110.435136)
		(width 0.508)
		(layer "F.Cu")
		(net "GND")
	)
	(segment
		(start 92.350082 -37.40023)
		(end 91.950286 -37.800026)
		(width 0.3048)
		(layer "F.Cu")
		(net "GND")
	)
	(segment
		(start 307.42001 -81.19999)
		(end 306.959 -81.661)
		(width 0.508)
		(layer "F.Cu")
		(net "GND")
	)
	(segment
		(start 98.75012 -34.99993)
		(end 98.658934 -34.99993)
		(width 0.3048)
		(layer "F.Cu")
		(net "GND")
	)
	(segment
		(start 296.09796 -200.935082)
		(end 296.48404 -201.321162)
		(width 0.3556)
		(layer "F.Cu")
		(net "GND")
	)
	(segment
		(start 177.927 -15.367)
		(end 177.8 -15.367)
		(width 0.508)
		(layer "F.Cu")
		(net "GND")
	)
	(segment
		(start 21.667216 -225.54438)
		(end 21.019516 -225.54438)
		(width 0.508)
		(layer "F.Cu")
		(net "GND")
	)
	(segment
		(start 120.350026 -107.350052)
		(end 120.850152 -107.850178)
		(width 0.4572)
		(layer "F.Cu")
		(net "GND")
	)
	(segment
		(start 200.3425 -227.838)
		(end 200.66 -227.838)
		(width 0.508)
		(layer "F.Cu")
		(net "GND")
	)
	(segment
		(start 201.676 -252.984)
		(end 201.676 -253.619)
		(width 0.508)
		(layer "F.Cu")
		(net "GND")
	)
	(segment
		(start 99.549712 -34.99993)
		(end 99.149916 -34.600134)
		(width 0.3048)
		(layer "F.Cu")
		(net "GND")
	)
	(segment
		(start 75.978766 -86.868)
		(end 74.657966 -86.868)
		(width 0.508)
		(layer "F.Cu")
		(net "GND")
	)
	(segment
		(start 327.359772 -164.029136)
		(end 325.954136 -164.029136)
		(width 0.3048)
		(layer "F.Cu")
		(net "GND")
	)
	(segment
		(start 112.84966 -92.8497)
		(end 112.349788 -92.349828)
		(width 0.4572)
		(layer "F.Cu")
		(net "GND")
	)
	(segment
		(start 333.150718 -146.662648)
		(end 332.2066 -146.662648)
		(width 0.508)
		(layer "F.Cu")
		(net "GND")
	)
	(segment
		(start 118.35003 -99.350068)
		(end 118.850156 -99.850194)
		(width 0.4572)
		(layer "F.Cu")
		(net "GND")
	)
	(segment
		(start 306.324 -84.31276)
		(end 306.451 -84.18576)
		(width 0.508)
		(layer "F.Cu")
		(net "GND")
	)
	(segment
		(start 111.000032 -256.25044)
		(end 111.000032 -253.32182)
		(width 0.508)
		(layer "F.Cu")
		(net "GND")
	)
	(segment
		(start 327.232772 -172.030136)
		(end 325.809864 -172.030136)
		(width 0.3048)
		(layer "F.Cu")
		(net "GND")
	)
	(segment
		(start 68.609972 -187.809886)
		(end 69.74078 -187.809886)
		(width 0.508)
		(layer "F.Cu")
		(net "GND")
	)
	(segment
		(start 78.000352 -256.25044)
		(end 78.000352 -253.51486)
		(width 0.508)
		(layer "F.Cu")
		(net "GND")
	)
	(segment
		(start 37.43325 -171.0055)
		(end 36.96208 -171.0055)
		(width 0.508)
		(layer "F.Cu")
		(net "GND")
	)
	(segment
		(start 45.98797 -144.653)
		(end 44.46397 -144.653)
		(width 0.508)
		(layer "F.Cu")
		(net "GND")
	)
	(segment
		(start 189.665864 -32.139636)
		(end 189.665864 -33.080452)
		(width 0.508)
		(layer "F.Cu")
		(net "GND")
	)
	(segment
		(start 101.999542 -252.621542)
		(end 101.981 -252.603)
		(width 0.508)
		(layer "F.Cu")
		(net "GND")
	)
	(segment
		(start 34.4805 -79.375)
		(end 33.655 -79.375)
		(width 0.508)
		(layer "F.Cu")
		(net "GND")
	)
	(segment
		(start 141.999462 -256.25044)
		(end 141.999462 -253.39675)
		(width 0.508)
		(layer "F.Cu")
		(net "GND")
	)
	(segment
		(start 284.898084 -196.135244)
		(end 284.898084 -195.689728)
		(width 0.3556)
		(layer "F.Cu")
		(net "GND")
	)
	(segment
		(start 125.36297 -81.4324)
		(end 125.36297 -82.336894)
		(width 0.508)
		(layer "F.Cu")
		(net "GND")
	)
	(segment
		(start 321.2592 -144.907)
		(end 321.691 -144.907)
		(width 0.508)
		(layer "F.Cu")
		(net "GND")
	)
	(segment
		(start 185.355992 -45.9105)
		(end 186.308492 -45.9105)
		(width 0.508)
		(layer "F.Cu")
		(net "GND")
	)
	(segment
		(start 11.126216 -237.73638)
		(end 11.43 -238.040164)
		(width 0.508)
		(layer "F.Cu")
		(net "GND")
	)
	(segment
		(start 146.4945 -15.748)
		(end 146.4945 -14.7955)
		(width 0.508)
		(layer "F.Cu")
		(net "GND")
	)
	(segment
		(start 314.833 -92.71)
		(end 314.833 -92.964)
		(width 0.508)
		(layer "F.Cu")
		(net "GND")
	)
	(segment
		(start 348.390718 -141.989048)
		(end 347.882718 -141.481048)
		(width 0.508)
		(layer "F.Cu")
		(net "GND")
	)
	(segment
		(start 332.431136 -199.462136)
		(end 331.724 -198.755)
		(width 0.508)
		(layer "F.Cu")
		(net "GND")
	)
	(segment
		(start 126.350014 -82.349848)
		(end 126.85014 -81.849722)
		(width 0.508)
		(layer "F.Cu")
		(net "GND")
	)
	(segment
		(start 301.634906 -176.240186)
		(end 301.625254 -176.240186)
		(width 0.3556)
		(layer "F.Cu")
		(net "GND")
	)
	(segment
		(start 99.549966 -47.790354)
		(end 99.549966 -47.800006)
		(width 0.3556)
		(layer "F.Cu")
		(net "GND")
	)
	(segment
		(start 95.54972 -34.99993)
		(end 95.149924 -34.600134)
		(width 0.3048)
		(layer "F.Cu")
		(net "GND")
	)
	(segment
		(start 260.341364 -220.209872)
		(end 259.452872 -220.209872)
		(width 0.508)
		(layer "F.Cu")
		(net "GND")
	)
	(segment
		(start 91.549982 -38.999922)
		(end 91.950286 -39.400226)
		(width 0.3048)
		(layer "F.Cu")
		(net "GND")
	)
	(segment
		(start 124.350018 -106.350054)
		(end 124.850144 -106.85018)
		(width 0.4572)
		(layer "F.Cu")
		(net "GND")
	)
	(segment
		(start 173.49597 -66.7385)
		(end 173.49597 -65.659)
		(width 0.508)
		(layer "F.Cu")
		(net "GND")
	)
	(segment
		(start 307.37302 -91.60002)
		(end 306.959 -91.186)
		(width 0.508)
		(layer "F.Cu")
		(net "GND")
	)
	(segment
		(start 104.349804 -44.59986)
		(end 104.350058 -44.59986)
		(width 0.3556)
		(layer "F.Cu")
		(net "GND")
	)
	(segment
		(start 68.707 -55.2704)
		(end 68.1482 -55.8292)
		(width 0.508)
		(layer "F.Cu")
		(net "GND")
	)
	(segment
		(start 120.35028 -93.349826)
		(end 120.850152 -93.849698)
		(width 0.4572)
		(layer "F.Cu")
		(net "GND")
	)
	(segment
		(start 53.369972 -187.809886)
		(end 53.369972 -188.940694)
		(width 0.508)
		(layer "F.Cu")
		(net "GND")
	)
	(segment
		(start 50.3555 -200.43775)
		(end 50.3555 -199.4535)
		(width 0.508)
		(layer "F.Cu")
		(net "GND")
	)
	(segment
		(start 96.350328 -53.399944)
		(end 96.350074 -53.399944)
		(width 0.3556)
		(layer "F.Cu")
		(net "GND")
	)
	(segment
		(start 332.096872 -226.297236)
		(end 332.096872 -224.671128)
		(width 0.3048)
		(layer "F.Cu")
		(net "GND")
	)
	(segment
		(start 319.151 -180.721)
		(end 319.405 -180.467)
		(width 0.508)
		(layer "F.Cu")
		(net "GND")
	)
	(segment
		(start 313.480958 -95.955866)
		(end 313.480958 -96.393)
		(width 0.508)
		(layer "F.Cu")
		(net "GND")
	)
	(segment
		(start 288.408872 -218.067636)
		(end 288.408872 -216.924128)
		(width 0.508)
		(layer "F.Cu")
		(net "GND")
	)
	(segment
		(start 126.350014 -104.350058)
		(end 126.85014 -104.850184)
		(width 0.4572)
		(layer "F.Cu")
		(net "GND")
	)
	(segment
		(start 307.36794 -71.60006)
		(end 306.959 -72.009)
		(width 0.508)
		(layer "F.Cu")
		(net "GND")
	)
	(segment
		(start 106.8705 -234.2388)
		(end 106.8705 -232.4735)
		(width 0.254)
		(layer "F.Cu")
		(net "GND")
	)
	(segment
		(start 93.150182 -45.39996)
		(end 92.78874 -45.038518)
		(width 0.254)
		(layer "F.Cu")
		(net "GND")
	)
	(segment
		(start 82.74685 -135.79348)
		(end 81.70545 -135.79348)
		(width 0.2032)
		(layer "F.Cu")
		(net "GND")
	)
	(segment
		(start 94.750128 -34.200338)
		(end 95.149924 -34.600134)
		(width 0.3048)
		(layer "F.Cu")
		(net "GND")
	)
	(segment
		(start 104.350312 -53.399944)
		(end 104.350058 -53.399944)
		(width 0.3556)
		(layer "F.Cu")
		(net "GND")
	)
	(segment
		(start 301.51578 -197.78472)
		(end 300.9265 -198.374)
		(width 0.508)
		(layer "F.Cu")
		(net "GND")
	)
	(segment
		(start 92.724732 -137.922762)
		(end 93.35897 -138.557)
		(width 0.2032)
		(layer "F.Cu")
		(net "GND")
	)
	(segment
		(start 145.000472 -256.25044)
		(end 145.000472 -253.41326)
		(width 0.508)
		(layer "F.Cu")
		(net "GND")
	)
	(segment
		(start 287.608772 -183.014112)
		(end 287.608772 -183.018176)
		(width 0.3556)
		(layer "F.Cu")
		(net "GND")
	)
	(segment
		(start 97.2185 -240.2205)
		(end 96.52 -239.522)
		(width 0.508)
		(layer "F.Cu")
		(net "GND")
	)
	(segment
		(start 215.011 -182.88)
		(end 214.884 -182.753)
		(width 0.508)
		(layer "F.Cu")
		(net "GND")
	)
	(segment
		(start 213.1695 -216.29624)
		(end 213.1695 -217.043)
		(width 0.381)
		(layer "F.Cu")
		(net "GND")
	)
	(segment
		(start 283.21 -160.655)
		(end 282.702 -160.147)
		(width 0.508)
		(layer "F.Cu")
		(net "GND")
	)
	(segment
		(start 301.498 -104.267)
		(end 301.625 -104.394)
		(width 0.508)
		(layer "F.Cu")
		(net "GND")
	)
	(segment
		(start 106.750104 -36.599876)
		(end 106.350308 -36.20008)
		(width 0.3048)
		(layer "F.Cu")
		(net "GND")
	)
	(segment
		(start 194.499992 -31.369)
		(end 195.58 -31.369)
		(width 0.508)
		(layer "F.Cu")
		(net "GND")
	)
	(segment
		(start 98.759518 -46.999906)
		(end 98.75012 -46.999906)
		(width 0.3556)
		(layer "F.Cu")
		(net "GND")
	)
	(segment
		(start 118.35003 -95.350076)
		(end 118.850156 -95.850202)
		(width 0.4572)
		(layer "F.Cu")
		(net "GND")
	)
	(segment
		(start 106.350308 -36.20008)
		(end 105.950258 -35.80003)
		(width 0.3048)
		(layer "F.Cu")
		(net "GND")
	)
	(segment
		(start 40.618918 -81.460086)
		(end 40.582596 -81.460086)
		(width 0.3048)
		(layer "F.Cu")
		(net "GND")
	)
	(segment
		(start 120.350026 -92.349828)
		(end 120.850152 -91.849702)
		(width 0.4572)
		(layer "F.Cu")
		(net "GND")
	)
	(segment
		(start 296.09796 -196.05498)
		(end 296.49928 -195.65366)
		(width 0.3556)
		(layer "F.Cu")
		(net "GND")
	)
	(segment
		(start 68.999862 -250.31065)
		(end 66.593212 -247.904)
		(width 0.508)
		(layer "F.Cu")
		(net "GND")
	)
	(segment
		(start 9.856216 -229.10038)
		(end 9.856216 -230.17988)
		(width 0.508)
		(layer "F.Cu")
		(net "GND")
	)
	(segment
		(start 284.835854 -172.239178)
		(end 284.835854 -172.231558)
		(width 0.3556)
		(layer "F.Cu")
		(net "GND")
	)
	(segment
		(start 308.675024 -81.19999)
		(end 307.42001 -81.19999)
		(width 0.508)
		(layer "F.Cu")
		(net "GND")
	)
	(segment
		(start 114.28603 -72.06996)
		(end 112.85093 -72.06996)
		(width 0.3048)
		(layer "F.Cu")
		(net "GND")
	)
	(segment
		(start 284.834838 -173.84014)
		(end 284.618684 -173.84014)
		(width 0.3556)
		(layer "F.Cu")
		(net "GND")
	)
	(segment
		(start 104.839262 -75.297792)
		(end 104.839262 -74.980292)
		(width 0.508)
		(layer "F.Cu")
		(net "GND")
	)
	(segment
		(start 294.498014 -196.925692)
		(end 294.099234 -196.526912)
		(width 0.3556)
		(layer "F.Cu")
		(net "GND")
	)
	(segment
		(start 103.549958 -46.999906)
		(end 103.949754 -47.399702)
		(width 0.3556)
		(layer "F.Cu")
		(net "GND")
	)
	(segment
		(start 288.424366 -180.65369)
		(end 288.428684 -180.649372)
		(width 0.3556)
		(layer "F.Cu")
		(net "GND")
	)
	(segment
		(start 301.97425 -218.8845)
		(end 301.97425 -217.58275)
		(width 0.508)
		(layer "F.Cu")
		(net "GND")
	)
	(segment
		(start 120.350026 -88.349836)
		(end 120.35028 -88.349836)
		(width 0.508)
		(layer "F.Cu")
		(net "GND")
	)
	(segment
		(start 39.54272 -138.1125)
		(end 39.54272 -137.26033)
		(width 0.508)
		(layer "F.Cu")
		(net "GND")
	)
	(segment
		(start 348.390718 -142.789148)
		(end 348.390718 -141.989048)
		(width 0.508)
		(layer "F.Cu")
		(net "GND")
	)
	(segment
		(start 187.799472 -253.331472)
		(end 187.799472 -253.13894)
		(width 0.508)
		(layer "F.Cu")
		(net "GND")
	)
	(segment
		(start 343.945718 -142.852648)
		(end 343.945718 -141.702282)
		(width 0.508)
		(layer "F.Cu")
		(net "GND")
	)
	(segment
		(start 77.361288 -128.392682)
		(end 77.50937 -128.2446)
		(width 0.3048)
		(layer "F.Cu")
		(net "GND")
	)
	(segment
		(start 34.6075 -79.248)
		(end 34.4805 -79.375)
		(width 0.508)
		(layer "F.Cu")
		(net "GND")
	)
	(segment
		(start 92.324682 -130.193288)
		(end 92.46997 -130.048)
		(width 0.2032)
		(layer "F.Cu")
		(net "GND")
	)
	(segment
		(start 262.290814 -221.824296)
		(end 262.2804 -221.813882)
		(width 0.3556)
		(layer "F.Cu")
		(net "GND")
	)
	(segment
		(start 325.698104 -172.205904)
		(end 325.7042 -172.212)
		(width 0.3048)
		(layer "F.Cu")
		(net "GND")
	)
	(segment
		(start 290.495482 -201.735182)
		(end 290.09594 -201.33564)
		(width 0.3556)
		(layer "F.Cu")
		(net "GND")
	)
	(segment
		(start 192.3415 -26.1747)
		(end 192.3288 -26.1874)
		(width 0.508)
		(layer "F.Cu")
		(net "GND")
	)
	(segment
		(start 313.125104 -70.000114)
		(end 315.134244 -70.000114)
		(width 0.508)
		(layer "F.Cu")
		(net "GND")
	)
	(segment
		(start 260.023864 -231.449372)
		(end 259.151628 -231.449372)
		(width 0.508)
		(layer "F.Cu")
		(net "GND")
	)
	(segment
		(start 118.999762 -256.25044)
		(end 118.999762 -253.57455)
		(width 0.508)
		(layer "F.Cu")
		(net "GND")
	)
	(segment
		(start 119.350028 -97.350072)
		(end 119.350028 -97.350326)
		(width 0.4572)
		(layer "F.Cu")
		(net "GND")
	)
	(segment
		(start 91.360498 -45.498512)
		(end 90.939366 -45.498512)
		(width 0.3048)
		(layer "F.Cu")
		(net "GND")
	)
	(segment
		(start 116.47297 -74.4855)
		(end 116.713 -74.24547)
		(width 0.508)
		(layer "F.Cu")
		(net "GND")
	)
	(segment
		(start 315.214 -196.977)
		(end 317.119 -196.977)
		(width 0.508)
		(layer "F.Cu")
		(net "GND")
	)
	(segment
		(start 319.396872 -120.417336)
		(end 319.396872 -121.539)
		(width 0.508)
		(layer "F.Cu")
		(net "GND")
	)
	(segment
		(start 83.45297 -128.7145)
		(end 84.80171 -128.7145)
		(width 0.508)
		(layer "F.Cu")
		(net "GND")
	)
	(segment
		(start 117.350032 -89.34958)
		(end 116.85016 -88.849708)
		(width 0.3048)
		(layer "F.Cu")
		(net "GND")
	)
	(segment
		(start 113.349786 -89.349834)
		(end 112.84966 -88.849708)
		(width 0.4572)
		(layer "F.Cu")
		(net "GND")
	)
	(segment
		(start 117.350032 -84.349844)
		(end 117.850158 -83.849718)
		(width 0.508)
		(layer "F.Cu")
		(net "GND")
	)
	(segment
		(start 103.959152 -45.80001)
		(end 104.350058 -46.190916)
		(width 0.3556)
		(layer "F.Cu")
		(net "GND")
	)
	(segment
		(start 20.702016 -225.86188)
		(end 20.778216 -225.78568)
		(width 0.508)
		(layer "F.Cu")
		(net "GND")
	)
	(segment
		(start 308.675024 -65.200022)
		(end 306.192936 -65.200022)
		(width 0.508)
		(layer "F.Cu")
		(net "GND")
	)
	(segment
		(start 57.319164 -185.269886)
		(end 58.449972 -185.269886)
		(width 0.508)
		(layer "F.Cu")
		(net "GND")
	)
	(segment
		(start 254.23876 -117.96776)
		(end 253.492 -117.221)
		(width 0.3048)
		(layer "F.Cu")
		(net "GND")
	)
	(segment
		(start 331.161136 -199.588628)
		(end 331.161136 -199.317864)
		(width 0.508)
		(layer "F.Cu")
		(net "GND")
	)
	(segment
		(start 166.614856 -125.847856)
		(end 166.243 -125.476)
		(width 0.508)
		(layer "F.Cu")
		(net "GND")
	)
	(segment
		(start 94.750128 -55.79999)
		(end 95.150178 -55.39994)
		(width 0.3556)
		(layer "F.Cu")
		(net "GND")
	)
	(segment
		(start 54.991 -110.4265)
		(end 54.0385 -110.4265)
		(width 0.508)
		(layer "F.Cu")
		(net "GND")
	)
	(segment
		(start 120.350026 -90.349832)
		(end 120.35028 -90.349832)
		(width 0.508)
		(layer "F.Cu")
		(net "GND")
	)
	(segment
		(start 114.349784 -107.350052)
		(end 114.349784 -107.932474)
		(width 0.3048)
		(layer "F.Cu")
		(net "GND")
	)
	(segment
		(start 279.332436 -225.6282)
		(end 280.162 -225.6282)
		(width 0.508)
		(layer "F.Cu")
		(net "GND")
	)
	(segment
		(start 296.48404 -201.330814)
		(end 296.488358 -201.335132)
		(width 0.3556)
		(layer "F.Cu")
		(net "GND")
	)
	(segment
		(start 300.834806 -177.040032)
		(end 300.834806 -177.030634)
		(width 0.3556)
		(layer "F.Cu")
		(net "GND")
	)
	(segment
		(start 52.90947 -141.74724)
		(end 52.90947 -142.91056)
		(width 0.3048)
		(layer "F.Cu")
		(net "GND")
	)
	(segment
		(start 128.000252 -256.25044)
		(end 128.000252 -253.29896)
		(width 0.508)
		(layer "F.Cu")
		(net "GND")
	)
	(segment
		(start 118.63959 -87.34171)
		(end 119.060722 -87.34171)
		(width 0.3048)
		(layer "F.Cu")
		(net "GND")
	)
	(segment
		(start 218.059 -110.8075)
		(end 216.9795 -110.8075)
		(width 0.508)
		(layer "F.Cu")
		(net "GND")
	)
	(segment
		(start 314.325 -73.200006)
		(end 314.579 -73.454006)
		(width 0.508)
		(layer "F.Cu")
		(net "GND")
	)
	(segment
		(start 217.56878 -88.42502)
		(end 217.89009 -88.10371)
		(width 0.254)
		(layer "F.Cu")
		(net "GND")
	)
	(segment
		(start 112.349788 -98.35007)
		(end 111.849662 -98.850196)
		(width 0.4572)
		(layer "F.Cu")
		(net "GND")
	)
	(segment
		(start 24.52624 -193.795904)
		(end 24.39924 -193.668904)
		(width 0.508)
		(layer "F.Cu")
		(net "GND")
	)
	(segment
		(start 40.259 -117.221)
		(end 39.217346 -117.221)
		(width 0.508)
		(layer "F.Cu")
		(net "GND")
	)
	(segment
		(start 36.96208 -171.0055)
		(end 36.32454 -171.64304)
		(width 0.508)
		(layer "F.Cu")
		(net "GND")
	)
	(segment
		(start 123.999752 -253.23546)
		(end 124.378212 -252.857)
		(width 0.508)
		(layer "F.Cu")
		(net "GND")
	)
	(segment
		(start 218.1352 -162.433)
		(end 217.17 -162.433)
		(width 0.3048)
		(layer "F.Cu")
		(net "GND")
	)
	(segment
		(start 331.4065 -217.17)
		(end 331.4065 -218.059)
		(width 0.508)
		(layer "F.Cu")
		(net "GND")
	)
	(segment
		(start 82.555842 -140.216382)
		(end 81.539842 -140.216382)
		(width 0.508)
		(layer "F.Cu")
		(net "GND")
	)
	(segment
		(start 308.675024 -88.400128)
		(end 307.373528 -88.400128)
		(width 0.508)
		(layer "F.Cu")
		(net "GND")
	)
	(segment
		(start 195.834 -116.6495)
		(end 195.834 -117.856)
		(width 0.508)
		(layer "F.Cu")
		(net "GND")
	)
	(segment
		(start 217.12428 -88.42502)
		(end 217.56878 -88.42502)
		(width 0.254)
		(layer "F.Cu")
		(net "GND")
	)
	(segment
		(start 39.30777 -137.02538)
		(end 39.30777 -136.98474)
		(width 0.508)
		(layer "F.Cu")
		(net "GND")
	)
	(segment
		(start 67.691 -55.372)
		(end 68.1482 -55.8292)
		(width 0.508)
		(layer "F.Cu")
		(net "GND")
	)
	(segment
		(start 236.4105 -13.081)
		(end 237.49 -13.081)
		(width 0.508)
		(layer "F.Cu")
		(net "GND")
	)
	(segment
		(start 52.199794 -79.590138)
		(end 52.199794 -81.460086)
		(width 0.3048)
		(layer "F.Cu")
		(net "GND")
	)
	(segment
		(start 100.350066 -43.800014)
		(end 100.749862 -44.19981)
		(width 0.3556)
		(layer "F.Cu")
		(net "GND")
	)
	(segment
		(start 338.1375 -30.4165)
		(end 338.074 -30.48)
		(width 0.508)
		(layer "F.Cu")
		(net "GND")
	)
	(segment
		(start 84.455 -237.6424)
		(end 84.8614 -237.6424)
		(width 0.508)
		(layer "F.Cu")
		(net "GND")
	)
	(segment
		(start 303.911 -193.3575)
		(end 303.965864 -193.302636)
		(width 0.508)
		(layer "F.Cu")
		(net "GND")
	)
	(segment
		(start 266.0015 -236.22)
		(end 264.795 -236.22)
		(width 0.508)
		(layer "F.Cu")
		(net "GND")
	)
	(segment
		(start 94.75597 -82.804)
		(end 93.86697 -81.915)
		(width 0.508)
		(layer "F.Cu")
		(net "GND")
	)
	(segment
		(start 282.020772 -67.516756)
		(end 280.368756 -67.516756)
		(width 0.3048)
		(layer "F.Cu")
		(net "GND")
	)
	(segment
		(start 288.421318 -180.65369)
		(end 288.424366 -180.65369)
		(width 0.3556)
		(layer "F.Cu")
		(net "GND")
	)
	(segment
		(start 52.197 -207.391)
		(end 51.943 -207.645)
		(width 0.508)
		(layer "F.Cu")
		(net "GND")
	)
	(segment
		(start 307.12283 -78.000098)
		(end 306.832 -78.290928)
		(width 0.508)
		(layer "F.Cu")
		(net "GND")
	)
	(segment
		(start 276.733 -103.8225)
		(end 276.733 -102.87)
		(width 0.508)
		(layer "F.Cu")
		(net "GND")
	)
	(segment
		(start 270.684752 -191.351916)
		(end 269.584424 -191.351916)
		(width 0.508)
		(layer "F.Cu")
		(net "GND")
	)
	(segment
		(start 97.150174 -46.999906)
		(end 97.54997 -47.399702)
		(width 0.3556)
		(layer "F.Cu")
		(net "GND")
	)
	(segment
		(start 179.102004 -33.056068)
		(end 178.749452 -33.40862)
		(width 0.3048)
		(layer "F.Cu")
		(net "GND")
	)
	(segment
		(start 8.522716 -214.54364)
		(end 8.522716 -213.8553)
		(width 0.381)
		(layer "F.Cu")
		(net "GND")
	)
	(segment
		(start 93.549978 -51.399694)
		(end 93.949774 -50.999898)
		(width 0.3556)
		(layer "F.Cu")
		(net "GND")
	)
	(segment
		(start 314.59678 -93.20022)
		(end 314.833 -92.964)
		(width 0.508)
		(layer "F.Cu")
		(net "GND")
	)
	(segment
		(start 118.282466 -48.133)
		(end 118.282466 -48.9204)
		(width 0.508)
		(layer "F.Cu")
		(net "GND")
	)
	(segment
		(start 327.524872 -168.410636)
		(end 327.787 -168.926764)
		(width 0.508)
		(layer "F.Cu")
		(net "GND")
	)
	(segment
		(start 179.33797 -66.7385)
		(end 179.33797 -65.659)
		(width 0.508)
		(layer "F.Cu")
		(net "GND")
	)
	(segment
		(start 184.13476 -121.36374)
		(end 184.13476 -119.652288)
		(width 0.381)
		(layer "F.Cu")
		(net "GND")
	)
	(segment
		(start 120.35028 -88.349836)
		(end 120.850152 -88.849708)
		(width 0.508)
		(layer "F.Cu")
		(net "GND")
	)
	(segment
		(start 345.596718 -158.627318)
		(end 346.2274 -159.258)
		(width 0.508)
		(layer "F.Cu")
		(net "GND")
	)
	(segment
		(start 103.251 -224.917)
		(end 104.267 -224.917)
		(width 0.508)
		(layer "F.Cu")
		(net "GND")
	)
	(segment
		(start 97.409 -238.379)
		(end 97.409 -238.633)
		(width 0.508)
		(layer "F.Cu")
		(net "GND")
	)
	(segment
		(start 188.087 -145.2245)
		(end 187.72886 -145.58264)
		(width 0.3556)
		(layer "F.Cu")
		(net "GND")
	)
	(segment
		(start 308.675024 -90.800174)
		(end 307.344826 -90.800174)
		(width 0.508)
		(layer "F.Cu")
		(net "GND")
	)
	(segment
		(start 116.350034 -96.350074)
		(end 116.85016 -96.8502)
		(width 0.4572)
		(layer "F.Cu")
		(net "GND")
	)
	(segment
		(start 60.989972 -187.809886)
		(end 60.989972 -188.940694)
		(width 0.508)
		(layer "F.Cu")
		(net "GND")
	)
	(segment
		(start 92.350082 -34.99993)
		(end 93.150182 -34.19983)
		(width 0.3048)
		(layer "F.Cu")
		(net "GND")
	)
	(segment
		(start 144.09547 -83.439)
		(end 144.73047 -82.804)
		(width 0.508)
		(layer "F.Cu")
		(net "GND")
	)
	(segment
		(start 55.909972 -187.809886)
		(end 55.909972 -188.940694)
		(width 0.508)
		(layer "F.Cu")
		(net "GND")
	)
	(segment
		(start 102.3493 -33.80486)
		(end 102.3493 -33.7947)
		(width 0.3048)
		(layer "F.Cu")
		(net "GND")
	)
	(segment
		(start 308.675024 -94.800166)
		(end 307.398166 -94.800166)
		(width 0.508)
		(layer "F.Cu")
		(net "GND")
	)
	(segment
		(start 66.069972 -187.809886)
		(end 66.069972 -188.940694)
		(width 0.508)
		(layer "F.Cu")
		(net "GND")
	)
	(segment
		(start 182.799482 -256.25044)
		(end 182.799482 -254.080518)
		(width 0.508)
		(layer "F.Cu")
		(net "GND")
	)
	(segment
		(start 279.904444 -209.129376)
		(end 279.019 -209.129376)
		(width 0.381)
		(layer "F.Cu")
		(net "GND")
	)
	(segment
		(start 117.4115 -46.99)
		(end 116.440966 -46.99)
		(width 0.3048)
		(layer "F.Cu")
		(net "GND")
	)
	(segment
		(start 184.565798 -35.785806)
		(end 184.720992 -35.941)
		(width 0.3048)
		(layer "F.Cu")
		(net "GND")
	)
	(segment
		(start 86.14156 -131.5466)
		(end 86.14156 -130.175)
		(width 0.2032)
		(layer "F.Cu")
		(net "GND")
	)
	(segment
		(start 292.834822 -168.240202)
		(end 292.439598 -167.844978)
		(width 0.3556)
		(layer "F.Cu")
		(net "GND")
	)
	(segment
		(start 111.34979 -91.34983)
		(end 110.849664 -90.849704)
		(width 0.4572)
		(layer "F.Cu")
		(net "GND")
	)
	(segment
		(start 121.350278 -83.349846)
		(end 121.85015 -83.849718)
		(width 0.508)
		(layer "F.Cu")
		(net "GND")
	)
	(segment
		(start 96.750124 -53.79974)
		(end 96.350328 -53.399944)
		(width 0.3556)
		(layer "F.Cu")
		(net "GND")
	)
	(segment
		(start 280.035 -67.056)
		(end 280.035 -67.183)
		(width 0.508)
		(layer "F.Cu")
		(net "GND")
	)
	(segment
		(start 116.350034 -107.974384)
		(end 116.50599 -108.13034)
		(width 0.3048)
		(layer "F.Cu")
		(net "GND")
	)
	(segment
		(start 120.350026 -93.349826)
		(end 120.35028 -93.349826)
		(width 0.4572)
		(layer "F.Cu")
		(net "GND")
	)
	(segment
		(start 284.834838 -172.240194)
		(end 284.835854 -172.239178)
		(width 0.3556)
		(layer "F.Cu")
		(net "GND")
	)
	(segment
		(start 104.349804 -99.350068)
		(end 103.849678 -99.850194)
		(width 0.4572)
		(layer "F.Cu")
		(net "GND")
	)
	(segment
		(start 270.722852 -193.368676)
		(end 269.670784 -193.368676)
		(width 0.508)
		(layer "F.Cu")
		(net "GND")
	)
	(segment
		(start 97.663 -221.0435)
		(end 96.9645 -221.0435)
		(width 0.508)
		(layer "F.Cu")
		(net "GND")
	)
	(segment
		(start 111.45266 -26.924)
		(end 111.45266 -27.94)
		(width 0.508)
		(layer "F.Cu")
		(net "GND")
	)
	(segment
		(start 287.234884 -183.44007)
		(end 287.234884 -183.432704)
		(width 0.3556)
		(layer "F.Cu")
		(net "GND")
	)
	(segment
		(start 120.350026 -97.350072)
		(end 120.35028 -97.350072)
		(width 0.4572)
		(layer "F.Cu")
		(net "GND")
	)
	(segment
		(start 103.124 -224.79)
		(end 103.251 -224.917)
		(width 0.508)
		(layer "F.Cu")
		(net "GND")
	)
	(segment
		(start 100.057966 -63.184278)
		(end 100.203 -63.039244)
		(width 0.508)
		(layer "F.Cu")
		(net "GND")
	)
	(segment
		(start 93.950028 -36.599876)
		(end 93.950536 -36.599876)
		(width 0.3048)
		(layer "F.Cu")
		(net "GND")
	)
	(segment
		(start 103.385366 -61.595)
		(end 104.121966 -62.3316)
		(width 0.3048)
		(layer "F.Cu")
		(net "GND")
	)
	(segment
		(start 279.8445 -196.215)
		(end 279.527 -196.215)
		(width 0.508)
		(layer "F.Cu")
		(net "GND")
	)
	(segment
		(start 97.409 -238.633)
		(end 96.52 -239.522)
		(width 0.508)
		(layer "F.Cu")
		(net "GND")
	)
	(segment
		(start 287.608772 -183.018176)
		(end 287.629092 -183.038496)
		(width 0.3556)
		(layer "F.Cu")
		(net "GND")
	)
	(segment
		(start 58.449972 -185.269886)
		(end 58.449972 -186.400694)
		(width 0.508)
		(layer "F.Cu")
		(net "GND")
	)
	(segment
		(start 93.150182 -50.199544)
		(end 93.150182 -50.199798)
		(width 0.3556)
		(layer "F.Cu")
		(net "GND")
	)
	(segment
		(start 113.349786 -99.350068)
		(end 113.849658 -98.850196)
		(width 0.4572)
		(layer "F.Cu")
		(net "GND")
	)
	(segment
		(start 284.979872 -215.146636)
		(end 283.980636 -215.146636)
		(width 0.508)
		(layer "F.Cu")
		(net "GND")
	)
	(segment
		(start 139.90701 -90.466672)
		(end 139.065 -91.308682)
		(width 0.3048)
		(layer "F.Cu")
		(net "GND")
	)
	(segment
		(start 108.59897 -74.9935)
		(end 109.2327 -74.9935)
		(width 0.508)
		(layer "F.Cu")
		(net "GND")
	)
	(segment
		(start 215.7095 -220.599)
		(end 216.5604 -220.599)
		(width 0.508)
		(layer "F.Cu")
		(net "GND")
	)
	(segment
		(start 110.43666 -26.924)
		(end 110.37316 -26.9875)
		(width 0.508)
		(layer "F.Cu")
		(net "GND")
	)
	(segment
		(start 316.463934 -198.755)
		(end 317.2206 -198.755)
		(width 0.3048)
		(layer "F.Cu")
		(net "GND")
	)
	(segment
		(start 36.32454 -171.64304)
		(end 36.32454 -171.8056)
		(width 0.508)
		(layer "F.Cu")
		(net "GND")
	)
	(segment
		(start 318.77 -181.864)
		(end 318.77 -182.753)
		(width 0.508)
		(layer "F.Cu")
		(net "GND")
	)
	(segment
		(start 301.752 -192.3415)
		(end 301.752 -193.675)
		(width 0.508)
		(layer "F.Cu")
		(net "GND")
	)
	(segment
		(start 102.356158 -44.196762)
		(end 102.750112 -44.590716)
		(width 0.3556)
		(layer "F.Cu")
		(net "GND")
	)
	(segment
		(start 285.634938 -169.840148)
		(end 285.254192 -170.220894)
		(width 0.3556)
		(layer "F.Cu")
		(net "GND")
	)
	(segment
		(start 308.675024 -78.800198)
		(end 307.146198 -78.800198)
		(width 0.508)
		(layer "F.Cu")
		(net "GND")
	)
	(segment
		(start 50.829972 -187.809886)
		(end 50.829972 -188.940694)
		(width 0.508)
		(layer "F.Cu")
		(net "GND")
	)
	(segment
		(start 137.7569 -83.1215)
		(end 136.9568 -82.3214)
		(width 0.508)
		(layer "F.Cu")
		(net "GND")
	)
	(segment
		(start 101.149912 -44.59986)
		(end 101.150166 -44.59986)
		(width 0.3556)
		(layer "F.Cu")
		(net "GND")
	)
	(segment
		(start 108.349796 -97.350072)
		(end 107.84967 -97.850198)
		(width 0.4572)
		(layer "F.Cu")
		(net "GND")
	)
	(segment
		(start 19.825716 -225.98888)
		(end 20.397216 -225.98888)
		(width 0.508)
		(layer "F.Cu")
		(net "GND")
	)
	(segment
		(start 182.426864 -38.616636)
		(end 182.426864 -39.75608)
		(width 0.508)
		(layer "F.Cu")
		(net "GND")
	)
	(segment
		(start 280.162 -192.2145)
		(end 279.273 -192.2145)
		(width 0.508)
		(layer "F.Cu")
		(net "GND")
	)
	(segment
		(start 313.125104 -54.000146)
		(end 314.477146 -54.000146)
		(width 0.508)
		(layer "F.Cu")
		(net "GND")
	)
	(segment
		(start 330.399136 -211.907628)
		(end 330.399136 -213.033864)
		(width 0.508)
		(layer "F.Cu")
		(net "GND")
	)
	(segment
		(start 123.83897 -91.849194)
		(end 123.861322 -91.826842)
		(width 0.2032)
		(layer "F.Cu")
		(net "GND")
	)
	(segment
		(start 54.99989 -77.08011)
		(end 54.99989 -75.557126)
		(width 0.3048)
		(layer "F.Cu")
		(net "GND")
	)
	(segment
		(start 346.231718 -142.268448)
		(end 345.647518 -141.684248)
		(width 0.508)
		(layer "F.Cu")
		(net "GND")
	)
	(segment
		(start 103.559102 -45.39996)
		(end 103.549958 -45.39996)
		(width 0.3556)
		(layer "F.Cu")
		(net "GND")
	)
	(segment
		(start 104.750362 -36.20008)
		(end 104.350566 -36.599876)
		(width 0.3048)
		(layer "F.Cu")
		(net "GND")
	)
	(segment
		(start 84.80171 -128.7145)
		(end 85.45703 -129.36982)
		(width 0.508)
		(layer "F.Cu")
		(net "GND")
	)
	(segment
		(start 194.6275 -35.179)
		(end 195.072 -35.179)
		(width 0.508)
		(layer "F.Cu")
		(net "GND")
	)
	(segment
		(start 283.074872 -63.114936)
		(end 284.729936 -63.114936)
		(width 0.508)
		(layer "F.Cu")
		(net "GND")
	)
	(segment
		(start 318.4525 -180.721)
		(end 319.151 -180.721)
		(width 0.508)
		(layer "F.Cu")
		(net "GND")
	)
	(segment
		(start 271.3355 -187.452)
		(end 271.907 -187.452)
		(width 0.508)
		(layer "F.Cu")
		(net "GND")
	)
	(segment
		(start 43.800014 -75.46848)
		(end 43.76039 -75.428856)
		(width 0.3048)
		(layer "F.Cu")
		(net "GND")
	)
	(segment
		(start 313.125104 -89.200228)
		(end 314.295028 -89.200228)
		(width 0.508)
		(layer "F.Cu")
		(net "GND")
	)
	(segment
		(start 304.546 -102.5525)
		(end 304.546 -103.505)
		(width 0.508)
		(layer "F.Cu")
		(net "GND")
	)
	(segment
		(start 119.358156 -88.060276)
		(end 119.358156 -87.639144)
		(width 0.3048)
		(layer "F.Cu")
		(net "GND")
	)
	(segment
		(start 314.238894 -74.000106)
		(end 314.579 -73.66)
		(width 0.508)
		(layer "F.Cu")
		(net "GND")
	)
	(segment
		(start 105.55605 -42.596562)
		(end 105.159302 -42.199814)
		(width 0.3556)
		(layer "F.Cu")
		(net "GND")
	)
	(segment
		(start 112.349788 -90.349832)
		(end 111.849662 -89.849706)
		(width 0.4572)
		(layer "F.Cu")
		(net "GND")
	)
	(segment
		(start 279.273 -65.9765)
		(end 279.273 -66.294)
		(width 0.508)
		(layer "F.Cu")
		(net "GND")
	)
	(segment
		(start 145.999962 -253.46025)
		(end 146.476212 -252.984)
		(width 0.508)
		(layer "F.Cu")
		(net "GND")
	)
	(segment
		(start 91.55049 -36.599876)
		(end 91.950286 -36.20008)
		(width 0.3556)
		(layer "F.Cu")
		(net "GND")
	)
	(segment
		(start 50.199798 -75.428602)
		(end 50.10023 -75.329034)
		(width 0.3048)
		(layer "F.Cu")
		(net "GND")
	)
	(segment
		(start 201.041 -197.6755)
		(end 201.041 -199.009)
		(width 0.508)
		(layer "F.Cu")
		(net "GND")
	)
	(segment
		(start 24.425148 -170.107356)
		(end 24.425148 -168.802812)
		(width 0.2032)
		(layer "F.Cu")
		(net "GND")
	)
	(segment
		(start 121.350024 -86.34984)
		(end 121.85015 -85.849714)
		(width 0.508)
		(layer "F.Cu")
		(net "GND")
	)
	(segment
		(start 99.149916 -34.600134)
		(end 98.75012 -34.99993)
		(width 0.3048)
		(layer "F.Cu")
		(net "GND")
	)
	(segment
		(start 107.54995 -49.390554)
		(end 107.54995 -49.399952)
		(width 0.3556)
		(layer "F.Cu")
		(net "GND")
	)
	(segment
		(start 167.459152 -112.649)
		(end 167.64 -112.649)
		(width 0.508)
		(layer "F.Cu")
		(net "GND")
	)
	(segment
		(start 46.199806 -77.08011)
		(end 46.199806 -75.514962)
		(width 0.3048)
		(layer "F.Cu")
		(net "GND")
	)
	(segment
		(start 269.745968 -51.187096)
		(end 269.24 -51.693064)
		(width 0.4064)
		(layer "F.Cu")
		(net "GND")
	)
	(segment
		(start 314.706 -86.36)
		(end 314.706 -86.0806)
		(width 0.508)
		(layer "F.Cu")
		(net "GND")
	)
	(segment
		(start 200.406 -140.589)
		(end 200.66 -140.843)
		(width 0.508)
		(layer "F.Cu")
		(net "GND")
	)
	(segment
		(start 123.000262 -253.38405)
		(end 122.473212 -252.857)
		(width 0.508)
		(layer "F.Cu")
		(net "GND")
	)
	(segment
		(start 53.975 -200.787)
		(end 53.975 -199.644)
		(width 0.508)
		(layer "F.Cu")
		(net "GND")
	)
	(segment
		(start 87.548466 -61.341)
		(end 87.986616 -61.77915)
		(width 0.508)
		(layer "F.Cu")
		(net "GND")
	)
	(segment
		(start 199.799702 -253.222252)
		(end 199.799702 -256.25044)
		(width 0.508)
		(layer "F.Cu")
		(net "GND")
	)
	(segment
		(start 288.034984 -181.040024)
		(end 288.421318 -180.65369)
		(width 0.3556)
		(layer "F.Cu")
		(net "GND")
	)
	(segment
		(start 308.675024 -82.00009)
		(end 307.175408 -82.00009)
		(width 0.508)
		(layer "F.Cu")
		(net "GND")
	)
	(segment
		(start 118.35003 -91.34983)
		(end 118.850156 -90.849704)
		(width 0.4572)
		(layer "F.Cu")
		(net "GND")
	)
	(segment
		(start 313.125104 -73.200006)
		(end 314.325 -73.200006)
		(width 0.508)
		(layer "F.Cu")
		(net "GND")
	)
	(segment
		(start 107.8611 -63.4111)
		(end 107.0356 -62.5856)
		(width 0.508)
		(layer "F.Cu")
		(net "GND")
	)
	(segment
		(start 45.654722 -140.892784)
		(end 45.654722 -142.160752)
		(width 0.508)
		(layer "F.Cu")
		(net "GND")
	)
	(segment
		(start 117.350032 -99.350068)
		(end 117.850158 -99.850194)
		(width 0.4572)
		(layer "F.Cu")
		(net "GND")
	)
	(segment
		(start 68.609972 -186.679078)
		(end 68.609972 -187.809886)
		(width 0.508)
		(layer "F.Cu")
		(net "GND")
	)
	(segment
		(start 118.35003 -93.349826)
		(end 118.850156 -92.8497)
		(width 0.4572)
		(layer "F.Cu")
		(net "GND")
	)
	(segment
		(start 305.7525 -219.0115)
		(end 305.816 -218.948)
		(width 0.381)
		(layer "F.Cu")
		(net "GND")
	)
	(segment
		(start 19.585178 -170.107356)
		(end 19.585178 -168.407842)
		(width 0.2032)
		(layer "F.Cu")
		(net "GND")
	)
	(segment
		(start 28.424378 -175.746156)
		(end 28.424378 -177.448718)
		(width 0.2032)
		(layer "F.Cu")
		(net "GND")
	)
	(segment
		(start 292.10127 -196.93509)
		(end 292.504368 -196.531992)
		(width 0.3556)
		(layer "F.Cu")
		(net "GND")
	)
	(segment
		(start 89.125552 -137.209276)
		(end 89.125552 -138.672062)
		(width 0.2032)
		(layer "F.Cu")
		(net "GND")
	)
	(segment
		(start 323.85 -151.892)
		(end 325.755 -151.892)
		(width 0.508)
		(layer "F.Cu")
		(net "GND")
	)
	(segment
		(start 305.392836 -66.000122)
		(end 305.352958 -66.04)
		(width 0.508)
		(layer "F.Cu")
		(net "GND")
	)
	(segment
		(start 90.750136 -46.999906)
		(end 90.304874 -46.999906)
		(width 0.3048)
		(layer "F.Cu")
		(net "GND")
	)
	(segment
		(start 194.6021 -36.6522)
		(end 195.8086 -36.6522)
		(width 0.508)
		(layer "F.Cu")
		(net "GND")
	)
	(segment
		(start 88.521794 -132.561076)
		(end 88.12911 -132.561076)
		(width 0.2032)
		(layer "F.Cu")
		(net "GND")
	)
	(segment
		(start 271.2085 -187.325)
		(end 271.3355 -187.452)
		(width 0.508)
		(layer "F.Cu")
		(net "GND")
	)
	(segment
		(start 84.328 -32.0294)
		(end 84.328 -32.112966)
		(width 0.254)
		(layer "F.Cu")
		(net "GND")
	)
	(segment
		(start 102.350062 -53.79974)
		(end 102.749858 -53.399944)
		(width 0.3556)
		(layer "F.Cu")
		(net "GND")
	)
	(segment
		(start 343.056718 -159.464248)
		(end 342.853518 -159.667448)
		(width 0.508)
		(layer "F.Cu")
		(net "GND")
	)
	(segment
		(start 120.850152 -86.849712)
		(end 120.35028 -86.34984)
		(width 0.3048)
		(layer "F.Cu")
		(net "GND")
	)
	(segment
		(start 341.122 -117.348)
		(end 341.122 -118.491)
		(width 0.508)
		(layer "F.Cu")
		(net "GND")
	)
	(segment
		(start 198.134732 -175.959516)
		(end 199.071484 -175.959516)
		(width 0.3048)
		(layer "F.Cu")
		(net "GND")
	)
	(segment
		(start 307.467 -50.8)
		(end 306.959 -51.308)
		(width 0.508)
		(layer "F.Cu")
		(net "GND")
	)
	(segment
		(start 181.9275 -219.456)
		(end 181.9275 -218.5035)
		(width 0.508)
		(layer "F.Cu")
		(net "GND")
	)
	(segment
		(start 109.349794 -100.350066)
		(end 108.849668 -100.850192)
		(width 0.4572)
		(layer "F.Cu")
		(net "GND")
	)
	(segment
		(start 305.299872 -193.302636)
		(end 305.299872 -192.405)
		(width 0.508)
		(layer "F.Cu")
		(net "GND")
	)
	(segment
		(start 39.54272 -137.26033)
		(end 39.30777 -137.02538)
		(width 0.508)
		(layer "F.Cu")
		(net "GND")
	)
	(segment
		(start 184.395872 -207.717136)
		(end 184.776872 -208.098136)
		(width 0.508)
		(layer "F.Cu")
		(net "GND")
	)
	(segment
		(start 293.707312 -202.535028)
		(end 294.097964 -202.144376)
		(width 0.3556)
		(layer "F.Cu")
		(net "GND")
	)
	(segment
		(start 48.4632 -118.6307)
		(end 48.4632 -117.5512)
		(width 0.508)
		(layer "F.Cu")
		(net "GND")
	)
	(segment
		(start 43.688 -169.291)
		(end 43.688 -169.70375)
		(width 0.508)
		(layer "F.Cu")
		(net "GND")
	)
	(segment
		(start 300.482 -102.5525)
		(end 300.482 -103.251)
		(width 0.508)
		(layer "F.Cu")
		(net "GND")
	)
	(segment
		(start 272.542 -160.782)
		(end 272.542 -161.925)
		(width 0.508)
		(layer "F.Cu")
		(net "GND")
	)
	(segment
		(start 283.6545 -207.518)
		(end 283.6545 -208.0895)
		(width 0.508)
		(layer "F.Cu")
		(net "GND")
	)
	(segment
		(start 308.675024 -72.40016)
		(end 307.35016 -72.40016)
		(width 0.508)
		(layer "F.Cu")
		(net "GND")
	)
	(segment
		(start 298.43476 -177.840132)
		(end 298.43476 -177.83048)
		(width 0.3556)
		(layer "F.Cu")
		(net "GND")
	)
	(segment
		(start 126.350014 -105.350056)
		(end 126.85014 -105.850182)
		(width 0.3048)
		(layer "F.Cu")
		(net "GND")
	)
	(segment
		(start 257.039364 -228.210872)
		(end 257.039364 -226.957636)
		(width 0.508)
		(layer "F.Cu")
		(net "GND")
	)
	(segment
		(start 290.703 -70.739)
		(end 291.0332 -71.0692)
		(width 0.508)
		(layer "F.Cu")
		(net "GND")
	)
	(segment
		(start 308.675024 -87.600028)
		(end 307.306218 -87.600028)
		(width 0.508)
		(layer "F.Cu")
		(net "GND")
	)
	(segment
		(start 137.599166 -61.9379)
		(end 137.599166 -63.177166)
		(width 0.254)
		(layer "F.Cu")
		(net "GND")
	)
	(segment
		(start 111.0615 -68.199)
		(end 111.506 -68.199)
		(width 0.508)
		(layer "F.Cu")
		(net "GND")
	)
	(segment
		(start 300.834806 -177.030634)
		(end 301.23003 -176.63541)
		(width 0.3556)
		(layer "F.Cu")
		(net "GND")
	)
	(segment
		(start 294.623236 -154.856688)
		(end 296.080688 -154.856688)
		(width 0.508)
		(layer "F.Cu")
		(net "GND")
	)
	(segment
		(start 171.46397 -66.421)
		(end 172.22597 -65.659)
		(width 0.508)
		(layer "F.Cu")
		(net "GND")
	)
	(segment
		(start 95.45447 -88.519)
		(end 94.75597 -88.519)
		(width 0.508)
		(layer "F.Cu")
		(net "GND")
	)
	(segment
		(start 51.25847 -133.96976)
		(end 49.90973 -133.96976)
		(width 0.3048)
		(layer "F.Cu")
		(net "GND")
	)
	(segment
		(start 49.699164 -187.809886)
		(end 50.829972 -187.809886)
		(width 0.508)
		(layer "F.Cu")
		(net "GND")
	)
	(segment
		(start 107.550458 -53.399944)
		(end 107.54995 -53.399944)
		(width 0.3556)
		(layer "F.Cu")
		(net "GND")
	)
	(segment
		(start 60.071 -219.964)
		(end 60.071 -219.71)
		(width 0.3048)
		(layer "F.Cu")
		(net "GND")
	)
	(segment
		(start 314.425076 -63.600076)
		(end 314.706 -63.881)
		(width 0.508)
		(layer "F.Cu")
		(net "GND")
	)
	(segment
		(start 113.349786 -104.350058)
		(end 112.858042 -104.841802)
		(width 0.3048)
		(layer "F.Cu")
		(net "GND")
	)
	(segment
		(start 199.8345 -142.494)
		(end 199.844152 -142.503652)
		(width 0.508)
		(layer "F.Cu")
		(net "GND")
	)
	(segment
		(start 271.609312 -53.066696)
		(end 272.415 -53.066696)
		(width 0.4064)
		(layer "F.Cu")
		(net "GND")
	)
	(segment
		(start 101.092 -221.0435)
		(end 101.092 -220.726)
		(width 0.508)
		(layer "F.Cu")
		(net "GND")
	)
	(segment
		(start 313.125104 -79.600044)
		(end 314.296044 -79.600044)
		(width 0.508)
		(layer "F.Cu")
		(net "GND")
	)
	(segment
		(start 306.5145 -109.855)
		(end 306.5145 -110.8075)
		(width 0.508)
		(layer "F.Cu")
		(net "GND")
	)
	(segment
		(start 53.369972 -186.679078)
		(end 53.369972 -187.809886)
		(width 0.508)
		(layer "F.Cu")
		(net "GND")
	)
	(segment
		(start 117.350032 -89.349834)
		(end 117.350032 -89.34958)
		(width 0.3048)
		(layer "F.Cu")
		(net "GND")
	)
	(segment
		(start 92.350082 -41.399968)
		(end 91.95816 -41.008046)
		(width 0.3048)
		(layer "F.Cu")
		(net "GND")
	)
	(segment
		(start 288.097976 -196.135244)
		(end 288.097976 -195.363084)
		(width 0.3556)
		(layer "F.Cu")
		(net "GND")
	)
	(segment
		(start 189.9412 -14.26591)
		(end 189.9412 -12.7508)
		(width 0.3048)
		(layer "F.Cu")
		(net "GND")
	)
	(segment
		(start 29.122116 -80.379062)
		(end 28.614116 -79.871062)
		(width 0.508)
		(layer "F.Cu")
		(net "GND")
	)
	(segment
		(start 25.159716 -225.41738)
		(end 25.159716 -224.21088)
		(width 0.508)
		(layer "F.Cu")
		(net "GND")
	)
	(segment
		(start 112.349788 -107.350052)
		(end 112.349788 -108.345478)
		(width 0.3048)
		(layer "F.Cu")
		(net "GND")
	)
	(segment
		(start 124.350018 -105.350056)
		(end 124.850144 -105.850182)
		(width 0.4572)
		(layer "F.Cu")
		(net "GND")
	)
	(segment
		(start 313.125104 -90.000074)
		(end 314.367926 -90.000074)
		(width 0.508)
		(layer "F.Cu")
		(net "GND")
	)
	(segment
		(start 188.800232 -256.25044)
		(end 188.800232 -254.332232)
		(width 0.508)
		(layer "F.Cu")
		(net "GND")
	)
	(segment
		(start 272.714466 -18.734532)
		(end 272.521934 -18.542)
		(width 0.508)
		(layer "F.Cu")
		(net "GND")
	)
	(segment
		(start 124.350018 -101.350064)
		(end 124.850144 -101.85019)
		(width 0.4572)
		(layer "F.Cu")
		(net "GND")
	)
	(segment
		(start 107.44327 -69.089524)
		(end 107.315 -68.961254)
		(width 0.508)
		(layer "F.Cu")
		(net "GND")
	)
	(segment
		(start 69.999352 -256.25044)
		(end 69.999352 -252.199648)
		(width 0.508)
		(layer "F.Cu")
		(net "GND")
	)
	(segment
		(start 313.125104 -51.6001)
		(end 314.6171 -51.6001)
		(width 0.508)
		(layer "F.Cu")
		(net "GND")
	)
	(segment
		(start 192.3415 -22.479)
		(end 193.294 -22.479)
		(width 0.508)
		(layer "F.Cu")
		(net "GND")
	)
	(segment
		(start 119.383556 -83.628738)
		(end 119.350028 -83.59521)
		(width 0.3048)
		(layer "F.Cu")
		(net "GND")
	)
	(segment
		(start 313.125104 -76.400152)
		(end 314.287154 -76.400152)
		(width 0.508)
		(layer "F.Cu")
		(net "GND")
	)
	(segment
		(start 276.987 -22.9362)
		(end 276.987 -22.352)
		(width 0.508)
		(layer "F.Cu")
		(net "GND")
	)
	(segment
		(start 129.921 -88.392)
		(end 128.71577 -88.392)
		(width 0.3048)
		(layer "F.Cu")
		(net "GND")
	)
	(segment
		(start 147.290028 -68.5038)
		(end 145.9738 -68.5038)
		(width 0.508)
		(layer "F.Cu")
		(net "GND")
	)
	(segment
		(start 199.7075 -138.811)
		(end 200.533 -138.811)
		(width 0.508)
		(layer "F.Cu")
		(net "GND")
	)
	(segment
		(start 28.024328 -170.107356)
		(end 28.024328 -168.831768)
		(width 0.2032)
		(layer "F.Cu")
		(net "GND")
	)
	(segment
		(start 284.834838 -171.440094)
		(end 284.834838 -171.449746)
		(width 0.3556)
		(layer "F.Cu")
		(net "GND")
	)
	(segment
		(start 120.35028 -90.349832)
		(end 120.850152 -90.849704)
		(width 0.508)
		(layer "F.Cu")
		(net "GND")
	)
	(segment
		(start 41.399968 -77.08011)
		(end 41.399968 -75.464924)
		(width 0.3048)
		(layer "F.Cu")
		(net "GND")
	)
	(segment
		(start 204.5335 -219.9005)
		(end 204.5335 -218.567)
		(width 0.508)
		(layer "F.Cu")
		(net "GND")
	)
	(segment
		(start 121.350024 -100.350066)
		(end 121.85015 -100.850192)
		(width 0.4572)
		(layer "F.Cu")
		(net "GND")
	)
	(segment
		(start 191.9605 -45.6565)
		(end 192.024 -45.72)
		(width 0.508)
		(layer "F.Cu")
		(net "GND")
	)
	(segment
		(start 118.35003 -107.350052)
		(end 118.35003 -107.85602)
		(width 0.3048)
		(layer "F.Cu")
		(net "GND")
	)
	(segment
		(start 41.47566 -132.60832)
		(end 41.45915 -132.60832)
		(width 0.508)
		(layer "F.Cu")
		(net "GND")
	)
	(segment
		(start 308.102 -185.674)
		(end 307.467 -186.309)
		(width 0.508)
		(layer "F.Cu")
		(net "GND")
	)
	(segment
		(start 115.350036 -97.350072)
		(end 115.850162 -97.850198)
		(width 0.4572)
		(layer "F.Cu")
		(net "GND")
	)
	(segment
		(start 80.333342 -133.269482)
		(end 80.333342 -132.151628)
		(width 0.508)
		(layer "F.Cu")
		(net "GND")
	)
	(segment
		(start 198.86676 -221.2975)
		(end 198.86676 -222.26524)
		(width 0.381)
		(layer "F.Cu")
		(net "GND")
	)
	(segment
		(start 178.16576 -222.6945)
		(end 177.1015 -222.6945)
		(width 0.381)
		(layer "F.Cu")
		(net "GND")
	)
	(segment
		(start 15.585948 -170.107356)
		(end 15.585948 -168.726612)
		(width 0.2032)
		(layer "F.Cu")
		(net "GND")
	)
	(segment
		(start 205.74 -185.8645)
		(end 205.74 -186.817)
		(width 0.508)
		(layer "F.Cu")
		(net "GND")
	)
	(segment
		(start 148.59 -65.0875)
		(end 147.630388 -66.047112)
		(width 0.508)
		(layer "F.Cu")
		(net "GND")
	)
	(segment
		(start 116.350034 -94.349824)
		(end 116.85016 -93.849698)
		(width 0.4572)
		(layer "F.Cu")
		(net "GND")
	)
	(segment
		(start 20.397216 -225.98888)
		(end 20.524216 -225.86188)
		(width 0.508)
		(layer "F.Cu")
		(net "GND")
	)
	(segment
		(start 22.048216 -207.06588)
		(end 21.794216 -207.31988)
		(width 0.508)
		(layer "F.Cu")
		(net "GND")
	)
	(segment
		(start 301.634906 -177.040032)
		(end 301.634652 -177.040032)
		(width 0.3556)
		(layer "F.Cu")
		(net "GND")
	)
	(segment
		(start 217.89009 -88.10371)
		(end 219.00388 -88.10371)
		(width 0.254)
		(layer "F.Cu")
		(net "GND")
	)
	(segment
		(start 144.399 -37.846)
		(end 144.399 -37.465)
		(width 0.508)
		(layer "F.Cu")
		(net "GND")
	)
	(segment
		(start 93.549978 -51.399694)
		(end 93.150182 -51.79949)
		(width 0.3556)
		(layer "F.Cu")
		(net "GND")
	)
	(segment
		(start 101.950012 -48.599852)
		(end 102.349808 -48.999648)
		(width 0.3556)
		(layer "F.Cu")
		(net "GND")
	)
	(segment
		(start 125.350016 -106.350054)
		(end 125.850142 -106.85018)
		(width 0.3048)
		(layer "F.Cu")
		(net "GND")
	)
	(segment
		(start 181.283864 -38.616636)
		(end 181.283864 -39.75608)
		(width 0.508)
		(layer "F.Cu")
		(net "GND")
	)
	(segment
		(start 292.123876 -203.023724)
		(end 291.9476 -203.2)
		(width 0.3556)
		(layer "F.Cu")
		(net "GND")
	)
	(segment
		(start 216.9795 -110.8075)
		(end 216.916 -110.871)
		(width 0.508)
		(layer "F.Cu")
		(net "GND")
	)
	(segment
		(start 126.999492 -253.31928)
		(end 126.537212 -252.857)
		(width 0.508)
		(layer "F.Cu")
		(net "GND")
	)
	(segment
		(start 184.395872 -206.942436)
		(end 184.395872 -207.717136)
		(width 0.508)
		(layer "F.Cu")
		(net "GND")
	)
	(segment
		(start 91.95816 -41.008046)
		(end 91.95816 -40.998648)
		(width 0.3048)
		(layer "F.Cu")
		(net "GND")
	)
	(segment
		(start 236.7915 -15.76324)
		(end 237.75924 -15.76324)
		(width 0.3048)
		(layer "F.Cu")
		(net "GND")
	)
	(segment
		(start 92.724732 -131.570476)
		(end 92.724732 -130.302762)
		(width 0.2032)
		(layer "F.Cu")
		(net "GND")
	)
	(segment
		(start 308.675024 -71.60006)
		(end 307.36794 -71.60006)
		(width 0.508)
		(layer "F.Cu")
		(net "GND")
	)
	(segment
		(start 121.350024 -96.350074)
		(end 121.85015 -96.8502)
		(width 0.4572)
		(layer "F.Cu")
		(net "GND")
	)
	(segment
		(start 32.424116 -79.299562)
		(end 32.424116 -79.462884)
		(width 0.508)
		(layer "F.Cu")
		(net "GND")
	)
	(segment
		(start 109.15015 -40.599868)
		(end 109.549946 -40.999664)
		(width 0.3556)
		(layer "F.Cu")
		(net "GND")
	)
	(segment
		(start 111.000032 -253.32182)
		(end 110.662212 -252.984)
		(width 0.508)
		(layer "F.Cu")
		(net "GND")
	)
	(segment
		(start 78.251812 -114.394742)
		(end 77.10043 -113.24336)
		(width 0.508)
		(layer "F.Cu")
		(net "GND")
	)
	(segment
		(start 177.499772 -194.219576)
		(end 177.499772 -193.455036)
		(width 0.3048)
		(layer "F.Cu")
		(net "GND")
	)
	(segment
		(start 107.931966 -63.4111)
		(end 107.8611 -63.4111)
		(width 0.508)
		(layer "F.Cu")
		(net "GND")
	)
	(segment
		(start 97.33026 -34.892234)
		(end 97.222564 -34.99993)
		(width 0.3048)
		(layer "F.Cu")
		(net "GND")
	)
	(segment
		(start 123.35002 -105.350056)
		(end 123.850146 -105.850182)
		(width 0.4572)
		(layer "F.Cu")
		(net "GND")
	)
	(segment
		(start 93.6625 -234.1118)
		(end 94.2848 -234.1118)
		(width 0.3048)
		(layer "F.Cu")
		(net "GND")
	)
	(segment
		(start 283.845 -156.0195)
		(end 282.829 -156.0195)
		(width 0.508)
		(layer "F.Cu")
		(net "GND")
	)
	(segment
		(start 106.3498 -106.350054)
		(end 105.849674 -106.85018)
		(width 0.4572)
		(layer "F.Cu")
		(net "GND")
	)
	(segment
		(start 79.3877 -24.0792)
		(end 79.786226 -24.0792)
		(width 0.508)
		(layer "F.Cu")
		(net "GND")
	)
	(segment
		(start 332.939136 -110.435136)
		(end 332.994 -110.49)
		(width 0.508)
		(layer "F.Cu")
		(net "GND")
	)
	(segment
		(start 104.349804 -87.349838)
		(end 103.849678 -86.849712)
		(width 0.4572)
		(layer "F.Cu")
		(net "GND")
	)
	(segment
		(start 197.799452 -253.685548)
		(end 197.799452 -256.25044)
		(width 0.508)
		(layer "F.Cu")
		(net "GND")
	)
	(segment
		(start 170.443652 -33.0708)
		(end 170.312588 -33.0708)
		(width 0.508)
		(layer "F.Cu")
		(net "GND")
	)
	(segment
		(start 120.383554 -85.628734)
		(end 120.350026 -85.595206)
		(width 0.3048)
		(layer "F.Cu")
		(net "GND")
	)
	(segment
		(start 98.660966 -61.105034)
		(end 99.187 -60.579)
		(width 0.3048)
		(layer "F.Cu")
		(net "GND")
	)
	(segment
		(start 105.549954 -47.399956)
		(end 105.150158 -47.00016)
		(width 0.3556)
		(layer "F.Cu")
		(net "GND")
	)
	(segment
		(start 165.779196 -146.745452)
		(end 164.71646 -146.745452)
		(width 0.3048)
		(layer "F.Cu")
		(net "GND")
	)
	(segment
		(start 188.599318 -138.358372)
		(end 187.481718 -138.358372)
		(width 0.508)
		(layer "F.Cu")
		(net "GND")
	)
	(segment
		(start 346.612718 -158.872682)
		(end 346.2274 -159.258)
		(width 0.508)
		(layer "F.Cu")
		(net "GND")
	)
	(segment
		(start 84.538566 -62.9666)
		(end 83.801966 -62.23)
		(width 0.508)
		(layer "F.Cu")
		(net "GND")
	)
	(segment
		(start 98.660966 -62.8777)
		(end 98.660966 -61.105034)
		(width 0.3048)
		(layer "F.Cu")
		(net "GND")
	)
	(segment
		(start 82.94243 -137.1854)
		(end 82.94243 -135.98906)
		(width 0.2032)
		(layer "F.Cu")
		(net "GND")
	)
	(segment
		(start 120.35028 -97.350072)
		(end 120.850152 -96.8502)
		(width 0.4572)
		(layer "F.Cu")
		(net "GND")
	)
	(segment
		(start 91.45905 -45.39996)
		(end 91.360498 -45.498512)
		(width 0.3048)
		(layer "F.Cu")
		(net "GND")
	)
	(segment
		(start 343.032842 -153.596848)
		(end 343.032842 -154.385772)
		(width 0.3048)
		(layer "F.Cu")
		(net "GND")
	)
	(segment
		(start 334.645 -230.1875)
		(end 334.844136 -230.386636)
		(width 0.508)
		(layer "F.Cu")
		(net "GND")
	)
	(segment
		(start 147.630388 -66.047112)
		(end 147.530312 -66.047112)
		(width 0.508)
		(layer "F.Cu")
		(net "GND")
	)
	(segment
		(start 104.121966 -62.3316)
		(end 104.121966 -62.821566)
		(width 0.508)
		(layer "F.Cu")
		(net "GND")
	)
	(segment
		(start 110.750096 -35.80003)
		(end 111.150146 -36.20008)
		(width 0.3048)
		(layer "F.Cu")
		(net "GND")
	)
	(segment
		(start 276.987 -22.352)
		(end 276.352 -21.717)
		(width 0.508)
		(layer "F.Cu")
		(net "GND")
	)
	(segment
		(start 287.234884 -182.640224)
		(end 287.608772 -183.014112)
		(width 0.3556)
		(layer "F.Cu")
		(net "GND")
	)
	(segment
		(start 243.8527 -114.22761)
		(end 245.29669 -114.22761)
		(width 0.3048)
		(layer "F.Cu")
		(net "GND")
	)
	(segment
		(start 62.399164 -187.809886)
		(end 63.529972 -187.809886)
		(width 0.508)
		(layer "F.Cu")
		(net "GND")
	)
	(segment
		(start 15.585948 -168.726612)
		(end 15.317216 -168.45788)
		(width 0.2032)
		(layer "F.Cu")
		(net "GND")
	)
	(segment
		(start 120.350026 -99.350068)
		(end 120.850152 -99.850194)
		(width 0.4572)
		(layer "F.Cu")
		(net "GND")
	)
	(segment
		(start 296.164 -156.083)
		(end 296.164 -155.934918)
		(width 0.508)
		(layer "F.Cu")
		(net "GND")
	)
	(segment
		(start 300.03496 -177.040032)
		(end 300.031912 -177.040032)
		(width 0.3556)
		(layer "F.Cu")
		(net "GND")
	)
	(segment
		(start 286.42818 -211.44738)
		(end 285.369 -211.44738)
		(width 0.508)
		(layer "F.Cu")
		(net "GND")
	)
	(segment
		(start 101.950012 -42.199814)
		(end 102.349808 -42.59961)
		(width 0.3556)
		(layer "F.Cu")
		(net "GND")
	)
	(segment
		(start 216.29497 -68.6435)
		(end 216.29497 -66.675)
		(width 0.508)
		(layer "F.Cu")
		(net "GND")
	)
	(segment
		(start 308.675024 -58.000138)
		(end 307.378862 -58.000138)
		(width 0.508)
		(layer "F.Cu")
		(net "GND")
	)
	(segment
		(start 28.024328 -168.831768)
		(end 28.271216 -168.58488)
		(width 0.2032)
		(layer "F.Cu")
		(net "GND")
	)
	(segment
		(start 11.43 -239.522)
		(end 11.811 -239.903)
		(width 0.508)
		(layer "F.Cu")
		(net "GND")
	)
	(segment
		(start 130.999992 -256.25044)
		(end 130.999992 -253.38278)
		(width 0.508)
		(layer "F.Cu")
		(net "GND")
	)
	(segment
		(start 78.000352 -253.51486)
		(end 78.658212 -252.857)
		(width 0.508)
		(layer "F.Cu")
		(net "GND")
	)
	(segment
		(start 315.134244 -70.000114)
		(end 315.309758 -69.8246)
		(width 0.508)
		(layer "F.Cu")
		(net "GND")
	)
	(segment
		(start 343.683336 -71.641462)
		(end 343.683336 -70.463664)
		(width 0.508)
		(layer "F.Cu")
		(net "GND")
	)
	(segment
		(start 124.350018 -103.35006)
		(end 124.850144 -103.850186)
		(width 0.4572)
		(layer "F.Cu")
		(net "GND")
	)
	(segment
		(start 10.110216 -238.05388)
		(end 10.110216 -238.329216)
		(width 0.508)
		(layer "F.Cu")
		(net "GND")
	)
	(segment
		(start 318.77 -182.753)
		(end 319.913 -183.896)
		(width 0.508)
		(layer "F.Cu")
		(net "GND")
	)
	(segment
		(start 120.850152 -86.849712)
		(end 120.350026 -87.349838)
		(width 0.508)
		(layer "F.Cu")
		(net "GND")
	)
	(segment
		(start 148.67001 -11.210036)
		(end 150.016718 -11.210036)
		(width 0.508)
		(layer "F.Cu")
		(net "GND")
	)
	(segment
		(start 81.448656 -16.805656)
		(end 81.407 -16.764)
		(width 0.381)
		(layer "F.Cu")
		(net "GND")
	)
	(segment
		(start 177.499772 -193.455036)
		(end 177.499772 -192.8749)
		(width 0.508)
		(layer "F.Cu")
		(net "GND")
	)
	(segment
		(start 178.749452 -33.752282)
		(end 178.575462 -33.926272)
		(width 0.3048)
		(layer "F.Cu")
		(net "GND")
	)
	(segment
		(start 282.194 -160.655)
		(end 282.702 -160.147)
		(width 0.508)
		(layer "F.Cu")
		(net "GND")
	)
	(segment
		(start 292.4175 -206.756)
		(end 292.481 -206.756)
		(width 0.508)
		(layer "F.Cu")
		(net "GND")
	)
	(segment
		(start 97.2185 -240.538)
		(end 97.2185 -240.2205)
		(width 0.508)
		(layer "F.Cu")
		(net "GND")
	)
	(segment
		(start 100.47097 -76.0095)
		(end 100.47097 -75.057)
		(width 0.508)
		(layer "F.Cu")
		(net "GND")
	)
	(segment
		(start 342.93175 -30.13075)
		(end 342.265 -29.464)
		(width 0.508)
		(layer "F.Cu")
		(net "GND")
	)
	(segment
		(start 93.54566 -46.59884)
		(end 93.55328 -46.59884)
		(width 0.3048)
		(layer "F.Cu")
		(net "GND")
	)
	(segment
		(start 102.750112 -44.590716)
		(end 102.750112 -44.59986)
		(width 0.3556)
		(layer "F.Cu")
		(net "GND")
	)
	(segment
		(start 114.349784 -101.350064)
		(end 113.849658 -101.85019)
		(width 0.4572)
		(layer "F.Cu")
		(net "GND")
	)
	(segment
		(start 327.914 -8.731504)
		(end 327.881996 -8.731504)
		(width 0.508)
		(layer "F.Cu")
		(net "GND")
	)
	(segment
		(start 308.675024 -84.400136)
		(end 307.031136 -84.400136)
		(width 0.508)
		(layer "F.Cu")
		(net "GND")
	)
	(segment
		(start 307.175408 -82.00009)
		(end 306.959 -81.783682)
		(width 0.508)
		(layer "F.Cu")
		(net "GND")
	)
	(segment
		(start 15.19936 -99.980242)
		(end 15.19936 -97.708466)
		(width 0.3556)
		(layer "F.Cu")
		(net "GND")
	)
	(segment
		(start 145.9738 -68.5038)
		(end 145.796 -68.326)
		(width 0.508)
		(layer "F.Cu")
		(net "GND")
	)
	(segment
		(start 272.521934 -18.542)
		(end 272.513552 -18.542)
		(width 0.508)
		(layer "F.Cu")
		(net "GND")
	)
	(segment
		(start 107.950254 -53.79974)
		(end 107.550458 -53.399944)
		(width 0.3556)
		(layer "F.Cu")
		(net "GND")
	)
	(segment
		(start 195.199 -34.036)
		(end 195.707 -34.544)
		(width 0.508)
		(layer "F.Cu")
		(net "GND")
	)
	(segment
		(start 81.448656 -17.869662)
		(end 81.448656 -16.805656)
		(width 0.381)
		(layer "F.Cu")
		(net "GND")
	)
	(segment
		(start 143.0655 -64.135)
		(end 143.0655 -66.675)
		(width 0.508)
		(layer "F.Cu")
		(net "GND")
	)
	(segment
		(start 245.29669 -114.22761)
		(end 245.89359 -114.82451)
		(width 0.3048)
		(layer "F.Cu")
		(net "GND")
	)
	(segment
		(start 118.35003 -90.349832)
		(end 118.850156 -89.849706)
		(width 0.4572)
		(layer "F.Cu")
		(net "GND")
	)
	(segment
		(start 109.54131 -27.6225)
		(end 109.35716 -27.6225)
		(width 0.508)
		(layer "F.Cu")
		(net "GND")
	)
	(segment
		(start 146.4945 -16.764)
		(end 146.4945 -15.748)
		(width 0.508)
		(layer "F.Cu")
		(net "GND")
	)
	(segment
		(start 328.549 -119.4562)
		(end 328.549 -120.65)
		(width 0.508)
		(layer "F.Cu")
		(net "GND")
	)
	(segment
		(start 84.328 -32.112966)
		(end 83.801966 -32.639)
		(width 0.254)
		(layer "F.Cu")
		(net "GND")
	)
	(segment
		(start 124.350018 -85.349842)
		(end 124.850144 -84.849716)
		(width 0.4572)
		(layer "F.Cu")
		(net "GND")
	)
	(segment
		(start 281.178 -161.0995)
		(end 281.178 -160.655)
		(width 0.508)
		(layer "F.Cu")
		(net "GND")
	)
	(segment
		(start 237.75924 -15.76324)
		(end 237.998 -16.002)
		(width 0.3048)
		(layer "F.Cu")
		(net "GND")
	)
	(segment
		(start 77.462888 -137.892282)
		(end 77.53477 -137.8204)
		(width 0.3048)
		(layer "F.Cu")
		(net "GND")
	)
	(segment
		(start 105.849674 -105.850182)
		(end 106.3498 -105.350056)
		(width 0.4572)
		(layer "F.Cu")
		(net "GND")
	)
	(segment
		(start 116.350034 -100.350066)
		(end 116.85016 -100.850192)
		(width 0.4572)
		(layer "F.Cu")
		(net "GND")
	)
	(segment
		(start 105.55605 -42.596562)
		(end 105.950004 -42.990516)
		(width 0.3556)
		(layer "F.Cu")
		(net "GND")
	)
	(segment
		(start 119.383556 -84.070698)
		(end 119.383556 -83.628738)
		(width 0.3048)
		(layer "F.Cu")
		(net "GND")
	)
	(segment
		(start 170.448224 -33.066228)
		(end 170.443652 -33.0708)
		(width 0.508)
		(layer "F.Cu")
		(net "GND")
	)
	(segment
		(start 297.942 -98.2345)
		(end 298.0055 -98.2345)
		(width 0.508)
		(layer "F.Cu")
		(net "GND")
	)
	(segment
		(start 115.350036 -101.350064)
		(end 115.850162 -101.85019)
		(width 0.4572)
		(layer "F.Cu")
		(net "GND")
	)
	(segment
		(start 308.675024 -51.6001)
		(end 307.2511 -51.6001)
		(width 0.508)
		(layer "F.Cu")
		(net "GND")
	)
	(segment
		(start 148.999702 -256.25044)
		(end 148.999702 -253.09449)
		(width 0.508)
		(layer "F.Cu")
		(net "GND")
	)
	(segment
		(start 277.550372 -219.274136)
		(end 277.550372 -218.435936)
		(width 0.508)
		(layer "F.Cu")
		(net "GND")
	)
	(segment
		(start 92.5195 -220.9165)
		(end 92.456 -220.853)
		(width 0.508)
		(layer "F.Cu")
		(net "GND")
	)
	(segment
		(start 255.905 -123.317)
		(end 255.9685 -123.2535)
		(width 0.3048)
		(layer "F.Cu")
		(net "GND")
	)
	(segment
		(start 128.000252 -253.29896)
		(end 128.442212 -252.857)
		(width 0.508)
		(layer "F.Cu")
		(net "GND")
	)
	(segment
		(start 262.294878 -222.18015)
		(end 262.294878 -221.824296)
		(width 0.3556)
		(layer "F.Cu")
		(net "GND")
	)
	(segment
		(start 118.35003 -97.350072)
		(end 118.850156 -97.850198)
		(width 0.4572)
		(layer "F.Cu")
		(net "GND")
	)
	(segment
		(start 314.706 -89.662)
		(end 314.706 -89.6112)
		(width 0.508)
		(layer "F.Cu")
		(net "GND")
	)
	(segment
		(start 321.691 -144.907)
		(end 322.453 -145.669)
		(width 0.508)
		(layer "F.Cu")
		(net "GND")
	)
	(segment
		(start 101.95433 -34.19983)
		(end 102.3493 -33.80486)
		(width 0.3048)
		(layer "F.Cu")
		(net "GND")
	)
	(segment
		(start 111.45266 -26.924)
		(end 110.43666 -26.924)
		(width 0.508)
		(layer "F.Cu")
		(net "GND")
	)
	(segment
		(start 309.97398 -151.59736)
		(end 309.97398 -152.30602)
		(width 0.508)
		(layer "F.Cu")
		(net "GND")
	)
	(segment
		(start 195.956936 -143.126714)
		(end 194.312286 -143.126714)
		(width 0.508)
		(layer "F.Cu")
		(net "GND")
	)
	(segment
		(start 117.350032 -100.350066)
		(end 117.850158 -100.850192)
		(width 0.4572)
		(layer "F.Cu")
		(net "GND")
	)
	(segment
		(start 292.834822 -170.640248)
		(end 292.439598 -170.245024)
		(width 0.3556)
		(layer "F.Cu")
		(net "GND")
	)
	(segment
		(start 104.833166 -63.532766)
		(end 104.833166 -63.8556)
		(width 0.508)
		(layer "F.Cu")
		(net "GND")
	)
	(segment
		(start 115.000532 -253.63932)
		(end 114.345212 -252.984)
		(width 0.508)
		(layer "F.Cu")
		(net "GND")
	)
	(segment
		(start 199.9742 -184.0738)
		(end 200.279 -183.769)
		(width 0.508)
		(layer "F.Cu")
		(net "GND")
	)
	(segment
		(start 306.959 -81.783682)
		(end 306.959 -81.661)
		(width 0.508)
		(layer "F.Cu")
		(net "GND")
	)
	(segment
		(start 307.378862 -58.000138)
		(end 306.832 -58.547)
		(width 0.508)
		(layer "F.Cu")
		(net "GND")
	)
	(segment
		(start 307.213 -142.748)
		(end 307.213 -142.72514)
		(width 0.508)
		(layer "F.Cu")
		(net "GND")
	)
	(segment
		(start 179.6034 -144.272)
		(end 179.2986 -144.5768)
		(width 0.508)
		(layer "F.Cu")
		(net "GND")
	)
	(segment
		(start 285.254192 -170.220894)
		(end 285.254192 -170.230546)
		(width 0.3556)
		(layer "F.Cu")
		(net "GND")
	)
	(segment
		(start 99.159568 -47.399956)
		(end 99.549966 -47.790354)
		(width 0.3556)
		(layer "F.Cu")
		(net "GND")
	)
	(segment
		(start 307.20538 -142.75562)
		(end 307.213 -142.748)
		(width 0.508)
		(layer "F.Cu")
		(net "GND")
	)
	(segment
		(start 33.414716 -228.96068)
		(end 33.414716 -227.44938)
		(width 0.3048)
		(layer "F.Cu")
		(net "GND")
	)
	(segment
		(start 279.273 -192.2145)
		(end 278.4475 -192.2145)
		(width 0.508)
		(layer "F.Cu")
		(net "GND")
	)
	(segment
		(start 50.3555 -199.4535)
		(end 50.292 -199.39)
		(width 0.508)
		(layer "F.Cu")
		(net "GND")
	)
	(segment
		(start 206.206852 -110.67796)
		(end 206.206852 -109.559852)
		(width 0.508)
		(layer "F.Cu")
		(net "GND")
	)
	(segment
		(start 211.3915 -219.31376)
		(end 209.81924 -219.31376)
		(width 0.381)
		(layer "F.Cu")
		(net "GND")
	)
	(segment
		(start 288.163 -211.836)
		(end 288.417 -212.09)
		(width 0.508)
		(layer "F.Cu")
		(net "GND")
	)
	(segment
		(start 92.350082 -40.603678)
		(end 91.956636 -40.997124)
		(width 0.3048)
		(layer "F.Cu")
		(net "GND")
	)
	(segment
		(start 323.259958 -87.557356)
		(end 323.259958 -88.650064)
		(width 0.508)
		(layer "F.Cu")
		(net "GND")
	)
	(segment
		(start 102.749858 -46.199806)
		(end 102.750112 -46.199806)
		(width 0.3556)
		(layer "F.Cu")
		(net "GND")
	)
	(segment
		(start 326.4535 -143.383)
		(end 326.4535 -144.2085)
		(width 0.508)
		(layer "F.Cu")
		(net "GND")
	)
	(segment
		(start 343.922096 -140.976096)
		(end 344.297 -141.351)
		(width 0.508)
		(layer "F.Cu")
		(net "GND")
	)
	(segment
		(start 262.972042 -51.606958)
		(end 263.148826 -51.606958)
		(width 0.508)
		(layer "F.Cu")
		(net "GND")
	)
	(segment
		(start 107.950254 -53.79974)
		(end 108.35005 -54.199536)
		(width 0.3556)
		(layer "F.Cu")
		(net "GND")
	)
	(segment
		(start 343.945718 -141.702282)
		(end 344.297 -141.351)
		(width 0.508)
		(layer "F.Cu")
		(net "GND")
	)
	(segment
		(start 101.950012 -46.999906)
		(end 102.349808 -47.399702)
		(width 0.3556)
		(layer "F.Cu")
		(net "GND")
	)
	(segment
		(start 313.125104 -66.800222)
		(end 314.72378 -66.800222)
		(width 0.508)
		(layer "F.Cu")
		(net "GND")
	)
	(segment
		(start 110.749842 -53.399944)
		(end 110.750096 -53.399944)
		(width 0.3556)
		(layer "F.Cu")
		(net "GND")
	)
	(segment
		(start 325.698104 -172.141896)
		(end 325.698104 -172.205904)
		(width 0.3048)
		(layer "F.Cu")
		(net "GND")
	)
	(segment
		(start 80.881728 -140.216382)
		(end 80.562196 -140.535914)
		(width 0.508)
		(layer "F.Cu")
		(net "GND")
	)
	(segment
		(start 118.35003 -87.349838)
		(end 118.631462 -87.349838)
		(width 0.3048)
		(layer "F.Cu")
		(net "GND")
	)
	(segment
		(start 95.00997 -81.661)
		(end 94.50197 -81.153)
		(width 0.508)
		(layer "F.Cu")
		(net "GND")
	)
	(segment
		(start 353.061016 -28.04541)
		(end 353.061016 -26.924)
		(width 0.508)
		(layer "F.Cu")
		(net "GND")
	)
	(segment
		(start 9.99998 -102.489762)
		(end 9.99998 -104.818942)
		(width 0.3556)
		(layer "F.Cu")
		(net "GND")
	)
	(segment
		(start 186.182 -49.022)
		(end 186.309 -49.149)
		(width 0.3048)
		(layer "F.Cu")
		(net "GND")
	)
	(segment
		(start 25.604216 -195.906644)
		(end 25.604216 -196.77888)
		(width 0.508)
		(layer "F.Cu")
		(net "GND")
	)
	(segment
		(start 170.191176 -27.399996)
		(end 169.607992 -26.816812)
		(width 0.508)
		(layer "F.Cu")
		(net "GND")
	)
	(segment
		(start 126.350014 -106.350054)
		(end 126.85014 -106.85018)
		(width 0.3048)
		(layer "F.Cu")
		(net "GND")
	)
	(segment
		(start 270.308832 -51.187096)
		(end 269.745968 -51.187096)
		(width 0.4064)
		(layer "F.Cu")
		(net "GND")
	)
	(segment
		(start 10.110216 -238.329216)
		(end 10.541 -238.76)
		(width 0.508)
		(layer "F.Cu")
		(net "GND")
	)
	(segment
		(start 131.999482 -256.25044)
		(end 131.999482 -253.23673)
		(width 0.508)
		(layer "F.Cu")
		(net "GND")
	)
	(segment
		(start 180.35397 -66.7385)
		(end 180.35397 -65.659)
		(width 0.508)
		(layer "F.Cu")
		(net "GND")
	)
	(segment
		(start 127.350012 -106.350054)
		(end 127.850138 -106.85018)
		(width 0.3048)
		(layer "F.Cu")
		(net "GND")
	)
	(segment
		(start 307.065934 -94.000066)
		(end 306.832 -94.234)
		(width 0.508)
		(layer "F.Cu")
		(net "GND")
	)
	(segment
		(start 67.479164 -185.269886)
		(end 68.609972 -185.269886)
		(width 0.508)
		(layer "F.Cu")
		(net "GND")
	)
	(segment
		(start 63.529972 -186.679078)
		(end 63.529972 -187.809886)
		(width 0.508)
		(layer "F.Cu")
		(net "GND")
	)
	(segment
		(start 115.350036 -91.34983)
		(end 115.850162 -90.849704)
		(width 0.508)
		(layer "F.Cu")
		(net "GND")
	)
	(segment
		(start 122.350022 -103.35006)
		(end 122.850148 -103.850186)
		(width 0.4572)
		(layer "F.Cu")
		(net "GND")
	)
	(segment
		(start 190.118746 -147.434046)
		(end 190.8302 -148.1455)
		(width 0.508)
		(layer "F.Cu")
		(net "GND")
	)
	(segment
		(start 223.5835 -161.671)
		(end 224.5868 -161.671)
		(width 0.508)
		(layer "F.Cu")
		(net "GND")
	)
	(segment
		(start 139.446 -38.1)
		(end 138.811 -37.465)
		(width 0.508)
		(layer "F.Cu")
		(net "GND")
	)
	(segment
		(start 73.000362 -256.25044)
		(end 73.000362 -253.29515)
		(width 0.508)
		(layer "F.Cu")
		(net "GND")
	)
	(segment
		(start 183.1848 -52.2732)
		(end 182.6768 -51.7652)
		(width 0.508)
		(layer "F.Cu")
		(net "GND")
	)
	(segment
		(start 278.765 -200.4695)
		(end 278.0665 -200.4695)
		(width 0.508)
		(layer "F.Cu")
		(net "GND")
	)
	(segment
		(start 76.999592 -256.25044)
		(end 76.999592 -253.35738)
		(width 0.508)
		(layer "F.Cu")
		(net "GND")
	)
	(segment
		(start 111.34979 -95.350076)
		(end 110.849664 -95.850202)
		(width 0.4572)
		(layer "F.Cu")
		(net "GND")
	)
	(segment
		(start 301.634652 -177.040032)
		(end 301.23003 -176.63541)
		(width 0.3556)
		(layer "F.Cu")
		(net "GND")
	)
	(segment
		(start 119.060722 -87.34171)
		(end 119.06885 -87.349838)
		(width 0.3048)
		(layer "F.Cu")
		(net "GND")
	)
	(segment
		(start 307.6575 -224.155)
		(end 307.721 -224.155)
		(width 0.508)
		(layer "F.Cu")
		(net "GND")
	)
	(segment
		(start 293.698168 -196.93509)
		(end 293.698168 -196.928232)
		(width 0.3556)
		(layer "F.Cu")
		(net "GND")
	)
	(segment
		(start 10.541 -238.76)
		(end 10.541 -239.141)
		(width 0.508)
		(layer "F.Cu")
		(net "GND")
	)
	(segment
		(start 347.90888 -28.04541)
		(end 347.90888 -27.01671)
		(width 0.508)
		(layer "F.Cu")
		(net "GND")
	)
	(segment
		(start 18.458688 -208.509616)
		(end 18.738088 -208.789016)
		(width 0.381)
		(layer "F.Cu")
		(net "GND")
	)
	(segment
		(start 313.125104 -54.799992)
		(end 314.389008 -54.799992)
		(width 0.508)
		(layer "F.Cu")
		(net "GND")
	)
	(segment
		(start 105.950004 -42.990516)
		(end 105.950004 -42.999914)
		(width 0.3556)
		(layer "F.Cu")
		(net "GND")
	)
	(segment
		(start 25.858216 -237.73638)
		(end 25.858216 -238.94288)
		(width 0.508)
		(layer "F.Cu")
		(net "GND")
	)
	(segment
		(start 50.829972 -187.809886)
		(end 51.96078 -187.809886)
		(width 0.508)
		(layer "F.Cu")
		(net "GND")
	)
	(segment
		(start 106.750104 -54.19979)
		(end 106.350054 -53.79974)
		(width 0.3556)
		(layer "F.Cu")
		(net "GND")
	)
	(segment
		(start 93.150182 -51.79949)
		(end 93.150182 -51.799998)
		(width 0.3556)
		(layer "F.Cu")
		(net "GND")
	)
	(segment
		(start 110.349792 -108.206032)
		(end 110.419642 -108.275882)
		(width 0.3048)
		(layer "F.Cu")
		(net "GND")
	)
	(segment
		(start 99.149916 -42.59961)
		(end 99.549712 -42.199814)
		(width 0.3556)
		(layer "F.Cu")
		(net "GND")
	)
	(segment
		(start 124.350018 -91.34983)
		(end 124.338334 -91.34983)
		(width 0.508)
		(layer "F.Cu")
		(net "GND")
	)
	(segment
		(start 147.323302 -11.210036)
		(end 148.67001 -11.210036)
		(width 0.508)
		(layer "F.Cu")
		(net "GND")
	)
	(segment
		(start 120.350026 -95.350076)
		(end 120.850152 -95.850202)
		(width 0.4572)
		(layer "F.Cu")
		(net "GND")
	)
	(segment
		(start 104.356408 -34.997898)
		(end 104.756966 -34.59734)
		(width 0.3048)
		(layer "F.Cu")
		(net "GND")
	)
	(segment
		(start 94.12097 -88.519)
		(end 94.37497 -88.265)
		(width 0.508)
		(layer "F.Cu")
		(net "GND")
	)
	(segment
		(start 104.349804 -95.350076)
		(end 103.849678 -95.850202)
		(width 0.4572)
		(layer "F.Cu")
		(net "GND")
	)
	(segment
		(start 50.1015 -109.601)
		(end 48.895 -109.601)
		(width 0.508)
		(layer "F.Cu")
		(net "GND")
	)
	(segment
		(start 282.126436 -187.682124)
		(end 282.14066 -187.6679)
		(width 0.508)
		(layer "F.Cu")
		(net "GND")
	)
	(segment
		(start 107.44327 -69.9008)
		(end 107.44327 -69.089524)
		(width 0.508)
		(layer "F.Cu")
		(net "GND")
	)
	(segment
		(start 98.75012 -37.399976)
		(end 98.350324 -37.00018)
		(width 0.3048)
		(layer "F.Cu")
		(net "GND")
	)
	(segment
		(start 24.969216 -225.60788)
		(end 25.159716 -225.41738)
		(width 0.508)
		(layer "F.Cu")
		(net "GND")
	)
	(segment
		(start 262.007096 -50.692812)
		(end 263.124188 -50.692812)
		(width 0.508)
		(layer "F.Cu")
		(net "GND")
	)
	(segment
		(start 189.6745 -145.2245)
		(end 188.722 -145.2245)
		(width 0.508)
		(layer "F.Cu")
		(net "GND")
	)
	(segment
		(start 111.34979 -97.350072)
		(end 111.849662 -96.8502)
		(width 0.4572)
		(layer "F.Cu")
		(net "GND")
	)
	(segment
		(start 258.387596 -54.502812)
		(end 258.387596 -55.695596)
		(width 0.508)
		(layer "F.Cu")
		(net "GND")
	)
	(segment
		(start 292.097968 -202.598528)
		(end 292.123876 -202.624436)
		(width 0.3556)
		(layer "F.Cu")
		(net "GND")
	)
	(segment
		(start 119.350028 -83.349846)
		(end 119.850154 -82.84972)
		(width 0.508)
		(layer "F.Cu")
		(net "GND")
	)
	(segment
		(start 100.203 -63.039244)
		(end 100.203 -62.930278)
		(width 0.508)
		(layer "F.Cu")
		(net "GND")
	)
	(segment
		(start 128.673606 -88.349836)
		(end 127.350012 -88.349836)
		(width 0.3048)
		(layer "F.Cu")
		(net "GND")
	)
	(segment
		(start 28.899866 -78.537562)
		(end 28.899866 -79.585312)
		(width 0.508)
		(layer "F.Cu")
		(net "GND")
	)
	(segment
		(start 24.765 -237.998)
		(end 24.765 -238.865664)
		(width 0.508)
		(layer "F.Cu")
		(net "GND")
	)
	(segment
		(start 196.834252 -174.079916)
		(end 195.744084 -174.079916)
		(width 0.3048)
		(layer "F.Cu")
		(net "GND")
	)
	(segment
		(start 181.791864 -22.106636)
		(end 181.791864 -20.993608)
		(width 0.508)
		(layer "F.Cu")
		(net "GND")
	)
	(segment
		(start 120.000522 -253.29769)
		(end 120.441212 -252.857)
		(width 0.508)
		(layer "F.Cu")
		(net "GND")
	)
	(segment
		(start 19.585178 -168.407842)
		(end 19.508216 -168.33088)
		(width 0.2032)
		(layer "F.Cu")
		(net "GND")
	)
	(segment
		(start 51.25847 -137.14476)
		(end 49.91989 -137.14476)
		(width 0.3048)
		(layer "F.Cu")
		(net "GND")
	)
	(segment
		(start 90.304874 -46.999906)
		(end 89.68359 -47.62119)
		(width 0.3048)
		(layer "F.Cu")
		(net "GND")
	)
	(segment
		(start 191.8462 -123.19)
		(end 191.8462 -124.2822)
		(width 0.508)
		(layer "F.Cu")
		(net "GND")
	)
	(segment
		(start 190.118746 -147.319746)
		(end 190.118746 -147.434046)
		(width 0.508)
		(layer "F.Cu")
		(net "GND")
	)
	(segment
		(start 112.349788 -108.345478)
		(end 112.40389 -108.39958)
		(width 0.3048)
		(layer "F.Cu")
		(net "GND")
	)
	(segment
		(start 120.350026 -87.349838)
		(end 119.350028 -87.349838)
		(width 0.3048)
		(layer "F.Cu")
		(net "GND")
	)
	(segment
		(start 104.350058 -42.999914)
		(end 103.949754 -42.59961)
		(width 0.3556)
		(layer "F.Cu")
		(net "GND")
	)
	(segment
		(start 178.181 -15.113)
		(end 177.927 -15.367)
		(width 0.508)
		(layer "F.Cu")
		(net "GND")
	)
	(segment
		(start 333.468218 -148.948648)
		(end 332.160118 -148.948648)
		(width 0.508)
		(layer "F.Cu")
		(net "GND")
	)
	(segment
		(start 194.6275 -34.036)
		(end 195.199 -34.036)
		(width 0.508)
		(layer "F.Cu")
		(net "GND")
	)
	(segment
		(start 215.15197 -68.6435)
		(end 215.15197 -66.675)
		(width 0.508)
		(layer "F.Cu")
		(net "GND")
	)
	(segment
		(start 307.373528 -88.400128)
		(end 306.959 -87.9856)
		(width 0.508)
		(layer "F.Cu")
		(net "GND")
	)
	(segment
		(start 108.349796 -94.349824)
		(end 107.84967 -93.849698)
		(width 0.4572)
		(layer "F.Cu")
		(net "GND")
	)
	(segment
		(start 109.949996 -36.599876)
		(end 109.5502 -36.20008)
		(width 0.3048)
		(layer "F.Cu")
		(net "GND")
	)
	(segment
		(start 281.178 -192.405)
		(end 280.9875 -192.2145)
		(width 0.508)
		(layer "F.Cu")
		(net "GND")
	)
	(segment
		(start 90.840814 -45.39996)
		(end 90.750136 -45.39996)
		(width 0.3048)
		(layer "F.Cu")
		(net "GND")
	)
	(segment
		(start 334.844136 -230.386636)
		(end 335.652364 -230.386636)
		(width 0.508)
		(layer "F.Cu")
		(net "GND")
	)
	(segment
		(start 307.071268 -69.200014)
		(end 306.832 -68.960746)
		(width 0.508)
		(layer "F.Cu")
		(net "GND")
	)
	(segment
		(start 41.399968 -75.464924)
		(end 41.29913 -75.364086)
		(width 0.3048)
		(layer "F.Cu")
		(net "GND")
	)
	(segment
		(start 68.000372 -256.25044)
		(end 68.000372 -250.799092)
		(width 0.508)
		(layer "F.Cu")
		(net "GND")
	)
	(segment
		(start 180.140864 -38.616636)
		(end 180.140864 -39.75608)
		(width 0.508)
		(layer "F.Cu")
		(net "GND")
	)
	(segment
		(start 120.350026 -100.350066)
		(end 120.850152 -100.850192)
		(width 0.4572)
		(layer "F.Cu")
		(net "GND")
	)
	(segment
		(start 87.12327 -113.35766)
		(end 87.14613 -113.3348)
		(width 0.3048)
		(layer "F.Cu")
		(net "GND")
	)
	(segment
		(start 321.0179 -215.38565)
		(end 321.056 -215.42375)
		(width 0.508)
		(layer "F.Cu")
		(net "GND")
	)
	(segment
		(start 284.6324 -71.6534)
		(end 284.6324 -71.7042)
		(width 0.508)
		(layer "F.Cu")
		(net "GND")
	)
	(segment
		(start 94.750128 -35.80003)
		(end 94.750128 -35.800284)
		(width 0.3048)
		(layer "F.Cu")
		(net "GND")
	)
	(segment
		(start 66.069972 -187.809886)
		(end 67.20078 -187.809886)
		(width 0.508)
		(layer "F.Cu")
		(net "GND")
	)
	(segment
		(start 43.688 -169.70375)
		(end 42.38625 -171.0055)
		(width 0.508)
		(layer "F.Cu")
		(net "GND")
	)
	(segment
		(start 102.749858 -53.399944)
		(end 102.750112 -53.399944)
		(width 0.3556)
		(layer "F.Cu")
		(net "GND")
	)
	(segment
		(start 104.349804 -91.34983)
		(end 103.849678 -90.849704)
		(width 0.4572)
		(layer "F.Cu")
		(net "GND")
	)
	(segment
		(start 255.9685 -123.2535)
		(end 255.9685 -122.047)
		(width 0.3048)
		(layer "F.Cu")
		(net "GND")
	)
	(segment
		(start 342.040718 -158.283148)
		(end 342.040718 -159.235648)
		(width 0.508)
		(layer "F.Cu")
		(net "GND")
	)
	(segment
		(start 92.350082 -39.00043)
		(end 91.950286 -39.400226)
		(width 0.3048)
		(layer "F.Cu")
		(net "GND")
	)
	(segment
		(start 323.1515 -143.383)
		(end 323.1515 -144.0815)
		(width 0.508)
		(layer "F.Cu")
		(net "GND")
	)
	(segment
		(start 217.12428 -89.50452)
		(end 217.12428 -88.42502)
		(width 0.508)
		(layer "F.Cu")
		(net "GND")
	)
	(segment
		(start 88.12911 -132.561076)
		(end 87.26297 -131.694936)
		(width 0.2032)
		(layer "F.Cu")
		(net "GND")
	)
	(segment
		(start 119.20347 -75.6793)
		(end 119.16537 -75.6412)
		(width 0.508)
		(layer "F.Cu")
		(net "GND")
	)
	(segment
		(start 293.698168 -201.735182)
		(end 293.698168 -201.74458)
		(width 0.3556)
		(layer "F.Cu")
		(net "GND")
	)
	(segment
		(start 200.279 -168.529)
		(end 199.517 -169.291)
		(width 0.508)
		(layer "F.Cu")
		(net "GND")
	)
	(segment
		(start 208.628996 -118.129812)
		(end 209.804 -118.129812)
		(width 0.508)
		(layer "F.Cu")
		(net "GND")
	)
	(segment
		(start 110.349792 -95.350076)
		(end 109.849666 -95.850202)
		(width 0.4572)
		(layer "F.Cu")
		(net "GND")
	)
	(segment
		(start 107.349798 -84.349844)
		(end 106.849672 -83.849718)
		(width 0.4572)
		(layer "F.Cu")
		(net "GND")
	)
	(segment
		(start 95.700342 -98.496882)
		(end 94.50197 -98.496882)
		(width 0.508)
		(layer "F.Cu")
		(net "GND")
	)
	(segment
		(start 319.309496 -170.434)
		(end 319.674748 -170.799252)
		(width 0.508)
		(layer "F.Cu")
		(net "GND")
	)
	(segment
		(start 106.350054 -53.79974)
		(end 105.950258 -53.399944)
		(width 0.3556)
		(layer "F.Cu")
		(net "GND")
	)
	(segment
		(start 66.069972 -185.269886)
		(end 67.20078 -185.269886)
		(width 0.508)
		(layer "F.Cu")
		(net "GND")
	)
	(segment
		(start 135.999982 -253.30023)
		(end 136.316212 -252.984)
		(width 0.508)
		(layer "F.Cu")
		(net "GND")
	)
	(segment
		(start 121.784872 -81.915)
		(end 121.83237 -81.915)
		(width 0.508)
		(layer "F.Cu")
		(net "GND")
	)
	(segment
		(start 77.88529 -112.4585)
		(end 77.10043 -113.24336)
		(width 0.508)
		(layer "F.Cu")
		(net "GND")
	)
	(segment
		(start 81.539842 -140.216382)
		(end 80.881728 -140.216382)
		(width 0.508)
		(layer "F.Cu")
		(net "GND")
	)
	(segment
		(start 305.3715 -192.333372)
		(end 305.299872 -192.405)
		(width 0.508)
		(layer "F.Cu")
		(net "GND")
	)
	(segment
		(start 167.503348 -125.847856)
		(end 166.614856 -125.847856)
		(width 0.508)
		(layer "F.Cu")
		(net "GND")
	)
	(segment
		(start 96.750124 -34.59988)
		(end 97.150174 -34.19983)
		(width 0.3048)
		(layer "F.Cu")
		(net "GND")
	)
	(segment
		(start 99.549966 -42.99966)
		(end 99.549966 -42.999914)
		(width 0.3556)
		(layer "F.Cu")
		(net "GND")
	)
	(segment
		(start 59.591956 -227.428044)
		(end 58.801 -228.219)
		(width 0.2032)
		(layer "F.Cu")
		(net "GND")
	)
	(segment
		(start 17.200118 -104.78008)
		(end 17.19961 -104.779572)
		(width 0.508)
		(layer "F.Cu")
		(net "GND")
	)
	(segment
		(start 120.350026 -86.34984)
		(end 120.350026 -86.104222)
		(width 0.3048)
		(layer "F.Cu")
		(net "GND")
	)
	(segment
		(start 193.1924 -24.003)
		(end 192.3415 -24.003)
		(width 0.508)
		(layer "F.Cu")
		(net "GND")
	)
	(segment
		(start 109.2327 -74.9935)
		(end 109.4105 -74.8157)
		(width 0.508)
		(layer "F.Cu")
		(net "GND")
	)
	(segment
		(start 224.714816 -83.491324)
		(end 225.7425 -82.46364)
		(width 0.508)
		(layer "F.Cu")
		(net "GND")
	)
	(segment
		(start 100.203 -62.930278)
		(end 100.311966 -62.821312)
		(width 0.508)
		(layer "F.Cu")
		(net "GND")
	)
	(segment
		(start 111.34979 -104.350058)
		(end 110.86719 -104.832658)
		(width 0.3048)
		(layer "F.Cu")
		(net "GND")
	)
	(segment
		(start 63.529972 -187.809886)
		(end 63.529972 -188.940694)
		(width 0.508)
		(layer "F.Cu")
		(net "GND")
	)
	(segment
		(start 221.8055 -104.013)
		(end 222.758 -104.013)
		(width 0.508)
		(layer "F.Cu")
		(net "GND")
	)
	(segment
		(start 100.584 -231.267)
		(end 100.711 -231.267)
		(width 0.254)
		(layer "F.Cu")
		(net "GND")
	)
	(segment
		(start 109.949996 -54.19979)
		(end 110.350046 -53.79974)
		(width 0.3556)
		(layer "F.Cu")
		(net "GND")
	)
	(segment
		(start 95.559626 -37.399976)
		(end 95.549974 -37.399976)
		(width 0.3556)
		(layer "F.Cu")
		(net "GND")
	)
	(segment
		(start 10.40003 -99.980242)
		(end 10.40003 -97.71634)
		(width 0.3556)
		(layer "F.Cu")
		(net "GND")
	)
	(segment
		(start 93.795088 -123.642882)
		(end 94.88297 -122.555)
		(width 0.508)
		(layer "F.Cu")
		(net "GND")
	)
	(segment
		(start 94.750128 -34.99993)
		(end 95.149924 -34.600134)
		(width 0.3048)
		(layer "F.Cu")
		(net "GND")
	)
	(segment
		(start 117.350032 -93.349826)
		(end 117.850158 -92.8497)
		(width 0.4572)
		(layer "F.Cu")
		(net "GND")
	)
	(segment
		(start 43.800014 -77.08011)
		(end 43.800014 -75.46848)
		(width 0.3048)
		(layer "F.Cu")
		(net "GND")
	)
	(segment
		(start 107.156504 -48.997108)
		(end 106.759248 -48.599852)
		(width 0.3556)
		(layer "F.Cu")
		(net "GND")
	)
	(segment
		(start 307.344826 -90.800174)
		(end 306.959 -91.186)
		(width 0.508)
		(layer "F.Cu")
		(net "GND")
	)
	(segment
		(start 128.38176 -90.4494)
		(end 129.02057 -90.4494)
		(width 0.381)
		(layer "F.Cu")
		(net "GND")
	)
	(segment
		(start 332.577948 -12.918948)
		(end 332.613 -12.954)
		(width 0.508)
		(layer "F.Cu")
		(net "GND")
	)
	(segment
		(start 127.350012 -100.350066)
		(end 127.850138 -100.850192)
		(width 0.4572)
		(layer "F.Cu")
		(net "GND")
	)
	(segment
		(start 200.279 -168.0845)
		(end 200.279 -168.529)
		(width 0.508)
		(layer "F.Cu")
		(net "GND")
	)
	(segment
		(start 314.367926 -90.000074)
		(end 314.706 -89.662)
		(width 0.508)
		(layer "F.Cu")
		(net "GND")
	)
	(segment
		(start 301.625254 -176.240186)
		(end 301.23003 -176.63541)
		(width 0.3556)
		(layer "F.Cu")
		(net "GND")
	)
	(segment
		(start 69.596 -232.664)
		(end 69.596 -234.061)
		(width 0.508)
		(layer "F.Cu")
		(net "GND")
	)
	(segment
		(start 202.144376 -148.200872)
		(end 202.827128 -148.200872)
		(width 0.508)
		(layer "F.Cu")
		(net "GND")
	)
	(segment
		(start 285.625286 -172.240194)
		(end 285.226252 -171.84116)
		(width 0.3556)
		(layer "F.Cu")
		(net "GND")
	)
	(segment
		(start 60.071 -219.71)
		(end 59.669934 -219.308934)
		(width 0.3048)
		(layer "F.Cu")
		(net "GND")
	)
	(segment
		(start 314.2488 -52.4002)
		(end 314.833 -51.816)
		(width 0.508)
		(layer "F.Cu")
		(net "GND")
	)
	(segment
		(start 254.59436 -130.4544)
		(end 254.59436 -132.03936)
		(width 0.3556)
		(layer "F.Cu")
		(net "GND")
	)
	(segment
		(start 109.349794 -104.350058)
		(end 108.844842 -104.85501)
		(width 0.3048)
		(layer "F.Cu")
		(net "GND")
	)
	(segment
		(start 116.350034 -99.350068)
		(end 116.85016 -99.850194)
		(width 0.4572)
		(layer "F.Cu")
		(net "GND")
	)
	(segment
		(start 47.159164 -187.809886)
		(end 48.289972 -187.809886)
		(width 0.508)
		(layer "F.Cu")
		(net "GND")
	)
	(segment
		(start 296.164 -155.934918)
		(end 296.030904 -155.801822)
		(width 0.508)
		(layer "F.Cu")
		(net "GND")
	)
	(segment
		(start 222.987362 -155.575)
		(end 222.885 -155.575)
		(width 0.508)
		(layer "F.Cu")
		(net "GND")
	)
	(segment
		(start 186.69 -198.247)
		(end 185.995564 -198.941436)
		(width 0.508)
		(layer "F.Cu")
		(net "GND")
	)
	(segment
		(start 94.2848 -234.1118)
		(end 94.472252 -234.299252)
		(width 0.3048)
		(layer "F.Cu")
		(net "GND")
	)
	(segment
		(start 296.09796 -202.535028)
		(end 296.492168 -202.14082)
		(width 0.3556)
		(layer "F.Cu")
		(net "GND")
	)
	(segment
		(start 199.844152 -142.503652)
		(end 200.669652 -142.503652)
		(width 0.508)
		(layer "F.Cu")
		(net "GND")
	)
	(segment
		(start 105.16997 -76.0095)
		(end 104.839262 -75.297792)
		(width 0.508)
		(layer "F.Cu")
		(net "GND")
	)
	(segment
		(start 19.585178 -176.889918)
		(end 18.746216 -177.72888)
		(width 0.2032)
		(layer "F.Cu")
		(net "GND")
	)
	(segment
		(start 38.9128 -167.7416)
		(end 38.0492 -167.7416)
		(width 0.508)
		(layer "F.Cu")
		(net "GND")
	)
	(segment
		(start 83.420966 -88.7222)
		(end 81.896966 -88.7222)
		(width 0.508)
		(layer "F.Cu")
		(net "GND")
	)
	(segment
		(start 127.350012 -96.350074)
		(end 127.850138 -96.8502)
		(width 0.4572)
		(layer "F.Cu")
		(net "GND")
	)
	(segment
		(start 331.161136 -199.317864)
		(end 331.724 -198.755)
		(width 0.508)
		(layer "F.Cu")
		(net "GND")
	)
	(segment
		(start 307.392578 -68.400168)
		(end 306.832 -68.960746)
		(width 0.508)
		(layer "F.Cu")
		(net "GND")
	)
	(segment
		(start 288.030666 -183.44007)
		(end 287.629092 -183.038496)
		(width 0.3556)
		(layer "F.Cu")
		(net "GND")
	)
	(segment
		(start 104.350058 -46.190916)
		(end 104.350058 -46.199806)
		(width 0.3556)
		(layer "F.Cu")
		(net "GND")
	)
	(segment
		(start 315.4934 -208.7499)
		(end 316.3951 -208.7499)
		(width 0.508)
		(layer "F.Cu")
		(net "GND")
	)
	(segment
		(start 293.46906 -207.86344)
		(end 293.46906 -207.772)
		(width 0.508)
		(layer "F.Cu")
		(net "GND")
	)
	(segment
		(start 120.350026 -94.349824)
		(end 120.850152 -93.849698)
		(width 0.4572)
		(layer "F.Cu")
		(net "GND")
	)
	(segment
		(start 307.975 -186.817)
		(end 307.467 -186.309)
		(width 0.508)
		(layer "F.Cu")
		(net "GND")
	)
	(segment
		(start 110.349792 -88.349836)
		(end 110.349792 -88.349582)
		(width 0.4064)
		(layer "F.Cu")
		(net "GND")
	)
	(segment
		(start 219.72397 -68.6435)
		(end 219.72397 -66.675)
		(width 0.508)
		(layer "F.Cu")
		(net "GND")
	)
	(segment
		(start 209.86496 -110.67796)
		(end 209.931 -110.744)
		(width 0.508)
		(layer "F.Cu")
		(net "GND")
	)
	(segment
		(start 106.3498 -103.35006)
		(end 106.349546 -103.35006)
		(width 0.4064)
		(layer "F.Cu")
		(net "GND")
	)
	(segment
		(start 201.676 -253.619)
		(end 201.799952 -253.742952)
		(width 0.508)
		(layer "F.Cu")
		(net "GND")
	)
	(segment
		(start 216.8525 -110.8075)
		(end 216.916 -110.871)
		(width 0.508)
		(layer "F.Cu")
		(net "GND")
	)
	(segment
		(start 306.192936 -65.200022)
		(end 305.392836 -66.000122)
		(width 0.508)
		(layer "F.Cu")
		(net "GND")
	)
	(segment
		(start 92.422218 -45.39996)
		(end 92.757244 -45.064934)
		(width 0.3048)
		(layer "F.Cu")
		(net "GND")
	)
	(segment
		(start 291.211 -158.0515)
		(end 291.211 -157.353)
		(width 0.381)
		(layer "F.Cu")
		(net "GND")
	)
	(segment
		(start 221.13875 -117.2845)
		(end 221.6658 -117.2845)
		(width 0.508)
		(layer "F.Cu")
		(net "GND")
	)
	(segment
		(start 122.350022 -107.350052)
		(end 122.850148 -107.850178)
		(width 0.4572)
		(layer "F.Cu")
		(net "GND")
	)
	(segment
		(start 272.923 -45.9232)
		(end 272.923 -47.117)
		(width 0.508)
		(layer "F.Cu")
		(net "GND")
	)
	(segment
		(start 110.349538 -93.349826)
		(end 109.849666 -93.849698)
		(width 0.4572)
		(layer "F.Cu")
		(net "GND")
	)
	(segment
		(start 112.820958 -73.914)
		(end 112.820958 -72.079612)
		(width 0.508)
		(layer "F.Cu")
		(net "GND")
	)
	(segment
		(start 208.391252 -110.67796)
		(end 209.86496 -110.67796)
		(width 0.508)
		(layer "F.Cu")
		(net "GND")
	)
	(segment
		(start 114.349784 -87.349838)
		(end 113.849658 -86.849712)
		(width 0.4572)
		(layer "F.Cu")
		(net "GND")
	)
	(segment
		(start 198.86676 -222.26524)
		(end 198.374 -222.758)
		(width 0.381)
		(layer "F.Cu")
		(net "GND")
	)
	(segment
		(start 294.498014 -202.535028)
		(end 294.488616 -202.535028)
		(width 0.3556)
		(layer "F.Cu")
		(net "GND")
	)
	(segment
		(start 296.09796 -196.135244)
		(end 296.09796 -196.05498)
		(width 0.3556)
		(layer "F.Cu")
		(net "GND")
	)
	(segment
		(start 120.383554 -86.070694)
		(end 120.383554 -85.628734)
		(width 0.3048)
		(layer "F.Cu")
		(net "GND")
	)
	(segment
		(start 48.289972 -187.809886)
		(end 49.42078 -187.809886)
		(width 0.508)
		(layer "F.Cu")
		(net "GND")
	)
	(segment
		(start 113.349786 -93.349826)
		(end 112.84966 -92.8497)
		(width 0.4572)
		(layer "F.Cu")
		(net "GND")
	)
	(segment
		(start 174.743872 -197.353936)
		(end 174.743872 -198.573136)
		(width 0.508)
		(layer "F.Cu")
		(net "GND")
	)
	(segment
		(start 179.451 -218.3765)
		(end 180.975 -218.3765)
		(width 0.508)
		(layer "F.Cu")
		(net "GND")
	)
	(segment
		(start 314.287154 -76.400152)
		(end 314.706 -76.818998)
		(width 0.508)
		(layer "F.Cu")
		(net "GND")
	)
	(segment
		(start 299.703236 -145.612104)
		(end 299.703236 -144.018)
		(width 0.508)
		(layer "F.Cu")
		(net "GND")
	)
	(segment
		(start 110.350046 -53.79974)
		(end 110.749842 -53.399944)
		(width 0.3556)
		(layer "F.Cu")
		(net "GND")
	)
	(segment
		(start 307.2511 -51.6001)
		(end 306.959 -51.308)
		(width 0.508)
		(layer "F.Cu")
		(net "GND")
	)
	(segment
		(start 116.250212 -252.984)
		(end 116.504212 -252.984)
		(width 0.508)
		(layer "F.Cu")
		(net "GND")
	)
	(segment
		(start 268.901164 -44.966636)
		(end 269.345918 -44.966636)
		(width 0.508)
		(layer "F.Cu")
		(net "GND")
	)
	(segment
		(start 44.194222 -136.498584)
		(end 43.266106 -136.498584)
		(width 0.508)
		(layer "F.Cu")
		(net "GND")
	)
	(segment
		(start 124.401834 -89.349834)
		(end 124.841 -89.789)
		(width 0.2032)
		(layer "F.Cu")
		(net "GND")
	)
	(segment
		(start 92.350082 -38.199822)
		(end 91.950286 -37.800026)
		(width 0.3048)
		(layer "F.Cu")
		(net "GND")
	)
	(segment
		(start 80.294226 -24.4602)
		(end 80.319626 -24.4856)
		(width 0.508)
		(layer "F.Cu")
		(net "GND")
	)
	(segment
		(start 122.350022 -82.349848)
		(end 122.350022 -82.349594)
		(width 0.508)
		(layer "F.Cu")
		(net "GND")
	)
	(segment
		(start 318.2874 -113.03)
		(end 319.850008 -113.03)
		(width 0.2032)
		(layer "F.Cu")
		(net "GND")
	)
	(segment
		(start 121.350024 -104.350058)
		(end 121.85015 -104.850184)
		(width 0.4572)
		(layer "F.Cu")
		(net "GND")
	)
	(segment
		(start 115.350036 -99.350068)
		(end 115.850162 -99.850194)
		(width 0.4572)
		(layer "F.Cu")
		(net "GND")
	)
	(segment
		(start 19.99996 -99.980242)
		(end 19.99996 -97.76841)
		(width 0.3556)
		(layer "F.Cu")
		(net "GND")
	)
	(segment
		(start 60.989972 -187.809886)
		(end 62.12078 -187.809886)
		(width 0.508)
		(layer "F.Cu")
		(net "GND")
	)
	(segment
		(start 300.031912 -177.040032)
		(end 299.636434 -177.43551)
		(width 0.3556)
		(layer "F.Cu")
		(net "GND")
	)
	(segment
		(start 58.449972 -185.269886)
		(end 59.58078 -185.269886)
		(width 0.508)
		(layer "F.Cu")
		(net "GND")
	)
	(segment
		(start 94.50197 -98.496882)
		(end 94.466156 -98.532696)
		(width 0.508)
		(layer "F.Cu")
		(net "GND")
	)
	(segment
		(start 313.125104 -67.600068)
		(end 315.29909 -67.600068)
		(width 0.508)
		(layer "F.Cu")
		(net "GND")
	)
	(segment
		(start 101.149912 -46.199806)
		(end 101.150166 -46.199806)
		(width 0.3556)
		(layer "F.Cu")
		(net "GND")
	)
	(segment
		(start 114.349784 -92.349828)
		(end 113.849658 -91.849702)
		(width 0.4572)
		(layer "F.Cu")
		(net "GND")
	)
	(segment
		(start 107.550204 -35.80003)
		(end 107.54995 -35.80003)
		(width 0.3048)
		(layer "F.Cu")
		(net "GND")
	)
	(segment
		(start 127.350012 -92.349828)
		(end 128.402842 -92.349828)
		(width 0.381)
		(layer "F.Cu")
		(net "GND")
	)
	(segment
		(start 115.350036 -84.349844)
		(end 115.850162 -83.849718)
		(width 0.508)
		(layer "F.Cu")
		(net "GND")
	)
	(segment
		(start 308.737 -153.543)
		(end 308.737 -153.7462)
		(width 0.508)
		(layer "F.Cu")
		(net "GND")
	)
	(segment
		(start 15.985998 -175.746156)
		(end 15.985998 -177.127662)
		(width 0.2032)
		(layer "F.Cu")
		(net "GND")
	)
	(segment
		(start 102.750112 -42.999914)
		(end 102.349808 -42.59961)
		(width 0.3556)
		(layer "F.Cu")
		(net "GND")
	)
	(segment
		(start 165.598856 -112.849152)
		(end 166.614856 -112.849152)
		(width 0.508)
		(layer "F.Cu")
		(net "GND")
	)
	(segment
		(start 220.709744 -174.678594)
		(end 220.545406 -174.678594)
		(width 0.381)
		(layer "F.Cu")
		(net "GND")
	)
	(segment
		(start 94.12097 -89.408)
		(end 94.12097 -88.519)
		(width 0.508)
		(layer "F.Cu")
		(net "GND")
	)
	(segment
		(start 14.80058 -102.489762)
		(end 14.80058 -104.77119)
		(width 0.3556)
		(layer "F.Cu")
		(net "GND")
	)
	(segment
		(start 313.125104 -52.4002)
		(end 314.2488 -52.4002)
		(width 0.508)
		(layer "F.Cu")
		(net "GND")
	)
	(segment
		(start 342.54313 -140.976096)
		(end 343.922096 -140.976096)
		(width 0.508)
		(layer "F.Cu")
		(net "GND")
	)
	(segment
		(start 92.350082 -37.399976)
		(end 92.350082 -37.40023)
		(width 0.3048)
		(layer "F.Cu")
		(net "GND")
	)
	(segment
		(start 124.350018 -83.349846)
		(end 125.350016 -82.349848)
		(width 0.4572)
		(layer "F.Cu")
		(net "GND")
	)
	(segment
		(start 108.000292 -256.25044)
		(end 108.000292 -252.653292)
		(width 0.508)
		(layer "F.Cu")
		(net "GND")
	)
	(segment
		(start 200.66 -227.838)
		(end 201.803 -227.838)
		(width 0.508)
		(layer "F.Cu")
		(net "GND")
	)
	(segment
		(start 118.35003 -101.350064)
		(end 118.850156 -101.85019)
		(width 0.4572)
		(layer "F.Cu")
		(net "GND")
	)
	(segment
		(start 272.513552 -18.542)
		(end 272.034 -18.062448)
		(width 0.508)
		(layer "F.Cu")
		(net "GND")
	)
	(segment
		(start 99.549966 -34.99993)
		(end 99.549712 -34.99993)
		(width 0.3048)
		(layer "F.Cu")
		(net "GND")
	)
	(segment
		(start 323.259958 -88.650064)
		(end 323.259958 -89.742772)
		(width 0.508)
		(layer "F.Cu")
		(net "GND")
	)
	(segment
		(start 92.350082 -35.80003)
		(end 92.350082 -35.800284)
		(width 0.3048)
		(layer "F.Cu")
		(net "GND")
	)
	(segment
		(start 60.56757 -143.7259)
		(end 61.5061 -143.7259)
		(width 0.508)
		(layer "F.Cu")
		(net "GND")
	)
	(segment
		(start 262.616188 -51.962812)
		(end 262.972042 -51.606958)
		(width 0.508)
		(layer "F.Cu")
		(net "GND")
	)
	(segment
		(start 119.20347 -76.581)
		(end 119.20347 -75.6793)
		(width 0.508)
		(layer "F.Cu")
		(net "GND")
	)
	(segment
		(start 116.350034 -92.349828)
		(end 116.85016 -91.849702)
		(width 0.4572)
		(layer "F.Cu")
		(net "GND")
	)
	(segment
		(start 103.0605 -224.79)
		(end 103.124 -224.79)
		(width 0.508)
		(layer "F.Cu")
		(net "GND")
	)
	(segment
		(start 28.424378 -168.738042)
		(end 28.271216 -168.58488)
		(width 0.2032)
		(layer "F.Cu")
		(net "GND")
	)
	(segment
		(start 95.45447 -96.5835)
		(end 95.45447 -95.377)
		(width 0.508)
		(layer "F.Cu")
		(net "GND")
	)
	(segment
		(start 238.24311 -94.36989)
		(end 237.744 -94.869)
		(width 0.508)
		(layer "F.Cu")
		(net "GND")
	)
	(segment
		(start 95.45447 -81.661)
		(end 95.00997 -81.661)
		(width 0.508)
		(layer "F.Cu")
		(net "GND")
	)
	(segment
		(start 93.950536 -36.599876)
		(end 94.350332 -36.20008)
		(width 0.3048)
		(layer "F.Cu")
		(net "GND")
	)
	(segment
		(start 97.150174 -54.19979)
		(end 96.750124 -53.79974)
		(width 0.3556)
		(layer "F.Cu")
		(net "GND")
	)
	(segment
		(start 119.350028 -82.349848)
		(end 119.850154 -81.849722)
		(width 0.508)
		(layer "F.Cu")
		(net "GND")
	)
	(segment
		(start 193.215768 -147.525232)
		(end 194.486276 -147.525232)
		(width 0.3556)
		(layer "F.Cu")
		(net "GND")
	)
	(segment
		(start 113.349786 -91.34983)
		(end 112.84966 -90.849704)
		(width 0.4572)
		(layer "F.Cu")
		(net "GND")
	)
	(segment
		(start 342.93175 -30.4165)
		(end 342.93175 -30.13075)
		(width 0.508)
		(layer "F.Cu")
		(net "GND")
	)
	(segment
		(start 141.999462 -253.39675)
		(end 142.412212 -252.984)
		(width 0.508)
		(layer "F.Cu")
		(net "GND")
	)
	(segment
		(start 307.086 -62.80023)
		(end 306.89423 -62.992)
		(width 0.508)
		(layer "F.Cu")
		(net "GND")
	)
	(segment
		(start 293.698168 -196.928232)
		(end 294.099234 -196.527166)
		(width 0.3556)
		(layer "F.Cu")
		(net "GND")
	)
	(segment
		(start 192.3415 -20.955)
		(end 193.294 -20.955)
		(width 0.508)
		(layer "F.Cu")
		(net "GND")
	)
	(segment
		(start 93.345 -220.9165)
		(end 92.5195 -220.9165)
		(width 0.508)
		(layer "F.Cu")
		(net "GND")
	)
	(segment
		(start 125.350016 -107.350052)
		(end 125.850142 -107.850178)
		(width 0.3048)
		(layer "F.Cu")
		(net "GND")
	)
	(segment
		(start 118.35003 -96.350074)
		(end 118.850156 -96.8502)
		(width 0.4572)
		(layer "F.Cu")
		(net "GND")
	)
	(segment
		(start 313.125104 -83.600036)
		(end 314.163964 -83.600036)
		(width 0.508)
		(layer "F.Cu")
		(net "GND")
	)
	(segment
		(start 284.48 -173.701456)
		(end 284.29331 -173.701456)
		(width 0.3556)
		(layer "F.Cu")
		(net "GND")
	)
	(segment
		(start 102.750112 -34.99993)
		(end 101.950012 -34.19983)
		(width 0.3048)
		(layer "F.Cu")
		(net "GND")
	)
	(segment
		(start 104.349804 -101.350064)
		(end 103.849678 -101.85019)
		(width 0.4572)
		(layer "F.Cu")
		(net "GND")
	)
	(segment
		(start 104.349804 -89.349834)
		(end 104.835198 -88.86444)
		(width 0.508)
		(layer "F.Cu")
		(net "GND")
	)
	(segment
		(start 96.350074 -38.190424)
		(end 96.350074 -38.199822)
		(width 0.3556)
		(layer "F.Cu")
		(net "GND")
	)
	(segment
		(start 49.800002 -79.590138)
		(end 49.800002 -81.079086)
		(width 0.3048)
		(layer "F.Cu")
		(net "GND")
	)
	(segment
		(start 126.999492 -256.25044)
		(end 126.999492 -253.31928)
		(width 0.508)
		(layer "F.Cu")
		(net "GND")
	)
	(segment
		(start 295.266872 -64.397636)
		(end 295.266872 -65.523872)
		(width 0.508)
		(layer "F.Cu")
		(net "GND")
	)
	(segment
		(start 61.5061 -143.7259)
		(end 61.595 -143.637)
		(width 0.508)
		(layer "F.Cu")
		(net "GND")
	)
	(segment
		(start 104.747568 -34.59734)
		(end 104.350058 -34.19983)
		(width 0.3048)
		(layer "F.Cu")
		(net "GND")
	)
	(segment
		(start 114.349784 -107.932474)
		(end 114.48415 -108.06684)
		(width 0.3048)
		(layer "F.Cu")
		(net "GND")
	)
	(segment
		(start 307.631846 -74.800206)
		(end 306.832 -75.600052)
		(width 0.508)
		(layer "F.Cu")
		(net "GND")
	)
	(segment
		(start 285.634938 -171.440094)
		(end 285.627318 -171.440094)
		(width 0.3556)
		(layer "F.Cu")
		(net "GND")
	)
	(segment
		(start 44.6786 -119.20601)
		(end 45.53839 -119.20601)
		(width 0.3048)
		(layer "F.Cu")
		(net "GND")
	)
	(segment
		(start 183.896 -121.6025)
		(end 184.13476 -121.36374)
		(width 0.381)
		(layer "F.Cu")
		(net "GND")
	)
	(segment
		(start 343.056718 -158.664148)
		(end 343.056718 -159.464248)
		(width 0.508)
		(layer "F.Cu")
		(net "GND")
	)
	(segment
		(start 48.289972 -186.679078)
		(end 48.289972 -187.809886)
		(width 0.508)
		(layer "F.Cu")
		(net "GND")
	)
	(segment
		(start 110.349792 -94.349824)
		(end 109.849666 -93.849698)
		(width 0.4572)
		(layer "F.Cu")
		(net "GND")
	)
	(segment
		(start 112.349788 -101.350064)
		(end 111.849662 -101.85019)
		(width 0.4572)
		(layer "F.Cu")
		(net "GND")
	)
	(segment
		(start 313.125104 -80.400144)
		(end 313.734958 -80.391)
		(width 0.508)
		(layer "F.Cu")
		(net "GND")
	)
	(segment
		(start 92.757244 -45.064934)
		(end 92.757244 -45.00245)
		(width 0.3048)
		(layer "F.Cu")
		(net "GND")
	)
	(segment
		(start 249.815096 -51.962812)
		(end 248.939812 -51.962812)
		(width 0.508)
		(layer "F.Cu")
		(net "GND")
	)
	(segment
		(start 42.38625 -174.99584)
		(end 43.69816 -174.99584)
		(width 0.508)
		(layer "F.Cu")
		(net "GND")
	)
	(segment
		(start 16.560038 -185.409586)
		(end 16.560038 -186.710066)
		(width 0.3048)
		(layer "F.Cu")
		(net "GND")
	)
	(segment
		(start 60.2615 -109.474)
		(end 59.055 -109.474)
		(width 0.508)
		(layer "F.Cu")
		(net "GND")
	)
	(segment
		(start 124.350018 -97.350072)
		(end 124.850144 -97.850198)
		(width 0.4572)
		(layer "F.Cu")
		(net "GND")
	)
	(segment
		(start 87.326216 -66.7004)
		(end 87.986616 -66.04)
		(width 0.508)
		(layer "F.Cu")
		(net "GND")
	)
	(segment
		(start 190.912242 -45.6565)
		(end 191.9605 -45.6565)
		(width 0.508)
		(layer "F.Cu")
		(net "GND")
	)
	(segment
		(start 109.349794 -84.349844)
		(end 108.849668 -83.849718)
		(width 0.4572)
		(layer "F.Cu")
		(net "GND")
	)
	(segment
		(start 111.506 -68.199)
		(end 111.887 -67.818)
		(width 0.508)
		(layer "F.Cu")
		(net "GND")
	)
	(segment
		(start 50.829972 -186.679078)
		(end 50.829972 -187.809886)
		(width 0.508)
		(layer "F.Cu")
		(net "GND")
	)
	(segment
		(start 298.43476 -177.040032)
		(end 298.829984 -177.435256)
		(width 0.3556)
		(layer "F.Cu")
		(net "GND")
	)
	(segment
		(start 334.971136 -203.462128)
		(end 334.971136 -201.603864)
		(width 0.508)
		(layer "F.Cu")
		(net "GND")
	)
	(segment
		(start 101.95941 -43.800014)
		(end 101.950012 -43.800014)
		(width 0.3556)
		(layer "F.Cu")
		(net "GND")
	)
	(segment
		(start 300.834806 -176.240186)
		(end 301.23003 -176.63541)
		(width 0.3556)
		(layer "F.Cu")
		(net "GND")
	)
	(segment
		(start 102.349808 -45.799756)
		(end 102.749858 -46.199806)
		(width 0.3556)
		(layer "F.Cu")
		(net "GND")
	)
	(segment
		(start 92.324682 -131.570476)
		(end 92.324682 -130.193288)
		(width 0.2032)
		(layer "F.Cu")
		(net "GND")
	)
	(segment
		(start 111.34979 -93.349826)
		(end 111.849662 -93.849698)
		(width 0.4572)
		(layer "F.Cu")
		(net "GND")
	)
	(segment
		(start 118.631462 -87.349838)
		(end 118.63959 -87.34171)
		(width 0.3048)
		(layer "F.Cu")
		(net "GND")
	)
	(segment
		(start 200.025 -197.6755)
		(end 200.025 -199.009)
		(width 0.508)
		(layer "F.Cu")
		(net "GND")
	)
	(segment
		(start 101.150166 -47.800006)
		(end 100.750116 -47.399956)
		(width 0.3556)
		(layer "F.Cu")
		(net "GND")
	)
	(segment
		(start 95.45447 -82.804)
		(end 94.75597 -82.804)
		(width 0.508)
		(layer "F.Cu")
		(net "GND")
	)
	(segment
		(start 25.596088 -195.898516)
		(end 25.604216 -195.906644)
		(width 0.508)
		(layer "F.Cu")
		(net "GND")
	)
	(segment
		(start 333.468218 -153.393648)
		(end 331.582014 -153.393648)
		(width 0.508)
		(layer "F.Cu")
		(net "GND")
	)
	(segment
		(start 262.007096 -53.232812)
		(end 263.124188 -53.232812)
		(width 0.508)
		(layer "F.Cu")
		(net "GND")
	)
	(segment
		(start 110.349792 -93.349826)
		(end 110.349538 -93.349826)
		(width 0.4572)
		(layer "F.Cu")
		(net "GND")
	)
	(segment
		(start 314.163964 -83.600036)
		(end 314.579 -83.185)
		(width 0.508)
		(layer "F.Cu")
		(net "GND")
	)
	(segment
		(start 113.349786 -95.350076)
		(end 112.84966 -95.850202)
		(width 0.4572)
		(layer "F.Cu")
		(net "GND")
	)
	(segment
		(start 53.213 -207.391)
		(end 52.197 -207.391)
		(width 0.508)
		(layer "F.Cu")
		(net "GND")
	)
	(segment
		(start 64.939164 -187.809886)
		(end 66.069972 -187.809886)
		(width 0.508)
		(layer "F.Cu")
		(net "GND")
	)
	(segment
		(start 95.549974 -54.19979)
		(end 95.149924 -53.79974)
		(width 0.3556)
		(layer "F.Cu")
		(net "GND")
	)
	(segment
		(start 121.350024 -88.349836)
		(end 120.850152 -88.849708)
		(width 0.508)
		(layer "F.Cu")
		(net "GND")
	)
	(segment
		(start 183.569864 -38.616636)
		(end 183.569864 -39.75608)
		(width 0.508)
		(layer "F.Cu")
		(net "GND")
	)
	(segment
		(start 109.352842 -82.3468)
		(end 109.352842 -81.496154)
		(width 0.4572)
		(layer "F.Cu")
		(net "GND")
	)
	(segment
		(start 319.850008 -113.03)
		(end 320.031872 -112.848136)
		(width 0.2032)
		(layer "F.Cu")
		(net "GND")
	)
	(segment
		(start 99.549966 -34.200084)
		(end 99.149916 -34.600134)
		(width 0.3048)
		(layer "F.Cu")
		(net "GND")
	)
	(segment
		(start 306.959 -87.947246)
		(end 306.959 -87.9856)
		(width 0.508)
		(layer "F.Cu")
		(net "GND")
	)
	(segment
		(start 81.000092 -253.29388)
		(end 80.563212 -252.857)
		(width 0.508)
		(layer "F.Cu")
		(net "GND")
	)
	(segment
		(start 116.350034 -101.350064)
		(end 116.85016 -101.85019)
		(width 0.4572)
		(layer "F.Cu")
		(net "GND")
	)
	(segment
		(start 292.10762 -196.135244)
		(end 292.504368 -196.531992)
		(width 0.3048)
		(layer "F.Cu")
		(net "GND")
	)
	(segment
		(start 286.639 -211.6582)
		(end 286.42818 -211.44738)
		(width 0.508)
		(layer "F.Cu")
		(net "GND")
	)
	(segment
		(start 318.4525 -170.434)
		(end 319.309496 -170.434)
		(width 0.508)
		(layer "F.Cu")
		(net "GND")
	)
	(segment
		(start 117.350032 -104.350058)
		(end 117.339618 -104.350058)
		(width 0.508)
		(layer "F.Cu")
		(net "GND")
	)
	(segment
		(start 121.350024 -85.349842)
		(end 121.350278 -85.349842)
		(width 0.508)
		(layer "F.Cu")
		(net "GND")
	)
	(segment
		(start 147.098766 -61.9379)
		(end 147.098766 -60.284868)
		(width 0.254)
		(layer "F.Cu")
		(net "GND")
	)
	(segment
		(start 313.125104 -70.800214)
		(end 314.334144 -70.800214)
		(width 0.508)
		(layer "F.Cu")
		(net "GND")
	)
	(segment
		(start 115.350036 -89.349834)
		(end 115.349782 -89.349834)
		(width 0.3048)
		(layer "F.Cu")
		(net "GND")
	)
	(segment
		(start 106.759248 -48.599852)
		(end 106.750104 -48.599852)
		(width 0.3556)
		(layer "F.Cu")
		(net "GND")
	)
	(segment
		(start 339.2932 -141.1478)
		(end 339.2932 -139.1666)
		(width 0.508)
		(layer "F.Cu")
		(net "GND")
	)
	(segment
		(start 104.350058 -34.19983)
		(end 103.549958 -34.99993)
		(width 0.3048)
		(layer "F.Cu")
		(net "GND")
	)
	(segment
		(start 79.38897 -112.4585)
		(end 77.88529 -112.4585)
		(width 0.508)
		(layer "F.Cu")
		(net "GND")
	)
	(segment
		(start 275.708872 -226.081336)
		(end 275.708872 -227.575872)
		(width 0.508)
		(layer "F.Cu")
		(net "GND")
	)
	(segment
		(start 33.414716 -227.44938)
		(end 33.732216 -227.13188)
		(width 0.3048)
		(layer "F.Cu")
		(net "GND")
	)
	(segment
		(start 112.349788 -87.349838)
		(end 111.849662 -86.849712)
		(width 0.3048)
		(layer "F.Cu")
		(net "GND")
	)
	(segment
		(start 115.350036 -104.350058)
		(end 115.850162 -104.850184)
		(width 0.4572)
		(layer "F.Cu")
		(net "GND")
	)
	(segment
		(start 50.199798 -77.08011)
		(end 50.199798 -75.428602)
		(width 0.3048)
		(layer "F.Cu")
		(net "GND")
	)
	(segment
		(start 119.350028 -84.349844)
		(end 119.350028 -84.104226)
		(width 0.3048)
		(layer "F.Cu")
		(net "GND")
	)
	(segment
		(start 110.349792 -88.349582)
		(end 110.849664 -87.84971)
		(width 0.4064)
		(layer "F.Cu")
		(net "GND")
	)
	(segment
		(start 188.722 -145.2245)
		(end 188.087 -145.2245)
		(width 0.381)
		(layer "F.Cu")
		(net "GND")
	)
	(segment
		(start 284.898084 -195.689728)
		(end 284.78861 -195.580254)
		(width 0.3556)
		(layer "F.Cu")
		(net "GND")
	)
	(segment
		(start 200.533 -138.811)
		(end 200.8124 -139.0904)
		(width 0.508)
		(layer "F.Cu")
		(net "GND")
	)
	(segment
		(start 59.859164 -187.809886)
		(end 60.989972 -187.809886)
		(width 0.508)
		(layer "F.Cu")
		(net "GND")
	)
	(segment
		(start 28.899866 -79.585312)
		(end 28.614116 -79.871062)
		(width 0.508)
		(layer "F.Cu")
		(net "GND")
	)
	(segment
		(start 19.185128 -170.107356)
		(end 19.185128 -168.653968)
		(width 0.2032)
		(layer "F.Cu")
		(net "GND")
	)
	(segment
		(start 25.159716 -224.21088)
		(end 24.933402 -223.984566)
		(width 0.3048)
		(layer "F.Cu")
		(net "GND")
	)
	(segment
		(start 303.965864 -193.302636)
		(end 305.299872 -193.302636)
		(width 0.508)
		(layer "F.Cu")
		(net "GND")
	)
	(segment
		(start 280.107136 -63.699136)
		(end 279.908 -63.5)
		(width 0.508)
		(layer "F.Cu")
		(net "GND")
	)
	(segment
		(start 139.45997 -83.1215)
		(end 137.7569 -83.1215)
		(width 0.508)
		(layer "F.Cu")
		(net "GND")
	)
	(segment
		(start 152.4635 -55.499)
		(end 153.289 -55.499)
		(width 0.508)
		(layer "F.Cu")
		(net "GND")
	)
	(segment
		(start 120.350026 -89.349834)
		(end 120.850152 -88.849708)
		(width 0.508)
		(layer "F.Cu")
		(net "GND")
	)
	(segment
		(start 5.855716 -214.68588)
		(end 2.675382 -214.68588)
		(width 0.508)
		(layer "F.Cu")
		(net "GND")
	)
	(segment
		(start 12.40028 -102.489762)
		(end 12.40028 -104.75849)
		(width 0.3556)
		(layer "F.Cu")
		(net "GND")
	)
	(segment
		(start 329.057 -8.6995)
		(end 327.946004 -8.6995)
		(width 0.508)
		(layer "F.Cu")
		(net "GND")
	)
	(segment
		(start 339.500718 -142.015718)
		(end 338.963 -141.478)
		(width 0.508)
		(layer "F.Cu")
		(net "GND")
	)
	(segment
		(start 73.999852 -256.25044)
		(end 73.999852 -253.32436)
		(width 0.508)
		(layer "F.Cu")
		(net "GND")
	)
	(segment
		(start 22.619716 -207.06588)
		(end 22.048216 -207.06588)
		(width 0.508)
		(layer "F.Cu")
		(net "GND")
	)
	(segment
		(start 42.79773 -131.28625)
		(end 41.47566 -132.60832)
		(width 0.508)
		(layer "F.Cu")
		(net "GND")
	)
	(segment
		(start 296.545 -156.464)
		(end 296.164 -156.083)
		(width 0.508)
		(layer "F.Cu")
		(net "GND")
	)
	(segment
		(start 115.000532 -256.25044)
		(end 115.000532 -253.63932)
		(width 0.508)
		(layer "F.Cu")
		(net "GND")
	)
	(segment
		(start 2.675382 -214.68588)
		(end 2.144268 -215.216994)
		(width 0.508)
		(layer "F.Cu")
		(net "GND")
	)
	(segment
		(start 340.961218 -158.473648)
		(end 340.961218 -159.426148)
		(width 0.508)
		(layer "F.Cu")
		(net "GND")
	)
	(segment
		(start 198.800212 -256.25044)
		(end 198.800212 -253.664212)
		(width 0.508)
		(layer "F.Cu")
		(net "GND")
	)
	(segment
		(start 284.729936 -63.114936)
		(end 285.242 -63.627)
		(width 0.508)
		(layer "F.Cu")
		(net "GND")
	)
	(segment
		(start 92.354654 -44.59986)
		(end 92.757244 -45.00245)
		(width 0.3048)
		(layer "F.Cu")
		(net "GND")
	)
	(segment
		(start 256.159 -137.2235)
		(end 256.159 -138.0998)
		(width 0.508)
		(layer "F.Cu")
		(net "GND")
	)
	(segment
		(start 189.357 -37.7825)
		(end 189.357 -36.83)
		(width 0.508)
		(layer "F.Cu")
		(net "GND")
	)
	(segment
		(start 120.350026 -91.34983)
		(end 120.850152 -90.849704)
		(width 0.4572)
		(layer "F.Cu")
		(net "GND")
	)
	(segment
		(start 318.77 -171.577)
		(end 318.897 -171.577)
		(width 0.508)
		(layer "F.Cu")
		(net "GND")
	)
	(segment
		(start 89.125552 -138.672062)
		(end 89.36101 -138.90752)
		(width 0.2032)
		(layer "F.Cu")
		(net "GND")
	)
	(segment
		(start 201.549 -183.896)
		(end 201.676 -183.769)
		(width 0.508)
		(layer "F.Cu")
		(net "GND")
	)
	(segment
		(start 294.488616 -202.535028)
		(end 294.097964 -202.144376)
		(width 0.3556)
		(layer "F.Cu")
		(net "GND")
	)
	(segment
		(start 116.350034 -87.349838)
		(end 116.85016 -86.849712)
		(width 0.4572)
		(layer "F.Cu")
		(net "GND")
	)
	(segment
		(start 60.989972 -186.679078)
		(end 60.989972 -187.809886)
		(width 0.508)
		(layer "F.Cu")
		(net "GND")
	)
	(segment
		(start 119.350028 -99.350068)
		(end 119.850154 -99.850194)
		(width 0.4572)
		(layer "F.Cu")
		(net "GND")
	)
	(segment
		(start 76.999592 -253.35738)
		(end 76.499212 -252.857)
		(width 0.508)
		(layer "F.Cu")
		(net "GND")
	)
	(segment
		(start 151.003 -61.0235)
		(end 151.003 -59.944)
		(width 0.508)
		(layer "F.Cu")
		(net "GND")
	)
	(segment
		(start 98.658934 -34.99993)
		(end 98.552508 -34.893504)
		(width 0.3048)
		(layer "F.Cu")
		(net "GND")
	)
	(segment
		(start 28.424378 -170.107356)
		(end 28.424378 -168.738042)
		(width 0.2032)
		(layer "F.Cu")
		(net "GND")
	)
	(segment
		(start 100.749862 -44.19981)
		(end 101.149912 -44.59986)
		(width 0.3556)
		(layer "F.Cu")
		(net "GND")
	)
	(segment
		(start 110.349792 -97.350072)
		(end 109.849666 -97.850198)
		(width 0.4572)
		(layer "F.Cu")
		(net "GND")
	)
	(segment
		(start 166.614856 -112.849152)
		(end 167.259 -112.849152)
		(width 0.508)
		(layer "F.Cu")
		(net "GND")
	)
	(segment
		(start 279.273 -66.294)
		(end 280.035 -67.056)
		(width 0.508)
		(layer "F.Cu")
		(net "GND")
	)
	(segment
		(start 307.146198 -78.800198)
		(end 306.832 -78.486)
		(width 0.508)
		(layer "F.Cu")
		(net "GND")
	)
	(segment
		(start 101.18979 -74.33818)
		(end 101.18979 -74.30516)
		(width 0.508)
		(layer "F.Cu")
		(net "GND")
	)
	(segment
		(start 175.505364 -34.997136)
		(end 175.505364 -36.075112)
		(width 0.508)
		(layer "F.Cu")
		(net "GND")
	)
	(segment
		(start 306.5145 -110.8075)
		(end 307.086 -111.379)
		(width 0.508)
		(layer "F.Cu")
		(net "GND")
	)
	(segment
		(start 280.47442 -187.682124)
		(end 282.126436 -187.682124)
		(width 0.508)
		(layer "F.Cu")
		(net "GND")
	)
	(segment
		(start 105.950004 -44.59986)
		(end 105.549954 -44.19981)
		(width 0.3556)
		(layer "F.Cu")
		(net "GND")
	)
	(segment
		(start 184.8485 -222.39224)
		(end 186.29376 -222.39224)
		(width 0.381)
		(layer "F.Cu")
		(net "GND")
	)
	(segment
		(start 327.946004 -8.6995)
		(end 327.914 -8.731504)
		(width 0.508)
		(layer "F.Cu")
		(net "GND")
	)
	(segment
		(start 68.609972 -185.269886)
		(end 69.74078 -185.269886)
		(width 0.508)
		(layer "F.Cu")
		(net "GND")
	)
	(segment
		(start 180.2765 -144.272)
		(end 179.6034 -144.272)
		(width 0.508)
		(layer "F.Cu")
		(net "GND")
	)
	(segment
		(start 88.725502 -132.357368)
		(end 88.521794 -132.561076)
		(width 0.2032)
		(layer "F.Cu")
		(net "GND")
	)
	(segment
		(start 93.949774 -49.399952)
		(end 93.950028 -49.399952)
		(width 0.3556)
		(layer "F.Cu")
		(net "GND")
	)
	(segment
		(start 286.057594 -220.40215)
		(end 287.34385 -220.40215)
		(width 0.3556)
		(layer "F.Cu")
		(net "GND")
	)
	(segment
		(start 326.4535 -144.2085)
		(end 326.771 -144.526)
		(width 0.508)
		(layer "F.Cu")
		(net "GND")
	)
	(segment
		(start 100.350066 -37.399976)
		(end 99.95027 -37.00018)
		(width 0.3048)
		(layer "F.Cu")
		(net "GND")
	)
	(segment
		(start 114.349784 -99.350068)
		(end 113.849658 -99.850194)
		(width 0.4572)
		(layer "F.Cu")
		(net "GND")
	)
	(segment
		(start 107.156504 -48.997108)
		(end 107.54995 -49.390554)
		(width 0.3556)
		(layer "F.Cu")
		(net "GND")
	)
	(segment
		(start 152.4635 -50.927)
		(end 153.543 -50.927)
		(width 0.508)
		(layer "F.Cu")
		(net "GND")
	)
	(segment
		(start 80.319626 -24.4856)
		(end 80.68564 -24.4856)
		(width 0.508)
		(layer "F.Cu")
		(net "GND")
	)
	(segment
		(start 73.000362 -253.29515)
		(end 72.562212 -252.857)
		(width 0.508)
		(layer "F.Cu")
		(net "GND")
	)
	(segment
		(start 68.609972 -187.809886)
		(end 68.609972 -188.940694)
		(width 0.508)
		(layer "F.Cu")
		(net "GND")
	)
	(segment
		(start 195.800472 -253.652528)
		(end 195.800472 -256.25044)
		(width 0.508)
		(layer "F.Cu")
		(net "GND")
	)
	(segment
		(start 313.125104 -86.000082)
		(end 314.625482 -86.000082)
		(width 0.508)
		(layer "F.Cu")
		(net "GND")
	)
	(segment
		(start 87.986616 -61.77915)
		(end 87.986616 -66.04)
		(width 0.508)
		(layer "F.Cu")
		(net "GND")
	)
	(segment
		(start 314.477146 -54.000146)
		(end 314.833 -54.356)
		(width 0.508)
		(layer "F.Cu")
		(net "GND")
	)
	(segment
		(start 292.123876 -202.624436)
		(end 292.123876 -203.023724)
		(width 0.3556)
		(layer "F.Cu")
		(net "GND")
	)
	(segment
		(start 217.17 -162.433)
		(end 216.916 -162.687)
		(width 0.3048)
		(layer "F.Cu")
		(net "GND")
	)
	(segment
		(start 95.13697 -80.518)
		(end 94.50197 -81.153)
		(width 0.508)
		(layer "F.Cu")
		(net "GND")
	)
	(segment
		(start 280.368756 -67.516756)
		(end 280.035 -67.183)
		(width 0.3048)
		(layer "F.Cu")
		(net "GND")
	)
	(segment
		(start 280.162 -160.655)
		(end 280.67 -160.147)
		(width 0.508)
		(layer "F.Cu")
		(net "GND")
	)
	(segment
		(start 171.174664 -24.014176)
		(end 170.295316 -24.014176)
		(width 0.508)
		(layer "F.Cu")
		(net "GND")
	)
	(segment
		(start 116.350034 -89.349834)
		(end 116.85016 -88.849708)
		(width 0.3048)
		(layer "F.Cu")
		(net "GND")
	)
	(segment
		(start 116.000022 -256.25044)
		(end 116.000022 -253.23419)
		(width 0.508)
		(layer "F.Cu")
		(net "GND")
	)
	(segment
		(start 101.150166 -42.999914)
		(end 100.749862 -42.59961)
		(width 0.3556)
		(layer "F.Cu")
		(net "GND")
	)
	(segment
		(start 19.585178 -175.746156)
		(end 19.585178 -176.889918)
		(width 0.2032)
		(layer "F.Cu")
		(net "GND")
	)
	(segment
		(start 296.89806 -196.05244)
		(end 296.49928 -195.65366)
		(width 0.3556)
		(layer "F.Cu")
		(net "GND")
	)
	(segment
		(start 117.339618 -104.350058)
		(end 116.845842 -103.856282)
		(width 0.508)
		(layer "F.Cu")
		(net "GND")
	)
	(segment
		(start 102.356158 -44.196762)
		(end 101.95941 -43.800014)
		(width 0.3556)
		(layer "F.Cu")
		(net "GND")
	)
	(segment
		(start 98.999802 -256.25044)
		(end 98.999802 -253.00559)
		(width 0.508)
		(layer "F.Cu")
		(net "GND")
	)
	(segment
		(start 307.20538 -143.57604)
		(end 307.20538 -142.75562)
		(width 0.508)
		(layer "F.Cu")
		(net "GND")
	)
	(segment
		(start 209.7659 -104.3305)
		(end 209.677 -104.4194)
		(width 0.508)
		(layer "F.Cu")
		(net "GND")
	)
	(segment
		(start 204.793596 -111.462312)
		(end 204.793596 -110.420404)
		(width 0.508)
		(layer "F.Cu")
		(net "GND")
	)
	(segment
		(start 338.963 -141.478)
		(end 339.2932 -141.1478)
		(width 0.508)
		(layer "F.Cu")
		(net "GND")
	)
	(segment
		(start 114.349784 -96.350074)
		(end 113.849658 -96.8502)
		(width 0.4572)
		(layer "F.Cu")
		(net "GND")
	)
	(segment
		(start 119.358156 -87.639144)
		(end 119.350028 -87.631016)
		(width 0.3048)
		(layer "F.Cu")
		(net "GND")
	)
	(segment
		(start 106.3498 -107.350052)
		(end 105.849674 -107.850178)
		(width 0.4572)
		(layer "F.Cu")
		(net "GND")
	)
	(segment
		(start 326.992488 -74.041)
		(end 329.057 -74.041)
		(width 0.508)
		(layer "F.Cu")
		(net "GND")
	)
	(segment
		(start 292.1 -154.559)
		(end 292.735 -154.559)
		(width 0.508)
		(layer "F.Cu")
		(net "GND")
	)
	(segment
		(start 184.712864 -38.616636)
		(end 184.712864 -39.75608)
		(width 0.508)
		(layer "F.Cu")
		(net "GND")
	)
	(segment
		(start 145.000472 -253.41326)
		(end 144.571212 -252.984)
		(width 0.508)
		(layer "F.Cu")
		(net "GND")
	)
	(segment
		(start 126.323852 -75.865482)
		(end 126.70917 -76.2508)
		(width 0.508)
		(layer "F.Cu")
		(net "GND")
	)
	(segment
		(start 347.374718 -142.789148)
		(end 347.374718 -141.989048)
		(width 0.508)
		(layer "F.Cu")
		(net "GND")
	)
	(segment
		(start 339.500718 -142.852648)
		(end 339.500718 -142.015718)
		(width 0.508)
		(layer "F.Cu")
		(net "GND")
	)
	(segment
		(start 95.957898 -37.798248)
		(end 96.350074 -38.190424)
		(width 0.3556)
		(layer "F.Cu")
		(net "GND")
	)
	(segment
		(start 185.284872 -207.590136)
		(end 184.776872 -208.098136)
		(width 0.508)
		(layer "F.Cu")
		(net "GND")
	)
	(segment
		(start 292.481 -206.756)
		(end 293.1922 -206.0448)
		(width 0.508)
		(layer "F.Cu")
		(net "GND")
	)
	(segment
		(start 313.734958 -80.391)
		(end 314.579 -80.391)
		(width 0.508)
		(layer "F.Cu")
		(net "GND")
	)
	(segment
		(start 224.356676 -83.491324)
		(end 224.714816 -83.491324)
		(width 0.508)
		(layer "F.Cu")
		(net "GND")
	)
	(segment
		(start 290.89096 -197.328028)
		(end 290.89096 -197.33768)
		(width 0.3556)
		(layer "F.Cu")
		(net "GND")
	)
	(segment
		(start 104.35209 -34.997898)
		(end 104.356408 -34.997898)
		(width 0.3048)
		(layer "F.Cu")
		(net "GND")
	)
	(segment
		(start 293.634922 -169.840148)
		(end 293.634922 -169.835322)
		(width 0.3556)
		(layer "F.Cu")
		(net "GND")
	)
	(segment
		(start 284.0482 -191.3255)
		(end 285.1912 -191.3255)
		(width 0.508)
		(layer "F.Cu")
		(net "GND")
	)
	(segment
		(start 278.384 -208.2165)
		(end 278.384 -208.494376)
		(width 0.508)
		(layer "F.Cu")
		(net "GND")
	)
	(segment
		(start 43.399964 -79.590138)
		(end 43.399964 -81.35112)
		(width 0.3048)
		(layer "F.Cu")
		(net "GND")
	)
	(segment
		(start 107.950254 -36.20008)
		(end 107.550204 -35.80003)
		(width 0.3048)
		(layer "F.Cu")
		(net "GND")
	)
	(segment
		(start 105.950258 -35.80003)
		(end 105.950004 -35.80003)
		(width 0.3048)
		(layer "F.Cu")
		(net "GND")
	)
	(segment
		(start 93.549978 -49.799748)
		(end 93.150182 -50.199544)
		(width 0.3556)
		(layer "F.Cu")
		(net "GND")
	)
	(segment
		(start 119.350028 -100.350066)
		(end 119.850154 -100.850192)
		(width 0.4572)
		(layer "F.Cu")
		(net "GND")
	)
	(segment
		(start 106.3498 -102.350062)
		(end 105.849674 -102.850188)
		(width 0.4064)
		(layer "F.Cu")
		(net "GND")
	)
	(segment
		(start 346.612718 -158.283148)
		(end 346.612718 -158.872682)
		(width 0.508)
		(layer "F.Cu")
		(net "GND")
	)
	(segment
		(start 169.607992 -26.816812)
		(end 169.607992 -26.416)
		(width 0.508)
		(layer "F.Cu")
		(net "GND")
	)
	(segment
		(start 328.024236 -169.164)
		(end 328.041 -169.164)
		(width 0.508)
		(layer "F.Cu")
		(net "GND")
	)
	(segment
		(start 34.370264 -78.502764)
		(end 34.6075 -78.74)
		(width 0.508)
		(layer "F.Cu")
		(net "GND")
	)
	(segment
		(start 315.29909 -67.600068)
		(end 315.411358 -67.4878)
		(width 0.508)
		(layer "F.Cu")
		(net "GND")
	)
	(segment
		(start 120.350026 -101.350064)
		(end 120.850152 -101.85019)
		(width 0.4572)
		(layer "F.Cu")
		(net "GND")
	)
	(segment
		(start 262.2804 -221.813882)
		(end 262.2804 -220.384878)
		(width 0.3556)
		(layer "F.Cu")
		(net "GND")
	)
	(segment
		(start 85.486748 -123.094242)
		(end 86.00313 -122.57786)
		(width 0.3048)
		(layer "F.Cu")
		(net "GND")
	)
	(segment
		(start 222.010224 -176.558194)
		(end 223.040194 -176.558194)
		(width 0.381)
		(layer "F.Cu")
		(net "GND")
	)
	(segment
		(start 195.444364 -47.665386)
		(end 194.339464 -47.665386)
		(width 0.508)
		(layer "F.Cu")
		(net "GND")
	)
	(segment
		(start 49.90973 -133.96976)
		(end 49.67097 -133.731)
		(width 0.3048)
		(layer "F.Cu")
		(net "GND")
	)
	(segment
		(start 164.71646 -146.745452)
		(end 164.402008 -146.431)
		(width 0.3048)
		(layer "F.Cu")
		(net "GND")
	)
	(segment
		(start 305.06924 -219.0115)
		(end 305.7525 -219.0115)
		(width 0.381)
		(layer "F.Cu")
		(net "GND")
	)
	(segment
		(start 116.350034 -107.350052)
		(end 116.350034 -107.974384)
		(width 0.3048)
		(layer "F.Cu")
		(net "GND")
	)
	(segment
		(start 66.069972 -184.139078)
		(end 66.069972 -185.269886)
		(width 0.508)
		(layer "F.Cu")
		(net "GND")
	)
	(segment
		(start 114.349784 -94.349824)
		(end 113.849658 -93.849698)
		(width 0.4572)
		(layer "F.Cu")
		(net "GND")
	)
	(segment
		(start 111.34979 -84.349844)
		(end 110.849664 -83.849718)
		(width 0.508)
		(layer "F.Cu")
		(net "GND")
	)
	(segment
		(start 91.549982 -36.599876)
		(end 91.55049 -36.599876)
		(width 0.3556)
		(layer "F.Cu")
		(net "GND")
	)
	(segment
		(start 67.479164 -187.809886)
		(end 68.609972 -187.809886)
		(width 0.508)
		(layer "F.Cu")
		(net "GND")
	)
	(segment
		(start 307.031136 -84.400136)
		(end 306.451 -83.82)
		(width 0.508)
		(layer "F.Cu")
		(net "GND")
	)
	(segment
		(start 112.349788 -92.349828)
		(end 111.34979 -91.34983)
		(width 0.4572)
		(layer "F.Cu")
		(net "GND")
	)
	(segment
		(start 104.778302 -74.919332)
		(end 104.778302 -74.8792)
		(width 0.508)
		(layer "F.Cu")
		(net "GND")
	)
	(segment
		(start 301.498 -102.5525)
		(end 301.498 -104.267)
		(width 0.508)
		(layer "F.Cu")
		(net "GND")
	)
	(segment
		(start 318.897 -171.577)
		(end 319.674748 -170.799252)
		(width 0.508)
		(layer "F.Cu")
		(net "GND")
	)
	(segment
		(start 106.2736 -72.8218)
		(end 105.791 -72.3392)
		(width 0.508)
		(layer "F.Cu")
		(net "GND")
	)
	(segment
		(start 292.034976 -167.440102)
		(end 292.034976 -167.440356)
		(width 0.3556)
		(layer "F.Cu")
		(net "GND")
	)
	(segment
		(start 119.350028 -84.104226)
		(end 119.383556 -84.070698)
		(width 0.3048)
		(layer "F.Cu")
		(net "GND")
	)
	(segment
		(start 14.700758 -104.871012)
		(end 14.80058 -104.77119)
		(width 0.508)
		(layer "F.Cu")
		(net "GND")
	)
	(segment
		(start 190.554864 -32.139636)
		(end 190.554864 -32.945832)
		(width 0.508)
		(layer "F.Cu")
		(net "GND")
	)
	(segment
		(start 306.832 -58.547)
		(end 306.832 -58.674)
		(width 0.508)
		(layer "F.Cu")
		(net "GND")
	)
	(segment
		(start 81.999582 -256.25044)
		(end 81.999582 -253.32563)
		(width 0.508)
		(layer "F.Cu")
		(net "GND")
	)
	(segment
		(start 105.349802 -84.349844)
		(end 104.849676 -83.849718)
		(width 0.4572)
		(layer "F.Cu")
		(net "GND")
	)
	(segment
		(start 29.566616 -80.379062)
		(end 29.122116 -80.379062)
		(width 0.508)
		(layer "F.Cu")
		(net "GND")
	)
	(segment
		(start 125.350016 -103.35006)
		(end 125.850142 -103.850186)
		(width 0.4572)
		(layer "F.Cu")
		(net "GND")
	)
	(segment
		(start 95.549974 -34.99993)
		(end 95.54972 -34.99993)
		(width 0.3048)
		(layer "F.Cu")
		(net "GND")
	)
	(segment
		(start 103.549958 -42.199814)
		(end 103.949754 -42.59961)
		(width 0.3556)
		(layer "F.Cu")
		(net "GND")
	)
	(segment
		(start 302.34636 -94.97314)
		(end 303.67986 -94.97314)
		(width 0.3048)
		(layer "F.Cu")
		(net "GND")
	)
	(segment
		(start 83.801966 -62.23)
		(end 83.801966 -61.341)
		(width 0.508)
		(layer "F.Cu")
		(net "GND")
	)
	(segment
		(start 80.562196 -140.535914)
		(end 80.473296 -140.535914)
		(width 0.508)
		(layer "F.Cu")
		(net "GND")
	)
	(segment
		(start 84.105242 -123.094242)
		(end 85.486748 -123.094242)
		(width 0.3048)
		(layer "F.Cu")
		(net "GND")
	)
	(segment
		(start 98.552508 -34.893504)
		(end 98.131376 -34.893504)
		(width 0.3048)
		(layer "F.Cu")
		(net "GND")
	)
	(segment
		(start 184.903872 -196.845936)
		(end 183.684672 -196.845936)
		(width 0.508)
		(layer "F.Cu")
		(net "GND")
	)
	(segment
		(start 290.498022 -196.93509)
		(end 290.89096 -197.328028)
		(width 0.3556)
		(layer "F.Cu")
		(net "GND")
	)
	(segment
		(start 86.54161 -131.5466)
		(end 86.54161 -130.57505)
		(width 0.2032)
		(layer "F.Cu")
		(net "GND")
	)
	(segment
		(start 119.06885 -87.349838)
		(end 119.350028 -87.349838)
		(width 0.3048)
		(layer "F.Cu")
		(net "GND")
	)
	(segment
		(start 305.3715 -191.262)
		(end 305.3715 -192.333372)
		(width 0.508)
		(layer "F.Cu")
		(net "GND")
	)
	(segment
		(start 190.4365 -116.23675)
		(end 190.4365 -115.316)
		(width 0.508)
		(layer "F.Cu")
		(net "GND")
	)
	(segment
		(start 105.150158 -47.00016)
		(end 105.150158 -46.999906)
		(width 0.3556)
		(layer "F.Cu")
		(net "GND")
	)
	(segment
		(start 117.350032 -91.34983)
		(end 117.850158 -90.849704)
		(width 0.4572)
		(layer "F.Cu")
		(net "GND")
	)
	(segment
		(start 192.142364 -29.663136)
		(end 193.172588 -29.663136)
		(width 0.508)
		(layer "F.Cu")
		(net "GND")
	)
	(segment
		(start 277.740872 -226.081336)
		(end 277.740872 -227.829872)
		(width 0.508)
		(layer "F.Cu")
		(net "GND")
	)
	(segment
		(start 121.350024 -98.35007)
		(end 121.85015 -98.850196)
		(width 0.4572)
		(layer "F.Cu")
		(net "GND")
	)
	(segment
		(start 108.349796 -90.349832)
		(end 107.84967 -89.849706)
		(width 0.4572)
		(layer "F.Cu")
		(net "GND")
	)
	(segment
		(start 117.350032 -95.350076)
		(end 117.850158 -95.850202)
		(width 0.4572)
		(layer "F.Cu")
		(net "GND")
	)
	(segment
		(start 314.625482 -86.000082)
		(end 314.706 -86.0806)
		(width 0.508)
		(layer "F.Cu")
		(net "GND")
	)
	(segment
		(start 221.3102 -121.666)
		(end 221.361 -121.7168)
		(width 0.508)
		(layer "F.Cu")
		(net "GND")
	)
	(segment
		(start 104.349804 -93.349826)
		(end 103.849678 -92.8497)
		(width 0.4572)
		(layer "F.Cu")
		(net "GND")
	)
	(segment
		(start 96.9645 -221.0435)
		(end 96.52 -221.488)
		(width 0.508)
		(layer "F.Cu")
		(net "GND")
	)
	(segment
		(start 80.64627 -112.4585)
		(end 79.38897 -112.4585)
		(width 0.508)
		(layer "F.Cu")
		(net "GND")
	)
	(segment
		(start 97.95002 -34.99993)
		(end 97.859088 -34.99993)
		(width 0.3048)
		(layer "F.Cu")
		(net "GND")
	)
	(segment
		(start 108.349796 -99.350068)
		(end 107.84967 -99.850194)
		(width 0.4572)
		(layer "F.Cu")
		(net "GND")
	)
	(segment
		(start 314.265818 -86.800182)
		(end 314.706 -86.36)
		(width 0.508)
		(layer "F.Cu")
		(net "GND")
	)
	(segment
		(start 127.350012 -102.350062)
		(end 127.850138 -102.850188)
		(width 0.4572)
		(layer "F.Cu")
		(net "GND")
	)
	(segment
		(start 307.5305 -224.028)
		(end 307.6575 -224.155)
		(width 0.508)
		(layer "F.Cu")
		(net "GND")
	)
	(segment
		(start 147.098766 -60.284868)
		(end 147.122134 -60.2615)
		(width 0.254)
		(layer "F.Cu")
		(net "GND")
	)
	(segment
		(start 60.2615 -106.426)
		(end 59.055 -106.426)
		(width 0.508)
		(layer "F.Cu")
		(net "GND")
	)
	(segment
		(start 124.338334 -91.34983)
		(end 123.861322 -91.826842)
		(width 0.508)
		(layer "F.Cu")
		(net "GND")
	)
	(segment
		(start 104.839262 -74.980292)
		(end 104.778302 -74.919332)
		(width 0.508)
		(layer "F.Cu")
		(net "GND")
	)
	(segment
		(start 184.031128 -13.707364)
		(end 185.157364 -13.707364)
		(width 0.508)
		(layer "F.Cu")
		(net "GND")
	)
	(segment
		(start 18.238216 -201.66838)
		(end 18.238216 -200.58888)
		(width 0.508)
		(layer "F.Cu")
		(net "GND")
	)
	(segment
		(start 313.125104 -95.600012)
		(end 313.480958 -95.955866)
		(width 0.508)
		(layer "F.Cu")
		(net "GND")
	)
	(segment
		(start 123.999752 -256.25044)
		(end 123.999752 -253.23546)
		(width 0.508)
		(layer "F.Cu")
		(net "GND")
	)
	(segment
		(start 201.549 -184.785)
		(end 201.549 -183.896)
		(width 0.508)
		(layer "F.Cu")
		(net "GND")
	)
	(segment
		(start 84.538566 -63.0936)
		(end 84.538566 -62.9666)
		(width 0.508)
		(layer "F.Cu")
		(net "GND")
	)
	(segment
		(start 346.231718 -142.789148)
		(end 346.231718 -142.268448)
		(width 0.508)
		(layer "F.Cu")
		(net "GND")
	)
	(segment
		(start 333.828136 -199.588628)
		(end 333.828136 -198.755)
		(width 0.508)
		(layer "F.Cu")
		(net "GND")
	)
	(segment
		(start 325.954136 -164.029136)
		(end 325.755 -163.83)
		(width 0.3048)
		(layer "F.Cu")
		(net "GND")
	)
	(segment
		(start 119.350028 -83.59521)
		(end 119.350028 -83.349846)
		(width 0.3048)
		(layer "F.Cu")
		(net "GND")
	)
	(segment
		(start 94.50197 -88.265)
		(end 94.37497 -88.265)
		(width 0.508)
		(layer "F.Cu")
		(net "GND")
	)
	(segment
		(start 281.178 -160.655)
		(end 280.67 -160.147)
		(width 0.508)
		(layer "F.Cu")
		(net "GND")
	)
	(segment
		(start 124.350018 -87.349838)
		(end 124.850144 -86.849712)
		(width 0.4572)
		(layer "F.Cu")
		(net "GND")
	)
	(segment
		(start 284.898084 -202.535028)
		(end 284.898084 -203.180696)
		(width 0.3556)
		(layer "F.Cu")
		(net "GND")
	)
	(segment
		(start 58.449972 -187.809886)
		(end 59.58078 -187.809886)
		(width 0.508)
		(layer "F.Cu")
		(net "GND")
	)
	(segment
		(start 345.088718 -142.789148)
		(end 345.088718 -142.243048)
		(width 0.508)
		(layer "F.Cu")
		(net "GND")
	)
	(segment
		(start 88.999822 -256.25044)
		(end 88.999822 -253.41961)
		(width 0.508)
		(layer "F.Cu")
		(net "GND")
	)
	(segment
		(start 308.06136 -197.0659)
		(end 308.06136 -198.374)
		(width 0.381)
		(layer "F.Cu")
		(net "GND")
	)
	(segment
		(start 100.057966 -63.253874)
		(end 100.057966 -63.184278)
		(width 0.508)
		(layer "F.Cu")
		(net "GND")
	)
	(segment
		(start 221.361 -121.7168)
		(end 221.361 -122.936)
		(width 0.508)
		(layer "F.Cu")
		(net "GND")
	)
	(segment
		(start 298.43476 -177.83048)
		(end 298.829984 -177.435256)
		(width 0.3556)
		(layer "F.Cu")
		(net "GND")
	)
	(segment
		(start 307.306218 -87.600028)
		(end 306.959 -87.947246)
		(width 0.508)
		(layer "F.Cu")
		(net "GND")
	)
	(segment
		(start 108.844842 -104.85501)
		(end 108.844842 -105.837482)
		(width 0.3048)
		(layer "F.Cu")
		(net "GND")
	)
	(segment
		(start 124.350018 -89.349834)
		(end 124.401834 -89.349834)
		(width 0.2032)
		(layer "F.Cu")
		(net "GND")
	)
	(segment
		(start 216.662 -180.594)
		(end 216.535 -180.467)
		(width 0.508)
		(layer "F.Cu")
		(net "GND")
	)
	(segment
		(start 338.700872 -171.839636)
		(end 338.700872 -172.72)
		(width 0.508)
		(layer "F.Cu")
		(net "GND")
	)
	(segment
		(start 78.613 -23.3045)
		(end 79.3877 -24.0792)
		(width 0.508)
		(layer "F.Cu")
		(net "GND")
	)
	(segment
		(start 18.48358 -228.952552)
		(end 18.48358 -230.247952)
		(width 0.3048)
		(layer "F.Cu")
		(net "GND")
	)
	(segment
		(start 210.947 -104.3305)
		(end 209.7659 -104.3305)
		(width 0.508)
		(layer "F.Cu")
		(net "GND")
	)
	(segment
		(start 314.6171 -51.6001)
		(end 314.833 -51.816)
		(width 0.508)
		(layer "F.Cu")
		(net "GND")
	)
	(segment
		(start 81.70545 -135.79348)
		(end 81.67497 -135.763)
		(width 0.2032)
		(layer "F.Cu")
		(net "GND")
	)
	(segment
		(start 112.349788 -94.349824)
		(end 111.849662 -93.849698)
		(width 0.4572)
		(layer "F.Cu")
		(net "GND")
	)
	(segment
		(start 45.53839 -119.20601)
		(end 46.4312 -118.3132)
		(width 0.3048)
		(layer "F.Cu")
		(net "GND")
	)
	(segment
		(start 343.683336 -70.463664)
		(end 344.043 -70.104)
		(width 0.508)
		(layer "F.Cu")
		(net "GND")
	)
	(segment
		(start 300.482 -103.251)
		(end 300.355 -103.378)
		(width 0.508)
		(layer "F.Cu")
		(net "GND")
	)
	(segment
		(start 12.80033 -99.980242)
		(end 12.80033 -97.708466)
		(width 0.3556)
		(layer "F.Cu")
		(net "GND")
	)
	(segment
		(start 68.609972 -185.269886)
		(end 68.609972 -186.400694)
		(width 0.508)
		(layer "F.Cu")
		(net "GND")
	)
	(segment
		(start 112.349788 -96.350074)
		(end 111.849662 -96.8502)
		(width 0.4572)
		(layer "F.Cu")
		(net "GND")
	)
	(segment
		(start 100.56368 -231.28732)
		(end 100.584 -231.267)
		(width 0.254)
		(layer "F.Cu")
		(net "GND")
	)
	(segment
		(start 202.827128 -148.200872)
		(end 203.835 -147.193)
		(width 0.508)
		(layer "F.Cu")
		(net "GND")
	)
	(segment
		(start 314.334144 -70.800214)
		(end 315.134244 -70.000114)
		(width 0.508)
		(layer "F.Cu")
		(net "GND")
	)
	(segment
		(start 127.350012 -90.349832)
		(end 128.282192 -90.349832)
		(width 0.381)
		(layer "F.Cu")
		(net "GND")
	)
	(segment
		(start 101.092 -220.726)
		(end 100.584 -220.218)
		(width 0.508)
		(layer "F.Cu")
		(net "GND")
	)
	(segment
		(start 104.835198 -88.86444)
		(end 104.85501 -88.86444)
		(width 0.508)
		(layer "F.Cu")
		(net "GND")
	)
	(segment
		(start 104.349804 -107.350052)
		(end 103.849678 -107.850178)
		(width 0.4572)
		(layer "F.Cu")
		(net "GND")
	)
	(segment
		(start 90.939366 -45.498512)
		(end 90.840814 -45.39996)
		(width 0.3048)
		(layer "F.Cu")
		(net "GND")
	)
	(segment
		(start 54.99989 -75.557126)
		(end 55.19293 -75.364086)
		(width 0.3048)
		(layer "F.Cu")
		(net "GND")
	)
	(segment
		(start 80.91297 -112.7252)
		(end 80.64627 -112.4585)
		(width 0.508)
		(layer "F.Cu")
		(net "GND")
	)
	(segment
		(start 24.933402 -223.984566)
		(end 24.933402 -222.325438)
		(width 0.3048)
		(layer "F.Cu")
		(net "GND")
	)
	(segment
		(start 198.890636 -168.251378)
		(end 198.890636 -168.664636)
		(width 0.508)
		(layer "F.Cu")
		(net "GND")
	)
	(segment
		(start 16.919448 -208.509616)
		(end 18.458688 -208.509616)
		(width 0.3556)
		(layer "F.Cu")
		(net "GND")
	)
	(segment
		(start 37.43325 -174.86884)
		(end 38.47084 -174.86884)
		(width 0.508)
		(layer "F.Cu")
		(net "GND")
	)
	(segment
		(start 101.950012 -54.19979)
		(end 102.350062 -53.79974)
		(width 0.3556)
		(layer "F.Cu")
		(net "GND")
	)
	(segment
		(start 104.349804 -103.35006)
		(end 103.849678 -103.850186)
		(width 0.4572)
		(layer "F.Cu")
		(net "GND")
	)
	(segment
		(start 313.125104 -74.000106)
		(end 314.238894 -74.000106)
		(width 0.508)
		(layer "F.Cu")
		(net "GND")
	)
	(segment
		(start 20.778216 -225.73488)
		(end 20.778216 -225.78568)
		(width 0.508)
		(layer "F.Cu")
		(net "GND")
	)
	(segment
		(start 91.128342 -123.642882)
		(end 93.795088 -123.642882)
		(width 0.508)
		(layer "F.Cu")
		(net "GND")
	)
	(segment
		(start 345.088718 -142.243048)
		(end 345.647518 -141.684248)
		(width 0.508)
		(layer "F.Cu")
		(net "GND")
	)
	(segment
		(start 118.35003 -107.85602)
		(end 118.53037 -108.03636)
		(width 0.3048)
		(layer "F.Cu")
		(net "GND")
	)
	(segment
		(start 314.186824 -64.400176)
		(end 314.706 -63.881)
		(width 0.508)
		(layer "F.Cu")
		(net "GND")
	)
	(segment
		(start 59.669934 -219.308934)
		(end 58.8645 -219.308934)
		(width 0.3048)
		(layer "F.Cu")
		(net "GND")
	)
	(segment
		(start 312.5851 -213.5759)
		(end 312.547 -213.614)
		(width 0.3048)
		(layer "F.Cu")
		(net "GND")
	)
	(segment
		(start 127.350012 -86.34984)
		(end 129.58953 -86.34984)
		(width 0.4572)
		(layer "F.Cu")
		(net "GND")
	)
	(segment
		(start 100.584 -220.218)
		(end 100.457 -220.218)
		(width 0.508)
		(layer "F.Cu")
		(net "GND")
	)
	(segment
		(start 87.12327 -114.25936)
		(end 87.12327 -113.35766)
		(width 0.3048)
		(layer "F.Cu")
		(net "GND")
	)
	(segment
		(start 292.097968 -196.135244)
		(end 292.10762 -196.135244)
		(width 0.3048)
		(layer "F.Cu")
		(net "GND")
	)
	(segment
		(start 318.4525 -177.673)
		(end 319.786 -177.673)
		(width 0.508)
		(layer "F.Cu")
		(net "GND")
	)
	(segment
		(start 283.6545 -208.0895)
		(end 284.734 -209.169)
		(width 0.508)
		(layer "F.Cu")
		(net "GND")
	)
	(segment
		(start 88.143842 -128.532382)
		(end 86.294468 -128.532382)
		(width 0.508)
		(layer "F.Cu")
		(net "GND")
	)
	(segment
		(start 332.160118 -148.948648)
		(end 331.880718 -149.228048)
		(width 0.508)
		(layer "F.Cu")
		(net "GND")
	)
	(segment
		(start 124.350018 -107.350052)
		(end 124.850144 -107.850178)
		(width 0.4572)
		(layer "F.Cu")
		(net "GND")
	)
	(segment
		(start 118.35003 -100.350066)
		(end 118.850156 -100.850192)
		(width 0.4572)
		(layer "F.Cu")
		(net "GND")
	)
	(segment
		(start 304.546 -103.505)
		(end 304.038 -104.013)
		(width 0.508)
		(layer "F.Cu")
		(net "GND")
	)
	(segment
		(start 93.949774 -50.999898)
		(end 93.950028 -50.999898)
		(width 0.3556)
		(layer "F.Cu")
		(net "GND")
	)
	(segment
		(start 98.02495 -34.99993)
		(end 97.95002 -34.99993)
		(width 0.3048)
		(layer "F.Cu")
		(net "GND")
	)
	(segment
		(start 212.86597 -68.6435)
		(end 212.86597 -66.675)
		(width 0.508)
		(layer "F.Cu")
		(net "GND")
	)
	(segment
		(start 342.138 -22.352)
		(end 342.138 -21.336)
		(width 0.508)
		(layer "F.Cu")
		(net "GND")
	)
	(segment
		(start 292.898068 -196.138292)
		(end 292.504368 -196.531992)
		(width 0.3048)
		(layer "F.Cu")
		(net "GND")
	)
	(segment
		(start 81.999582 -253.32563)
		(end 82.468212 -252.857)
		(width 0.508)
		(layer "F.Cu")
		(net "GND")
	)
	(segment
		(start 323.1515 -144.0815)
		(end 322.834 -144.399)
		(width 0.508)
		(layer "F.Cu")
		(net "GND")
	)
	(segment
		(start 296.48404 -201.321162)
		(end 296.48404 -201.330814)
		(width 0.3556)
		(layer "F.Cu")
		(net "GND")
	)
	(segment
		(start 343.032842 -154.385772)
		(end 343.691718 -155.044648)
		(width 0.3048)
		(layer "F.Cu")
		(net "GND")
	)
	(segment
		(start 279.264872 -225.560636)
		(end 279.332436 -225.6282)
		(width 0.508)
		(layer "F.Cu")
		(net "GND")
	)
	(segment
		(start 92.350082 -38.999922)
		(end 92.350082 -39.00043)
		(width 0.3048)
		(layer "F.Cu")
		(net "GND")
	)
	(segment
		(start 110.17631 -26.9875)
		(end 109.54131 -27.6225)
		(width 0.508)
		(layer "F.Cu")
		(net "GND")
	)
	(segment
		(start 322.453 -145.669)
		(end 322.834 -145.669)
		(width 0.508)
		(layer "F.Cu")
		(net "GND")
	)
	(segment
		(start 345.596718 -158.283148)
		(end 345.596718 -158.627318)
		(width 0.508)
		(layer "F.Cu")
		(net "GND")
	)
	(segment
		(start 284.099 -71.12)
		(end 284.6324 -71.6534)
		(width 0.508)
		(layer "F.Cu")
		(net "GND")
	)
	(segment
		(start 127.350012 -94.349824)
		(end 128.402842 -94.349824)
		(width 0.381)
		(layer "F.Cu")
		(net "GND")
	)
	(segment
		(start 20.651216 -181.47538)
		(end 20.651216 -180.39588)
		(width 0.508)
		(layer "F.Cu")
		(net "GND")
	)
	(segment
		(start 92.350082 -46.199806)
		(end 91.952318 -46.59757)
		(width 0.254)
		(layer "F.Cu")
		(net "GND")
	)
	(segment
		(start 115.350036 -95.350076)
		(end 115.850162 -95.850202)
		(width 0.4572)
		(layer "F.Cu")
		(net "GND")
	)
	(segment
		(start 336.423 -80.264)
		(end 335.788 -80.899)
		(width 0.508)
		(layer "F.Cu")
		(net "GND")
	)
	(segment
		(start 110.37316 -26.9875)
		(end 110.17631 -26.9875)
		(width 0.508)
		(layer "F.Cu")
		(net "GND")
	)
	(segment
		(start 286.9565 -156.972)
		(end 286.004 -156.972)
		(width 0.508)
		(layer "F.Cu")
		(net "GND")
	)
	(segment
		(start 119.350028 -87.631016)
		(end 119.350028 -87.349838)
		(width 0.3048)
		(layer "F.Cu")
		(net "GND")
	)
	(segment
		(start 125.350016 -105.350056)
		(end 125.850142 -105.850182)
		(width 0.3048)
		(layer "F.Cu")
		(net "GND")
	)
	(segment
		(start 104.121966 -62.821566)
		(end 104.833166 -63.532766)
		(width 0.508)
		(layer "F.Cu")
		(net "GND")
	)
	(segment
		(start 92.350082 -44.59986)
		(end 92.354654 -44.59986)
		(width 0.3048)
		(layer "F.Cu")
		(net "GND")
	)
	(segment
		(start 92.724732 -137.209276)
		(end 92.724732 -137.922762)
		(width 0.2032)
		(layer "F.Cu")
		(net "GND")
	)
	(segment
		(start 308.675024 -94.000066)
		(end 307.065934 -94.000066)
		(width 0.508)
		(layer "F.Cu")
		(net "GND")
	)
	(segment
		(start 286.49803 -202.535028)
		(end 286.49803 -203.18349)
		(width 0.3556)
		(layer "F.Cu")
		(net "GND")
	)
	(segment
		(start 99.30384 -64.008)
		(end 100.057966 -63.253874)
		(width 0.508)
		(layer "F.Cu")
		(net "GND")
	)
	(segment
		(start 99.549712 -42.199814)
		(end 99.549966 -42.199814)
		(width 0.3556)
		(layer "F.Cu")
		(net "GND")
	)
	(segment
		(start 299.225208 -177.040032)
		(end 298.829984 -177.435256)
		(width 0.3556)
		(layer "F.Cu")
		(net "GND")
	)
	(segment
		(start 107.31627 -72.8218)
		(end 106.2736 -72.8218)
		(width 0.508)
		(layer "F.Cu")
		(net "GND")
	)
	(segment
		(start 294.099234 -196.527166)
		(end 294.099234 -196.526912)
		(width 0.3556)
		(layer "F.Cu")
		(net "GND")
	)
	(segment
		(start 104.350058 -34.99993)
		(end 104.35209 -34.997898)
		(width 0.3048)
		(layer "F.Cu")
		(net "GND")
	)
	(segment
		(start 105.150158 -48.599852)
		(end 105.549954 -48.999648)
		(width 0.3556)
		(layer "F.Cu")
		(net "GND")
	)
	(segment
		(start 285.634938 -172.240194)
		(end 285.625286 -172.240194)
		(width 0.3556)
		(layer "F.Cu")
		(net "GND")
	)
	(segment
		(start 127.350012 -103.35006)
		(end 127.850138 -103.850186)
		(width 0.4572)
		(layer "F.Cu")
		(net "GND")
	)
	(segment
		(start 97.222564 -34.99993)
		(end 97.150174 -34.99993)
		(width 0.3048)
		(layer "F.Cu")
		(net "GND")
	)
	(segment
		(start 308.675024 -74.800206)
		(end 307.631846 -74.800206)
		(width 0.508)
		(layer "F.Cu")
		(net "GND")
	)
	(segment
		(start 313.125104 -86.800182)
		(end 314.265818 -86.800182)
		(width 0.508)
		(layer "F.Cu")
		(net "GND")
	)
	(segment
		(start 308.675024 -75.600052)
		(end 306.832 -75.600052)
		(width 0.508)
		(layer "F.Cu")
		(net "GND")
	)
	(segment
		(start 291.3126 -153.5938)
		(end 291.3126 -153.7716)
		(width 0.508)
		(layer "F.Cu")
		(net "GND")
	)
	(segment
		(start 60.071 -210.6295)
		(end 60.96 -210.6295)
		(width 0.508)
		(layer "F.Cu")
		(net "GND")
	)
	(segment
		(start 220.0148 -162.433)
		(end 221.234 -162.433)
		(width 0.3048)
		(layer "F.Cu")
		(net "GND")
	)
	(segment
		(start 204.461872 -188.095128)
		(end 205.74 -186.817)
		(width 0.508)
		(layer "F.Cu")
		(net "GND")
	)
	(segment
		(start 110.349792 -101.350064)
		(end 109.849666 -101.85019)
		(width 0.4572)
		(layer "F.Cu")
		(net "GND")
	)
	(segment
		(start 314.579 -79.883)
		(end 314.579 -80.391)
		(width 0.508)
		(layer "F.Cu")
		(net "GND")
	)
	(segment
		(start 99.549966 -34.19983)
		(end 99.549966 -34.200084)
		(width 0.3048)
		(layer "F.Cu")
		(net "GND")
	)
	(segment
		(start 119.350028 -88.068404)
		(end 119.358156 -88.060276)
		(width 0.3048)
		(layer "F.Cu")
		(net "GND")
	)
	(segment
		(start 214.9475 -162.179)
		(end 214.9475 -163.1315)
		(width 0.508)
		(layer "F.Cu")
		(net "GND")
	)
	(segment
		(start 306.324 -84.946236)
		(end 306.324 -84.31276)
		(width 0.508)
		(layer "F.Cu")
		(net "GND")
	)
	(segment
		(start 93.150182 -46.994318)
		(end 93.54566 -46.59884)
		(width 0.3048)
		(layer "F.Cu")
		(net "GND")
	)
	(segment
		(start 280.162 -161.0995)
		(end 280.162 -160.655)
		(width 0.508)
		(layer "F.Cu")
		(net "GND")
	)
	(segment
		(start 111.999522 -253.55169)
		(end 112.567212 -252.984)
		(width 0.508)
		(layer "F.Cu")
		(net "GND")
	)
	(segment
		(start 220.545406 -174.678594)
		(end 219.837 -175.387)
		(width 0.381)
		(layer "F.Cu")
		(net "GND")
	)
	(segment
		(start 45.98797 -143.5227)
		(end 45.98797 -142.494)
		(width 0.3048)
		(layer "F.Cu")
		(net "GND")
	)
	(segment
		(start 111.34979 -86.34984)
		(end 111.849662 -86.849712)
		(width 0.3048)
		(layer "F.Cu")
		(net "GND")
	)
	(segment
		(start 178.8795 -15.113)
		(end 178.181 -15.113)
		(width 0.508)
		(layer "F.Cu")
		(net "GND")
	)
	(segment
		(start 212.605874 -102.650798)
		(end 211.489798 -102.650798)
		(width 0.3048)
		(layer "F.Cu")
		(net "GND")
	)
	(segment
		(start 104.833166 -63.8556)
		(end 104.833166 -65.8876)
		(width 0.508)
		(layer "F.Cu")
		(net "GND")
	)
	(segment
		(start 283.591 -71.12)
		(end 284.099 -71.12)
		(width 0.508)
		(layer "F.Cu")
		(net "GND")
	)
	(segment
		(start 113.349786 -84.349844)
		(end 112.84966 -83.849718)
		(width 0.508)
		(layer "F.Cu")
		(net "GND")
	)
	(segment
		(start 105.159302 -42.199814)
		(end 105.150158 -42.199814)
		(width 0.3556)
		(layer "F.Cu")
		(net "GND")
	)
	(segment
		(start 195.072 -35.179)
		(end 195.707 -34.544)
		(width 0.508)
		(layer "F.Cu")
		(net "GND")
	)
	(segment
		(start 348.835218 -150.853648)
		(end 349.964248 -150.853648)
		(width 0.508)
		(layer "F.Cu")
		(net "GND")
	)
	(segment
		(start 296.545 -157.6705)
		(end 296.545 -156.464)
		(width 0.508)
		(layer "F.Cu")
		(net "GND")
	)
	(segment
		(start 189.992 -147.193)
		(end 190.118746 -147.319746)
		(width 0.508)
		(layer "F.Cu")
		(net "GND")
	)
	(segment
		(start 91.95816 -40.998648)
		(end 91.956636 -40.997124)
		(width 0.3048)
		(layer "F.Cu")
		(net "GND")
	)
	(segment
		(start 292.898068 -196.135244)
		(end 292.898068 -196.138292)
		(width 0.3048)
		(layer "F.Cu")
		(net "GND")
	)
	(segment
		(start 111.999522 -256.25044)
		(end 111.999522 -253.55169)
		(width 0.508)
		(layer "F.Cu")
		(net "GND")
	)
	(segment
		(start 306.832 -78.290928)
		(end 306.832 -78.486)
		(width 0.508)
		(layer "F.Cu")
		(net "GND")
	)
	(segment
		(start 17.19961 -102.489762)
		(end 17.19961 -104.779572)
		(width 0.3556)
		(layer "F.Cu")
		(net "GND")
	)
	(segment
		(start 314.579 -83.185)
		(end 314.579 -82.80019)
		(width 0.508)
		(layer "F.Cu")
		(net "GND")
	)
	(segment
		(start 100.350066 -45.39996)
		(end 100.749862 -45.799756)
		(width 0.3556)
		(layer "F.Cu")
		(net "GND")
	)
	(segment
		(start 306.451 -84.18576)
		(end 306.451 -83.82)
		(width 0.508)
		(layer "F.Cu")
		(net "GND")
	)
	(segment
		(start 283.21 -161.0995)
		(end 283.21 -160.655)
		(width 0.508)
		(layer "F.Cu")
		(net "GND")
	)
	(segment
		(start 103.385366 -61.4426)
		(end 103.385366 -61.595)
		(width 0.3048)
		(layer "F.Cu")
		(net "GND")
	)
	(segment
		(start 331.4065 -218.7575)
		(end 331.1525 -219.0115)
		(width 0.508)
		(layer "F.Cu")
		(net "GND")
	)
	(segment
		(start 85.452966 -88.7222)
		(end 83.420966 -88.7222)
		(width 0.508)
		(layer "F.Cu")
		(net "GND")
	)
	(segment
		(start 66.069972 -185.269886)
		(end 66.069972 -186.400694)
		(width 0.508)
		(layer "F.Cu")
		(net "GND")
	)
	(segment
		(start 257.039364 -223.511872)
		(end 255.786128 -223.511872)
		(width 0.508)
		(layer "F.Cu")
		(net "GND")
	)
	(segment
		(start 280.9875 -192.2145)
		(end 280.162 -192.2145)
		(width 0.508)
		(layer "F.Cu")
		(net "GND")
	)
	(segment
		(start 54.0385 -110.4265)
		(end 53.975 -110.49)
		(width 0.508)
		(layer "F.Cu")
		(net "GND")
	)
	(segment
		(start 80.333342 -126.284482)
		(end 81.340452 -126.284482)
		(width 0.508)
		(layer "F.Cu")
		(net "GND")
	)
	(segment
		(start 304.474372 -205.177136)
		(end 304.474372 -204.288136)
		(width 0.508)
		(layer "F.Cu")
		(net "GND")
	)
	(segment
		(start 178.749452 -33.40862)
		(end 178.749452 -33.752282)
		(width 0.3048)
		(layer "F.Cu")
		(net "GND")
	)
	(segment
		(start 80.473296 -140.535914)
		(end 80.04429 -140.96492)
		(width 0.508)
		(layer "F.Cu")
		(net "GND")
	)
	(segment
		(start 223.72828 -89.31402)
		(end 224.56648 -89.31402)
		(width 0.508)
		(layer "F.Cu")
		(net "GND")
	)
	(segment
		(start 106.3498 -105.350056)
		(end 107.349798 -104.350058)
		(width 0.4572)
		(layer "F.Cu")
		(net "GND")
	)
	(segment
		(start 294.498014 -196.93509)
		(end 294.498014 -196.925692)
		(width 0.3556)
		(layer "F.Cu")
		(net "GND")
	)
	(segment
		(start 307.5305 -223.139)
		(end 307.5305 -224.028)
		(width 0.508)
		(layer "F.Cu")
		(net "GND")
	)
	(segment
		(start 186.563 -138.811)
		(end 186.563 -139.065)
		(width 0.508)
		(layer "F.Cu")
		(net "GND")
	)
	(segment
		(start 139.065 -91.308682)
		(end 139.065 -91.482672)
		(width 0.3048)
		(layer "F.Cu")
		(net "GND")
	)
	(segment
		(start 111.549942 -36.599876)
		(end 111.150146 -36.20008)
		(width 0.3048)
		(layer "F.Cu")
		(net "GND")
	)
	(segment
		(start 125.350016 -104.350058)
		(end 125.850142 -104.850184)
		(width 0.4572)
		(layer "F.Cu")
		(net "GND")
	)
	(segment
		(start 21.019516 -225.54438)
		(end 20.778216 -225.78568)
		(width 0.508)
		(layer "F.Cu")
		(net "GND")
	)
	(segment
		(start 101.950012 -45.39996)
		(end 102.349808 -45.799756)
		(width 0.3556)
		(layer "F.Cu")
		(net "GND")
	)
	(segment
		(start 63.529972 -187.809886)
		(end 64.66078 -187.809886)
		(width 0.508)
		(layer "F.Cu")
		(net "GND")
	)
	(segment
		(start 184.565798 -34.235136)
		(end 184.565798 -35.785806)
		(width 0.3048)
		(layer "F.Cu")
		(net "GND")
	)
	(segment
		(start 16.560038 -186.710066)
		(end 16.325088 -186.945016)
		(width 0.3048)
		(layer "F.Cu")
		(net "GND")
	)
	(segment
		(start 273.7485 -160.401)
		(end 272.923 -160.401)
		(width 0.508)
		(layer "F.Cu")
		(net "GND")
	)
	(segment
		(start 120.350026 -85.595206)
		(end 120.350026 -85.349842)
		(width 0.3048)
		(layer "F.Cu")
		(net "GND")
	)
	(segment
		(start 119.20347 -77.597)
		(end 119.20347 -76.581)
		(width 0.508)
		(layer "F.Cu")
		(net "GND")
	)
	(segment
		(start 13.094716 -215.82888)
		(end 14.047216 -215.82888)
		(width 0.508)
		(layer "F.Cu")
		(net "GND")
	)
	(segment
		(start 144.9705 -38.4175)
		(end 144.399 -37.846)
		(width 0.508)
		(layer "F.Cu")
		(net "GND")
	)
	(segment
		(start 108.349796 -88.349836)
		(end 107.84967 -87.84971)
		(width 0.4572)
		(layer "F.Cu")
		(net "GND")
	)
	(segment
		(start 98.660966 -64.008)
		(end 99.30384 -64.008)
		(width 0.508)
		(layer "F.Cu")
		(net "GND")
	)
	(segment
		(start 94.750128 -35.800284)
		(end 94.350332 -36.20008)
		(width 0.3048)
		(layer "F.Cu")
		(net "GND")
	)
	(segment
		(start 218.567 -186.436)
		(end 218.567 -188.087)
		(width 0.508)
		(layer "F.Cu")
		(net "GND")
	)
	(segment
		(start 288.163 -210.93684)
		(end 288.163 -211.836)
		(width 0.508)
		(layer "F.Cu")
		(net "GND")
	)
	(segment
		(start 185.800492 -256.25044)
		(end 185.800492 -253.111)
		(width 0.508)
		(layer "F.Cu")
		(net "GND")
	)
	(segment
		(start 84.8614 -237.6424)
		(end 85.09 -237.871)
		(width 0.508)
		(layer "F.Cu")
		(net "GND")
	)
	(segment
		(start 109.352842 -81.496154)
		(end 109.350302 -81.493614)
		(width 0.4572)
		(layer "F.Cu")
		(net "GND")
	)
	(segment
		(start 109.4105 -74.8157)
		(end 109.4486 -74.8157)
		(width 0.508)
		(layer "F.Cu")
		(net "GND")
	)
	(segment
		(start 307.35016 -72.40016)
		(end 306.959 -72.009)
		(width 0.508)
		(layer "F.Cu")
		(net "GND")
	)
	(segment
		(start 105.950004 -47.800006)
		(end 105.549954 -47.399956)
		(width 0.3556)
		(layer "F.Cu")
		(net "GND")
	)
	(segment
		(start 76.537566 -84.328)
		(end 75.673966 -84.328)
		(width 0.3048)
		(layer "F.Cu")
		(net "GND")
	)
	(segment
		(start 47.4472 -118.6307)
		(end 46.7487 -118.6307)
		(width 0.508)
		(layer "F.Cu")
		(net "GND")
	)
	(segment
		(start 204.461872 -188.921136)
		(end 204.461872 -188.095128)
		(width 0.508)
		(layer "F.Cu")
		(net "GND")
	)
	(segment
		(start 144.73047 -82.804)
		(end 145.17497 -82.804)
		(width 0.508)
		(layer "F.Cu")
		(net "GND")
	)
	(segment
		(start 263.124188 -50.692812)
		(end 263.144 -50.673)
		(width 0.508)
		(layer "F.Cu")
		(net "GND")
	)
	(segment
		(start 86.294468 -128.532382)
		(end 85.45703 -129.36982)
		(width 0.508)
		(layer "F.Cu")
		(net "GND")
	)
	(segment
		(start 135.999982 -256.25044)
		(end 135.999982 -253.30023)
		(width 0.508)
		(layer "F.Cu")
		(net "GND")
	)
	(segment
		(start 285.254192 -170.230546)
		(end 285.23819 -170.246548)
		(width 0.3556)
		(layer "F.Cu")
		(net "GND")
	)
	(segment
		(start 339.12175 -30.4165)
		(end 338.1375 -30.4165)
		(width 0.508)
		(layer "F.Cu")
		(net "GND")
	)
	(segment
		(start 92.350082 -40.599868)
		(end 92.350082 -40.603678)
		(width 0.3048)
		(layer "F.Cu")
		(net "GND")
	)
	(segment
		(start 53.369972 -187.809886)
		(end 54.50078 -187.809886)
		(width 0.508)
		(layer "F.Cu")
		(net "GND")
	)
	(segment
		(start 251.11964 -49.595278)
		(end 251.11964 -48.387)
		(width 0.508)
		(layer "F.Cu")
		(net "GND")
	)
	(segment
		(start 55.909972 -187.809886)
		(end 57.04078 -187.809886)
		(width 0.508)
		(layer "F.Cu")
		(net "GND")
	)
	(segment
		(start 339.2932 -139.1666)
		(end 339.8266 -138.6332)
		(width 0.508)
		(layer "F.Cu")
		(net "GND")
	)
	(segment
		(start 17.730216 -213.35238)
		(end 17.730216 -212.27288)
		(width 0.508)
		(layer "F.Cu")
		(net "GND")
	)
	(segment
		(start 100.350066 -46.999906)
		(end 100.750116 -47.399956)
		(width 0.3556)
		(layer "F.Cu")
		(net "GND")
	)
	(segment
		(start 322.190872 -119.833136)
		(end 322.190872 -120.768872)
		(width 0.508)
		(layer "F.Cu")
		(net "GND")
	)
	(segment
		(start 262.007096 -51.962812)
		(end 262.616188 -51.962812)
		(width 0.508)
		(layer "F.Cu")
		(net "GND")
	)
	(segment
		(start 120.350026 -98.35007)
		(end 120.850152 -98.850196)
		(width 0.4572)
		(layer "F.Cu")
		(net "GND")
	)
	(segment
		(start 93.150182 -46.999906)
		(end 93.150182 -46.994318)
		(width 0.3048)
		(layer "F.Cu")
		(net "GND")
	)
	(segment
		(start 100.311966 -62.821312)
		(end 100.311966 -62.738)
		(width 0.508)
		(layer "F.Cu")
		(net "GND")
	)
	(segment
		(start 85.4964 -32.0294)
		(end 85.852 -32.385)
		(width 0.254)
		(layer "F.Cu")
		(net "GND")
	)
	(segment
		(start 336.423 -78.6765)
		(end 336.423 -80.264)
		(width 0.508)
		(layer "F.Cu")
		(net "GND")
	)
	(segment
		(start 199.8345 -140.589)
		(end 200.406 -140.589)
		(width 0.508)
		(layer "F.Cu")
		(net "GND")
	)
	(segment
		(start 84.999322 -253.35611)
		(end 84.500212 -252.857)
		(width 0.508)
		(layer "F.Cu")
		(net "GND")
	)
	(segment
		(start 43.399964 -81.35112)
		(end 43.50893 -81.460086)
		(width 0.3048)
		(layer "F.Cu")
		(net "GND")
	)
	(segment
		(start 128.282192 -90.349832)
		(end 128.38176 -90.4494)
		(width 0.381)
		(layer "F.Cu")
		(net "GND")
	)
	(segment
		(start 79.786226 -24.0792)
		(end 80.167226 -24.4602)
		(width 0.508)
		(layer "F.Cu")
		(net "GND")
	)
	(segment
		(start 214.884 -182.753)
		(end 213.995 -182.753)
		(width 0.508)
		(layer "F.Cu")
		(net "GND")
	)
	(segment
		(start 284.834838 -169.843196)
		(end 285.23819 -170.246548)
		(width 0.3556)
		(layer "F.Cu")
		(net "GND")
	)
	(segment
		(start 104.349804 -97.350072)
		(end 103.849678 -97.850198)
		(width 0.4572)
		(layer "F.Cu")
		(net "GND")
	)
	(segment
		(start 314.72378 -66.800222)
		(end 315.411358 -67.4878)
		(width 0.508)
		(layer "F.Cu")
		(net "GND")
	)
	(segment
		(start 288.097976 -202.535028)
		(end 288.097976 -203.195936)
		(width 0.3556)
		(layer "F.Cu")
		(net "GND")
	)
	(segment
		(start 189.3316 -223.85655)
		(end 189.3316 -222.9104)
		(width 0.3048)
		(layer "F.Cu")
		(net "GND")
	)
	(segment
		(start 331.4065 -218.059)
		(end 331.4065 -218.7575)
		(width 0.508)
		(layer "F.Cu")
		(net "GND")
	)
	(segment
		(start 298.0055 -98.2345)
		(end 298.831 -97.409)
		(width 0.508)
		(layer "F.Cu")
		(net "GND")
	)
	(segment
		(start 38.0492 -167.7416)
		(end 37.8714 -167.9194)
		(width 0.508)
		(layer "F.Cu")
		(net "GND")
	)
	(segment
		(start 94.750128 -34.19983)
		(end 94.750128 -34.200338)
		(width 0.3048)
		(layer "F.Cu")
		(net "GND")
	)
	(segment
		(start 17.200118 -107.424982)
		(end 17.200118 -104.78008)
		(width 0.508)
		(layer "F.Cu")
		(net "GND")
	)
	(segment
		(start 339.8266 -138.6332)
		(end 341.030306 -138.6332)
		(width 0.508)
		(layer "F.Cu")
		(net "GND")
	)
	(segment
		(start 190.8302 -148.1455)
		(end 192.024 -148.1455)
		(width 0.508)
		(layer "F.Cu")
		(net "GND")
	)
	(segment
		(start 22.302216 -213.35238)
		(end 22.302216 -212.27288)
		(width 0.508)
		(layer "F.Cu")
		(net "GND")
	)
	(segment
		(start 131.999482 -253.23673)
		(end 132.379212 -252.857)
		(width 0.508)
		(layer "F.Cu")
		(net "GND")
	)
	(segment
		(start 330.2 -143.383)
		(end 329.565 -142.748)
		(width 0.508)
		(layer "F.Cu")
		(net "GND")
	)
	(segment
		(start 110.349792 -100.350066)
		(end 109.849666 -100.850192)
		(width 0.4572)
		(layer "F.Cu")
		(net "GND")
	)
	(segment
		(start 262.294878 -221.824296)
		(end 262.290814 -221.824296)
		(width 0.3556)
		(layer "F.Cu")
		(net "GND")
	)
	(segment
		(start 127.350012 -98.35007)
		(end 127.850138 -98.850196)
		(width 0.4572)
		(layer "F.Cu")
		(net "GND")
	)
	(segment
		(start 206.206852 -109.559852)
		(end 205.994 -109.347)
		(width 0.508)
		(layer "F.Cu")
		(net "GND")
	)
	(segment
		(start 92.350082 -33.399984)
		(end 91.549982 -33.399984)
		(width 0.3048)
		(layer "F.Cu")
		(net "GND")
	)
	(segment
		(start 65.532 -218.313)
		(end 65.913 -218.313)
		(width 0.508)
		(layer "F.Cu")
		(net "GND")
	)
	(segment
		(start 106.788966 -63.4111)
		(end 106.788966 -62.5856)
		(width 0.508)
		(layer "F.Cu")
		(net "GND")
	)
	(segment
		(start 213.995 -184.023)
		(end 213.995 -182.753)
		(width 0.508)
		(layer "F.Cu")
		(net "GND")
	)
	(segment
		(start 52.6288 -209.042)
		(end 52.6288 -208.3308)
		(width 0.508)
		(layer "F.Cu")
		(net "GND")
	)
	(segment
		(start 92.350082 -36.599876)
		(end 91.950286 -36.20008)
		(width 0.3048)
		(layer "F.Cu")
		(net "GND")
	)
	(segment
		(start 121.350278 -85.349842)
		(end 121.85015 -85.849714)
		(width 0.508)
		(layer "F.Cu")
		(net "GND")
	)
	(segment
		(start 112.820958 -72.079612)
		(end 112.84077 -72.0598)
		(width 0.508)
		(layer "F.Cu")
		(net "GND")
	)
	(segment
		(start 186.055 -122.4915)
		(end 186.055 -123.317)
		(width 0.508)
		(layer "F.Cu")
		(net "GND")
	)
	(segment
		(start 185.792872 -198.941436)
		(end 184.776872 -198.941436)
		(width 0.508)
		(layer "F.Cu")
		(net "GND")
	)
	(segment
		(start 126.20117 -81.026)
		(end 125.76937 -81.026)
		(width 0.508)
		(layer "F.Cu")
		(net "GND")
	)
	(segment
		(start 91.553792 -41.399968)
		(end 91.956636 -40.997124)
		(width 0.3048)
		(layer "F.Cu")
		(net "GND")
	)
	(segment
		(start 152.4635 -54.356)
		(end 153.289 -54.356)
		(width 0.508)
		(layer "F.Cu")
		(net "GND")
	)
	(segment
		(start 126.73457 -80.4926)
		(end 126.20117 -81.026)
		(width 0.508)
		(layer "F.Cu")
		(net "GND")
	)
	(segment
		(start 110.349792 -99.350068)
		(end 109.849666 -99.850194)
		(width 0.4572)
		(layer "F.Cu")
		(net "GND")
	)
	(segment
		(start 193.07175 -167.8305)
		(end 193.07175 -169.38625)
		(width 0.508)
		(layer "F.Cu")
		(net "GND")
	)
	(segment
		(start 217.6145 -180.594)
		(end 216.662 -180.594)
		(width 0.508)
		(layer "F.Cu")
		(net "GND")
	)
	(segment
		(start 274.240752 -192.230248)
		(end 273.685 -192.786)
		(width 0.508)
		(layer "F.Cu")
		(net "GND")
	)
	(segment
		(start 271.907 -187.452)
		(end 272.161 -187.706)
		(width 0.508)
		(layer "F.Cu")
		(net "GND")
	)
	(segment
		(start 110.109 -60.8965)
		(end 110.5535 -60.8965)
		(width 0.254)
		(layer "F.Cu")
		(net "GND")
	)
	(segment
		(start 314.579 -73.454006)
		(end 314.579 -73.66)
		(width 0.508)
		(layer "F.Cu")
		(net "GND")
	)
	(segment
		(start 293.46906 -207.772)
		(end 292.4175 -207.772)
		(width 0.508)
		(layer "F.Cu")
		(net "GND")
	)
	(segment
		(start 308.675024 -62.80023)
		(end 307.086 -62.80023)
		(width 0.508)
		(layer "F.Cu")
		(net "GND")
	)
	(segment
		(start 296.89806 -196.135244)
		(end 296.89806 -196.05244)
		(width 0.3556)
		(layer "F.Cu")
		(net "GND")
	)
	(segment
		(start 96.350074 -34.99993)
		(end 96.750124 -34.59988)
		(width 0.3048)
		(layer "F.Cu")
		(net "GND")
	)
	(segment
		(start 82.94243 -135.98906)
		(end 82.74685 -135.79348)
		(width 0.2032)
		(layer "F.Cu")
		(net "GND")
	)
	(segment
		(start 112.858042 -104.841802)
		(end 112.858042 -105.888282)
		(width 0.3048)
		(layer "F.Cu")
		(net "GND")
	)
	(segment
		(start 214.5538 -184.531)
		(end 214.503 -184.531)
		(width 0.508)
		(layer "F.Cu")
		(net "GND")
	)
	(segment
		(start 105.150158 -54.19979)
		(end 104.750108 -53.79974)
		(width 0.3556)
		(layer "F.Cu")
		(net "GND")
	)
	(segment
		(start 331.582014 -153.393648)
		(end 331.58049 -153.395172)
		(width 0.508)
		(layer "F.Cu")
		(net "GND")
	)
	(segment
		(start 91.549982 -41.399968)
		(end 91.553792 -41.399968)
		(width 0.3048)
		(layer "F.Cu")
		(net "GND")
	)
	(segment
		(start 166.249858 -11.210036)
		(end 167.596566 -11.210036)
		(width 0.508)
		(layer "F.Cu")
		(net "GND")
	)
	(segment
		(start 125.507242 -75.865482)
		(end 126.323852 -75.865482)
		(width 0.508)
		(layer "F.Cu")
		(net "GND")
	)
	(segment
		(start 314.296044 -79.600044)
		(end 314.579 -79.883)
		(width 0.508)
		(layer "F.Cu")
		(net "GND")
	)
	(segment
		(start 331.40904 -12.918948)
		(end 332.577948 -12.918948)
		(width 0.508)
		(layer "F.Cu")
		(net "GND")
	)
	(segment
		(start 304.474372 -204.288136)
		(end 304.474372 -203.398628)
		(width 0.508)
		(layer "F.Cu")
		(net "GND")
	)
	(segment
		(start 121.350024 -82.349848)
		(end 121.784872 -81.915)
		(width 0.508)
		(layer "F.Cu")
		(net "GND")
	)
	(segment
		(start 314.295028 -89.200228)
		(end 314.706 -89.6112)
		(width 0.508)
		(layer "F.Cu")
		(net "GND")
	)
	(segment
		(start 121.350024 -94.349824)
		(end 121.85015 -93.849698)
		(width 0.4572)
		(layer "F.Cu")
		(net "GND")
	)
	(segment
		(start 121.915428 -81.915)
		(end 121.83237 -81.915)
		(width 0.508)
		(layer "F.Cu")
		(net "GND")
	)
	(segment
		(start 100.749862 -45.799756)
		(end 101.149912 -46.199806)
		(width 0.3556)
		(layer "F.Cu")
		(net "GND")
	)
	(segment
		(start 117.350032 -97.350072)
		(end 117.850158 -97.850198)
		(width 0.4572)
		(layer "F.Cu")
		(net "GND")
	)
	(segment
		(start 308.675024 -85.200236)
		(end 306.578 -85.200236)
		(width 0.508)
		(layer "F.Cu")
		(net "GND")
	)
	(segment
		(start 139.446 -38.4175)
		(end 139.446 -38.1)
		(width 0.508)
		(layer "F.Cu")
		(net "GND")
	)
	(segment
		(start 93.557344 -48.19777)
		(end 93.950028 -47.805086)
		(width 0.3556)
		(layer "F.Cu")
		(net "GND")
	)
	(segment
		(start 110.86719 -105.82783)
		(end 110.876842 -105.837482)
		(width 0.3048)
		(layer "F.Cu")
		(net "GND")
	)
	(segment
		(start 115.350036 -93.349826)
		(end 115.850162 -92.8497)
		(width 0.4572)
		(layer "F.Cu")
		(net "GND")
	)
	(segment
		(start 19.185128 -168.653968)
		(end 19.508216 -168.33088)
		(width 0.2032)
		(layer "F.Cu")
		(net "GND")
	)
	(segment
		(start 94.466156 -98.532696)
		(end 94.432374 -98.532696)
		(width 0.508)
		(layer "F.Cu")
		(net "GND")
	)
	(segment
		(start 92.350082 -45.39996)
		(end 92.422218 -45.39996)
		(width 0.3048)
		(layer "F.Cu")
		(net "GND")
	)
	(segment
		(start 287.234884 -183.432704)
		(end 287.629092 -183.038496)
		(width 0.3556)
		(layer "F.Cu")
		(net "GND")
	)
	(segment
		(start 116.3955 -29.845)
		(end 116.205 -30.0355)
		(width 0.508)
		(layer "F.Cu")
		(net "GND")
	)
	(segment
		(start 34.370264 -77.747622)
		(end 34.370264 -78.502764)
		(width 0.508)
		(layer "F.Cu")
		(net "GND")
	)
	(segment
		(start 94.75597 -88.519)
		(end 94.50197 -88.265)
		(width 0.508)
		(layer "F.Cu")
		(net "GND")
	)
	(segment
		(start 119.350028 -97.350326)
		(end 118.850156 -97.850198)
		(width 0.4572)
		(layer "F.Cu")
		(net "GND")
	)
	(segment
		(start 106.8705 -232.4735)
		(end 106.553 -232.156)
		(width 0.254)
		(layer "F.Cu")
		(net "GND")
	)
	(segment
		(start 66.069972 -186.679078)
		(end 66.069972 -187.809886)
		(width 0.508)
		(layer "F.Cu")
		(net "GND")
	)
	(segment
		(start 104.349804 -105.350056)
		(end 103.849678 -105.850182)
		(width 0.508)
		(layer "F.Cu")
		(net "GND")
	)
	(segment
		(start 293.1922 -206.0448)
		(end 293.1922 -205.64094)
		(width 0.508)
		(layer "F.Cu")
		(net "GND")
	)
	(segment
		(start 87.483442 -114.619532)
		(end 87.483442 -115.555522)
		(width 0.3048)
		(layer "F.Cu")
		(net "GND")
	)
	(segment
		(start 87.12327 -114.25936)
		(end 87.483442 -114.619532)
		(width 0.3048)
		(layer "F.Cu")
		(net "GND")
	)
	(segment
		(start 103.549958 -48.599852)
		(end 103.949754 -48.999648)
		(width 0.3556)
		(layer "F.Cu")
		(net "GND")
	)
	(segment
		(start 102.750112 -47.800006)
		(end 102.349808 -47.399702)
		(width 0.3556)
		(layer "F.Cu")
		(net "GND")
	)
	(segment
		(start 320.7385 -197.866)
		(end 321.945 -197.866)
		(width 0.508)
		(layer "F.Cu")
		(net "GND")
	)
	(segment
		(start 190.554864 -32.945832)
		(end 190.69812 -33.089088)
		(width 0.508)
		(layer "F.Cu")
		(net "GND")
	)
	(segment
		(start 313.125104 -63.600076)
		(end 314.425076 -63.600076)
		(width 0.508)
		(layer "F.Cu")
		(net "GND")
	)
	(segment
		(start 298.43476 -178.640232)
		(end 298.43476 -177.840132)
		(width 0.3556)
		(layer "F.Cu")
		(net "GND")
	)
	(segment
		(start 97.150174 -34.99993)
		(end 96.750124 -34.59988)
		(width 0.3048)
		(layer "F.Cu")
		(net "GND")
	)
	(segment
		(start 125.36297 -82.336894)
		(end 125.350016 -82.349848)
		(width 0.508)
		(layer "F.Cu")
		(net "GND")
	)
	(segment
		(start 111.34979 -88.349836)
		(end 110.849664 -87.84971)
		(width 0.4572)
		(layer "F.Cu")
		(net "GND")
	)
	(segment
		(start 188.800232 -254.332232)
		(end 187.799472 -253.331472)
		(width 0.508)
		(layer "F.Cu")
		(net "GND")
	)
	(segment
		(start 99.3394 -231.28732)
		(end 100.56368 -231.28732)
		(width 0.254)
		(layer "F.Cu")
		(net "GND")
	)
	(segment
		(start 112.349788 -89.349834)
		(end 111.849662 -88.849708)
		(width 0.4572)
		(layer "F.Cu")
		(net "GND")
	)
	(segment
		(start 10.173716 -210.65363)
		(end 10.173716 -209.28838)
		(width 0.508)
		(layer "F.Cu")
		(net "GND")
	)
	(segment
		(start 46.7487 -118.6307)
		(end 46.4312 -118.3132)
		(width 0.508)
		(layer "F.Cu")
		(net "GND")
	)
	(segment
		(start 250.00204 -49.595278)
		(end 249.16384 -49.595278)
		(width 0.508)
		(layer "F.Cu")
		(net "GND")
	)
	(segment
		(start 103.549958 -43.800014)
		(end 103.949754 -44.19981)
		(width 0.3556)
		(layer "F.Cu")
		(net "GND")
	)
	(segment
		(start 278.0665 -200.4695)
		(end 277.622 -200.914)
		(width 0.508)
		(layer "F.Cu")
		(net "GND")
	)
	(segment
		(start 176.991772 -203.236576)
		(end 178.645312 -203.236576)
		(width 0.3048)
		(layer "F.Cu")
		(net "GND")
	)
	(segment
		(start 123.83897 -92.964)
		(end 123.83897 -91.849194)
		(width 0.2032)
		(layer "F.Cu")
		(net "GND")
	)
	(segment
		(start 110.349792 -91.34983)
		(end 110.349792 -91.349576)
		(width 0.4572)
		(layer "F.Cu")
		(net "GND")
	)
	(segment
		(start 39.217346 -117.221)
		(end 38.6207 -117.817646)
		(width 0.508)
		(layer "F.Cu")
		(net "GND")
	)
	(segment
		(start 73.999852 -253.32436)
		(end 74.467212 -252.857)
		(width 0.508)
		(layer "F.Cu")
		(net "GND")
	)
	(segment
		(start 105.950004 -46.190916)
		(end 105.950004 -46.199806)
		(width 0.3556)
		(layer "F.Cu")
		(net "GND")
	)
	(segment
		(start 308.675024 -78.000098)
		(end 307.12283 -78.000098)
		(width 0.508)
		(layer "F.Cu")
		(net "GND")
	)
	(segment
		(start 25.282144 -193.795904)
		(end 24.52624 -193.795904)
		(width 0.508)
		(layer "F.Cu")
		(net "GND")
	)
	(segment
		(start 185.284872 -206.942436)
		(end 185.284872 -207.590136)
		(width 0.508)
		(layer "F.Cu")
		(net "GND")
	)
	(segment
		(start 100.350066 -42.199814)
		(end 100.749862 -42.59961)
		(width 0.3556)
		(layer "F.Cu")
		(net "GND")
	)
	(segment
		(start 288.428684 -180.649372)
		(end 288.43478 -180.649372)
		(width 0.3556)
		(layer "F.Cu")
		(net "GND")
	)
	(segment
		(start 20.524216 -225.86188)
		(end 20.702016 -225.86188)
		(width 0.508)
		(layer "F.Cu")
		(net "GND")
	)
	(segment
		(start 92.78874 -45.038518)
		(end 92.78874 -45.033946)
		(width 0.254)
		(layer "F.Cu")
		(net "GND")
	)
	(segment
		(start 49.91989 -137.14476)
		(end 49.71415 -137.3505)
		(width 0.3048)
		(layer "F.Cu")
		(net "GND")
	)
	(segment
		(start 110.5535 -60.8965)
		(end 110.871 -61.214)
		(width 0.254)
		(layer "F.Cu")
		(net "GND")
	)
	(segment
		(start 65.913 -218.313)
		(end 66.421 -217.805)
		(width 0.508)
		(layer "F.Cu")
		(net "GND")
	)
	(segment
		(start 187.481718 -138.358372)
		(end 187.015628 -138.358372)
		(width 0.508)
		(layer "F.Cu")
		(net "GND")
	)
	(segment
		(start 110.349792 -89.349834)
		(end 110.349792 -88.349836)
		(width 0.4572)
		(layer "F.Cu")
		(net "GND")
	)
	(segment
		(start 146.4945 -14.7955)
		(end 146.558 -14.732)
		(width 0.508)
		(layer "F.Cu")
		(net "GND")
	)
	(segment
		(start 330.835 -143.383)
		(end 330.2 -143.383)
		(width 0.508)
		(layer "F.Cu")
		(net "GND")
	)
	(segment
		(start 269.345918 -44.966636)
		(end 269.369286 -44.990004)
		(width 0.508)
		(layer "F.Cu")
		(net "GND")
	)
	(segment
		(start 99.187 -60.579)
		(end 99.314 -60.579)
		(width 0.3048)
		(layer "F.Cu")
		(net "GND")
	)
	(segment
		(start 110.349792 -107.350052)
		(end 110.349792 -108.206032)
		(width 0.3048)
		(layer "F.Cu")
		(net "GND")
	)
	(segment
		(start 111.34979 -99.350068)
		(end 111.849662 -98.850196)
		(width 0.4572)
		(layer "F.Cu")
		(net "GND")
	)
	(segment
		(start 95.45447 -80.518)
		(end 95.13697 -80.518)
		(width 0.508)
		(layer "F.Cu")
		(net "GND")
	)
	(segment
		(start 57.319164 -187.809886)
		(end 58.449972 -187.809886)
		(width 0.508)
		(layer "F.Cu")
		(net "GND")
	)
	(segment
		(start 145.999962 -256.25044)
		(end 145.999962 -253.46025)
		(width 0.508)
		(layer "F.Cu")
		(net "GND")
	)
	(segment
		(start 282.194 -161.0995)
		(end 282.194 -160.655)
		(width 0.508)
		(layer "F.Cu")
		(net "GND")
	)
	(segment
		(start 288.097976 -195.363084)
		(end 288.09823 -195.36283)
		(width 0.3556)
		(layer "F.Cu")
		(net "GND")
	)
	(segment
		(start 214.503 -184.531)
		(end 213.995 -184.023)
		(width 0.508)
		(layer "F.Cu")
		(net "GND")
	)
	(segment
		(start 292.4175 -208.915)
		(end 293.46906 -207.86344)
		(width 0.508)
		(layer "F.Cu")
		(net "GND")
	)
	(segment
		(start 104.350058 -47.800006)
		(end 103.949754 -47.399702)
		(width 0.3556)
		(layer "F.Cu")
		(net "GND")
	)
	(segment
		(start 116.713 -74.24547)
		(end 116.713 -73.6854)
		(width 0.508)
		(layer "F.Cu")
		(net "GND")
	)
	(segment
		(start 93.949774 -34.19983)
		(end 93.549978 -33.800034)
		(width 0.3048)
		(layer "F.Cu")
		(net "GND")
	)
	(segment
		(start 93.950028 -47.805086)
		(end 93.950028 -47.800006)
		(width 0.3556)
		(layer "F.Cu")
		(net "GND")
	)
	(segment
		(start 108.349796 -92.349828)
		(end 107.84967 -91.849702)
		(width 0.4572)
		(layer "F.Cu")
		(net "GND")
	)
	(segment
		(start 207.7085 -215.773)
		(end 206.756 -215.773)
		(width 0.508)
		(layer "F.Cu")
		(net "GND")
	)
	(via
		(at 105.549954 -48.999648)
		(size 0.508)
		(drill 0.254)
		(layers "F.Cu" "B.Cu")
		(net "GND")
	)
	(via
		(at 46.199806 -75.514962)
		(size 0.5588)
		(drill 0.3048)
		(layers "F.Cu" "B.Cu")
		(net "GND")
	)
	(via
		(at 110.871 -61.214)
		(size 0.508)
		(drill 0.254)
		(layers "F.Cu" "B.Cu")
		(net "GND")
	)
	(via
		(at 1.143 -124.281438)
		(size 0.7112)
		(drill 0.4064)
		(layers "F.Cu" "B.Cu")
		(net "GND")
	)
	(via
		(at 125.850142 -103.850186)
		(size 0.508)
		(drill 0.254)
		(layers "F.Cu" "B.Cu")
		(net "GND")
	)
	(via
		(at 134.027418 -81.834228)
		(size 0.508)
		(drill 0.254)
		(layers "F.Cu" "B.Cu")
		(net "GND")
	)
	(via
		(at 170.815 -116.967)
		(size 0.5588)
		(drill 0.3048)
		(layers "F.Cu" "B.Cu")
		(net "GND")
	)
	(via
		(at 309.1815 -219.0115)
		(size 0.5588)
		(drill 0.3048)
		(layers "F.Cu" "B.Cu")
		(net "GND")
	)
	(via
		(at 292.439598 -167.844978)
		(size 0.508)
		(drill 0.254)
		(layers "F.Cu" "B.Cu")
		(net "GND")
	)
	(via
		(at 292.4302 -174.245016)
		(size 0.508)
		(drill 0.254)
		(layers "F.Cu" "B.Cu")
		(net "GND")
	)
	(via
		(at 176.276 -128.905)
		(size 0.7112)
		(drill 0.4064)
		(layers "F.Cu" "B.Cu")
		(net "GND")
	)
	(via
		(at 322.834 -145.669)
		(size 0.5588)
		(drill 0.3048)
		(layers "F.Cu" "B.Cu")
		(net "GND")
	)
	(via
		(at 33.655 -79.375)
		(size 0.5588)
		(drill 0.3048)
		(layers "F.Cu" "B.Cu")
		(net "GND")
	)
	(via
		(at 271.78 -248.92)
		(size 0.5588)
		(drill 0.254)
		(layers "F.Cu" "B.Cu")
		(net "GND")
	)
	(via
		(at 294.829992 -175.844962)
		(size 0.508)
		(drill 0.254)
		(layers "F.Cu" "B.Cu")
		(net "GND")
	)
	(via
		(at 301.061882 -73.790302)
		(size 0.5588)
		(drill 0.3048)
		(layers "F.Cu" "B.Cu")
		(net "GND")
	)
	(via
		(at 179.2986 -144.5768)
		(size 0.5588)
		(drill 0.3048)
		(layers "F.Cu" "B.Cu")
		(net "GND")
	)
	(via
		(at 116.85016 -101.85019)
		(size 0.508)
		(drill 0.254)
		(layers "F.Cu" "B.Cu")
		(net "GND")
	)
	(via
		(at 110.849664 -87.84971)
		(size 0.508)
		(drill 0.254)
		(layers "F.Cu" "B.Cu")
		(net "GND")
	)
	(via
		(at 28.614116 -79.871062)
		(size 0.5588)
		(drill 0.3048)
		(layers "F.Cu" "B.Cu")
		(net "GND")
	)
	(via
		(at 86.14156 -130.175)
		(size 0.5588)
		(drill 0.3048)
		(layers "F.Cu" "B.Cu")
		(net "GND")
	)
	(via
		(at 100.311966 -62.738)
		(size 0.5588)
		(drill 0.3048)
		(layers "F.Cu" "B.Cu")
		(net "GND")
	)
	(via
		(at 119.171212 -202.819)
		(size 0.5588)
		(drill 0.3048)
		(layers "F.Cu" "B.Cu")
		(net "GND")
	)
	(via
		(at 347.472 -114.427)
		(size 0.5588)
		(drill 0.3048)
		(layers "F.Cu" "B.Cu")
		(net "GND")
	)
	(via
		(at 112.84966 -97.850198)
		(size 0.508)
		(drill 0.254)
		(layers "F.Cu" "B.Cu")
		(net "GND")
	)
	(via
		(at 322.834 -144.399)
		(size 0.5588)
		(drill 0.3048)
		(layers "F.Cu" "B.Cu")
		(net "GND")
	)
	(via
		(at 52.90947 -142.91056)
		(size 0.5588)
		(drill 0.3048)
		(layers "F.Cu" "B.Cu")
		(net "GND")
	)
	(via
		(at 341.3506 -111.379)
		(size 0.5588)
		(drill 0.3048)
		(layers "F.Cu" "B.Cu")
		(net "GND")
	)
	(via
		(at 295.630092 -174.245016)
		(size 0.508)
		(drill 0.254)
		(layers "F.Cu" "B.Cu")
		(net "GND")
	)
	(via
		(at 317.119 -196.977)
		(size 0.5588)
		(drill 0.3048)
		(layers "F.Cu" "B.Cu")
		(net "GND")
	)
	(via
		(at 199.39 -5.08)
		(size 0.5588)
		(drill 0.254)
		(layers "F.Cu" "B.Cu")
		(net "GND")
	)
	(via
		(at 42.799 -228.854)
		(size 0.5588)
		(drill 0.3048)
		(layers "F.Cu" "B.Cu")
		(net "GND")
	)
	(via
		(at 279.4 -248.92)
		(size 0.5588)
		(drill 0.254)
		(layers "F.Cu" "B.Cu")
		(net "GND")
	)
	(via
		(at 321.31 -42.926)
		(size 0.5588)
		(drill 0.3048)
		(layers "F.Cu" "B.Cu")
		(net "GND")
	)
	(via
		(at 124.850144 -103.850186)
		(size 0.508)
		(drill 0.254)
		(layers "F.Cu" "B.Cu")
		(net "GND")
	)
	(via
		(at 254.635 -132.08)
		(size 0.5588)
		(drill 0.3048)
		(layers "F.Cu" "B.Cu")
		(net "GND")
	)
	(via
		(at 342.853518 -159.667448)
		(size 0.5588)
		(drill 0.3048)
		(layers "F.Cu" "B.Cu")
		(net "GND")
	)
	(via
		(at 118.850156 -93.849698)
		(size 0.508)
		(drill 0.254)
		(layers "F.Cu" "B.Cu")
		(net "GND")
	)
	(via
		(at 295.55567 -199.012302)
		(size 0.508)
		(drill 0.254)
		(layers "F.Cu" "B.Cu")
		(net "GND")
	)
	(via
		(at 38.989 -175.32985)
		(size 0.5588)
		(drill 0.3048)
		(layers "F.Cu" "B.Cu")
		(net "GND")
	)
	(via
		(at 95.94977 -48.199802)
		(size 0.508)
		(drill 0.254)
		(layers "F.Cu" "B.Cu")
		(net "GND")
	)
	(via
		(at 126.85014 -107.850178)
		(size 0.508)
		(drill 0.254)
		(layers "F.Cu" "B.Cu")
		(net "GND")
	)
	(via
		(at 154.686 -87.757)
		(size 0.7112)
		(drill 0.4064)
		(layers "F.Cu" "B.Cu")
		(net "GND")
	)
	(via
		(at 215.138 -103.251)
		(size 0.5588)
		(drill 0.3048)
		(layers "F.Cu" "B.Cu")
		(net "GND")
	)
	(via
		(at 219.992448 -21.749004)
		(size 0.508)
		(drill 0.254)
		(layers "F.Cu" "B.Cu")
		(net "GND")
	)
	(via
		(at 127.850138 -106.85018)
		(size 0.508)
		(drill 0.254)
		(layers "F.Cu" "B.Cu")
		(net "GND")
	)
	(via
		(at 102.84968 -83.849718)
		(size 0.508)
		(drill 0.254)
		(layers "F.Cu" "B.Cu")
		(net "GND")
	)
	(via
		(at 2.144268 -215.216994)
		(size 0.5588)
		(drill 0.3048)
		(layers "F.Cu" "B.Cu")
		(net "GND")
	)
	(via
		(at 48.09617 -133.72338)
		(size 0.5588)
		(drill 0.3048)
		(layers "F.Cu" "B.Cu")
		(net "GND")
	)
	(via
		(at 103.949754 -44.19981)
		(size 0.508)
		(drill 0.254)
		(layers "F.Cu" "B.Cu")
		(net "GND")
	)
	(via
		(at 269.1892 -73.8124)
		(size 0.7112)
		(drill 0.4064)
		(layers "F.Cu" "B.Cu")
		(net "GND")
	)
	(via
		(at 212.09 -1.27)
		(size 0.5588)
		(drill 0.254)
		(layers "F.Cu" "B.Cu")
		(net "GND")
	)
	(via
		(at 110.350046 -44.19981)
		(size 0.508)
		(drill 0.254)
		(layers "F.Cu" "B.Cu")
		(net "GND")
	)
	(via
		(at 171.069 -84.836)
		(size 0.7112)
		(drill 0.4064)
		(layers "F.Cu" "B.Cu")
		(net "GND")
	)
	(via
		(at 111.150146 -36.20008)
		(size 0.508)
		(drill 0.254)
		(layers "F.Cu" "B.Cu")
		(net "GND")
	)
	(via
		(at 300.9265 -198.374)
		(size 0.5588)
		(drill 0.3048)
		(layers "F.Cu" "B.Cu")
		(net "GND")
	)
	(via
		(at 9.99998 -104.818942)
		(size 0.5588)
		(drill 0.3048)
		(layers "F.Cu" "B.Cu")
		(net "GND")
	)
	(via
		(at 224.5868 -161.671)
		(size 0.5588)
		(drill 0.3048)
		(layers "F.Cu" "B.Cu")
		(net "GND")
	)
	(via
		(at 137.668 -63.246)
		(size 0.508)
		(drill 0.254)
		(layers "F.Cu" "B.Cu")
		(net "GND")
	)
	(via
		(at 128.402842 -92.349828)
		(size 0.508)
		(drill 0.254)
		(layers "F.Cu" "B.Cu")
		(net "GND")
	)
	(via
		(at 329.057 -74.041)
		(size 0.5588)
		(drill 0.3048)
		(layers "F.Cu" "B.Cu")
		(net "GND")
	)
	(via
		(at 285.23819 -170.246548)
		(size 0.508)
		(drill 0.254)
		(layers "F.Cu" "B.Cu")
		(net "GND")
	)
	(via
		(at 108.749846 -48.999648)
		(size 0.508)
		(drill 0.254)
		(layers "F.Cu" "B.Cu")
		(net "GND")
	)
	(via
		(at 203.2 -25.4)
		(size 0.7112)
		(drill 0.4064)
		(layers "F.Cu" "B.Cu")
		(net "GND")
	)
	(via
		(at 116.713 -73.6854)
		(size 0.5588)
		(drill 0.3048)
		(layers "F.Cu" "B.Cu")
		(net "GND")
	)
	(via
		(at 1.143 -119.201438)
		(size 0.7112)
		(drill 0.4064)
		(layers "F.Cu" "B.Cu")
		(net "GND")
	)
	(via
		(at 216.916 -110.871)
		(size 0.5588)
		(drill 0.3048)
		(layers "F.Cu" "B.Cu")
		(net "GND")
	)
	(via
		(at 118.850156 -96.8502)
		(size 0.508)
		(drill 0.254)
		(layers "F.Cu" "B.Cu")
		(net "GND")
	)
	(via
		(at 104.849676 -83.849718)
		(size 0.508)
		(drill 0.254)
		(layers "F.Cu" "B.Cu")
		(net "GND")
	)
	(via
		(at 120.850152 -96.8502)
		(size 0.508)
		(drill 0.254)
		(layers "F.Cu" "B.Cu")
		(net "GND")
	)
	(via
		(at 268.2494 -77.0128)
		(size 0.7112)
		(drill 0.4064)
		(layers "F.Cu" "B.Cu")
		(net "GND")
	)
	(via
		(at 2.18186 -80.92186)
		(size 0.7112)
		(drill 0.4064)
		(layers "F.Cu" "B.Cu")
		(net "GND")
	)
	(via
		(at 221.488 -19.177)
		(size 0.5588)
		(drill 0.3048)
		(layers "F.Cu" "B.Cu")
		(net "GND")
	)
	(via
		(at 287.34385 -220.40215)
		(size 0.5588)
		(drill 0.3048)
		(layers "F.Cu" "B.Cu")
		(net "GND")
	)
	(via
		(at 296.1894 -185.801)
		(size 0.508)
		(drill 0.254)
		(layers "F.Cu" "B.Cu")
		(net "GND")
	)
	(via
		(at 201.803 -248.285)
		(size 0.7112)
		(drill 0.4064)
		(layers "F.Cu" "B.Cu")
		(net "GND")
	)
	(via
		(at 292.735 -154.559)
		(size 0.5588)
		(drill 0.3048)
		(layers "F.Cu" "B.Cu")
		(net "GND")
	)
	(via
		(at 215.138 -100.711)
		(size 0.5588)
		(drill 0.3048)
		(layers "F.Cu" "B.Cu")
		(net "GND")
	)
	(via
		(at 153.289 -54.356)
		(size 0.508)
		(drill 0.254)
		(layers "F.Cu" "B.Cu")
		(net "GND")
	)
	(via
		(at 108.749846 -50.599594)
		(size 0.508)
		(drill 0.254)
		(layers "F.Cu" "B.Cu")
		(net "GND")
	)
	(via
		(at 19.05 -247.65)
		(size 0.7112)
		(drill 0.4064)
		(layers "F.Cu" "B.Cu")
		(net "GND")
	)
	(via
		(at 200.025 -199.009)
		(size 0.5588)
		(drill 0.3048)
		(layers "F.Cu" "B.Cu")
		(net "GND")
	)
	(via
		(at 296.691304 -78.751684)
		(size 0.5588)
		(drill 0.3048)
		(layers "F.Cu" "B.Cu")
		(net "GND")
	)
	(via
		(at 86.00313 -122.57786)
		(size 0.5588)
		(drill 0.3048)
		(layers "F.Cu" "B.Cu")
		(net "GND")
	)
	(via
		(at 110.341156 -52.200556)
		(size 0.508)
		(drill 0.254)
		(layers "F.Cu" "B.Cu")
		(net "GND")
	)
	(via
		(at 232.41 -209.55)
		(size 0.7112)
		(drill 0.4064)
		(layers "F.Cu" "B.Cu")
		(net "GND")
	)
	(via
		(at 66.421 -47.9806)
		(size 0.7112)
		(drill 0.4064)
		(layers "F.Cu" "B.Cu")
		(net "GND")
	)
	(via
		(at 248.939812 -51.962812)
		(size 0.5588)
		(drill 0.3048)
		(layers "F.Cu" "B.Cu")
		(net "GND")
	)
	(via
		(at 81.534 -8.509)
		(size 0.7112)
		(drill 0.4064)
		(layers "F.Cu" "B.Cu")
		(net "GND")
	)
	(via
		(at 16.079216 -179.50688)
		(size 0.5588)
		(drill 0.3048)
		(layers "F.Cu" "B.Cu")
		(net "GND")
	)
	(via
		(at 93.8276 -1.1176)
		(size 0.5588)
		(drill 0.3048)
		(layers "F.Cu" "B.Cu")
		(net "GND")
	)
	(via
		(at 291.6301 -177.444908)
		(size 0.508)
		(drill 0.254)
		(layers "F.Cu" "B.Cu")
		(net "GND")
	)
	(via
		(at 323.85 -185.928)
		(size 0.508)
		(drill 0.254)
		(layers "F.Cu" "B.Cu")
		(net "GND")
	)
	(via
		(at 259.452872 -220.209872)
		(size 0.5588)
		(drill 0.3048)
		(layers "F.Cu" "B.Cu")
		(net "GND")
	)
	(via
		(at 162.97275 -118.20525)
		(size 0.5588)
		(drill 0.3048)
		(layers "F.Cu" "B.Cu")
		(net "GND")
	)
	(via
		(at 43.274996 -90.096086)
		(size 0.5588)
		(drill 0.3048)
		(layers "F.Cu" "B.Cu")
		(net "GND")
	)
	(via
		(at 90.913966 -70.358)
		(size 0.7112)
		(drill 0.4064)
		(layers "F.Cu" "B.Cu")
		(net "GND")
	)
	(via
		(at 212.86597 -66.675)
		(size 0.5588)
		(drill 0.3048)
		(layers "F.Cu" "B.Cu")
		(net "GND")
	)
	(via
		(at 129.921 -88.392)
		(size 0.508)
		(drill 0.254)
		(layers "F.Cu" "B.Cu")
		(net "GND")
	)
	(via
		(at 211.455 -92.329)
		(size 0.7112)
		(drill 0.3556)
		(layers "F.Cu" "B.Cu")
		(net "GND")
	)
	(via
		(at 290.034472 -172.736256)
		(size 0.508)
		(drill 0.254)
		(layers "F.Cu" "B.Cu")
		(net "GND")
	)
	(via
		(at 132.67563 -79.171546)
		(size 0.508)
		(drill 0.254)
		(layers "F.Cu" "B.Cu")
		(net "GND")
	)
	(via
		(at 318.151256 -73.803764)
		(size 0.5588)
		(drill 0.3048)
		(layers "F.Cu" "B.Cu")
		(net "GND")
	)
	(via
		(at 325.7042 -172.212)
		(size 0.5588)
		(drill 0.3048)
		(layers "F.Cu" "B.Cu")
		(net "GND")
	)
	(via
		(at 169.545 -116.459)
		(size 0.5588)
		(drill 0.3048)
		(layers "F.Cu" "B.Cu")
		(net "GND")
	)
	(via
		(at 324.739 -113.919)
		(size 0.5588)
		(drill 0.3048)
		(layers "F.Cu" "B.Cu")
		(net "GND")
	)
	(via
		(at 119.850154 -100.850192)
		(size 0.508)
		(drill 0.254)
		(layers "F.Cu" "B.Cu")
		(net "GND")
	)
	(via
		(at 106.788966 -62.5856)
		(size 0.5588)
		(drill 0.3048)
		(layers "F.Cu" "B.Cu")
		(net "GND")
	)
	(via
		(at 264.033 -40.513)
		(size 0.5588)
		(drill 0.3048)
		(layers "F.Cu" "B.Cu")
		(net "GND")
	)
	(via
		(at 142.24 -5.08)
		(size 0.7112)
		(drill 0.4064)
		(layers "F.Cu" "B.Cu")
		(net "GND")
	)
	(via
		(at 184.720992 -35.941)
		(size 0.7112)
		(drill 0.4064)
		(layers "F.Cu" "B.Cu")
		(net "GND")
	)
	(via
		(at 108.749846 -46.599602)
		(size 0.508)
		(drill 0.254)
		(layers "F.Cu" "B.Cu")
		(net "GND")
	)
	(via
		(at 79.0702 -42.418)
		(size 0.508)
		(drill 0.254)
		(layers "F.Cu" "B.Cu")
		(net "GND")
	)
	(via
		(at 256.54 -248.92)
		(size 0.5588)
		(drill 0.254)
		(layers "F.Cu" "B.Cu")
		(net "GND")
	)
	(via
		(at 111.849662 -88.849708)
		(size 0.508)
		(drill 0.254)
		(layers "F.Cu" "B.Cu")
		(net "GND")
	)
	(via
		(at 319.151 -42.291)
		(size 0.5588)
		(drill 0.3048)
		(layers "F.Cu" "B.Cu")
		(net "GND")
	)
	(via
		(at 109.849666 -97.850198)
		(size 0.508)
		(drill 0.254)
		(layers "F.Cu" "B.Cu")
		(net "GND")
	)
	(via
		(at 294.4114 -162.7632)
		(size 0.508)
		(drill 0.254)
		(layers "F.Cu" "B.Cu")
		(net "GND")
	)
	(via
		(at 83.8835 -20.32)
		(size 0.508)
		(drill 0.254)
		(layers "F.Cu" "B.Cu")
		(net "GND")
	)
	(via
		(at 282.897072 -215.146636)
		(size 0.5588)
		(drill 0.3048)
		(layers "F.Cu" "B.Cu")
		(net "GND")
	)
	(via
		(at 36.32454 -171.8056)
		(size 0.5588)
		(drill 0.3048)
		(layers "F.Cu" "B.Cu")
		(net "GND")
	)
	(via
		(at 339.725 -1.27)
		(size 0.5588)
		(drill 0.254)
		(layers "F.Cu" "B.Cu")
		(net "GND")
	)
	(via
		(at 246.38 -5.08)
		(size 0.5588)
		(drill 0.254)
		(layers "F.Cu" "B.Cu")
		(net "GND")
	)
	(via
		(at 293.230046 -177.444908)
		(size 0.508)
		(drill 0.254)
		(layers "F.Cu" "B.Cu")
		(net "GND")
	)
	(via
		(at 183.1848 -52.2732)
		(size 0.5588)
		(drill 0.3048)
		(layers "F.Cu" "B.Cu")
		(net "GND")
	)
	(via
		(at 193.294 -22.479)
		(size 0.5588)
		(drill 0.3048)
		(layers "F.Cu" "B.Cu")
		(net "GND")
	)
	(via
		(at 170.815 -114.808)
		(size 0.5588)
		(drill 0.3048)
		(layers "F.Cu" "B.Cu")
		(net "GND")
	)
	(via
		(at 303.784 -180.467)
		(size 0.508)
		(drill 0.254)
		(layers "F.Cu" "B.Cu")
		(net "GND")
	)
	(via
		(at 144.399 -37.465)
		(size 0.508)
		(drill 0.254)
		(layers "F.Cu" "B.Cu")
		(net "GND")
	)
	(via
		(at 292.613842 -186.257946)
		(size 0.508)
		(drill 0.254)
		(layers "F.Cu" "B.Cu")
		(net "GND")
	)
	(via
		(at 232.41 -229.87)
		(size 0.7112)
		(drill 0.4064)
		(layers "F.Cu" "B.Cu")
		(net "GND")
	)
	(via
		(at 91.957144 -43.402504)
		(size 0.508)
		(drill 0.254)
		(layers "F.Cu" "B.Cu")
		(net "GND")
	)
	(via
		(at 276.733 -102.87)
		(size 0.508)
		(drill 0.254)
		(layers "F.Cu" "B.Cu")
		(net "GND")
	)
	(via
		(at 280.67 -160.147)
		(size 0.508)
		(drill 0.254)
		(layers "F.Cu" "B.Cu")
		(net "GND")
	)
	(via
		(at 294.724582 -191.4144)
		(size 0.5588)
		(drill 0.3048)
		(layers "F.Cu" "B.Cu")
		(net "GND")
	)
	(via
		(at 124.850144 -95.850202)
		(size 0.508)
		(drill 0.254)
		(layers "F.Cu" "B.Cu")
		(net "GND")
	)
	(via
		(at 64.643 -46.736)
		(size 0.7112)
		(drill 0.3556)
		(layers "F.Cu" "B.Cu")
		(net "GND")
	)
	(via
		(at 110.849664 -83.849718)
		(size 0.508)
		(drill 0.254)
		(layers "F.Cu" "B.Cu")
		(net "GND")
	)
	(via
		(at 296.49928 -195.65366)
		(size 0.508)
		(drill 0.254)
		(layers "F.Cu" "B.Cu")
		(net "GND")
	)
	(via
		(at 257.302 -71.755)
		(size 0.7112)
		(drill 0.4064)
		(layers "F.Cu" "B.Cu")
		(net "GND")
	)
	(via
		(at 118.850156 -99.850194)
		(size 0.508)
		(drill 0.254)
		(layers "F.Cu" "B.Cu")
		(net "GND")
	)
	(via
		(at 232.41 -234.95)
		(size 0.7112)
		(drill 0.4064)
		(layers "F.Cu" "B.Cu")
		(net "GND")
	)
	(via
		(at 254 -5.08)
		(size 0.5588)
		(drill 0.254)
		(layers "F.Cu" "B.Cu")
		(net "GND")
	)
	(via
		(at 124.378212 -252.857)
		(size 0.7112)
		(drill 0.4064)
		(layers "F.Cu" "B.Cu")
		(net "GND")
	)
	(via
		(at 192.024 -45.72)
		(size 0.508)
		(drill 0.254)
		(layers "F.Cu" "B.Cu")
		(net "GND")
	)
	(via
		(at 40.353996 -90.096086)
		(size 0.5588)
		(drill 0.3048)
		(layers "F.Cu" "B.Cu")
		(net "GND")
	)
	(via
		(at 92.757244 -45.00245)
		(size 0.508)
		(drill 0.254)
		(layers "F.Cu" "B.Cu")
		(net "GND")
	)
	(via
		(at 232.41 -219.71)
		(size 0.7112)
		(drill 0.4064)
		(layers "F.Cu" "B.Cu")
		(net "GND")
	)
	(via
		(at 227.33 -1.27)
		(size 0.5588)
		(drill 0.254)
		(layers "F.Cu" "B.Cu")
		(net "GND")
	)
	(via
		(at 13.97 -247.65)
		(size 0.7112)
		(drill 0.4064)
		(layers "F.Cu" "B.Cu")
		(net "GND")
	)
	(via
		(at 80.4926 -16.7386)
		(size 0.5588)
		(drill 0.3048)
		(layers "F.Cu" "B.Cu")
		(net "GND")
	)
	(via
		(at 175.26 -116.967)
		(size 0.5588)
		(drill 0.3048)
		(layers "F.Cu" "B.Cu")
		(net "GND")
	)
	(via
		(at 292.4302 -176.644808)
		(size 0.508)
		(drill 0.254)
		(layers "F.Cu" "B.Cu")
		(net "GND")
	)
	(via
		(at 193.1924 -24.003)
		(size 0.5588)
		(drill 0.3048)
		(layers "F.Cu" "B.Cu")
		(net "GND")
	)
	(via
		(at 78.105 -75.946)
		(size 0.5588)
		(drill 0.254)
		(layers "F.Cu" "B.Cu")
		(net "GND")
	)
	(via
		(at 77.578966 -56.642)
		(size 0.5588)
		(drill 0.3048)
		(layers "F.Cu" "B.Cu")
		(net "GND")
	)
	(via
		(at 320.294 -74.295)
		(size 0.5588)
		(drill 0.3048)
		(layers "F.Cu" "B.Cu")
		(net "GND")
	)
	(via
		(at 98.806 -153.416)
		(size 0.5588)
		(drill 0.3048)
		(layers "F.Cu" "B.Cu")
		(net "GND")
	)
	(via
		(at 143.002 -116.205)
		(size 0.7112)
		(drill 0.4064)
		(layers "F.Cu" "B.Cu")
		(net "GND")
	)
	(via
		(at 131.953 -92.837)
		(size 0.508)
		(drill 0.254)
		(layers "F.Cu" "B.Cu")
		(net "GND")
	)
	(via
		(at 259.207 -224.155)
		(size 0.7112)
		(drill 0.4064)
		(layers "F.Cu" "B.Cu")
		(net "GND")
	)
	(via
		(at 215.9 -5.08)
		(size 0.5588)
		(drill 0.254)
		(layers "F.Cu" "B.Cu")
		(net "GND")
	)
	(via
		(at 204.793596 -110.420404)
		(size 0.5588)
		(drill 0.3048)
		(layers "F.Cu" "B.Cu")
		(net "GND")
	)
	(via
		(at 143.002 -118.491)
		(size 0.7112)
		(drill 0.4064)
		(layers "F.Cu" "B.Cu")
		(net "GND")
	)
	(via
		(at 86.741 -78.613)
		(size 0.5588)
		(drill 0.3048)
		(layers "F.Cu" "B.Cu")
		(net "GND")
	)
	(via
		(at 288.097976 -203.195936)
		(size 0.508)
		(drill 0.254)
		(layers "F.Cu" "B.Cu")
		(net "GND")
	)
	(via
		(at 334.772 -95.377)
		(size 0.7112)
		(drill 0.4064)
		(layers "F.Cu" "B.Cu")
		(net "GND")
	)
	(via
		(at 101.543866 -36.202874)
		(size 0.508)
		(drill 0.254)
		(layers "F.Cu" "B.Cu")
		(net "GND")
	)
	(via
		(at 136.316212 -252.984)
		(size 0.7112)
		(drill 0.4064)
		(layers "F.Cu" "B.Cu")
		(net "GND")
	)
	(via
		(at 10.541 -239.141)
		(size 0.5588)
		(drill 0.3048)
		(layers "F.Cu" "B.Cu")
		(net "GND")
	)
	(via
		(at 98.349816 -44.999656)
		(size 0.508)
		(drill 0.254)
		(layers "F.Cu" "B.Cu")
		(net "GND")
	)
	(via
		(at 109.849666 -95.850202)
		(size 0.508)
		(drill 0.254)
		(layers "F.Cu" "B.Cu")
		(net "GND")
	)
	(via
		(at 157.607 -215.519)
		(size 0.7112)
		(drill 0.4064)
		(layers "F.Cu" "B.Cu")
		(net "GND")
	)
	(via
		(at 1.143 -190.321438)
		(size 0.7112)
		(drill 0.4064)
		(layers "F.Cu" "B.Cu")
		(net "GND")
	)
	(via
		(at 195.744084 -174.079916)
		(size 0.5588)
		(drill 0.3048)
		(layers "F.Cu" "B.Cu")
		(net "GND")
	)
	(via
		(at 111.887 -67.818)
		(size 0.5588)
		(drill 0.3048)
		(layers "F.Cu" "B.Cu")
		(net "GND")
	)
	(via
		(at 331.343 -212.852)
		(size 0.5588)
		(drill 0.3048)
		(layers "F.Cu" "B.Cu")
		(net "GND")
	)
	(via
		(at 93.35897 -138.557)
		(size 0.5588)
		(drill 0.3048)
		(layers "F.Cu" "B.Cu")
		(net "GND")
	)
	(via
		(at 95.45447 -96.5835)
		(size 0.5588)
		(drill 0.3048)
		(layers "F.Cu" "B.Cu")
		(net "GND")
	)
	(via
		(at 106.849672 -83.849718)
		(size 0.508)
		(drill 0.254)
		(layers "F.Cu" "B.Cu")
		(net "GND")
	)
	(via
		(at 322.444872 -111.705136)
		(size 0.5588)
		(drill 0.3048)
		(layers "F.Cu" "B.Cu")
		(net "GND")
	)
	(via
		(at 331.525118 -155.552648)
		(size 0.508)
		(drill 0.254)
		(layers "F.Cu" "B.Cu")
		(net "GND")
	)
	(via
		(at 89.36101 -138.90752)
		(size 0.5588)
		(drill 0.3048)
		(layers "F.Cu" "B.Cu")
		(net "GND")
	)
	(via
		(at 147.122134 -60.2615)
		(size 0.508)
		(drill 0.254)
		(layers "F.Cu" "B.Cu")
		(net "GND")
	)
	(via
		(at 344.1446 -132.7404)
		(size 0.508)
		(drill 0.254)
		(layers "F.Cu" "B.Cu")
		(net "GND")
	)
	(via
		(at 120.850152 -93.849698)
		(size 0.508)
		(drill 0.254)
		(layers "F.Cu" "B.Cu")
		(net "GND")
	)
	(via
		(at 148.508212 -252.603)
		(size 0.7112)
		(drill 0.4064)
		(layers "F.Cu" "B.Cu")
		(net "GND")
	)
	(via
		(at 306.959 -72.009)
		(size 0.5588)
		(drill 0.3048)
		(layers "F.Cu" "B.Cu")
		(net "GND")
	)
	(via
		(at 109.849666 -98.850196)
		(size 0.508)
		(drill 0.254)
		(layers "F.Cu" "B.Cu")
		(net "GND")
	)
	(via
		(at 293.1922 -205.64094)
		(size 0.508)
		(drill 0.254)
		(layers "F.Cu" "B.Cu")
		(net "GND")
	)
	(via
		(at 104.85501 -88.86444)
		(size 0.508)
		(drill 0.254)
		(layers "F.Cu" "B.Cu")
		(net "GND")
	)
	(via
		(at 117.850158 -100.850192)
		(size 0.508)
		(drill 0.254)
		(layers "F.Cu" "B.Cu")
		(net "GND")
	)
	(via
		(at 160.909 -190.373)
		(size 0.7112)
		(drill 0.4064)
		(layers "F.Cu" "B.Cu")
		(net "GND")
	)
	(via
		(at 116.85016 -91.849702)
		(size 0.508)
		(drill 0.254)
		(layers "F.Cu" "B.Cu")
		(net "GND")
	)
	(via
		(at 314.833 -54.356)
		(size 0.5588)
		(drill 0.3048)
		(layers "F.Cu" "B.Cu")
		(net "GND")
	)
	(via
		(at 280.162 -225.6282)
		(size 0.5588)
		(drill 0.3048)
		(layers "F.Cu" "B.Cu")
		(net "GND")
	)
	(via
		(at 283.980636 -215.146636)
		(size 0.5588)
		(drill 0.3048)
		(layers "F.Cu" "B.Cu")
		(net "GND")
	)
	(via
		(at 175.505364 -36.075112)
		(size 0.7112)
		(drill 0.4064)
		(layers "F.Cu" "B.Cu")
		(net "GND")
	)
	(via
		(at 305.689 -177.42408)
		(size 0.508)
		(drill 0.254)
		(layers "F.Cu" "B.Cu")
		(net "GND")
	)
	(via
		(at 298.831 -97.409)
		(size 0.5588)
		(drill 0.3048)
		(layers "F.Cu" "B.Cu")
		(net "GND")
	)
	(via
		(at 69.514212 -243.332)
		(size 0.5588)
		(drill 0.3048)
		(layers "F.Cu" "B.Cu")
		(net "GND")
	)
	(via
		(at 294.64 -80.899)
		(size 0.5588)
		(drill 0.3048)
		(layers "F.Cu" "B.Cu")
		(net "GND")
	)
	(via
		(at 216.916 -162.687)
		(size 0.5588)
		(drill 0.3048)
		(layers "F.Cu" "B.Cu")
		(net "GND")
	)
	(via
		(at 107.949746 -40.999664)
		(size 0.508)
		(drill 0.254)
		(layers "F.Cu" "B.Cu")
		(net "GND")
	)
	(via
		(at 164.211 -25.654)
		(size 0.5588)
		(drill 0.3048)
		(layers "F.Cu" "B.Cu")
		(net "GND")
	)
	(via
		(at 136.87425 -35.052)
		(size 0.508)
		(drill 0.254)
		(layers "F.Cu" "B.Cu")
		(net "GND")
	)
	(via
		(at 106.242612 -216.916)
		(size 0.5588)
		(drill 0.3048)
		(layers "F.Cu" "B.Cu")
		(net "GND")
	)
	(via
		(at 101.99497 -80.772)
		(size 0.5588)
		(drill 0.3048)
		(layers "F.Cu" "B.Cu")
		(net "GND")
	)
	(via
		(at 232.41 -204.47)
		(size 0.7112)
		(drill 0.4064)
		(layers "F.Cu" "B.Cu")
		(net "GND")
	)
	(via
		(at 103.15575 -37.796216)
		(size 0.508)
		(drill 0.254)
		(layers "F.Cu" "B.Cu")
		(net "GND")
	)
	(via
		(at 269.24 -5.08)
		(size 0.5588)
		(drill 0.254)
		(layers "F.Cu" "B.Cu")
		(net "GND")
	)
	(via
		(at 111.849662 -93.849698)
		(size 0.508)
		(drill 0.254)
		(layers "F.Cu" "B.Cu")
		(net "GND")
	)
	(via
		(at 122.850148 -107.850178)
		(size 0.508)
		(drill 0.254)
		(layers "F.Cu" "B.Cu")
		(net "GND")
	)
	(via
		(at 176.276 -124.968)
		(size 0.7112)
		(drill 0.4064)
		(layers "F.Cu" "B.Cu")
		(net "GND")
	)
	(via
		(at 296.030904 -155.801822)
		(size 0.5588)
		(drill 0.3048)
		(layers "F.Cu" "B.Cu")
		(net "GND")
	)
	(via
		(at 42.38625 -172.28439)
		(size 0.5588)
		(drill 0.3048)
		(layers "F.Cu" "B.Cu")
		(net "GND")
	)
	(via
		(at 134.4676 -89.6112)
		(size 0.508)
		(drill 0.254)
		(layers "F.Cu" "B.Cu")
		(net "GND")
	)
	(via
		(at 89.68359 -47.62119)
		(size 0.508)
		(drill 0.254)
		(layers "F.Cu" "B.Cu")
		(net "GND")
	)
	(via
		(at 91.950286 -39.400226)
		(size 0.508)
		(drill 0.254)
		(layers "F.Cu" "B.Cu")
		(net "GND")
	)
	(via
		(at 151.003 -59.944)
		(size 0.508)
		(drill 0.254)
		(layers "F.Cu" "B.Cu")
		(net "GND")
	)
	(via
		(at 334.9498 -135.509)
		(size 0.508)
		(drill 0.254)
		(layers "F.Cu" "B.Cu")
		(net "GND")
	)
	(via
		(at 110.350046 -40.999918)
		(size 0.508)
		(drill 0.254)
		(layers "F.Cu" "B.Cu")
		(net "GND")
	)
	(via
		(at 334.971136 -201.603864)
		(size 0.5588)
		(drill 0.3048)
		(layers "F.Cu" "B.Cu")
		(net "GND")
	)
	(via
		(at 181.283864 -39.75608)
		(size 0.7112)
		(drill 0.4064)
		(layers "F.Cu" "B.Cu")
		(net "GND")
	)
	(via
		(at 204.5335 -219.9005)
		(size 0.5588)
		(drill 0.3048)
		(layers "F.Cu" "B.Cu")
		(net "GND")
	)
	(via
		(at 39.591996 -78.793086)
		(size 0.5588)
		(drill 0.3048)
		(layers "F.Cu" "B.Cu")
		(net "GND")
	)
	(via
		(at 120.441212 -252.857)
		(size 0.7112)
		(drill 0.4064)
		(layers "F.Cu" "B.Cu")
		(net "GND")
	)
	(via
		(at 318.567562 -71.82358)
		(size 0.5588)
		(drill 0.3048)
		(layers "F.Cu" "B.Cu")
		(net "GND")
	)
	(via
		(at 16.325088 -186.945016)
		(size 0.5588)
		(drill 0.3048)
		(layers "F.Cu" "B.Cu")
		(net "GND")
	)
	(via
		(at 332.613 -12.954)
		(size 0.5588)
		(drill 0.3048)
		(layers "F.Cu" "B.Cu")
		(net "GND")
	)
	(via
		(at 99.149916 -56.999632)
		(size 0.508)
		(drill 0.254)
		(layers "F.Cu" "B.Cu")
		(net "GND")
	)
	(via
		(at 344.297 -141.351)
		(size 0.5588)
		(drill 0.3048)
		(layers "F.Cu" "B.Cu")
		(net "GND")
	)
	(via
		(at 79.483966 -97.028)
		(size 0.7112)
		(drill 0.3556)
		(layers "F.Cu" "B.Cu")
		(net "GND")
	)
	(via
		(at 283.582872 -219.909136)
		(size 0.5588)
		(drill 0.3048)
		(layers "F.Cu" "B.Cu")
		(net "GND")
	)
	(via
		(at 186.553348 -140.598652)
		(size 0.5588)
		(drill 0.3048)
		(layers "F.Cu" "B.Cu")
		(net "GND")
	)
	(via
		(at 40.582596 -81.460086)
		(size 0.5588)
		(drill 0.3048)
		(layers "F.Cu" "B.Cu")
		(net "GND")
	)
	(via
		(at 275.6281 -40.2336)
		(size 0.7112)
		(drill 0.4064)
		(layers "F.Cu" "B.Cu")
		(net "GND")
	)
	(via
		(at 95.95231 -39.407084)
		(size 0.508)
		(drill 0.254)
		(layers "F.Cu" "B.Cu")
		(net "GND")
	)
	(via
		(at 95.957898 -37.798248)
		(size 0.508)
		(drill 0.254)
		(layers "F.Cu" "B.Cu")
		(net "GND")
	)
	(via
		(at 5.08 -96.52)
		(size 0.7112)
		(drill 0.4064)
		(layers "F.Cu" "B.Cu")
		(net "GND")
	)
	(via
		(at 76.0222 -21.3868)
		(size 0.5588)
		(drill 0.254)
		(layers "F.Cu" "B.Cu")
		(net "GND")
	)
	(via
		(at 200.3044 -114.1222)
		(size 0.5588)
		(drill 0.3048)
		(layers "F.Cu" "B.Cu")
		(net "GND")
	)
	(via
		(at 231.14 -5.08)
		(size 0.5588)
		(drill 0.254)
		(layers "F.Cu" "B.Cu")
		(net "GND")
	)
	(via
		(at 119.90197 -107.95)
		(size 0.5588)
		(drill 0.3048)
		(layers "F.Cu" "B.Cu")
		(net "GND")
	)
	(via
		(at 179.197 -89.535)
		(size 0.7112)
		(drill 0.4064)
		(layers "F.Cu" "B.Cu")
		(net "GND")
	)
	(via
		(at 118.850156 -97.850198)
		(size 0.508)
		(drill 0.254)
		(layers "F.Cu" "B.Cu")
		(net "GND")
	)
	(via
		(at 305.299872 -192.405)
		(size 0.5588)
		(drill 0.3048)
		(layers "F.Cu" "B.Cu")
		(net "GND")
	)
	(via
		(at 112.567212 -252.984)
		(size 0.7112)
		(drill 0.4064)
		(layers "F.Cu" "B.Cu")
		(net "GND")
	)
	(via
		(at 107.315 -194.183)
		(size 0.7112)
		(drill 0.4064)
		(layers "F.Cu" "B.Cu")
		(net "GND")
	)
	(via
		(at 268.732 -40.513)
		(size 0.5588)
		(drill 0.3048)
		(layers "F.Cu" "B.Cu")
		(net "GND")
	)
	(via
		(at 93.98 -12.954)
		(size 0.7112)
		(drill 0.4064)
		(layers "F.Cu" "B.Cu")
		(net "GND")
	)
	(via
		(at 48.4632 -117.5512)
		(size 0.5588)
		(drill 0.3048)
		(layers "F.Cu" "B.Cu")
		(net "GND")
	)
	(via
		(at 120.850152 -101.85019)
		(size 0.508)
		(drill 0.254)
		(layers "F.Cu" "B.Cu")
		(net "GND")
	)
	(via
		(at 292.4302 -175.844962)
		(size 0.508)
		(drill 0.254)
		(layers "F.Cu" "B.Cu")
		(net "GND")
	)
	(via
		(at 269.367 -71.755)
		(size 0.7112)
		(drill 0.4064)
		(layers "F.Cu" "B.Cu")
		(net "GND")
	)
	(via
		(at 321.31 -44.196)
		(size 0.5588)
		(drill 0.3048)
		(layers "F.Cu" "B.Cu")
		(net "GND")
	)
	(via
		(at 112.40389 -108.39958)
		(size 0.508)
		(drill 0.254)
		(layers "F.Cu" "B.Cu")
		(net "GND")
	)
	(via
		(at 180.975 -218.3765)
		(size 0.5588)
		(drill 0.3048)
		(layers "F.Cu" "B.Cu")
		(net "GND")
	)
	(via
		(at 1.143 -230.961438)
		(size 0.7112)
		(drill 0.4064)
		(layers "F.Cu" "B.Cu")
		(net "GND")
	)
	(via
		(at 43.266106 -136.498584)
		(size 0.5588)
		(drill 0.3048)
		(layers "F.Cu" "B.Cu")
		(net "GND")
	)
	(via
		(at 179.959 -94.234)
		(size 0.7112)
		(drill 0.4064)
		(layers "F.Cu" "B.Cu")
		(net "GND")
	)
	(via
		(at 52.197 -227.838)
		(size 0.5588)
		(drill 0.3048)
		(layers "F.Cu" "B.Cu")
		(net "GND")
	)
	(via
		(at 304.038 -94.615)
		(size 0.5588)
		(drill 0.3048)
		(layers "F.Cu" "B.Cu")
		(net "GND")
	)
	(via
		(at 209.931 -110.744)
		(size 0.5588)
		(drill 0.3048)
		(layers "F.Cu" "B.Cu")
		(net "GND")
	)
	(via
		(at 112.338612 -214.884)
		(size 0.5588)
		(drill 0.3048)
		(layers "F.Cu" "B.Cu")
		(net "GND")
	)
	(via
		(at 116.224812 -223.4438)
		(size 0.5588)
		(drill 0.3048)
		(layers "F.Cu" "B.Cu")
		(net "GND")
	)
	(via
		(at 94.50197 -81.153)
		(size 0.5588)
		(drill 0.3048)
		(layers "F.Cu" "B.Cu")
		(net "GND")
	)
	(via
		(at 255.778 -3.048)
		(size 0.7112)
		(drill 0.4064)
		(layers "F.Cu" "B.Cu")
		(net "GND")
	)
	(via
		(at 104.750108 -39.399972)
		(size 0.508)
		(drill 0.254)
		(layers "F.Cu" "B.Cu")
		(net "GND")
	)
	(via
		(at 28.424378 -177.448718)
		(size 0.5588)
		(drill 0.3048)
		(layers "F.Cu" "B.Cu")
		(net "GND")
	)
	(via
		(at 100.749862 -42.59961)
		(size 0.508)
		(drill 0.254)
		(layers "F.Cu" "B.Cu")
		(net "GND")
	)
	(via
		(at 121.85015 -100.850192)
		(size 0.508)
		(drill 0.254)
		(layers "F.Cu" "B.Cu")
		(net "GND")
	)
	(via
		(at 291.338 -157.226)
		(size 0.5588)
		(drill 0.3048)
		(layers "F.Cu" "B.Cu")
		(net "GND")
	)
	(via
		(at 84.0486 -34.163)
		(size 0.508)
		(drill 0.254)
		(layers "F.Cu" "B.Cu")
		(net "GND")
	)
	(via
		(at 164.211 -103.759)
		(size 0.7112)
		(drill 0.4064)
		(layers "F.Cu" "B.Cu")
		(net "GND")
	)
	(via
		(at 86.233 -237.871)
		(size 0.5588)
		(drill 0.3048)
		(layers "F.Cu" "B.Cu")
		(net "GND")
	)
	(via
		(at 165.1762 -85.4456)
		(size 0.7112)
		(drill 0.3556)
		(layers "F.Cu" "B.Cu")
		(net "GND")
	)
	(via
		(at 117.647212 -202.819)
		(size 0.5588)
		(drill 0.3048)
		(layers "F.Cu" "B.Cu")
		(net "GND")
	)
	(via
		(at 142.412212 -252.984)
		(size 0.7112)
		(drill 0.4064)
		(layers "F.Cu" "B.Cu")
		(net "GND")
	)
	(via
		(at 329.565 -142.748)
		(size 0.5588)
		(drill 0.3048)
		(layers "F.Cu" "B.Cu")
		(net "GND")
	)
	(via
		(at 266.954 -224.4344)
		(size 0.7112)
		(drill 0.4064)
		(layers "F.Cu" "B.Cu")
		(net "GND")
	)
	(via
		(at 205.74 -186.817)
		(size 0.5588)
		(drill 0.3048)
		(layers "F.Cu" "B.Cu")
		(net "GND")
	)
	(via
		(at 99.953826 -38.60546)
		(size 0.508)
		(drill 0.254)
		(layers "F.Cu" "B.Cu")
		(net "GND")
	)
	(via
		(at 155.829 -87.757)
		(size 0.7112)
		(drill 0.4064)
		(layers "F.Cu" "B.Cu")
		(net "GND")
	)
	(via
		(at 280.67 -246.38)
		(size 0.7112)
		(drill 0.4064)
		(layers "F.Cu" "B.Cu")
		(net "GND")
	)
	(via
		(at 186.29376 -222.39224)
		(size 0.5588)
		(drill 0.3048)
		(layers "F.Cu" "B.Cu")
		(net "GND")
	)
	(via
		(at 93.549978 -51.399694)
		(size 0.508)
		(drill 0.254)
		(layers "F.Cu" "B.Cu")
		(net "GND")
	)
	(via
		(at 144.571212 -252.984)
		(size 0.7112)
		(drill 0.4064)
		(layers "F.Cu" "B.Cu")
		(net "GND")
	)
	(via
		(at 170.295316 -24.014176)
		(size 0.7112)
		(drill 0.4064)
		(layers "F.Cu" "B.Cu")
		(net "GND")
	)
	(via
		(at 297.434 -58.928)
		(size 0.5588)
		(drill 0.3048)
		(layers "F.Cu" "B.Cu")
		(net "GND")
	)
	(via
		(at 280.67 -3.81)
		(size 0.5588)
		(drill 0.254)
		(layers "F.Cu" "B.Cu")
		(net "GND")
	)
	(via
		(at 189.665864 -33.080452)
		(size 0.7112)
		(drill 0.4064)
		(layers "F.Cu" "B.Cu")
		(net "GND")
	)
	(via
		(at 285.75 -246.38)
		(size 0.7112)
		(drill 0.4064)
		(layers "F.Cu" "B.Cu")
		(net "GND")
	)
	(via
		(at 19.99996 -97.76841)
		(size 0.5588)
		(drill 0.3048)
		(layers "F.Cu" "B.Cu")
		(net "GND")
	)
	(via
		(at 183.642 -253.111)
		(size 0.508)
		(drill 0.254)
		(layers "F.Cu" "B.Cu")
		(net "GND")
	)
	(via
		(at 24.842216 -238.94288)
		(size 0.5588)
		(drill 0.3048)
		(layers "F.Cu" "B.Cu")
		(net "GND")
	)
	(via
		(at 116.50599 -108.13034)
		(size 0.5588)
		(drill 0.3048)
		(layers "F.Cu" "B.Cu")
		(net "GND")
	)
	(via
		(at 341.532718 -149.532848)
		(size 0.5588)
		(drill 0.3048)
		(layers "F.Cu" "B.Cu")
		(net "GND")
	)
	(via
		(at 108.844842 -105.837482)
		(size 0.508)
		(drill 0.254)
		(layers "F.Cu" "B.Cu")
		(net "GND")
	)
	(via
		(at 265.176 -38.862)
		(size 0.5588)
		(drill 0.3048)
		(layers "F.Cu" "B.Cu")
		(net "GND")
	)
	(via
		(at 111.506 -64.643)
		(size 0.5588)
		(drill 0.3048)
		(layers "F.Cu" "B.Cu")
		(net "GND")
	)
	(via
		(at 183.007 -121.6025)
		(size 0.508)
		(drill 0.254)
		(layers "F.Cu" "B.Cu")
		(net "GND")
	)
	(via
		(at 50.038 -227.838)
		(size 0.5588)
		(drill 0.3048)
		(layers "F.Cu" "B.Cu")
		(net "GND")
	)
	(via
		(at 171.831 -116.459)
		(size 0.5588)
		(drill 0.3048)
		(layers "F.Cu" "B.Cu")
		(net "GND")
	)
	(via
		(at 103.849678 -86.849712)
		(size 0.508)
		(drill 0.254)
		(layers "F.Cu" "B.Cu")
		(net "GND")
	)
	(via
		(at 263.906 -224.663)
		(size 0.5588)
		(drill 0.3048)
		(layers "F.Cu" "B.Cu")
		(net "GND")
	)
	(via
		(at 1.143 -159.841438)
		(size 0.7112)
		(drill 0.4064)
		(layers "F.Cu" "B.Cu")
		(net "GND")
	)
	(via
		(at 1.143 -241.121438)
		(size 0.7112)
		(drill 0.4064)
		(layers "F.Cu" "B.Cu")
		(net "GND")
	)
	(via
		(at 296.418 -81.534)
		(size 0.5588)
		(drill 0.3048)
		(layers "F.Cu" "B.Cu")
		(net "GND")
	)
	(via
		(at 101.549962 -52.99964)
		(size 0.508)
		(drill 0.254)
		(layers "F.Cu" "B.Cu")
		(net "GND")
	)
	(via
		(at 338.700872 -172.72)
		(size 0.5588)
		(drill 0.3048)
		(layers "F.Cu" "B.Cu")
		(net "GND")
	)
	(via
		(at 124.4854 -41.1734)
		(size 0.5588)
		(drill 0.3048)
		(layers "F.Cu" "B.Cu")
		(net "GND")
	)
	(via
		(at 41.45915 -132.60832)
		(size 0.5588)
		(drill 0.3048)
		(layers "F.Cu" "B.Cu")
		(net "GND")
	)
	(via
		(at 242.57 -1.27)
		(size 0.5588)
		(drill 0.254)
		(layers "F.Cu" "B.Cu")
		(net "GND")
	)
	(via
		(at 110.662212 -252.984)
		(size 0.7112)
		(drill 0.4064)
		(layers "F.Cu" "B.Cu")
		(net "GND")
	)
	(via
		(at 77.50937 -128.2446)
		(size 0.508)
		(drill 0.254)
		(layers "F.Cu" "B.Cu")
		(net "GND")
	)
	(via
		(at 99.149916 -34.600134)
		(size 0.508)
		(drill 0.254)
		(layers "F.Cu" "B.Cu")
		(net "GND")
	)
	(via
		(at 130.81 -1.27)
		(size 0.5588)
		(drill 0.254)
		(layers "F.Cu" "B.Cu")
		(net "GND")
	)
	(via
		(at 218.567 -186.436)
		(size 0.5588)
		(drill 0.3048)
		(layers "F.Cu" "B.Cu")
		(net "GND")
	)
	(via
		(at 100.711 -231.267)
		(size 0.508)
		(drill 0.254)
		(layers "F.Cu" "B.Cu")
		(net "GND")
	)
	(via
		(at 37.719 -224.663)
		(size 0.7112)
		(drill 0.3556)
		(layers "F.Cu" "B.Cu")
		(net "GND")
	)
	(via
		(at 89.535 -28.702)
		(size 0.5588)
		(drill 0.3048)
		(layers "F.Cu" "B.Cu")
		(net "GND")
	)
	(via
		(at 20.778216 -225.73488)
		(size 0.5588)
		(drill 0.3048)
		(layers "F.Cu" "B.Cu")
		(net "GND")
	)
	(via
		(at 120.850152 -86.849712)
		(size 0.508)
		(drill 0.254)
		(layers "F.Cu" "B.Cu")
		(net "GND")
	)
	(via
		(at 288.29 -205.74)
		(size 0.508)
		(drill 0.254)
		(layers "F.Cu" "B.Cu")
		(net "GND")
	)
	(via
		(at 259.151628 -231.449372)
		(size 0.5588)
		(drill 0.3048)
		(layers "F.Cu" "B.Cu")
		(net "GND")
	)
	(via
		(at 317.540132 -82.921602)
		(size 0.5588)
		(drill 0.3048)
		(layers "F.Cu" "B.Cu")
		(net "GND")
	)
	(via
		(at 153.543 -52.07)
		(size 0.508)
		(drill 0.254)
		(layers "F.Cu" "B.Cu")
		(net "GND")
	)
	(via
		(at 349.9612 -153.3652)
		(size 0.508)
		(drill 0.254)
		(layers "F.Cu" "B.Cu")
		(net "GND")
	)
	(via
		(at 184.799732 -253.111)
		(size 0.508)
		(drill 0.254)
		(layers "F.Cu" "B.Cu")
		(net "GND")
	)
	(via
		(at 126.619 -220.345)
		(size 0.5588)
		(drill 0.3048)
		(layers "F.Cu" "B.Cu")
		(net "GND")
	)
	(via
		(at 293.37 -151.003)
		(size 0.5588)
		(drill 0.3048)
		(layers "F.Cu" "B.Cu")
		(net "GND")
	)
	(via
		(at 288.43478 -180.649372)
		(size 0.508)
		(drill 0.254)
		(layers "F.Cu" "B.Cu")
		(net "GND")
	)
	(via
		(at 89.027 -1.1176)
		(size 0.5588)
		(drill 0.3048)
		(layers "F.Cu" "B.Cu")
		(net "GND")
	)
	(via
		(at 24.13 -247.65)
		(size 0.7112)
		(drill 0.4064)
		(layers "F.Cu" "B.Cu")
		(net "GND")
	)
	(via
		(at 341.532718 -150.726648)
		(size 0.5588)
		(drill 0.3048)
		(layers "F.Cu" "B.Cu")
		(net "GND")
	)
	(via
		(at 118.53037 -108.03636)
		(size 0.5588)
		(drill 0.3048)
		(layers "F.Cu" "B.Cu")
		(net "GND")
	)
	(via
		(at 111.849662 -86.849712)
		(size 0.508)
		(drill 0.254)
		(layers "F.Cu" "B.Cu")
		(net "GND")
	)
	(via
		(at 324.485 -192.405)
		(size 0.7112)
		(drill 0.4064)
		(layers "F.Cu" "B.Cu")
		(net "GND")
	)
	(via
		(at 345.647518 -141.684248)
		(size 0.5588)
		(drill 0.3048)
		(layers "F.Cu" "B.Cu")
		(net "GND")
	)
	(via
		(at 213.995 -182.753)
		(size 0.5588)
		(drill 0.3048)
		(layers "F.Cu" "B.Cu")
		(net "GND")
	)
	(via
		(at 293.230046 -174.245016)
		(size 0.508)
		(drill 0.254)
		(layers "F.Cu" "B.Cu")
		(net "GND")
	)
	(via
		(at 93.98 -15.24)
		(size 0.7112)
		(drill 0.4064)
		(layers "F.Cu" "B.Cu")
		(net "GND")
	)
	(via
		(at 153.924 -86.741)
		(size 0.7112)
		(drill 0.4064)
		(layers "F.Cu" "B.Cu")
		(net "GND")
	)
	(via
		(at 110.849664 -90.849704)
		(size 0.5588)
		(drill 0.3048)
		(layers "F.Cu" "B.Cu")
		(net "GND")
	)
	(via
		(at 46.576996 -83.492086)
		(size 0.5588)
		(drill 0.3048)
		(layers "F.Cu" "B.Cu")
		(net "GND")
	)
	(via
		(at 193.6115 -18.034)
		(size 0.5588)
		(drill 0.3048)
		(layers "F.Cu" "B.Cu")
		(net "GND")
	)
	(via
		(at 276.352 -21.717)
		(size 0.5588)
		(drill 0.3048)
		(layers "F.Cu" "B.Cu")
		(net "GND")
	)
	(via
		(at 199.517 -169.291)
		(size 0.5588)
		(drill 0.3048)
		(layers "F.Cu" "B.Cu")
		(net "GND")
	)
	(via
		(at 295.630092 -176.644808)
		(size 0.508)
		(drill 0.254)
		(layers "F.Cu" "B.Cu")
		(net "GND")
	)
	(via
		(at 288.417 -212.09)
		(size 0.508)
		(drill 0.254)
		(layers "F.Cu" "B.Cu")
		(net "GND")
	)
	(via
		(at 126.365 -211.582)
		(size 0.7112)
		(drill 0.3556)
		(layers "F.Cu" "B.Cu")
		(net "GND")
	)
	(via
		(at 109.350302 -81.493614)
		(size 0.508)
		(drill 0.254)
		(layers "F.Cu" "B.Cu")
		(net "GND")
	)
	(via
		(at 28.271216 -168.58488)
		(size 0.5588)
		(drill 0.3048)
		(layers "F.Cu" "B.Cu")
		(net "GND")
	)
	(via
		(at 283.083 -225.044)
		(size 0.5588)
		(drill 0.3048)
		(layers "F.Cu" "B.Cu")
		(net "GND")
	)
	(via
		(at 249.16384 -49.595278)
		(size 0.5588)
		(drill 0.3048)
		(layers "F.Cu" "B.Cu")
		(net "GND")
	)
	(via
		(at 292.49751 -200.139554)
		(size 0.508)
		(drill 0.254)
		(layers "F.Cu" "B.Cu")
		(net "GND")
	)
	(via
		(at 294.030146 -176.644808)
		(size 0.508)
		(drill 0.254)
		(layers "F.Cu" "B.Cu")
		(net "GND")
	)
	(via
		(at 48.73625 -203.99375)
		(size 0.5588)
		(drill 0.3048)
		(layers "F.Cu" "B.Cu")
		(net "GND")
	)
	(via
		(at 124.587 -203.2)
		(size 0.7112)
		(drill 0.4064)
		(layers "F.Cu" "B.Cu")
		(net "GND")
	)
	(via
		(at 58.801 -228.219)
		(size 0.5588)
		(drill 0.3048)
		(layers "F.Cu" "B.Cu")
		(net "GND")
	)
	(via
		(at 320.04 -111.76)
		(size 0.5588)
		(drill 0.3048)
		(layers "F.Cu" "B.Cu")
		(net "GND")
	)
	(via
		(at 87.26297 -131.318)
		(size 0.5588)
		(drill 0.3048)
		(layers "F.Cu" "B.Cu")
		(net "GND")
	)
	(via
		(at 90.17 -1.1176)
		(size 0.5588)
		(drill 0.3048)
		(layers "F.Cu" "B.Cu")
		(net "GND")
	)
	(via
		(at 295.9862 -205.64094)
		(size 0.508)
		(drill 0.254)
		(layers "F.Cu" "B.Cu")
		(net "GND")
	)
	(via
		(at 101.554026 -38.5953)
		(size 0.508)
		(drill 0.254)
		(layers "F.Cu" "B.Cu")
		(net "GND")
	)
	(via
		(at 118.850156 -88.849708)
		(size 0.508)
		(drill 0.254)
		(layers "F.Cu" "B.Cu")
		(net "GND")
	)
	(via
		(at 288.429954 -174.235618)
		(size 0.508)
		(drill 0.254)
		(layers "F.Cu" "B.Cu")
		(net "GND")
	)
	(via
		(at 34.257996 -90.096086)
		(size 0.5588)
		(drill 0.3048)
		(layers "F.Cu" "B.Cu")
		(net "GND")
	)
	(via
		(at 318.389 -77.47)
		(size 0.5588)
		(drill 0.3048)
		(layers "F.Cu" "B.Cu")
		(net "GND")
	)
	(via
		(at 40.132 -228.854)
		(size 0.5588)
		(drill 0.3048)
		(layers "F.Cu" "B.Cu")
		(net "GND")
	)
	(via
		(at 104.778302 -74.8792)
		(size 0.5588)
		(drill 0.3048)
		(layers "F.Cu" "B.Cu")
		(net "GND")
	)
	(via
		(at 176.276 -127.127)
		(size 0.7112)
		(drill 0.4064)
		(layers "F.Cu" "B.Cu")
		(net "GND")
	)
	(via
		(at 98.353626 -40.20566)
		(size 0.508)
		(drill 0.254)
		(layers "F.Cu" "B.Cu")
		(net "GND")
	)
	(via
		(at 218.7575 -164.9095)
		(size 0.5588)
		(drill 0.3048)
		(layers "F.Cu" "B.Cu")
		(net "GND")
	)
	(via
		(at 115.850162 -104.850184)
		(size 0.508)
		(drill 0.254)
		(layers "F.Cu" "B.Cu")
		(net "GND")
	)
	(via
		(at 183.315864 -31.822136)
		(size 0.5588)
		(drill 0.3048)
		(layers "F.Cu" "B.Cu")
		(net "GND")
	)
	(via
		(at 266.437872 -38.299136)
		(size 0.5588)
		(drill 0.3048)
		(layers "F.Cu" "B.Cu")
		(net "GND")
	)
	(via
		(at 184.15 -5.08)
		(size 0.5588)
		(drill 0.254)
		(layers "F.Cu" "B.Cu")
		(net "GND")
	)
	(via
		(at 86.54161 -138.64336)
		(size 0.5588)
		(drill 0.3048)
		(layers "F.Cu" "B.Cu")
		(net "GND")
	)
	(via
		(at 331.724 -198.755)
		(size 0.5588)
		(drill 0.3048)
		(layers "F.Cu" "B.Cu")
		(net "GND")
	)
	(via
		(at 291.6301 -173.444916)
		(size 0.508)
		(drill 0.254)
		(layers "F.Cu" "B.Cu")
		(net "GND")
	)
	(via
		(at 348.615 -105.41)
		(size 0.7112)
		(drill 0.4064)
		(layers "F.Cu" "B.Cu")
		(net "GND")
	)
	(via
		(at 122.409966 -32.131)
		(size 0.5588)
		(drill 0.3048)
		(layers "F.Cu" "B.Cu")
		(net "GND")
	)
	(via
		(at 128.143 -181.61)
		(size 0.7112)
		(drill 0.4064)
		(layers "F.Cu" "B.Cu")
		(net "GND")
	)
	(via
		(at 55.88 -193.04)
		(size 0.7112)
		(drill 0.4064)
		(layers "F.Cu" "B.Cu")
		(net "GND")
	)
	(via
		(at 279.4 -45.72)
		(size 0.7112)
		(drill 0.4064)
		(layers "F.Cu" "B.Cu")
		(net "GND")
	)
	(via
		(at 89.7382 -55.4736)
		(size 0.5588)
		(drill 0.3048)
		(layers "F.Cu" "B.Cu")
		(net "GND")
	)
	(via
		(at 294.829992 -177.444908)
		(size 0.508)
		(drill 0.254)
		(layers "F.Cu" "B.Cu")
		(net "GND")
	)
	(via
		(at 342.265 -29.464)
		(size 0.5588)
		(drill 0.3048)
		(layers "F.Cu" "B.Cu")
		(net "GND")
	)
	(via
		(at 200.914 -142.748)
		(size 0.5588)
		(drill 0.3048)
		(layers "F.Cu" "B.Cu")
		(net "GND")
	)
	(via
		(at 103.949754 -47.399702)
		(size 0.508)
		(drill 0.254)
		(layers "F.Cu" "B.Cu")
		(net "GND")
	)
	(via
		(at 294.030146 -177.444908)
		(size 0.508)
		(drill 0.254)
		(layers "F.Cu" "B.Cu")
		(net "GND")
	)
	(via
		(at 132.379212 -252.857)
		(size 0.7112)
		(drill 0.4064)
		(layers "F.Cu" "B.Cu")
		(net "GND")
	)
	(via
		(at 138.811 -37.465)
		(size 0.508)
		(drill 0.254)
		(layers "F.Cu" "B.Cu")
		(net "GND")
	)
	(via
		(at 314.706 -63.881)
		(size 0.5588)
		(drill 0.3048)
		(layers "F.Cu" "B.Cu")
		(net "GND")
	)
	(via
		(at 185.347864 -30.806136)
		(size 0.5588)
		(drill 0.3048)
		(layers "F.Cu" "B.Cu")
		(net "GND")
	)
	(via
		(at 83.801966 -32.639)
		(size 0.5588)
		(drill 0.3048)
		(layers "F.Cu" "B.Cu")
		(net "GND")
	)
	(via
		(at 288.408872 -216.924128)
		(size 0.5588)
		(drill 0.3048)
		(layers "F.Cu" "B.Cu")
		(net "GND")
	)
	(via
		(at 10.40003 -97.71634)
		(size 0.5588)
		(drill 0.3048)
		(layers "F.Cu" "B.Cu")
		(net "GND")
	)
	(via
		(at 205.74 -248.92)
		(size 0.5588)
		(drill 0.254)
		(layers "F.Cu" "B.Cu")
		(net "GND")
	)
	(via
		(at 100.750116 -47.399956)
		(size 0.508)
		(drill 0.254)
		(layers "F.Cu" "B.Cu")
		(net "GND")
	)
	(via
		(at 262.636 -39.37)
		(size 0.5588)
		(drill 0.3048)
		(layers "F.Cu" "B.Cu")
		(net "GND")
	)
	(via
		(at 182.88 -229.87)
		(size 0.7112)
		(drill 0.4064)
		(layers "F.Cu" "B.Cu")
		(net "GND")
	)
	(via
		(at 78.010766 -36.322)
		(size 0.508)
		(drill 0.254)
		(layers "F.Cu" "B.Cu")
		(net "GND")
	)
	(via
		(at 24.969216 -225.60788)
		(size 0.5588)
		(drill 0.3048)
		(layers "F.Cu" "B.Cu")
		(net "GND")
	)
	(via
		(at 290.07054 -205.613)
		(size 0.508)
		(drill 0.254)
		(layers "F.Cu" "B.Cu")
		(net "GND")
	)
	(via
		(at 1.143 -164.921438)
		(size 0.7112)
		(drill 0.4064)
		(layers "F.Cu" "B.Cu")
		(net "GND")
	)
	(via
		(at 328.041 -169.164)
		(size 0.5588)
		(drill 0.3048)
		(layers "F.Cu" "B.Cu")
		(net "GND")
	)
	(via
		(at 103.959152 -45.80001)
		(size 0.508)
		(drill 0.254)
		(layers "F.Cu" "B.Cu")
		(net "GND")
	)
	(via
		(at 184.776872 -208.098136)
		(size 0.5588)
		(drill 0.3048)
		(layers "F.Cu" "B.Cu")
		(net "GND")
	)
	(via
		(at 287.02 -248.92)
		(size 0.5588)
		(drill 0.254)
		(layers "F.Cu" "B.Cu")
		(net "GND")
	)
	(via
		(at 305.816 -218.948)
		(size 0.5588)
		(drill 0.3048)
		(layers "F.Cu" "B.Cu")
		(net "GND")
	)
	(via
		(at 153.543 -50.927)
		(size 0.508)
		(drill 0.254)
		(layers "F.Cu" "B.Cu")
		(net "GND")
	)
	(via
		(at 125.850142 -105.850182)
		(size 0.508)
		(drill 0.254)
		(layers "F.Cu" "B.Cu")
		(net "GND")
	)
	(via
		(at 128.442212 -78.973934)
		(size 0.508)
		(drill 0.254)
		(layers "F.Cu" "B.Cu")
		(net "GND")
	)
	(via
		(at 167.64 -112.649)
		(size 0.5588)
		(drill 0.3048)
		(layers "F.Cu" "B.Cu")
		(net "GND")
	)
	(via
		(at 286.004 -156.972)
		(size 0.5588)
		(drill 0.3048)
		(layers "F.Cu" "B.Cu")
		(net "GND")
	)
	(via
		(at 265.176 -40.005)
		(size 0.5588)
		(drill 0.3048)
		(layers "F.Cu" "B.Cu")
		(net "GND")
	)
	(via
		(at 186.250072 -192.527936)
		(size 0.5588)
		(drill 0.3048)
		(layers "F.Cu" "B.Cu")
		(net "GND")
	)
	(via
		(at 1.143 -175.081438)
		(size 0.7112)
		(drill 0.4064)
		(layers "F.Cu" "B.Cu")
		(net "GND")
	)
	(via
		(at 74.467212 -252.857)
		(size 0.7112)
		(drill 0.4064)
		(layers "F.Cu" "B.Cu")
		(net "GND")
	)
	(via
		(at 120.850152 -88.849708)
		(size 0.508)
		(drill 0.254)
		(layers "F.Cu" "B.Cu")
		(net "GND")
	)
	(via
		(at 95.149924 -53.79974)
		(size 0.508)
		(drill 0.254)
		(layers "F.Cu" "B.Cu")
		(net "GND")
	)
	(via
		(at 282.566872 -221.052136)
		(size 0.5588)
		(drill 0.3048)
		(layers "F.Cu" "B.Cu")
		(net "GND")
	)
	(via
		(at 172.974 -116.967)
		(size 0.5588)
		(drill 0.3048)
		(layers "F.Cu" "B.Cu")
		(net "GND")
	)
	(via
		(at 272.034 -18.034)
		(size 0.5588)
		(drill 0.3048)
		(layers "F.Cu" "B.Cu")
		(net "GND")
	)
	(via
		(at 82.423 -2.667)
		(size 0.5588)
		(drill 0.3048)
		(layers "F.Cu" "B.Cu")
		(net "GND")
	)
	(via
		(at 81.534 -14.478)
		(size 0.7112)
		(drill 0.4064)
		(layers "F.Cu" "B.Cu")
		(net "GND")
	)
	(via
		(at 248.92 -184.277)
		(size 0.7112)
		(drill 0.4064)
		(layers "F.Cu" "B.Cu")
		(net "GND")
	)
	(via
		(at 259.207 -225.298)
		(size 0.7112)
		(drill 0.4064)
		(layers "F.Cu" "B.Cu")
		(net "GND")
	)
	(via
		(at 111.849662 -89.849706)
		(size 0.508)
		(drill 0.254)
		(layers "F.Cu" "B.Cu")
		(net "GND")
	)
	(via
		(at 110.876842 -105.837482)
		(size 0.508)
		(drill 0.254)
		(layers "F.Cu" "B.Cu")
		(net "GND")
	)
	(via
		(at 134.62 -86.868)
		(size 0.508)
		(drill 0.254)
		(layers "F.Cu" "B.Cu")
		(net "GND")
	)
	(via
		(at 192.3288 -26.1874)
		(size 0.5588)
		(drill 0.3048)
		(layers "F.Cu" "B.Cu")
		(net "GND")
	)
	(via
		(at 66.339212 -249.18416)
		(size 0.7112)
		(drill 0.4064)
		(layers "F.Cu" "B.Cu")
		(net "GND")
	)
	(via
		(at 101.549962 -55.399686)
		(size 0.508)
		(drill 0.254)
		(layers "F.Cu" "B.Cu")
		(net "GND")
	)
	(via
		(at 314.579 -82.80019)
		(size 0.5588)
		(drill 0.3048)
		(layers "F.Cu" "B.Cu")
		(net "GND")
	)
	(via
		(at 131.490466 -31.9405)
		(size 0.5588)
		(drill 0.3048)
		(layers "F.Cu" "B.Cu")
		(net "GND")
	)
	(via
		(at 118.282466 -48.9204)
		(size 0.508)
		(drill 0.254)
		(layers "F.Cu" "B.Cu")
		(net "GND")
	)
	(via
		(at 77.10043 -113.24336)
		(size 0.5588)
		(drill 0.3048)
		(layers "F.Cu" "B.Cu")
		(net "GND")
	)
	(via
		(at 118.850156 -90.849704)
		(size 0.508)
		(drill 0.254)
		(layers "F.Cu" "B.Cu")
		(net "GND")
	)
	(via
		(at 108.749846 -41.79951)
		(size 0.508)
		(drill 0.254)
		(layers "F.Cu" "B.Cu")
		(net "GND")
	)
	(via
		(at 108.749846 -43.39971)
		(size 0.508)
		(drill 0.254)
		(layers "F.Cu" "B.Cu")
		(net "GND")
	)
	(via
		(at 132.969 -86.868)
		(size 0.508)
		(drill 0.254)
		(layers "F.Cu" "B.Cu")
		(net "GND")
	)
	(via
		(at 262.89 -223.647)
		(size 0.5588)
		(drill 0.3048)
		(layers "F.Cu" "B.Cu")
		(net "GND")
	)
	(via
		(at 97.54997 -48.999648)
		(size 0.508)
		(drill 0.254)
		(layers "F.Cu" "B.Cu")
		(net "GND")
	)
	(via
		(at 124.850144 -84.849716)
		(size 0.508)
		(drill 0.254)
		(layers "F.Cu" "B.Cu")
		(net "GND")
	)
	(via
		(at 64.40297 -155.829)
		(size 0.5588)
		(drill 0.3048)
		(layers "F.Cu" "B.Cu")
		(net "GND")
	)
	(via
		(at 291.6301 -175.044862)
		(size 0.508)
		(drill 0.254)
		(layers "F.Cu" "B.Cu")
		(net "GND")
	)
	(via
		(at 81.534 -13.335)
		(size 0.7112)
		(drill 0.4064)
		(layers "F.Cu" "B.Cu")
		(net "GND")
	)
	(via
		(at 342.726518 -150.726648)
		(size 0.5588)
		(drill 0.3048)
		(layers "F.Cu" "B.Cu")
		(net "GND")
	)
	(via
		(at 88.5952 -56.134)
		(size 0.7112)
		(drill 0.3556)
		(layers "F.Cu" "B.Cu")
		(net "GND")
	)
	(via
		(at 195.8086 -36.6522)
		(size 0.5588)
		(drill 0.3048)
		(layers "F.Cu" "B.Cu")
		(net "GND")
	)
	(via
		(at 87.14613 -113.3348)
		(size 0.5588)
		(drill 0.3048)
		(layers "F.Cu" "B.Cu")
		(net "GND")
	)
	(via
		(at 121.85015 -98.850196)
		(size 0.508)
		(drill 0.254)
		(layers "F.Cu" "B.Cu")
		(net "GND")
	)
	(via
		(at 126.85014 -103.850186)
		(size 0.508)
		(drill 0.254)
		(layers "F.Cu" "B.Cu")
		(net "GND")
	)
	(via
		(at 119.850154 -81.849722)
		(size 0.508)
		(drill 0.254)
		(layers "F.Cu" "B.Cu")
		(net "GND")
	)
	(via
		(at 1.143 -220.801438)
		(size 0.7112)
		(drill 0.4064)
		(layers "F.Cu" "B.Cu")
		(net "GND")
	)
	(via
		(at 1.143 -139.521438)
		(size 0.7112)
		(drill 0.4064)
		(layers "F.Cu" "B.Cu")
		(net "GND")
	)
	(via
		(at 125.850142 -106.85018)
		(size 0.508)
		(drill 0.254)
		(layers "F.Cu" "B.Cu")
		(net "GND")
	)
	(via
		(at 280.67 -19.05)
		(size 0.5588)
		(drill 0.254)
		(layers "F.Cu" "B.Cu")
		(net "GND")
	)
	(via
		(at 347.882718 -141.481048)
		(size 0.5588)
		(drill 0.3048)
		(layers "F.Cu" "B.Cu")
		(net "GND")
	)
	(via
		(at 45.974 -228.854)
		(size 0.5588)
		(drill 0.3048)
		(layers "F.Cu" "B.Cu")
		(net "GND")
	)
	(via
		(at 327.152 -112.268)
		(size 0.7112)
		(drill 0.4064)
		(layers "F.Cu" "B.Cu")
		(net "GND")
	)
	(via
		(at 105.55605 -42.596562)
		(size 0.508)
		(drill 0.254)
		(layers "F.Cu" "B.Cu")
		(net "GND")
	)
	(via
		(at 273.685 -38.1)
		(size 0.7112)
		(drill 0.4064)
		(layers "F.Cu" "B.Cu")
		(net "GND")
	)
	(via
		(at 155.829 -192.786)
		(size 0.7112)
		(drill 0.4064)
		(layers "F.Cu" "B.Cu")
		(net "GND")
	)
	(via
		(at 134.641082 -252.857)
		(size 0.7112)
		(drill 0.4064)
		(layers "F.Cu" "B.Cu")
		(net "GND")
	)
	(via
		(at 106.350054 -53.79974)
		(size 0.508)
		(drill 0.254)
		(layers "F.Cu" "B.Cu")
		(net "GND")
	)
	(via
		(at 280.67 -34.29)
		(size 0.5588)
		(drill 0.254)
		(layers "F.Cu" "B.Cu")
		(net "GND")
	)
	(via
		(at 81.534 -12.192)
		(size 0.7112)
		(drill 0.4064)
		(layers "F.Cu" "B.Cu")
		(net "GND")
	)
	(via
		(at 290.89731 -197.34403)
		(size 0.508)
		(drill 0.254)
		(layers "F.Cu" "B.Cu")
		(net "GND")
	)
	(via
		(at 126.435612 -215.138)
		(size 0.5588)
		(drill 0.3048)
		(layers "F.Cu" "B.Cu")
		(net "GND")
	)
	(via
		(at 115.850162 -92.8497)
		(size 0.508)
		(drill 0.254)
		(layers "F.Cu" "B.Cu")
		(net "GND")
	)
	(via
		(at 186.563 -139.065)
		(size 0.5588)
		(drill 0.3048)
		(layers "F.Cu" "B.Cu")
		(net "GND")
	)
	(via
		(at 170.312588 -33.0708)
		(size 0.7112)
		(drill 0.4064)
		(layers "F.Cu" "B.Cu")
		(net "GND")
	)
	(via
		(at 132.969 -90.805)
		(size 0.508)
		(drill 0.254)
		(layers "F.Cu" "B.Cu")
		(net "GND")
	)
	(via
		(at 116.504212 -252.984)
		(size 0.7112)
		(drill 0.4064)
		(layers "F.Cu" "B.Cu")
		(net "GND")
	)
	(via
		(at 124.850144 -105.850182)
		(size 0.508)
		(drill 0.254)
		(layers "F.Cu" "B.Cu")
		(net "GND")
	)
	(via
		(at 1.143 -185.241438)
		(size 0.7112)
		(drill 0.4064)
		(layers "F.Cu" "B.Cu")
		(net "GND")
	)
	(via
		(at 316.3951 -208.7499)
		(size 0.5588)
		(drill 0.3048)
		(layers "F.Cu" "B.Cu")
		(net "GND")
	)
	(via
		(at 104.121966 -62.3316)
		(size 0.5588)
		(drill 0.3048)
		(layers "F.Cu" "B.Cu")
		(net "GND")
	)
	(via
		(at 113.849658 -88.849708)
		(size 0.508)
		(drill 0.254)
		(layers "F.Cu" "B.Cu")
		(net "GND")
	)
	(via
		(at 352.3488 -148.3614)
		(size 0.508)
		(drill 0.254)
		(layers "F.Cu" "B.Cu")
		(net "GND")
	)
	(via
		(at 283.083 -217.297)
		(size 0.7112)
		(drill 0.4064)
		(layers "F.Cu" "B.Cu")
		(net "GND")
	)
	(via
		(at 176.276 -122.809)
		(size 0.7112)
		(drill 0.4064)
		(layers "F.Cu" "B.Cu")
		(net "GND")
	)
	(via
		(at 25.858216 -238.94288)
		(size 0.5588)
		(drill 0.3048)
		(layers "F.Cu" "B.Cu")
		(net "GND")
	)
	(via
		(at 165.1 -27.94)
		(size 0.7112)
		(drill 0.4064)
		(layers "F.Cu" "B.Cu")
		(net "GND")
	)
	(via
		(at 109.773212 -202.692)
		(size 0.5588)
		(drill 0.3048)
		(layers "F.Cu" "B.Cu")
		(net "GND")
	)
	(via
		(at 82.423 -1.524)
		(size 0.5588)
		(drill 0.3048)
		(layers "F.Cu" "B.Cu")
		(net "GND")
	)
	(via
		(at 107.156504 -44.19727)
		(size 0.508)
		(drill 0.254)
		(layers "F.Cu" "B.Cu")
		(net "GND")
	)
	(via
		(at 189.3316 -222.9104)
		(size 0.5588)
		(drill 0.3048)
		(layers "F.Cu" "B.Cu")
		(net "GND")
	)
	(via
		(at 115.850162 -83.849718)
		(size 0.508)
		(drill 0.254)
		(layers "F.Cu" "B.Cu")
		(net "GND")
	)
	(via
		(at 145.17497 -82.804)
		(size 0.5588)
		(drill 0.3048)
		(layers "F.Cu" "B.Cu")
		(net "GND")
	)
	(via
		(at 193.07175 -169.38625)
		(size 0.5588)
		(drill 0.3048)
		(layers "F.Cu" "B.Cu")
		(net "GND")
	)
	(via
		(at 266.954 -225.679)
		(size 0.7112)
		(drill 0.4064)
		(layers "F.Cu" "B.Cu")
		(net "GND")
	)
	(via
		(at 107.156504 -45.797216)
		(size 0.508)
		(drill 0.254)
		(layers "F.Cu" "B.Cu")
		(net "GND")
	)
	(via
		(at 126.435612 -214.122)
		(size 0.5588)
		(drill 0.3048)
		(layers "F.Cu" "B.Cu")
		(net "GND")
	)
	(via
		(at 280.67 -26.67)
		(size 0.5588)
		(drill 0.254)
		(layers "F.Cu" "B.Cu")
		(net "GND")
	)
	(via
		(at 59.055 -106.426)
		(size 0.5588)
		(drill 0.3048)
		(layers "F.Cu" "B.Cu")
		(net "GND")
	)
	(via
		(at 91.956636 -40.997124)
		(size 0.508)
		(drill 0.254)
		(layers "F.Cu" "B.Cu")
		(net "GND")
	)
	(via
		(at 115.850162 -99.850194)
		(size 0.508)
		(drill 0.254)
		(layers "F.Cu" "B.Cu")
		(net "GND")
	)
	(via
		(at 87.484966 -79.248)
		(size 0.5588)
		(drill 0.3048)
		(layers "F.Cu" "B.Cu")
		(net "GND")
	)
	(via
		(at 181.61 -1.27)
		(size 0.5588)
		(drill 0.254)
		(layers "F.Cu" "B.Cu")
		(net "GND")
	)
	(via
		(at 304.038 -104.013)
		(size 0.5588)
		(drill 0.3048)
		(layers "F.Cu" "B.Cu")
		(net "GND")
	)
	(via
		(at 110.350046 -45.799756)
		(size 0.508)
		(drill 0.254)
		(layers "F.Cu" "B.Cu")
		(net "GND")
	)
	(via
		(at 286.49803 -203.18349)
		(size 0.508)
		(drill 0.254)
		(layers "F.Cu" "B.Cu")
		(net "GND")
	)
	(via
		(at 176.276 -130.556)
		(size 0.7112)
		(drill 0.4064)
		(layers "F.Cu" "B.Cu")
		(net "GND")
	)
	(via
		(at 324.358 -180.975)
		(size 0.508)
		(drill 0.254)
		(layers "F.Cu" "B.Cu")
		(net "GND")
	)
	(via
		(at 262.128 -20.955)
		(size 0.7112)
		(drill 0.4064)
		(layers "F.Cu" "B.Cu")
		(net "GND")
	)
	(via
		(at 315.411358 -67.4878)
		(size 0.5588)
		(drill 0.3048)
		(layers "F.Cu" "B.Cu")
		(net "GND")
	)
	(via
		(at 251.11964 -48.387)
		(size 0.5588)
		(drill 0.3048)
		(layers "F.Cu" "B.Cu")
		(net "GND")
	)
	(via
		(at 81.340452 -126.284482)
		(size 0.508)
		(drill 0.254)
		(layers "F.Cu" "B.Cu")
		(net "GND")
	)
	(via
		(at 124.841 -89.789)
		(size 0.508)
		(drill 0.254)
		(layers "F.Cu" "B.Cu")
		(net "GND")
	)
	(via
		(at 106.242612 -215.011)
		(size 0.5588)
		(drill 0.3048)
		(layers "F.Cu" "B.Cu")
		(net "GND")
	)
	(via
		(at 273.05 -246.38)
		(size 0.7112)
		(drill 0.4064)
		(layers "F.Cu" "B.Cu")
		(net "GND")
	)
	(via
		(at 126.85014 -104.850184)
		(size 0.508)
		(drill 0.254)
		(layers "F.Cu" "B.Cu")
		(net "GND")
	)
	(via
		(at 107.84967 -89.849706)
		(size 0.508)
		(drill 0.254)
		(layers "F.Cu" "B.Cu")
		(net "GND")
	)
	(via
		(at 294.030146 -174.245016)
		(size 0.508)
		(drill 0.254)
		(layers "F.Cu" "B.Cu")
		(net "GND")
	)
	(via
		(at 100.749862 -52.199794)
		(size 0.508)
		(drill 0.254)
		(layers "F.Cu" "B.Cu")
		(net "GND")
	)
	(via
		(at 1.143 -246.201438)
		(size 0.7112)
		(drill 0.4064)
		(layers "F.Cu" "B.Cu")
		(net "GND")
	)
	(via
		(at 201.803 -249.428)
		(size 0.7112)
		(drill 0.4064)
		(layers "F.Cu" "B.Cu")
		(net "GND")
	)
	(via
		(at 113.849658 -96.8502)
		(size 0.508)
		(drill 0.254)
		(layers "F.Cu" "B.Cu")
		(net "GND")
	)
	(via
		(at 206.756 -215.773)
		(size 0.5588)
		(drill 0.3048)
		(layers "F.Cu" "B.Cu")
		(net "GND")
	)
	(via
		(at 126.85014 -81.849722)
		(size 0.508)
		(drill 0.254)
		(layers "F.Cu" "B.Cu")
		(net "GND")
	)
	(via
		(at 340.4108 -111.3282)
		(size 0.5588)
		(drill 0.3048)
		(layers "F.Cu" "B.Cu")
		(net "GND")
	)
	(via
		(at 284.6324 -71.7042)
		(size 0.5588)
		(drill 0.3048)
		(layers "F.Cu" "B.Cu")
		(net "GND")
	)
	(via
		(at 116.186966 -43.561)
		(size 0.5588)
		(drill 0.3048)
		(layers "F.Cu" "B.Cu")
		(net "GND")
	)
	(via
		(at 224.56648 -89.31402)
		(size 0.5588)
		(drill 0.3048)
		(layers "F.Cu" "B.Cu")
		(net "GND")
	)
	(via
		(at 344.043 -178.689)
		(size 0.7112)
		(drill 0.4064)
		(layers "F.Cu" "B.Cu")
		(net "GND")
	)
	(via
		(at 99.15017 -36.20008)
		(size 0.508)
		(drill 0.254)
		(layers "F.Cu" "B.Cu")
		(net "GND")
	)
	(via
		(at 52.199794 -81.460086)
		(size 0.5588)
		(drill 0.3048)
		(layers "F.Cu" "B.Cu")
		(net "GND")
	)
	(via
		(at 125.87097 -93.853)
		(size 0.5588)
		(drill 0.3048)
		(layers "F.Cu" "B.Cu")
		(net "GND")
	)
	(via
		(at 201.676 -183.769)
		(size 0.5588)
		(drill 0.3048)
		(layers "F.Cu" "B.Cu")
		(net "GND")
	)
	(via
		(at 322.444872 -112.848136)
		(size 0.5588)
		(drill 0.3048)
		(layers "F.Cu" "B.Cu")
		(net "GND")
	)
	(via
		(at 21.794216 -207.31988)
		(size 0.5588)
		(drill 0.3048)
		(layers "F.Cu" "B.Cu")
		(net "GND")
	)
	(via
		(at 338.201 -109.855)
		(size 0.7112)
		(drill 0.4064)
		(layers "F.Cu" "B.Cu")
		(net "GND")
	)
	(via
		(at 320.294 -53.721)
		(size 0.5588)
		(drill 0.3048)
		(layers "F.Cu" "B.Cu")
		(net "GND")
	)
	(via
		(at 93.98 -14.097)
		(size 0.7112)
		(drill 0.4064)
		(layers "F.Cu" "B.Cu")
		(net "GND")
	)
	(via
		(at 120.850152 -95.850202)
		(size 0.508)
		(drill 0.254)
		(layers "F.Cu" "B.Cu")
		(net "GND")
	)
	(via
		(at 128.442212 -252.857)
		(size 0.7112)
		(drill 0.4064)
		(layers "F.Cu" "B.Cu")
		(net "GND")
	)
	(via
		(at 267.97 -246.38)
		(size 0.7112)
		(drill 0.4064)
		(layers "F.Cu" "B.Cu")
		(net "GND")
	)
	(via
		(at 325.755 -163.83)
		(size 0.5588)
		(drill 0.3048)
		(layers "F.Cu" "B.Cu")
		(net "GND")
	)
	(via
		(at 205.74 -30.48)
		(size 0.7112)
		(drill 0.4064)
		(layers "F.Cu" "B.Cu")
		(net "GND")
	)
	(via
		(at 278.765 -199.263)
		(size 0.5588)
		(drill 0.3048)
		(layers "F.Cu" "B.Cu")
		(net "GND")
	)
	(via
		(at 111.76 -1.27)
		(size 0.5588)
		(drill 0.254)
		(layers "F.Cu" "B.Cu")
		(net "GND")
	)
	(via
		(at 269.369286 -44.990004)
		(size 0.5588)
		(drill 0.3048)
		(layers "F.Cu" "B.Cu")
		(net "GND")
	)
	(via
		(at 245.11 -184.277)
		(size 0.7112)
		(drill 0.4064)
		(layers "F.Cu" "B.Cu")
		(net "GND")
	)
	(via
		(at 103.849678 -107.850178)
		(size 0.508)
		(drill 0.254)
		(layers "F.Cu" "B.Cu")
		(net "GND")
	)
	(via
		(at 253.492 -117.221)
		(size 0.5588)
		(drill 0.3048)
		(layers "F.Cu" "B.Cu")
		(net "GND")
	)
	(via
		(at 1.143 -103.961438)
		(size 0.7112)
		(drill 0.4064)
		(layers "F.Cu" "B.Cu")
		(net "GND")
	)
	(via
		(at 92.075 -16.256)
		(size 0.7112)
		(drill 0.4064)
		(layers "F.Cu" "B.Cu")
		(net "GND")
	)
	(via
		(at 183.315864 -30.806136)
		(size 0.5588)
		(drill 0.3048)
		(layers "F.Cu" "B.Cu")
		(net "GND")
	)
	(via
		(at 295.783 -226.06)
		(size 0.7112)
		(drill 0.4064)
		(layers "F.Cu" "B.Cu")
		(net "GND")
	)
	(via
		(at 258.387596 -55.695596)
		(size 0.5588)
		(drill 0.3048)
		(layers "F.Cu" "B.Cu")
		(net "GND")
	)
	(via
		(at 116.84 -1.27)
		(size 0.5588)
		(drill 0.254)
		(layers "F.Cu" "B.Cu")
		(net "GND")
	)
	(via
		(at 105.849674 -107.850178)
		(size 0.508)
		(drill 0.254)
		(layers "F.Cu" "B.Cu")
		(net "GND")
	)
	(via
		(at 263.144 -50.673)
		(size 0.5588)
		(drill 0.3048)
		(layers "F.Cu" "B.Cu")
		(net "GND")
	)
	(via
		(at 319.913 -183.896)
		(size 0.508)
		(drill 0.254)
		(layers "F.Cu" "B.Cu")
		(net "GND")
	)
	(via
		(at 114.345212 -252.984)
		(size 0.7112)
		(drill 0.4064)
		(layers "F.Cu" "B.Cu")
		(net "GND")
	)
	(via
		(at 172.974 -114.808)
		(size 0.5588)
		(drill 0.3048)
		(layers "F.Cu" "B.Cu")
		(net "GND")
	)
	(via
		(at 94.472252 -234.299252)
		(size 0.5588)
		(drill 0.3048)
		(layers "F.Cu" "B.Cu")
		(net "GND")
	)
	(via
		(at 270.51 -39.116)
		(size 0.7112)
		(drill 0.4064)
		(layers "F.Cu" "B.Cu")
		(net "GND")
	)
	(via
		(at 165.227 -25.654)
		(size 0.5588)
		(drill 0.3048)
		(layers "F.Cu" "B.Cu")
		(net "GND")
	)
	(via
		(at 181.791864 -20.993608)
		(size 0.5588)
		(drill 0.3048)
		(layers "F.Cu" "B.Cu")
		(net "GND")
	)
	(via
		(at 113.849658 -98.850196)
		(size 0.508)
		(drill 0.254)
		(layers "F.Cu" "B.Cu")
		(net "GND")
	)
	(via
		(at 300.99 -248.92)
		(size 0.5588)
		(drill 0.254)
		(layers "F.Cu" "B.Cu")
		(net "GND")
	)
	(via
		(at 109.549946 -44.999656)
		(size 0.508)
		(drill 0.254)
		(layers "F.Cu" "B.Cu")
		(net "GND")
	)
	(via
		(at 169.607992 -26.416)
		(size 0.5588)
		(drill 0.3048)
		(layers "F.Cu" "B.Cu")
		(net "GND")
	)
	(via
		(at 103.849678 -95.850202)
		(size 0.508)
		(drill 0.254)
		(layers "F.Cu" "B.Cu")
		(net "GND")
	)
	(via
		(at 223.139 -176.657)
		(size 0.5588)
		(drill 0.3048)
		(layers "F.Cu" "B.Cu")
		(net "GND")
	)
	(via
		(at 199.3646 -115.062)
		(size 0.5588)
		(drill 0.3048)
		(layers "F.Cu" "B.Cu")
		(net "GND")
	)
	(via
		(at 124.850144 -106.85018)
		(size 0.508)
		(drill 0.254)
		(layers "F.Cu" "B.Cu")
		(net "GND")
	)
	(via
		(at 105.559098 -45.80001)
		(size 0.508)
		(drill 0.254)
		(layers "F.Cu" "B.Cu")
		(net "GND")
	)
	(via
		(at 123.850146 -105.850182)
		(size 0.508)
		(drill 0.254)
		(layers "F.Cu" "B.Cu")
		(net "GND")
	)
	(via
		(at 345.44 -248.92)
		(size 0.5588)
		(drill 0.254)
		(layers "F.Cu" "B.Cu")
		(net "GND")
	)
	(via
		(at 208.407 -194.437)
		(size 0.7112)
		(drill 0.4064)
		(layers "F.Cu" "B.Cu")
		(net "GND")
	)
	(via
		(at 75.946 -37.592)
		(size 0.508)
		(drill 0.254)
		(layers "F.Cu" "B.Cu")
		(net "GND")
	)
	(via
		(at 86.532466 -52.0446)
		(size 0.5588)
		(drill 0.3048)
		(layers "F.Cu" "B.Cu")
		(net "GND")
	)
	(via
		(at 197.485 -89.154)
		(size 0.7112)
		(drill 0.4064)
		(layers "F.Cu" "B.Cu")
		(net "GND")
	)
	(via
		(at 124.850144 -97.850198)
		(size 0.508)
		(drill 0.254)
		(layers "F.Cu" "B.Cu")
		(net "GND")
	)
	(via
		(at 308.737 -153.7462)
		(size 0.5588)
		(drill 0.3048)
		(layers "F.Cu" "B.Cu")
		(net "GND")
	)
	(via
		(at 76.499212 -252.857)
		(size 0.7112)
		(drill 0.4064)
		(layers "F.Cu" "B.Cu")
		(net "GND")
	)
	(via
		(at 95.94977 -51.399694)
		(size 0.508)
		(drill 0.254)
		(layers "F.Cu" "B.Cu")
		(net "GND")
	)
	(via
		(at 91.950286 -37.800026)
		(size 0.508)
		(drill 0.254)
		(layers "F.Cu" "B.Cu")
		(net "GND")
	)
	(via
		(at 94.35338 -42.606214)
		(size 0.508)
		(drill 0.254)
		(layers "F.Cu" "B.Cu")
		(net "GND")
	)
	(via
		(at 337.82 -108.712)
		(size 0.7112)
		(drill 0.4064)
		(layers "F.Cu" "B.Cu")
		(net "GND")
	)
	(via
		(at 345.059 -73.384664)
		(size 0.5588)
		(drill 0.3048)
		(layers "F.Cu" "B.Cu")
		(net "GND")
	)
	(via
		(at 237.998 -16.002)
		(size 0.508)
		(drill 0.254)
		(layers "F.Cu" "B.Cu")
		(net "GND")
	)
	(via
		(at 66.04 -193.04)
		(size 0.7112)
		(drill 0.4064)
		(layers "F.Cu" "B.Cu")
		(net "GND")
	)
	(via
		(at 350.139 -91.44)
		(size 0.7112)
		(drill 0.4064)
		(layers "F.Cu" "B.Cu")
		(net "GND")
	)
	(via
		(at 52.324 -249.428)
		(size 0.7112)
		(drill 0.4064)
		(layers "F.Cu" "B.Cu")
		(net "GND")
	)
	(via
		(at 292.4302 -177.444908)
		(size 0.508)
		(drill 0.254)
		(layers "F.Cu" "B.Cu")
		(net "GND")
	)
	(via
		(at 262.128 -26.289)
		(size 0.7112)
		(drill 0.4064)
		(layers "F.Cu" "B.Cu")
		(net "GND")
	)
	(via
		(at 298.829984 -177.435256)
		(size 0.508)
		(drill 0.254)
		(layers "F.Cu" "B.Cu")
		(net "GND")
	)
	(via
		(at 103.949754 -48.999648)
		(size 0.508)
		(drill 0.254)
		(layers "F.Cu" "B.Cu")
		(net "GND")
	)
	(via
		(at 112.948212 -202.7936)
		(size 0.5588)
		(drill 0.3048)
		(layers "F.Cu" "B.Cu")
		(net "GND")
	)
	(via
		(at 291.9476 -203.2)
		(size 0.508)
		(drill 0.254)
		(layers "F.Cu" "B.Cu")
		(net "GND")
	)
	(via
		(at 303.868836 -73.802494)
		(size 0.5588)
		(drill 0.3048)
		(layers "F.Cu" "B.Cu")
		(net "GND")
	)
	(via
		(at 94.350332 -36.20008)
		(size 0.508)
		(drill 0.254)
		(layers "F.Cu" "B.Cu")
		(net "GND")
	)
	(via
		(at 85.6996 -34.163)
		(size 0.508)
		(drill 0.254)
		(layers "F.Cu" "B.Cu")
		(net "GND")
	)
	(via
		(at 123.850146 -102.850188)
		(size 0.508)
		(drill 0.254)
		(layers "F.Cu" "B.Cu")
		(net "GND")
	)
	(via
		(at 215.011 -91.948)
		(size 0.7112)
		(drill 0.4064)
		(layers "F.Cu" "B.Cu")
		(net "GND")
	)
	(via
		(at 93.549978 -49.799748)
		(size 0.508)
		(drill 0.254)
		(layers "F.Cu" "B.Cu")
		(net "GND")
	)
	(via
		(at 294.030146 -175.044862)
		(size 0.508)
		(drill 0.254)
		(layers "F.Cu" "B.Cu")
		(net "GND")
	)
	(via
		(at 292.439598 -170.245024)
		(size 0.508)
		(drill 0.254)
		(layers "F.Cu" "B.Cu")
		(net "GND")
	)
	(via
		(at 124.850144 -101.85019)
		(size 0.508)
		(drill 0.254)
		(layers "F.Cu" "B.Cu")
		(net "GND")
	)
	(via
		(at 1.143 -83.641438)
		(size 0.7112)
		(drill 0.4064)
		(layers "F.Cu" "B.Cu")
		(net "GND")
	)
	(via
		(at 121.85015 -96.8502)
		(size 0.508)
		(drill 0.254)
		(layers "F.Cu" "B.Cu")
		(net "GND")
	)
	(via
		(at 286.05734 -191.21374)
		(size 0.5588)
		(drill 0.3048)
		(layers "F.Cu" "B.Cu")
		(net "GND")
	)
	(via
		(at 323.2658 -176.5046)
		(size 0.508)
		(drill 0.254)
		(layers "F.Cu" "B.Cu")
		(net "GND")
	)
	(via
		(at 293.37 -248.92)
		(size 0.5588)
		(drill 0.254)
		(layers "F.Cu" "B.Cu")
		(net "GND")
	)
	(via
		(at 103.849678 -92.8497)
		(size 0.508)
		(drill 0.254)
		(layers "F.Cu" "B.Cu")
		(net "GND")
	)
	(via
		(at 330.399136 -213.033864)
		(size 0.5588)
		(drill 0.3048)
		(layers "F.Cu" "B.Cu")
		(net "GND")
	)
	(via
		(at 262.89 -225.679)
		(size 0.5588)
		(drill 0.3048)
		(layers "F.Cu" "B.Cu")
		(net "GND")
	)
	(via
		(at 294.097964 -202.144376)
		(size 0.508)
		(drill 0.254)
		(layers "F.Cu" "B.Cu")
		(net "GND")
	)
	(via
		(at 190.732664 -33.089088)
		(size 0.7112)
		(drill 0.4064)
		(layers "F.Cu" "B.Cu")
		(net "GND")
	)
	(via
		(at 178.645312 -203.236576)
		(size 0.5588)
		(drill 0.3048)
		(layers "F.Cu" "B.Cu")
		(net "GND")
	)
	(via
		(at 60.96 -210.6295)
		(size 0.5588)
		(drill 0.3048)
		(layers "F.Cu" "B.Cu")
		(net "GND")
	)
	(via
		(at 100.750116 -53.79974)
		(size 0.508)
		(drill 0.254)
		(layers "F.Cu" "B.Cu")
		(net "GND")
	)
	(via
		(at 262.128 -22.86)
		(size 0.7112)
		(drill 0.4064)
		(layers "F.Cu" "B.Cu")
		(net "GND")
	)
	(via
		(at 179.33797 -65.659)
		(size 0.5588)
		(drill 0.3048)
		(layers "F.Cu" "B.Cu")
		(net "GND")
	)
	(via
		(at 255.905 -123.825)
		(size 0.5588)
		(drill 0.3048)
		(layers "F.Cu" "B.Cu")
		(net "GND")
	)
	(via
		(at 101.550216 -37.00018)
		(size 0.508)
		(drill 0.254)
		(layers "F.Cu" "B.Cu")
		(net "GND")
	)
	(via
		(at 258.191 -131.953)
		(size 0.5588)
		(drill 0.3048)
		(layers "F.Cu" "B.Cu")
		(net "GND")
	)
	(via
		(at 229.108 -16.002)
		(size 0.508)
		(drill 0.254)
		(layers "F.Cu" "B.Cu")
		(net "GND")
	)
	(via
		(at 143.002 -115.062)
		(size 0.7112)
		(drill 0.4064)
		(layers "F.Cu" "B.Cu")
		(net "GND")
	)
	(via
		(at 37.432996 -90.096086)
		(size 0.5588)
		(drill 0.3048)
		(layers "F.Cu" "B.Cu")
		(net "GND")
	)
	(via
		(at 186.055 -123.317)
		(size 0.5588)
		(drill 0.3048)
		(layers "F.Cu" "B.Cu")
		(net "GND")
	)
	(via
		(at 111.297212 -202.819)
		(size 0.5588)
		(drill 0.3048)
		(layers "F.Cu" "B.Cu")
		(net "GND")
	)
	(via
		(at 65.659 -155.829)
		(size 0.5588)
		(drill 0.3048)
		(layers "F.Cu" "B.Cu")
		(net "GND")
	)
	(via
		(at 129.90957 -86.0298)
		(size 0.508)
		(drill 0.254)
		(layers "F.Cu" "B.Cu")
		(net "GND")
	)
	(via
		(at 94.358206 -40.998394)
		(size 0.508)
		(drill 0.254)
		(layers "F.Cu" "B.Cu")
		(net "GND")
	)
	(via
		(at 213.868 -93.218)
		(size 0.7112)
		(drill 0.4064)
		(layers "F.Cu" "B.Cu")
		(net "GND")
	)
	(via
		(at 1.143 -93.801438)
		(size 0.7112)
		(drill 0.4064)
		(layers "F.Cu" "B.Cu")
		(net "GND")
	)
	(via
		(at 124.850144 -86.849712)
		(size 0.508)
		(drill 0.254)
		(layers "F.Cu" "B.Cu")
		(net "GND")
	)
	(via
		(at 306.832 -75.600052)
		(size 0.5588)
		(drill 0.3048)
		(layers "F.Cu" "B.Cu")
		(net "GND")
	)
	(via
		(at 299.085 -73.66)
		(size 0.5588)
		(drill 0.3048)
		(layers "F.Cu" "B.Cu")
		(net "GND")
	)
	(via
		(at 130.429 -80.2132)
		(size 0.508)
		(drill 0.254)
		(layers "F.Cu" "B.Cu")
		(net "GND")
	)
	(via
		(at 16.333216 -177.47488)
		(size 0.5588)
		(drill 0.3048)
		(layers "F.Cu" "B.Cu")
		(net "GND")
	)
	(via
		(at 317.9318 -69.596)
		(size 0.5588)
		(drill 0.3048)
		(layers "F.Cu" "B.Cu")
		(net "GND")
	)
	(via
		(at 276.86 -5.08)
		(size 0.5588)
		(drill 0.254)
		(layers "F.Cu" "B.Cu")
		(net "GND")
	)
	(via
		(at 101.549962 -56.199786)
		(size 0.508)
		(drill 0.254)
		(layers "F.Cu" "B.Cu")
		(net "GND")
	)
	(via
		(at 95.943674 -45.796708)
		(size 0.508)
		(drill 0.254)
		(layers "F.Cu" "B.Cu")
		(net "GND")
	)
	(via
		(at 322.444872 -113.864136)
		(size 0.5588)
		(drill 0.3048)
		(layers "F.Cu" "B.Cu")
		(net "GND")
	)
	(via
		(at 168.529 -114.808)
		(size 0.5588)
		(drill 0.3048)
		(layers "F.Cu" "B.Cu")
		(net "GND")
	)
	(via
		(at 216.5604 -220.599)
		(size 0.5588)
		(drill 0.3048)
		(layers "F.Cu" "B.Cu")
		(net "GND")
	)
	(via
		(at 1.143 -180.161438)
		(size 0.7112)
		(drill 0.4064)
		(layers "F.Cu" "B.Cu")
		(net "GND")
	)
	(via
		(at 211.455 -102.616)
		(size 0.5588)
		(drill 0.3048)
		(layers "F.Cu" "B.Cu")
		(net "GND")
	)
	(via
		(at 332.439518 -151.234648)
		(size 0.5588)
		(drill 0.3048)
		(layers "F.Cu" "B.Cu")
		(net "GND")
	)
	(via
		(at 121.85015 -104.850184)
		(size 0.508)
		(drill 0.254)
		(layers "F.Cu" "B.Cu")
		(net "GND")
	)
	(via
		(at 338.074 -30.48)
		(size 0.5588)
		(drill 0.3048)
		(layers "F.Cu" "B.Cu")
		(net "GND")
	)
	(via
		(at 103.149908 -40.199818)
		(size 0.508)
		(drill 0.254)
		(layers "F.Cu" "B.Cu")
		(net "GND")
	)
	(via
		(at 332.994 -165.5826)
		(size 0.5588)
		(drill 0.3048)
		(layers "F.Cu" "B.Cu")
		(net "GND")
	)
	(via
		(at 216.408 -101.981)
		(size 0.5588)
		(drill 0.3048)
		(layers "F.Cu" "B.Cu")
		(net "GND")
	)
	(via
		(at 297.2562 -205.64094)
		(size 0.508)
		(drill 0.254)
		(layers "F.Cu" "B.Cu")
		(net "GND")
	)
	(via
		(at 296.672 -76.835)
		(size 0.5588)
		(drill 0.3048)
		(layers "F.Cu" "B.Cu")
		(net "GND")
	)
	(via
		(at 109.549946 -43.39971)
		(size 0.508)
		(drill 0.254)
		(layers "F.Cu" "B.Cu")
		(net "GND")
	)
	(via
		(at 68.326 -234.061)
		(size 0.5588)
		(drill 0.3048)
		(layers "F.Cu" "B.Cu")
		(net "GND")
	)
	(via
		(at 193.172588 -29.663136)
		(size 0.7112)
		(drill 0.4064)
		(layers "F.Cu" "B.Cu")
		(net "GND")
	)
	(via
		(at 25.604216 -196.77888)
		(size 0.5588)
		(drill 0.3048)
		(layers "F.Cu" "B.Cu")
		(net "GND")
	)
	(via
		(at 185.157364 -13.707364)
		(size 0.5588)
		(drill 0.3048)
		(layers "F.Cu" "B.Cu")
		(net "GND")
	)
	(via
		(at 229.7684 -103.2764)
		(size 0.5588)
		(drill 0.3048)
		(layers "F.Cu" "B.Cu")
		(net "GND")
	)
	(via
		(at 100.749862 -48.999648)
		(size 0.508)
		(drill 0.254)
		(layers "F.Cu" "B.Cu")
		(net "GND")
	)
	(via
		(at 113.849658 -99.850194)
		(size 0.508)
		(drill 0.254)
		(layers "F.Cu" "B.Cu")
		(net "GND")
	)
	(via
		(at 11.43 -248.92)
		(size 0.7112)
		(drill 0.4064)
		(layers "F.Cu" "B.Cu")
		(net "GND")
	)
	(via
		(at 126.435612 -212.979)
		(size 0.5588)
		(drill 0.3048)
		(layers "F.Cu" "B.Cu")
		(net "GND")
	)
	(via
		(at 317.2333 -198.7423)
		(size 0.5588)
		(drill 0.3048)
		(layers "F.Cu" "B.Cu")
		(net "GND")
	)
	(via
		(at 175.387 -118.872)
		(size 0.7112)
		(drill 0.4064)
		(layers "F.Cu" "B.Cu")
		(net "GND")
	)
	(via
		(at 101.55809 -35.40125)
		(size 0.508)
		(drill 0.254)
		(layers "F.Cu" "B.Cu")
		(net "GND")
	)
	(via
		(at 203.327 -249.428)
		(size 0.7112)
		(drill 0.4064)
		(layers "F.Cu" "B.Cu")
		(net "GND")
	)
	(via
		(at 273.685 -192.786)
		(size 0.5588)
		(drill 0.3048)
		(layers "F.Cu" "B.Cu")
		(net "GND")
	)
	(via
		(at 143.002 -117.348)
		(size 0.7112)
		(drill 0.4064)
		(layers "F.Cu" "B.Cu")
		(net "GND")
	)
	(via
		(at 349.758 -96.266)
		(size 0.7112)
		(drill 0.4064)
		(layers "F.Cu" "B.Cu")
		(net "GND")
	)
	(via
		(at 305.689 -87.63)
		(size 0.5588)
		(drill 0.3048)
		(layers "F.Cu" "B.Cu")
		(net "GND")
	)
	(via
		(at 102.349808 -42.59961)
		(size 0.508)
		(drill 0.254)
		(layers "F.Cu" "B.Cu")
		(net "GND")
	)
	(via
		(at 232.41 -214.63)
		(size 0.7112)
		(drill 0.4064)
		(layers "F.Cu" "B.Cu")
		(net "GND")
	)
	(via
		(at 301.625 -104.394)
		(size 0.5588)
		(drill 0.3048)
		(layers "F.Cu" "B.Cu")
		(net "GND")
	)
	(via
		(at 216.535 -180.467)
		(size 0.5588)
		(drill 0.3048)
		(layers "F.Cu" "B.Cu")
		(net "GND")
	)
	(via
		(at 120.850152 -100.850192)
		(size 0.508)
		(drill 0.254)
		(layers "F.Cu" "B.Cu")
		(net "GND")
	)
	(via
		(at 110.350046 -48.999902)
		(size 0.508)
		(drill 0.254)
		(layers "F.Cu" "B.Cu")
		(net "GND")
	)
	(via
		(at 324.739 -112.776)
		(size 0.5588)
		(drill 0.3048)
		(layers "F.Cu" "B.Cu")
		(net "GND")
	)
	(via
		(at 93.86697 -81.915)
		(size 0.5588)
		(drill 0.3048)
		(layers "F.Cu" "B.Cu")
		(net "GND")
	)
	(via
		(at 301.97425 -217.58275)
		(size 0.5588)
		(drill 0.3048)
		(layers "F.Cu" "B.Cu")
		(net "GND")
	)
	(via
		(at 1.143 -236.041438)
		(size 0.7112)
		(drill 0.4064)
		(layers "F.Cu" "B.Cu")
		(net "GND")
	)
	(via
		(at 92.456 -220.853)
		(size 0.5588)
		(drill 0.3048)
		(layers "F.Cu" "B.Cu")
		(net "GND")
	)
	(via
		(at 322.072 -1.27)
		(size 0.5588)
		(drill 0.254)
		(layers "F.Cu" "B.Cu")
		(net "GND")
	)
	(via
		(at 80.8228 -40.4114)
		(size 0.508)
		(drill 0.254)
		(layers "F.Cu" "B.Cu")
		(net "GND")
	)
	(via
		(at 211.074 -152.019)
		(size 0.5588)
		(drill 0.3048)
		(layers "F.Cu" "B.Cu")
		(net "GND")
	)
	(via
		(at 116.440966 -46.99)
		(size 0.508)
		(drill 0.254)
		(layers "F.Cu" "B.Cu")
		(net "GND")
	)
	(via
		(at 102.349808 -45.799756)
		(size 0.508)
		(drill 0.254)
		(layers "F.Cu" "B.Cu")
		(net "GND")
	)
	(via
		(at 39.30777 -136.98474)
		(size 0.5588)
		(drill 0.3048)
		(layers "F.Cu" "B.Cu")
		(net "GND")
	)
	(via
		(at 143.0655 -66.675)
		(size 0.508)
		(drill 0.254)
		(layers "F.Cu" "B.Cu")
		(net "GND")
	)
	(via
		(at 125.850142 -104.850184)
		(size 0.508)
		(drill 0.254)
		(layers "F.Cu" "B.Cu")
		(net "GND")
	)
	(via
		(at 262.128 -27.94)
		(size 0.7112)
		(drill 0.4064)
		(layers "F.Cu" "B.Cu")
		(net "GND")
	)
	(via
		(at 164.36975 -109.06125)
		(size 0.5588)
		(drill 0.3048)
		(layers "F.Cu" "B.Cu")
		(net "GND")
	)
	(via
		(at 157.607 -84.582)
		(size 0.7112)
		(drill 0.4064)
		(layers "F.Cu" "B.Cu")
		(net "GND")
	)
	(via
		(at 103.849678 -99.850194)
		(size 0.508)
		(drill 0.254)
		(layers "F.Cu" "B.Cu")
		(net "GND")
	)
	(via
		(at 308.06136 -198.374)
		(size 0.5588)
		(drill 0.3048)
		(layers "F.Cu" "B.Cu")
		(net "GND")
	)
	(via
		(at 100.749862 -40.199564)
		(size 0.508)
		(drill 0.254)
		(layers "F.Cu" "B.Cu")
		(net "GND")
	)
	(via
		(at 68.117212 -242.697)
		(size 0.5588)
		(drill 0.3048)
		(layers "F.Cu" "B.Cu")
		(net "GND")
	)
	(via
		(at 121.85015 -85.849714)
		(size 0.508)
		(drill 0.254)
		(layers "F.Cu" "B.Cu")
		(net "GND")
	)
	(via
		(at 5.08 -111.76)
		(size 0.7112)
		(drill 0.4064)
		(layers "F.Cu" "B.Cu")
		(net "GND")
	)
	(via
		(at 164.402008 -146.431)
		(size 0.5588)
		(drill 0.3048)
		(layers "F.Cu" "B.Cu")
		(net "GND")
	)
	(via
		(at 92.6846 -1.1176)
		(size 0.5588)
		(drill 0.3048)
		(layers "F.Cu" "B.Cu")
		(net "GND")
	)
	(via
		(at 292.735 -80.899)
		(size 0.5588)
		(drill 0.3048)
		(layers "F.Cu" "B.Cu")
		(net "GND")
	)
	(via
		(at 118.850156 -101.85019)
		(size 0.508)
		(drill 0.254)
		(layers "F.Cu" "B.Cu")
		(net "GND")
	)
	(via
		(at 294.829992 -173.444916)
		(size 0.508)
		(drill 0.254)
		(layers "F.Cu" "B.Cu")
		(net "GND")
	)
	(via
		(at 216.29497 -66.675)
		(size 0.5588)
		(drill 0.3048)
		(layers "F.Cu" "B.Cu")
		(net "GND")
	)
	(via
		(at 277.241 -215.011)
		(size 0.7112)
		(drill 0.4064)
		(layers "F.Cu" "B.Cu")
		(net "GND")
	)
	(via
		(at 268.732 -225.933)
		(size 0.7112)
		(drill 0.4064)
		(layers "F.Cu" "B.Cu")
		(net "GND")
	)
	(via
		(at 326.517 -120.65)
		(size 0.7112)
		(drill 0.4064)
		(layers "F.Cu" "B.Cu")
		(net "GND")
	)
	(via
		(at 319.278 -78.994)
		(size 0.5588)
		(drill 0.3048)
		(layers "F.Cu" "B.Cu")
		(net "GND")
	)
	(via
		(at 306.959 -87.9856)
		(size 0.5588)
		(drill 0.3048)
		(layers "F.Cu" "B.Cu")
		(net "GND")
	)
	(via
		(at 277.550372 -218.435936)
		(size 0.5588)
		(drill 0.3048)
		(layers "F.Cu" "B.Cu")
		(net "GND")
	)
	(via
		(at 132.8674 -92.5322)
		(size 0.508)
		(drill 0.254)
		(layers "F.Cu" "B.Cu")
		(net "GND")
	)
	(via
		(at 97.54997 -40.199564)
		(size 0.508)
		(drill 0.254)
		(layers "F.Cu" "B.Cu")
		(net "GND")
	)
	(via
		(at 57.404 -249.428)
		(size 0.7112)
		(drill 0.4064)
		(layers "F.Cu" "B.Cu")
		(net "GND")
	)
	(via
		(at 186.308492 -45.9105)
		(size 0.5588)
		(drill 0.3048)
		(layers "F.Cu" "B.Cu")
		(net "GND")
	)
	(via
		(at 228.6 -248.92)
		(size 0.5588)
		(drill 0.254)
		(layers "F.Cu" "B.Cu")
		(net "GND")
	)
	(via
		(at 107.95 -252.603)
		(size 0.5588)
		(drill 0.3048)
		(layers "F.Cu" "B.Cu")
		(net "GND")
	)
	(via
		(at 186.69 -198.247)
		(size 0.5588)
		(drill 0.3048)
		(layers "F.Cu" "B.Cu")
		(net "GND")
	)
	(via
		(at 209.804 -118.129812)
		(size 0.5588)
		(drill 0.3048)
		(layers "F.Cu" "B.Cu")
		(net "GND")
	)
	(via
		(at 65.1002 -47.9552)
		(size 0.7112)
		(drill 0.4064)
		(layers "F.Cu" "B.Cu")
		(net "GND")
	)
	(via
		(at 232.41 -224.79)
		(size 0.7112)
		(drill 0.4064)
		(layers "F.Cu" "B.Cu")
		(net "GND")
	)
	(via
		(at 139.065 -91.482672)
		(size 0.508)
		(drill 0.254)
		(layers "F.Cu" "B.Cu")
		(net "GND")
	)
	(via
		(at 35.56 -187.96)
		(size 0.7112)
		(drill 0.4064)
		(layers "F.Cu" "B.Cu")
		(net "GND")
	)
	(via
		(at 284.78861 -195.563744)
		(size 0.508)
		(drill 0.254)
		(layers "F.Cu" "B.Cu")
		(net "GND")
	)
	(via
		(at 262.944864 -224.654872)
		(size 0.5588)
		(drill 0.3048)
		(layers "F.Cu" "B.Cu")
		(net "GND")
	)
	(via
		(at 5.08 -121.92)
		(size 0.7112)
		(drill 0.4064)
		(layers "F.Cu" "B.Cu")
		(net "GND")
	)
	(via
		(at 79.121 -38.862)
		(size 0.508)
		(drill 0.254)
		(layers "F.Cu" "B.Cu")
		(net "GND")
	)
	(via
		(at 187.706 -30.5816)
		(size 0.7112)
		(drill 0.3556)
		(layers "F.Cu" "B.Cu")
		(net "GND")
	)
	(via
		(at 1.143 -109.041438)
		(size 0.7112)
		(drill 0.4064)
		(layers "F.Cu" "B.Cu")
		(net "GND")
	)
	(via
		(at 269.670784 -193.368676)
		(size 0.508)
		(drill 0.254)
		(layers "F.Cu" "B.Cu")
		(net "GND")
	)
	(via
		(at 107.84967 -87.84971)
		(size 0.508)
		(drill 0.254)
		(layers "F.Cu" "B.Cu")
		(net "GND")
	)
	(via
		(at 91.952318 -46.606968)
		(size 0.508)
		(drill 0.254)
		(layers "F.Cu" "B.Cu")
		(net "GND")
	)
	(via
		(at 50.292 -199.39)
		(size 0.5588)
		(drill 0.3048)
		(layers "F.Cu" "B.Cu")
		(net "GND")
	)
	(via
		(at 90.18016 -45.72)
		(size 0.508)
		(drill 0.254)
		(layers "F.Cu" "B.Cu")
		(net "GND")
	)
	(via
		(at 157.861 -86.741)
		(size 0.7112)
		(drill 0.4064)
		(layers "F.Cu" "B.Cu")
		(net "GND")
	)
	(via
		(at 120.850152 -107.850178)
		(size 0.508)
		(drill 0.254)
		(layers "F.Cu" "B.Cu")
		(net "GND")
	)
	(via
		(at 296.164 -73.66)
		(size 0.5588)
		(drill 0.3048)
		(layers "F.Cu" "B.Cu")
		(net "GND")
	)
	(via
		(at 207.01 -5.08)
		(size 0.5588)
		(drill 0.254)
		(layers "F.Cu" "B.Cu")
		(net "GND")
	)
	(via
		(at 126.85014 -106.85018)
		(size 0.508)
		(drill 0.254)
		(layers "F.Cu" "B.Cu")
		(net "GND")
	)
	(via
		(at 1.143 -205.561438)
		(size 0.7112)
		(drill 0.4064)
		(layers "F.Cu" "B.Cu")
		(net "GND")
	)
	(via
		(at 286.49803 -195.57238)
		(size 0.508)
		(drill 0.254)
		(layers "F.Cu" "B.Cu")
		(net "GND")
	)
	(via
		(at 43.69816 -174.99584)
		(size 0.5588)
		(drill 0.3048)
		(layers "F.Cu" "B.Cu")
		(net "GND")
	)
	(via
		(at 112.84966 -90.849704)
		(size 0.508)
		(drill 0.254)
		(layers "F.Cu" "B.Cu")
		(net "GND")
	)
	(via
		(at 306.832 -68.960746)
		(size 0.5588)
		(drill 0.3048)
		(layers "F.Cu" "B.Cu")
		(net "GND")
	)
	(via
		(at 213.868 -95.885)
		(size 0.7112)
		(drill 0.4064)
		(layers "F.Cu" "B.Cu")
		(net "GND")
	)
	(via
		(at 97.54997 -39.399718)
		(size 0.508)
		(drill 0.254)
		(layers "F.Cu" "B.Cu")
		(net "GND")
	)
	(via
		(at 109.601 -225.044)
		(size 0.5588)
		(drill 0.3048)
		(layers "F.Cu" "B.Cu")
		(net "GND")
	)
	(via
		(at 174.51197 -65.659)
		(size 0.5588)
		(drill 0.3048)
		(layers "F.Cu" "B.Cu")
		(net "GND")
	)
	(via
		(at 295.630092 -177.444908)
		(size 0.508)
		(drill 0.254)
		(layers "F.Cu" "B.Cu")
		(net "GND")
	)
	(via
		(at 296.488358 -201.335132)
		(size 0.508)
		(drill 0.254)
		(layers "F.Cu" "B.Cu")
		(net "GND")
	)
	(via
		(at 97.544128 -42.596562)
		(size 0.508)
		(drill 0.254)
		(layers "F.Cu" "B.Cu")
		(net "GND")
	)
	(via
		(at 222.885 -155.575)
		(size 0.5588)
		(drill 0.3048)
		(layers "F.Cu" "B.Cu")
		(net "GND")
	)
	(via
		(at 95.150178 -55.39994)
		(size 0.508)
		(drill 0.254)
		(layers "F.Cu" "B.Cu")
		(net "GND")
	)
	(via
		(at 111.170212 -225.044)
		(size 0.5588)
		(drill 0.3048)
		(layers "F.Cu" "B.Cu")
		(net "GND")
	)
	(via
		(at 161.036 -186.563)
		(size 0.7112)
		(drill 0.4064)
		(layers "F.Cu" "B.Cu")
		(net "GND")
	)
	(via
		(at 77.2414 -42.418)
		(size 0.508)
		(drill 0.254)
		(layers "F.Cu" "B.Cu")
		(net "GND")
	)
	(via
		(at 118.850156 -98.850196)
		(size 0.508)
		(drill 0.254)
		(layers "F.Cu" "B.Cu")
		(net "GND")
	)
	(via
		(at 291.6301 -174.245016)
		(size 0.508)
		(drill 0.254)
		(layers "F.Cu" "B.Cu")
		(net "GND")
	)
	(via
		(at 111.849662 -101.85019)
		(size 0.508)
		(drill 0.254)
		(layers "F.Cu" "B.Cu")
		(net "GND")
	)
	(via
		(at 295.266872 -65.523872)
		(size 0.5588)
		(drill 0.3048)
		(layers "F.Cu" "B.Cu")
		(net "GND")
	)
	(via
		(at 95.94977 -49.799748)
		(size 0.508)
		(drill 0.254)
		(layers "F.Cu" "B.Cu")
		(net "GND")
	)
	(via
		(at 329.700636 -230.386636)
		(size 0.5588)
		(drill 0.3048)
		(layers "F.Cu" "B.Cu")
		(net "GND")
	)
	(via
		(at 153.924 -233.299)
		(size 0.7112)
		(drill 0.4064)
		(layers "F.Cu" "B.Cu")
		(net "GND")
	)
	(via
		(at 323.596 -113.538)
		(size 0.5588)
		(drill 0.3048)
		(layers "F.Cu" "B.Cu")
		(net "GND")
	)
	(via
		(at 106.553 -232.156)
		(size 0.508)
		(drill 0.254)
		(layers "F.Cu" "B.Cu")
		(net "GND")
	)
	(via
		(at 95.946214 -45.005752)
		(size 0.508)
		(drill 0.254)
		(layers "F.Cu" "B.Cu")
		(net "GND")
	)
	(via
		(at 266.437872 -40.458136)
		(size 0.5588)
		(drill 0.3048)
		(layers "F.Cu" "B.Cu")
		(net "GND")
	)
	(via
		(at 132.461 -160.655)
		(size 0.5588)
		(drill 0.3048)
		(layers "F.Cu" "B.Cu")
		(net "GND")
	)
	(via
		(at 95.94977 -50.599594)
		(size 0.508)
		(drill 0.254)
		(layers "F.Cu" "B.Cu")
		(net "GND")
	)
	(via
		(at 15.19936 -97.708466)
		(size 0.5588)
		(drill 0.3048)
		(layers "F.Cu" "B.Cu")
		(net "GND")
	)
	(via
		(at 130.474212 -252.857)
		(size 0.7112)
		(drill 0.4064)
		(layers "F.Cu" "B.Cu")
		(net "GND")
	)
	(via
		(at 5.08 -116.84)
		(size 0.7112)
		(drill 0.4064)
		(layers "F.Cu" "B.Cu")
		(net "GND")
	)
	(via
		(at 290.09594 -201.33564)
		(size 0.508)
		(drill 0.254)
		(layers "F.Cu" "B.Cu")
		(net "GND")
	)
	(via
		(at 323.596 -112.268)
		(size 0.5588)
		(drill 0.3048)
		(layers "F.Cu" "B.Cu")
		(net "GND")
	)
	(via
		(at 291.6301 -176.644808)
		(size 0.508)
		(drill 0.254)
		(layers "F.Cu" "B.Cu")
		(net "GND")
	)
	(via
		(at 181.36997 -65.659)
		(size 0.5588)
		(drill 0.3048)
		(layers "F.Cu" "B.Cu")
		(net "GND")
	)
	(via
		(at 306.832 -58.674)
		(size 0.5588)
		(drill 0.3048)
		(layers "F.Cu" "B.Cu")
		(net "GND")
	)
	(via
		(at 100.749862 -52.99964)
		(size 0.508)
		(drill 0.254)
		(layers "F.Cu" "B.Cu")
		(net "GND")
	)
	(via
		(at 170.815 -115.824)
		(size 0.5588)
		(drill 0.3048)
		(layers "F.Cu" "B.Cu")
		(net "GND")
	)
	(via
		(at 97.559622 -38.599872)
		(size 0.508)
		(drill 0.254)
		(layers "F.Cu" "B.Cu")
		(net "GND")
	)
	(via
		(at 132.68071 -80.35671)
		(size 0.508)
		(drill 0.254)
		(layers "F.Cu" "B.Cu")
		(net "GND")
	)
	(via
		(at 101.18979 -74.30516)
		(size 0.5588)
		(drill 0.3048)
		(layers "F.Cu" "B.Cu")
		(net "GND")
	)
	(via
		(at 279.019 -209.129376)
		(size 0.5588)
		(drill 0.3048)
		(layers "F.Cu" "B.Cu")
		(net "GND")
	)
	(via
		(at 116.205 -30.734)
		(size 0.5588)
		(drill 0.3048)
		(layers "F.Cu" "B.Cu")
		(net "GND")
	)
	(via
		(at 156.591 -181.483)
		(size 0.7112)
		(drill 0.4064)
		(layers "F.Cu" "B.Cu")
		(net "GND")
	)
	(via
		(at 116.85016 -100.850192)
		(size 0.508)
		(drill 0.254)
		(layers "F.Cu" "B.Cu")
		(net "GND")
	)
	(via
		(at 155.067 -84.582)
		(size 0.7112)
		(drill 0.4064)
		(layers "F.Cu" "B.Cu")
		(net "GND")
	)
	(via
		(at 109.474 -183.896)
		(size 0.7112)
		(drill 0.4064)
		(layers "F.Cu" "B.Cu")
		(net "GND")
	)
	(via
		(at 162.306 -84.328)
		(size 0.7112)
		(drill 0.4064)
		(layers "F.Cu" "B.Cu")
		(net "GND")
	)
	(via
		(at 29.414216 -202.87488)
		(size 0.5588)
		(drill 0.3048)
		(layers "F.Cu" "B.Cu")
		(net "GND")
	)
	(via
		(at 98.999802 -253.00559)
		(size 0.7112)
		(drill 0.4064)
		(layers "F.Cu" "B.Cu")
		(net "GND")
	)
	(via
		(at 219.71 -1.27)
		(size 0.5588)
		(drill 0.254)
		(layers "F.Cu" "B.Cu")
		(net "GND")
	)
	(via
		(at 307.086 -111.379)
		(size 0.5588)
		(drill 0.3048)
		(layers "F.Cu" "B.Cu")
		(net "GND")
	)
	(via
		(at 183.315864 -32.838136)
		(size 0.5588)
		(drill 0.3048)
		(layers "F.Cu" "B.Cu")
		(net "GND")
	)
	(via
		(at 273.05 -1.27)
		(size 0.5588)
		(drill 0.254)
		(layers "F.Cu" "B.Cu")
		(net "GND")
	)
	(via
		(at 288.09823 -195.36283)
		(size 0.508)
		(drill 0.254)
		(layers "F.Cu" "B.Cu")
		(net "GND")
	)
	(via
		(at 127.635 -203.2)
		(size 0.7112)
		(drill 0.4064)
		(layers "F.Cu" "B.Cu")
		(net "GND")
	)
	(via
		(at 306.959 -51.308)
		(size 0.5588)
		(drill 0.3048)
		(layers "F.Cu" "B.Cu")
		(net "GND")
	)
	(via
		(at 296.164 -58.928)
		(size 0.5588)
		(drill 0.3048)
		(layers "F.Cu" "B.Cu")
		(net "GND")
	)
	(via
		(at 322.58 -121.158)
		(size 0.5588)
		(drill 0.3048)
		(layers "F.Cu" "B.Cu")
		(net "GND")
	)
	(via
		(at 269.24 -52.705)
		(size 0.5588)
		(drill 0.3048)
		(layers "F.Cu" "B.Cu")
		(net "GND")
	)
	(via
		(at 100.749862 -50.599594)
		(size 0.508)
		(drill 0.254)
		(layers "F.Cu" "B.Cu")
		(net "GND")
	)
	(via
		(at 291.6301 -175.844962)
		(size 0.508)
		(drill 0.254)
		(layers "F.Cu" "B.Cu")
		(net "GND")
	)
	(via
		(at 349.377 -83.312)
		(size 0.5588)
		(drill 0.3048)
		(layers "F.Cu" "B.Cu")
		(net "GND")
	)
	(via
		(at 104.750108 -53.79974)
		(size 0.508)
		(drill 0.254)
		(layers "F.Cu" "B.Cu")
		(net "GND")
	)
	(via
		(at 12.80033 -97.708466)
		(size 0.5588)
		(drill 0.3048)
		(layers "F.Cu" "B.Cu")
		(net "GND")
	)
	(via
		(at 307.721 -21.717)
		(size 0.5588)
		(drill 0.254)
		(layers "F.Cu" "B.Cu")
		(net "GND")
	)
	(via
		(at 31.209996 -90.096086)
		(size 0.5588)
		(drill 0.3048)
		(layers "F.Cu" "B.Cu")
		(net "GND")
	)
	(via
		(at 1.143 -215.721438)
		(size 0.7112)
		(drill 0.4064)
		(layers "F.Cu" "B.Cu")
		(net "GND")
	)
	(via
		(at 38.972998 -81.396332)
		(size 0.5588)
		(drill 0.3048)
		(layers "F.Cu" "B.Cu")
		(net "GND")
	)
	(via
		(at 18.738088 -208.789016)
		(size 0.5588)
		(drill 0.3048)
		(layers "F.Cu" "B.Cu")
		(net "GND")
	)
	(via
		(at 126.905766 -45.3136)
		(size 0.5588)
		(drill 0.3048)
		(layers "F.Cu" "B.Cu")
		(net "GND")
	)
	(via
		(at 220.98 -248.92)
		(size 0.5588)
		(drill 0.254)
		(layers "F.Cu" "B.Cu")
		(net "GND")
	)
	(via
		(at 107.156504 -48.997108)
		(size 0.508)
		(drill 0.254)
		(layers "F.Cu" "B.Cu")
		(net "GND")
	)
	(via
		(at 100.750116 -51.399948)
		(size 0.508)
		(drill 0.254)
		(layers "F.Cu" "B.Cu")
		(net "GND")
	)
	(via
		(at 44.46397 -144.653)
		(size 0.5588)
		(drill 0.3048)
		(layers "F.Cu" "B.Cu")
		(net "GND")
	)
	(via
		(at 107.315 -68.961254)
		(size 0.5588)
		(drill 0.3048)
		(layers "F.Cu" "B.Cu")
		(net "GND")
	)
	(via
		(at 146.476212 -252.984)
		(size 0.7112)
		(drill 0.4064)
		(layers "F.Cu" "B.Cu")
		(net "GND")
	)
	(via
		(at 93.55328 -46.59884)
		(size 0.508)
		(drill 0.254)
		(layers "F.Cu" "B.Cu")
		(net "GND")
	)
	(via
		(at 90.778076 -33.399984)
		(size 0.508)
		(drill 0.254)
		(layers "F.Cu" "B.Cu")
		(net "GND")
	)
	(via
		(at 189.357 -36.83)
		(size 0.5588)
		(drill 0.3048)
		(layers "F.Cu" "B.Cu")
		(net "GND")
	)
	(via
		(at 350.139 -92.71)
		(size 0.7112)
		(drill 0.4064)
		(layers "F.Cu" "B.Cu")
		(net "GND")
	)
	(via
		(at 298.45 -246.38)
		(size 0.7112)
		(drill 0.4064)
		(layers "F.Cu" "B.Cu")
		(net "GND")
	)
	(via
		(at 353.061016 -26.924)
		(size 0.5588)
		(drill 0.3048)
		(layers "F.Cu" "B.Cu")
		(net "GND")
	)
	(via
		(at 49.71415 -137.3505)
		(size 0.5588)
		(drill 0.3048)
		(layers "F.Cu" "B.Cu")
		(net "GND")
	)
	(via
		(at 113.849658 -101.85019)
		(size 0.508)
		(drill 0.254)
		(layers "F.Cu" "B.Cu")
		(net "GND")
	)
	(via
		(at 104.648 -183.896)
		(size 0.7112)
		(drill 0.4064)
		(layers "F.Cu" "B.Cu")
		(net "GND")
	)
	(via
		(at 120.850152 -98.850196)
		(size 0.508)
		(drill 0.254)
		(layers "F.Cu" "B.Cu")
		(net "GND")
	)
	(via
		(at 342.040718 -159.235648)
		(size 0.5588)
		(drill 0.3048)
		(layers "F.Cu" "B.Cu")
		(net "GND")
	)
	(via
		(at 106.299 -216.027)
		(size 0.7112)
		(drill 0.3556)
		(layers "F.Cu" "B.Cu")
		(net "GND")
	)
	(via
		(at 275.586952 -39.167562)
		(size 0.7112)
		(drill 0.4064)
		(layers "F.Cu" "B.Cu")
		(net "GND")
	)
	(via
		(at 166.751 -230.124)
		(size 0.7112)
		(drill 0.4064)
		(layers "F.Cu" "B.Cu")
		(net "GND")
	)
	(via
		(at 61.595 -143.637)
		(size 0.508)
		(drill 0.254)
		(layers "F.Cu" "B.Cu")
		(net "GND")
	)
	(via
		(at 177.854864 -39.717472)
		(size 0.7112)
		(drill 0.4064)
		(layers "F.Cu" "B.Cu")
		(net "GND")
	)
	(via
		(at 109.4486 -74.8157)
		(size 0.5588)
		(drill 0.3048)
		(layers "F.Cu" "B.Cu")
		(net "GND")
	)
	(via
		(at 85.852 -32.385)
		(size 0.508)
		(drill 0.254)
		(layers "F.Cu" "B.Cu")
		(net "GND")
	)
	(via
		(at 219.72397 -66.675)
		(size 0.5588)
		(drill 0.3048)
		(layers "F.Cu" "B.Cu")
		(net "GND")
	)
	(via
		(at 19.373088 -193.676016)
		(size 0.5588)
		(drill 0.3048)
		(layers "F.Cu" "B.Cu")
		(net "GND")
	)
	(via
		(at 91.950286 -36.20008)
		(size 0.508)
		(drill 0.254)
		(layers "F.Cu" "B.Cu")
		(net "GND")
	)
	(via
		(at 350.139 -93.98)
		(size 0.7112)
		(drill 0.4064)
		(layers "F.Cu" "B.Cu")
		(net "GND")
	)
	(via
		(at 340.4108 -110.363)
		(size 0.5588)
		(drill 0.3048)
		(layers "F.Cu" "B.Cu")
		(net "GND")
	)
	(via
		(at 17.730216 -212.27288)
		(size 0.5588)
		(drill 0.3048)
		(layers "F.Cu" "B.Cu")
		(net "GND")
	)
	(via
		(at 321.056 -216.662)
		(size 0.5588)
		(drill 0.3048)
		(layers "F.Cu" "B.Cu")
		(net "GND")
	)
	(via
		(at 307.721 -27.305)
		(size 0.5588)
		(drill 0.254)
		(layers "F.Cu" "B.Cu")
		(net "GND")
	)
	(via
		(at 81.534 -9.652)
		(size 0.7112)
		(drill 0.4064)
		(layers "F.Cu" "B.Cu")
		(net "GND")
	)
	(via
		(at 1.143 -195.401438)
		(size 0.7112)
		(drill 0.4064)
		(layers "F.Cu" "B.Cu")
		(net "GND")
	)
	(via
		(at 81.534 -15.621)
		(size 0.7112)
		(drill 0.4064)
		(layers "F.Cu" "B.Cu")
		(net "GND")
	)
	(via
		(at 125.43917 -79.4258)
		(size 0.508)
		(drill 0.254)
		(layers "F.Cu" "B.Cu")
		(net "GND")
	)
	(via
		(at 257.81 -1.27)
		(size 0.5588)
		(drill 0.254)
		(layers "F.Cu" "B.Cu")
		(net "GND")
	)
	(via
		(at 75.673966 -85.344)
		(size 0.5588)
		(drill 0.3048)
		(layers "F.Cu" "B.Cu")
		(net "GND")
	)
	(via
		(at 274.447 -38.989)
		(size 0.7112)
		(drill 0.4064)
		(layers "F.Cu" "B.Cu")
		(net "GND")
	)
	(via
		(at 308.61 -246.38)
		(size 0.7112)
		(drill 0.4064)
		(layers "F.Cu" "B.Cu")
		(net "GND")
	)
	(via
		(at 260.985 -63.119)
		(size 0.7112)
		(drill 0.4064)
		(layers "F.Cu" "B.Cu")
		(net "GND")
	)
	(via
		(at 161.798 -110.871)
		(size 0.7112)
		(drill 0.4064)
		(layers "F.Cu" "B.Cu")
		(net "GND")
	)
	(via
		(at 101.981 -252.603)
		(size 0.5588)
		(drill 0.3048)
		(layers "F.Cu" "B.Cu")
		(net "GND")
	)
	(via
		(at 43.76039 -75.428856)
		(size 0.5588)
		(drill 0.3048)
		(layers "F.Cu" "B.Cu")
		(net "GND")
	)
	(via
		(at 104.749854 -52.19954)
		(size 0.508)
		(drill 0.254)
		(layers "F.Cu" "B.Cu")
		(net "GND")
	)
	(via
		(at 107.949746 -51.399694)
		(size 0.508)
		(drill 0.254)
		(layers "F.Cu" "B.Cu")
		(net "GND")
	)
	(via
		(at 209.677 -104.4194)
		(size 0.5588)
		(drill 0.3048)
		(layers "F.Cu" "B.Cu")
		(net "GND")
	)
	(via
		(at 90.18397 -100.076)
		(size 0.5588)
		(drill 0.3048)
		(layers "F.Cu" "B.Cu")
		(net "GND")
	)
	(via
		(at 167.64 -30.48)
		(size 0.7112)
		(drill 0.4064)
		(layers "F.Cu" "B.Cu")
		(net "GND")
	)
	(via
		(at 136.9568 -82.3214)
		(size 0.508)
		(drill 0.254)
		(layers "F.Cu" "B.Cu")
		(net "GND")
	)
	(via
		(at 99.949762 -53.799486)
		(size 0.508)
		(drill 0.254)
		(layers "F.Cu" "B.Cu")
		(net "GND")
	)
	(via
		(at 16.51 -248.92)
		(size 0.7112)
		(drill 0.4064)
		(layers "F.Cu" "B.Cu")
		(net "GND")
	)
	(via
		(at 98.350324 -37.00018)
		(size 0.508)
		(drill 0.254)
		(layers "F.Cu" "B.Cu")
		(net "GND")
	)
	(via
		(at 96.139 -206.248)
		(size 0.7112)
		(drill 0.4064)
		(layers "F.Cu" "B.Cu")
		(net "GND")
	)
	(via
		(at 118.850156 -91.849702)
		(size 0.508)
		(drill 0.254)
		(layers "F.Cu" "B.Cu")
		(net "GND")
	)
	(via
		(at 294.099234 -196.526912)
		(size 0.508)
		(drill 0.254)
		(layers "F.Cu" "B.Cu")
		(net "GND")
	)
	(via
		(at 99.314 -60.579)
		(size 0.5588)
		(drill 0.3048)
		(layers "F.Cu" "B.Cu")
		(net "GND")
	)
	(via
		(at 50.10023 -75.329034)
		(size 0.5588)
		(drill 0.3048)
		(layers "F.Cu" "B.Cu")
		(net "GND")
	)
	(via
		(at 80.563212 -252.857)
		(size 0.7112)
		(drill 0.4064)
		(layers "F.Cu" "B.Cu")
		(net "GND")
	)
	(via
		(at 262.128 -24.638)
		(size 0.7112)
		(drill 0.4064)
		(layers "F.Cu" "B.Cu")
		(net "GND")
	)
	(via
		(at 132.969 -89.408)
		(size 0.508)
		(drill 0.254)
		(layers "F.Cu" "B.Cu")
		(net "GND")
	)
	(via
		(at 119.16537 -75.6412)
		(size 0.5588)
		(drill 0.3048)
		(layers "F.Cu" "B.Cu")
		(net "GND")
	)
	(via
		(at 77.2922 -40.6908)
		(size 0.508)
		(drill 0.254)
		(layers "F.Cu" "B.Cu")
		(net "GND")
	)
	(via
		(at 98.23577 -113.6142)
		(size 0.5588)
		(drill 0.3048)
		(layers "F.Cu" "B.Cu")
		(net "GND")
	)
	(via
		(at 115.056412 -204.5716)
		(size 0.5588)
		(drill 0.3048)
		(layers "F.Cu" "B.Cu")
		(net "GND")
	)
	(via
		(at 87.865966 -46.482)
		(size 0.5588)
		(drill 0.3048)
		(layers "F.Cu" "B.Cu")
		(net "GND")
	)
	(via
		(at 123.99137 -80.1878)
		(size 0.508)
		(drill 0.254)
		(layers "F.Cu" "B.Cu")
		(net "GND")
	)
	(via
		(at 134.2644 -80.4418)
		(size 0.508)
		(drill 0.254)
		(layers "F.Cu" "B.Cu")
		(net "GND")
	)
	(via
		(at 180.721 -96.012)
		(size 0.7112)
		(drill 0.4064)
		(layers "F.Cu" "B.Cu")
		(net "GND")
	)
	(via
		(at 335.1276 -132.6134)
		(size 0.508)
		(drill 0.254)
		(layers "F.Cu" "B.Cu")
		(net "GND")
	)
	(via
		(at 307.721 -34.925)
		(size 0.5588)
		(drill 0.254)
		(layers "F.Cu" "B.Cu")
		(net "GND")
	)
	(via
		(at 93.557344 -48.19777)
		(size 0.508)
		(drill 0.254)
		(layers "F.Cu" "B.Cu")
		(net "GND")
	)
	(via
		(at 294.12946 -210.058)
		(size 0.508)
		(drill 0.254)
		(layers "F.Cu" "B.Cu")
		(net "GND")
	)
	(via
		(at 90.69197 -96.647)
		(size 0.5588)
		(drill 0.3048)
		(layers "F.Cu" "B.Cu")
		(net "GND")
	)
	(via
		(at 60.071 -219.964)
		(size 0.5588)
		(drill 0.3048)
		(layers "F.Cu" "B.Cu")
		(net "GND")
	)
	(via
		(at 78.658212 -252.857)
		(size 0.7112)
		(drill 0.4064)
		(layers "F.Cu" "B.Cu")
		(net "GND")
	)
	(via
		(at 199.205596 -123.513596)
		(size 0.5588)
		(drill 0.3048)
		(layers "F.Cu" "B.Cu")
		(net "GND")
	)
	(via
		(at 105.549954 -44.19981)
		(size 0.508)
		(drill 0.254)
		(layers "F.Cu" "B.Cu")
		(net "GND")
	)
	(via
		(at 166.243 -125.476)
		(size 0.5588)
		(drill 0.3048)
		(layers "F.Cu" "B.Cu")
		(net "GND")
	)
	(via
		(at 294.7162 -205.64094)
		(size 0.508)
		(drill 0.254)
		(layers "F.Cu" "B.Cu")
		(net "GND")
	)
	(via
		(at 35.56 -182.88)
		(size 0.7112)
		(drill 0.4064)
		(layers "F.Cu" "B.Cu")
		(net "GND")
	)
	(via
		(at 264.16 -248.92)
		(size 0.5588)
		(drill 0.254)
		(layers "F.Cu" "B.Cu")
		(net "GND")
	)
	(via
		(at 284.29331 -173.701456)
		(size 0.508)
		(drill 0.254)
		(layers "F.Cu" "B.Cu")
		(net "GND")
	)
	(via
		(at 112.84966 -92.8497)
		(size 0.508)
		(drill 0.254)
		(layers "F.Cu" "B.Cu")
		(net "GND")
	)
	(via
		(at 298.387008 -81.408016)
		(size 0.5588)
		(drill 0.3048)
		(layers "F.Cu" "B.Cu")
		(net "GND")
	)
	(via
		(at 84.500212 -252.857)
		(size 0.7112)
		(drill 0.4064)
		(layers "F.Cu" "B.Cu")
		(net "GND")
	)
	(via
		(at 118.850156 -89.849706)
		(size 0.508)
		(drill 0.254)
		(layers "F.Cu" "B.Cu")
		(net "GND")
	)
	(via
		(at 324.485 -197.739)
		(size 0.7112)
		(drill 0.4064)
		(layers "F.Cu" "B.Cu")
		(net "GND")
	)
	(via
		(at 19.762216 -196.52488)
		(size 0.5588)
		(drill 0.3048)
		(layers "F.Cu" "B.Cu")
		(net "GND")
	)
	(via
		(at 351.6376 -151.9682)
		(size 0.508)
		(drill 0.254)
		(layers "F.Cu" "B.Cu")
		(net "GND")
	)
	(via
		(at 181.283864 -30.806136)
		(size 0.5588)
		(drill 0.3048)
		(layers "F.Cu" "B.Cu")
		(net "GND")
	)
	(via
		(at 100.749862 -45.799756)
		(size 0.508)
		(drill 0.254)
		(layers "F.Cu" "B.Cu")
		(net "GND")
	)
	(via
		(at 184.331864 -30.806136)
		(size 0.5588)
		(drill 0.3048)
		(layers "F.Cu" "B.Cu")
		(net "GND")
	)
	(via
		(at 48.989996 -85.828378)
		(size 0.5588)
		(drill 0.3048)
		(layers "F.Cu" "B.Cu")
		(net "GND")
	)
	(via
		(at 118.688612 -214.884)
		(size 0.5588)
		(drill 0.3048)
		(layers "F.Cu" "B.Cu")
		(net "GND")
	)
	(via
		(at 330.2 -248.92)
		(size 0.5588)
		(drill 0.254)
		(layers "F.Cu" "B.Cu")
		(net "GND")
	)
	(via
		(at 173.99 -1.27)
		(size 0.5588)
		(drill 0.254)
		(layers "F.Cu" "B.Cu")
		(net "GND")
	)
	(via
		(at 115.640612 -214.884)
		(size 0.5588)
		(drill 0.3048)
		(layers "F.Cu" "B.Cu")
		(net "GND")
	)
	(via
		(at 106.350308 -36.20008)
		(size 0.508)
		(drill 0.254)
		(layers "F.Cu" "B.Cu")
		(net "GND")
	)
	(via
		(at 332.2066 -146.662648)
		(size 0.5588)
		(drill 0.3048)
		(layers "F.Cu" "B.Cu")
		(net "GND")
	)
	(via
		(at 84.836 -37.4904)
		(size 0.508)
		(drill 0.254)
		(layers "F.Cu" "B.Cu")
		(net "GND")
	)
	(via
		(at 344.3986 -136.2964)
		(size 0.508)
		(drill 0.254)
		(layers "F.Cu" "B.Cu")
		(net "GND")
	)
	(via
		(at 222.1103 -117.729)
		(size 0.5588)
		(drill 0.3048)
		(layers "F.Cu" "B.Cu")
		(net "GND")
	)
	(via
		(at 116.85016 -93.849698)
		(size 0.508)
		(drill 0.254)
		(layers "F.Cu" "B.Cu")
		(net "GND")
	)
	(via
		(at 20.651216 -180.39588)
		(size 0.5588)
		(drill 0.3048)
		(layers "F.Cu" "B.Cu")
		(net "GND")
	)
	(via
		(at 96.139 -209.423)
		(size 0.7112)
		(drill 0.4064)
		(layers "F.Cu" "B.Cu")
		(net "GND")
	)
	(via
		(at 99.949762 -52.99964)
		(size 0.508)
		(drill 0.254)
		(layers "F.Cu" "B.Cu")
		(net "GND")
	)
	(via
		(at 195.58 -31.369)
		(size 0.7112)
		(drill 0.4064)
		(layers "F.Cu" "B.Cu")
		(net "GND")
	)
	(via
		(at 52.599844 -75.544172)
		(size 0.5588)
		(drill 0.3048)
		(layers "F.Cu" "B.Cu")
		(net "GND")
	)
	(via
		(at 331.880718 -149.228048)
		(size 0.5588)
		(drill 0.3048)
		(layers "F.Cu" "B.Cu")
		(net "GND")
	)
	(via
		(at 24.207216 -168.58488)
		(size 0.5588)
		(drill 0.3048)
		(layers "F.Cu" "B.Cu")
		(net "GND")
	)
	(via
		(at 1.143 -114.121438)
		(size 0.7112)
		(drill 0.4064)
		(layers "F.Cu" "B.Cu")
		(net "GND")
	)
	(via
		(at 92.46997 -130.048)
		(size 0.5588)
		(drill 0.3048)
		(layers "F.Cu" "B.Cu")
		(net "GND")
	)
	(via
		(at 176.149 -119.888)
		(size 0.7112)
		(drill 0.4064)
		(layers "F.Cu" "B.Cu")
		(net "GND")
	)
	(via
		(at 238.76 -5.08)
		(size 0.5588)
		(drill 0.254)
		(layers "F.Cu" "B.Cu")
		(net "GND")
	)
	(via
		(at 87.865966 -85.471)
		(size 0.5588)
		(drill 0.3048)
		(layers "F.Cu" "B.Cu")
		(net "GND")
	)
	(via
		(at 151.937212 -249.809)
		(size 0.7112)
		(drill 0.4064)
		(layers "F.Cu" "B.Cu")
		(net "GND")
	)
	(via
		(at 124.850144 -107.850178)
		(size 0.508)
		(drill 0.254)
		(layers "F.Cu" "B.Cu")
		(net "GND")
	)
	(via
		(at 119.742966 -33.909)
		(size 0.5588)
		(drill 0.3048)
		(layers "F.Cu" "B.Cu")
		(net "GND")
	)
	(via
		(at 280.67 -1.27)
		(size 0.5588)
		(drill 0.254)
		(layers "F.Cu" "B.Cu")
		(net "GND")
	)
	(via
		(at 337.684872 -169.282872)
		(size 0.5588)
		(drill 0.3048)
		(layers "F.Cu" "B.Cu")
		(net "GND")
	)
	(via
		(at 109.849666 -99.850194)
		(size 0.508)
		(drill 0.254)
		(layers "F.Cu" "B.Cu")
		(net "GND")
	)
	(via
		(at 176.53 -5.08)
		(size 0.5588)
		(drill 0.254)
		(layers "F.Cu" "B.Cu")
		(net "GND")
	)
	(via
		(at 179.578 -97.79)
		(size 0.7112)
		(drill 0.4064)
		(layers "F.Cu" "B.Cu")
		(net "GND")
	)
	(via
		(at 306.832 -94.234)
		(size 0.5588)
		(drill 0.3048)
		(layers "F.Cu" "B.Cu")
		(net "GND")
	)
	(via
		(at 321.31 -53.721)
		(size 0.5588)
		(drill 0.3048)
		(layers "F.Cu" "B.Cu")
		(net "GND")
	)
	(via
		(at 97.544128 -44.196762)
		(size 0.508)
		(drill 0.254)
		(layers "F.Cu" "B.Cu")
		(net "GND")
	)
	(via
		(at 307.721 -1.397)
		(size 0.5588)
		(drill 0.254)
		(layers "F.Cu" "B.Cu")
		(net "GND")
	)
	(via
		(at 349.123 -102.108)
		(size 0.7112)
		(drill 0.4064)
		(layers "F.Cu" "B.Cu")
		(net "GND")
	)
	(via
		(at 107.84967 -99.850194)
		(size 0.508)
		(drill 0.254)
		(layers "F.Cu" "B.Cu")
		(net "GND")
	)
	(via
		(at 90.05316 -50.546)
		(size 0.508)
		(drill 0.254)
		(layers "F.Cu" "B.Cu")
		(net "GND")
	)
	(via
		(at 17.19961 -104.779572)
		(size 0.5588)
		(drill 0.3048)
		(layers "F.Cu" "B.Cu")
		(net "GND")
	)
	(via
		(at 1.143 -200.481438)
		(size 0.7112)
		(drill 0.4064)
		(layers "F.Cu" "B.Cu")
		(net "GND")
	)
	(via
		(at 105.549954 -47.399956)
		(size 0.508)
		(drill 0.254)
		(layers "F.Cu" "B.Cu")
		(net "GND")
	)
	(via
		(at 95.149924 -34.600134)
		(size 0.508)
		(drill 0.254)
		(layers "F.Cu" "B.Cu")
		(net "GND")
	)
	(via
		(at 66.3956 -45.6692)
		(size 0.7112)
		(drill 0.4064)
		(layers "F.Cu" "B.Cu")
		(net "GND")
	)
	(via
		(at 123.861322 -91.826842)
		(size 0.508)
		(drill 0.254)
		(layers "F.Cu" "B.Cu")
		(net "GND")
	)
	(via
		(at 105.849674 -106.85018)
		(size 0.508)
		(drill 0.254)
		(layers "F.Cu" "B.Cu")
		(net "GND")
	)
	(via
		(at 121.85015 -83.849718)
		(size 0.508)
		(drill 0.254)
		(layers "F.Cu" "B.Cu")
		(net "GND")
	)
	(via
		(at 113.849658 -91.849702)
		(size 0.508)
		(drill 0.254)
		(layers "F.Cu" "B.Cu")
		(net "GND")
	)
	(via
		(at 117.850158 -97.850198)
		(size 0.508)
		(drill 0.254)
		(layers "F.Cu" "B.Cu")
		(net "GND")
	)
	(via
		(at 65.659 -154.559)
		(size 0.5588)
		(drill 0.3048)
		(layers "F.Cu" "B.Cu")
		(net "GND")
	)
	(via
		(at 215.15197 -66.675)
		(size 0.5588)
		(drill 0.3048)
		(layers "F.Cu" "B.Cu")
		(net "GND")
	)
	(via
		(at 156.591 -86.741)
		(size 0.7112)
		(drill 0.4064)
		(layers "F.Cu" "B.Cu")
		(net "GND")
	)
	(via
		(at 109.549946 -40.999664)
		(size 0.508)
		(drill 0.254)
		(layers "F.Cu" "B.Cu")
		(net "GND")
	)
	(via
		(at 24.39924 -193.668904)
		(size 0.5588)
		(drill 0.3048)
		(layers "F.Cu" "B.Cu")
		(net "GND")
	)
	(via
		(at 268.732 -229.235)
		(size 0.7112)
		(drill 0.4064)
		(layers "F.Cu" "B.Cu")
		(net "GND")
	)
	(via
		(at 198.8185 -214.8205)
		(size 0.5588)
		(drill 0.3048)
		(layers "F.Cu" "B.Cu")
		(net "GND")
	)
	(via
		(at 347.90888 -27.01671)
		(size 0.5588)
		(drill 0.3048)
		(layers "F.Cu" "B.Cu")
		(net "GND")
	)
	(via
		(at 285.369 -211.44738)
		(size 0.508)
		(drill 0.254)
		(layers "F.Cu" "B.Cu")
		(net "GND")
	)
	(via
		(at 213.868 -101.981)
		(size 0.5588)
		(drill 0.3048)
		(layers "F.Cu" "B.Cu")
		(net "GND")
	)
	(via
		(at 325.755 -151.892)
		(size 0.5588)
		(drill 0.3048)
		(layers "F.Cu" "B.Cu")
		(net "GND")
	)
	(via
		(at 76.791566 -56.8452)
		(size 0.7112)
		(drill 0.3556)
		(layers "F.Cu" "B.Cu")
		(net "GND")
	)
	(via
		(at 97.409 -238.379)
		(size 0.5588)
		(drill 0.3048)
		(layers "F.Cu" "B.Cu")
		(net "GND")
	)
	(via
		(at 294.829992 -175.044862)
		(size 0.508)
		(drill 0.254)
		(layers "F.Cu" "B.Cu")
		(net "GND")
	)
	(via
		(at 307.213 -142.72514)
		(size 0.5588)
		(drill 0.3048)
		(layers "F.Cu" "B.Cu")
		(net "GND")
	)
	(via
		(at 266.437872 -39.442136)
		(size 0.5588)
		(drill 0.3048)
		(layers "F.Cu" "B.Cu")
		(net "GND")
	)
	(via
		(at 85.25383 -113.19002)
		(size 0.7112)
		(drill 0.4064)
		(layers "F.Cu" "B.Cu")
		(net "GND")
	)
	(via
		(at 45.80001 -81.587086)
		(size 0.5588)
		(drill 0.3048)
		(layers "F.Cu" "B.Cu")
		(net "GND")
	)
	(via
		(at 204.47 -1.27)
		(size 0.5588)
		(drill 0.254)
		(layers "F.Cu" "B.Cu")
		(net "GND")
	)
	(via
		(at 340.961218 -159.426148)
		(size 0.5588)
		(drill 0.3048)
		(layers "F.Cu" "B.Cu")
		(net "GND")
	)
	(via
		(at 108.749846 -44.999656)
		(size 0.508)
		(drill 0.254)
		(layers "F.Cu" "B.Cu")
		(net "GND")
	)
	(via
		(at 96.750124 -53.79974)
		(size 0.508)
		(drill 0.254)
		(layers "F.Cu" "B.Cu")
		(net "GND")
	)
	(via
		(at 103.849678 -103.850186)
		(size 0.508)
		(drill 0.254)
		(layers "F.Cu" "B.Cu")
		(net "GND")
	)
	(via
		(at 272.923 -159.385)
		(size 0.5588)
		(drill 0.3048)
		(layers "F.Cu" "B.Cu")
		(net "GND")
	)
	(via
		(at 165.481 -103.759)
		(size 0.7112)
		(drill 0.4064)
		(layers "F.Cu" "B.Cu")
		(net "GND")
	)
	(via
		(at 99.149916 -56.199786)
		(size 0.508)
		(drill 0.254)
		(layers "F.Cu" "B.Cu")
		(net "GND")
	)
	(via
		(at 161.798 -109.601)
		(size 0.7112)
		(drill 0.4064)
		(layers "F.Cu" "B.Cu")
		(net "GND")
	)
	(via
		(at 86.6648 -1.0922)
		(size 0.5588)
		(drill 0.3048)
		(layers "F.Cu" "B.Cu")
		(net "GND")
	)
	(via
		(at 177.8 -15.367)
		(size 0.5588)
		(drill 0.254)
		(layers "F.Cu" "B.Cu")
		(net "GND")
	)
	(via
		(at 277.740872 -227.829872)
		(size 0.5588)
		(drill 0.3048)
		(layers "F.Cu" "B.Cu")
		(net "GND")
	)
	(via
		(at 168.529 -115.824)
		(size 0.5588)
		(drill 0.3048)
		(layers "F.Cu" "B.Cu")
		(net "GND")
	)
	(via
		(at 109.849666 -91.849702)
		(size 0.508)
		(drill 0.254)
		(layers "F.Cu" "B.Cu")
		(net "GND")
	)
	(via
		(at 107.950254 -53.79974)
		(size 0.508)
		(drill 0.254)
		(layers "F.Cu" "B.Cu")
		(net "GND")
	)
	(via
		(at 267.589 -38.862)
		(size 0.5588)
		(drill 0.3048)
		(layers "F.Cu" "B.Cu")
		(net "GND")
	)
	(via
		(at 292.504368 -196.531992)
		(size 0.508)
		(drill 0.254)
		(layers "F.Cu" "B.Cu")
		(net "GND")
	)
	(via
		(at 40.557196 -83.466686)
		(size 0.5588)
		(drill 0.3048)
		(layers "F.Cu" "B.Cu")
		(net "GND")
	)
	(via
		(at 168.210992 -25.654)
		(size 0.5588)
		(drill 0.3048)
		(layers "F.Cu" "B.Cu")
		(net "GND")
	)
	(via
		(at 159.5755 -144.8308)
		(size 0.5588)
		(drill 0.3048)
		(layers "F.Cu" "B.Cu")
		(net "GND")
	)
	(via
		(at 245.89359 -114.82451)
		(size 0.5588)
		(drill 0.3048)
		(layers "F.Cu" "B.Cu")
		(net "GND")
	)
	(via
		(at 96.750124 -34.59988)
		(size 0.508)
		(drill 0.254)
		(layers "F.Cu" "B.Cu")
		(net "GND")
	)
	(via
		(at 292.481 -114.046)
		(size 0.5588)
		(drill 0.3048)
		(layers "F.Cu" "B.Cu")
		(net "GND")
	)
	(via
		(at 319.532 -52.07)
		(size 0.5588)
		(drill 0.3048)
		(layers "F.Cu" "B.Cu")
		(net "GND")
	)
	(via
		(at 112.84966 -95.850202)
		(size 0.508)
		(drill 0.254)
		(layers "F.Cu" "B.Cu")
		(net "GND")
	)
	(via
		(at 46.4312 -118.3132)
		(size 0.5588)
		(drill 0.3048)
		(layers "F.Cu" "B.Cu")
		(net "GND")
	)
	(via
		(at 344.043 -70.104)
		(size 0.5588)
		(drill 0.3048)
		(layers "F.Cu" "B.Cu")
		(net "GND")
	)
	(via
		(at 108.849668 -83.849718)
		(size 0.508)
		(drill 0.254)
		(layers "F.Cu" "B.Cu")
		(net "GND")
	)
	(via
		(at 288.798 -226.06)
		(size 0.7112)
		(drill 0.4064)
		(layers "F.Cu" "B.Cu")
		(net "GND")
	)
	(via
		(at 136.9822 -80.6704)
		(size 0.508)
		(drill 0.254)
		(layers "F.Cu" "B.Cu")
		(net "GND")
	)
	(via
		(at 103.149908 -39.399718)
		(size 0.508)
		(drill 0.254)
		(layers "F.Cu" "B.Cu")
		(net "GND")
	)
	(via
		(at 116.85016 -96.8502)
		(size 0.508)
		(drill 0.254)
		(layers "F.Cu" "B.Cu")
		(net "GND")
	)
	(via
		(at 311.277 -181.483)
		(size 0.5588)
		(drill 0.3048)
		(layers "F.Cu" "B.Cu")
		(net "GND")
	)
	(via
		(at 294.829992 -176.644808)
		(size 0.508)
		(drill 0.254)
		(layers "F.Cu" "B.Cu")
		(net "GND")
	)
	(via
		(at 118.850156 -100.850192)
		(size 0.508)
		(drill 0.254)
		(layers "F.Cu" "B.Cu")
		(net "GND")
	)
	(via
		(at 219.837 -175.387)
		(size 0.5588)
		(drill 0.3048)
		(layers "F.Cu" "B.Cu")
		(net "GND")
	)
	(via
		(at 315.722 -113.4491)
		(size 0.5588)
		(drill 0.3048)
		(layers "F.Cu" "B.Cu")
		(net "GND")
	)
	(via
		(at 92.757244 -43.402504)
		(size 0.508)
		(drill 0.254)
		(layers "F.Cu" "B.Cu")
		(net "GND")
	)
	(via
		(at 120.850152 -99.850194)
		(size 0.508)
		(drill 0.254)
		(layers "F.Cu" "B.Cu")
		(net "GND")
	)
	(via
		(at 80.68564 -24.4856)
		(size 0.5588)
		(drill 0.3048)
		(layers "F.Cu" "B.Cu")
		(net "GND")
	)
	(via
		(at 321.183 -113.411)
		(size 0.5588)
		(drill 0.3048)
		(layers "F.Cu" "B.Cu")
		(net "GND")
	)
	(via
		(at 112.84966 -83.849718)
		(size 0.508)
		(drill 0.254)
		(layers "F.Cu" "B.Cu")
		(net "GND")
	)
	(via
		(at 80.04429 -140.96492)
		(size 0.5588)
		(drill 0.3048)
		(layers "F.Cu" "B.Cu")
		(net "GND")
	)
	(via
		(at 284.099 -225.044)
		(size 0.5588)
		(drill 0.3048)
		(layers "F.Cu" "B.Cu")
		(net "GND")
	)
	(via
		(at 214.9475 -163.1315)
		(size 0.5588)
		(drill 0.3048)
		(layers "F.Cu" "B.Cu")
		(net "GND")
	)
	(via
		(at 324.739 -111.633)
		(size 0.5588)
		(drill 0.3048)
		(layers "F.Cu" "B.Cu")
		(net "GND")
	)
	(via
		(at 118.850156 -95.850202)
		(size 0.508)
		(drill 0.254)
		(layers "F.Cu" "B.Cu")
		(net "GND")
	)
	(via
		(at 107.84967 -97.850198)
		(size 0.508)
		(drill 0.254)
		(layers "F.Cu" "B.Cu")
		(net "GND")
	)
	(via
		(at 179.578 -96.012)
		(size 0.7112)
		(drill 0.4064)
		(layers "F.Cu" "B.Cu")
		(net "GND")
	)
	(via
		(at 1.143 -210.641438)
		(size 0.7112)
		(drill 0.4064)
		(layers "F.Cu" "B.Cu")
		(net "GND")
	)
	(via
		(at 118.409212 -252.984)
		(size 0.7112)
		(drill 0.4064)
		(layers "F.Cu" "B.Cu")
		(net "GND")
	)
	(via
		(at 102.3493 -33.7947)
		(size 0.508)
		(drill 0.254)
		(layers "F.Cu" "B.Cu")
		(net "GND")
	)
	(via
		(at 317.246 -183.7055)
		(size 0.508)
		(drill 0.254)
		(layers "F.Cu" "B.Cu")
		(net "GND")
	)
	(via
		(at 75.673966 -84.328)
		(size 0.5588)
		(drill 0.3048)
		(layers "F.Cu" "B.Cu")
		(net "GND")
	)
	(via
		(at 100.749862 -39.399718)
		(size 0.508)
		(drill 0.254)
		(layers "F.Cu" "B.Cu")
		(net "GND")
	)
	(via
		(at 5.08 -127)
		(size 0.7112)
		(drill 0.4064)
		(layers "F.Cu" "B.Cu")
		(net "GND")
	)
	(via
		(at 278.892 -196.85)
		(size 0.5588)
		(drill 0.3048)
		(layers "F.Cu" "B.Cu")
		(net "GND")
	)
	(via
		(at 76.228448 -122.880882)
		(size 0.5588)
		(drill 0.3048)
		(layers "F.Cu" "B.Cu")
		(net "GND")
	)
	(via
		(at 122.23877 -81.28)
		(size 0.508)
		(drill 0.254)
		(layers "F.Cu" "B.Cu")
		(net "GND")
	)
	(via
		(at 284.598872 -221.052136)
		(size 0.5588)
		(drill 0.3048)
		(layers "F.Cu" "B.Cu")
		(net "GND")
	)
	(via
		(at 171.831 -115.316)
		(size 0.5588)
		(drill 0.3048)
		(layers "F.Cu" "B.Cu")
		(net "GND")
	)
	(via
		(at 1.143 -129.361438)
		(size 0.7112)
		(drill 0.4064)
		(layers "F.Cu" "B.Cu")
		(net "GND")
	)
	(via
		(at 82.785966 -32.4358)
		(size 0.5588)
		(drill 0.3048)
		(layers "F.Cu" "B.Cu")
		(net "GND")
	)
	(via
		(at 350.920812 -154.207718)
		(size 0.508)
		(drill 0.254)
		(layers "F.Cu" "B.Cu")
		(net "GND")
	)
	(via
		(at 350.139 -95.123)
		(size 0.7112)
		(drill 0.4064)
		(layers "F.Cu" "B.Cu")
		(net "GND")
	)
	(via
		(at 51.054 -158.877)
		(size 0.5588)
		(drill 0.3048)
		(layers "F.Cu" "B.Cu")
		(net "GND")
	)
	(via
		(at 97.54997 -49.799748)
		(size 0.508)
		(drill 0.254)
		(layers "F.Cu" "B.Cu")
		(net "GND")
	)
	(via
		(at 178.575462 -33.926272)
		(size 0.7112)
		(drill 0.4064)
		(layers "F.Cu" "B.Cu")
		(net "GND")
	)
	(via
		(at 123.317 -79.502)
		(size 0.7112)
		(drill 0.3556)
		(layers "F.Cu" "B.Cu")
		(net "GND")
	)
	(via
		(at 103.251 -181.229)
		(size 0.7112)
		(drill 0.4064)
		(layers "F.Cu" "B.Cu")
		(net "GND")
	)
	(via
		(at 62.484 -249.428)
		(size 0.7112)
		(drill 0.4064)
		(layers "F.Cu" "B.Cu")
		(net "GND")
	)
	(via
		(at 265.675872 -47.117)
		(size 0.5588)
		(drill 0.3048)
		(layers "F.Cu" "B.Cu")
		(net "GND")
	)
	(via
		(at 343.691718 -155.044648)
		(size 0.5588)
		(drill 0.3048)
		(layers "F.Cu" "B.Cu")
		(net "GND")
	)
	(via
		(at 126.70917 -79.0194)
		(size 0.508)
		(drill 0.254)
		(layers "F.Cu" "B.Cu")
		(net "GND")
	)
	(via
		(at 115.869212 -202.692)
		(size 0.5588)
		(drill 0.3048)
		(layers "F.Cu" "B.Cu")
		(net "GND")
	)
	(via
		(at 321.945 -197.866)
		(size 0.5588)
		(drill 0.3048)
		(layers "F.Cu" "B.Cu")
		(net "GND")
	)
	(via
		(at 76.073 -1.397)
		(size 0.7112)
		(drill 0.4064)
		(layers "F.Cu" "B.Cu")
		(net "GND")
	)
	(via
		(at 93.549978 -33.800034)
		(size 0.508)
		(drill 0.254)
		(layers "F.Cu" "B.Cu")
		(net "GND")
	)
	(via
		(at 106.242612 -213.36)
		(size 0.5588)
		(drill 0.3048)
		(layers "F.Cu" "B.Cu")
		(net "GND")
	)
	(via
		(at 120.850152 -90.849704)
		(size 0.508)
		(drill 0.254)
		(layers "F.Cu" "B.Cu")
		(net "GND")
	)
	(via
		(at 94.432374 -98.532696)
		(size 0.508)
		(drill 0.254)
		(layers "F.Cu" "B.Cu")
		(net "GND")
	)
	(via
		(at 336.071718 -159.108648)
		(size 0.5588)
		(drill 0.3048)
		(layers "F.Cu" "B.Cu")
		(net "GND")
	)
	(via
		(at 267.589 -40.005)
		(size 0.5588)
		(drill 0.3048)
		(layers "F.Cu" "B.Cu")
		(net "GND")
	)
	(via
		(at 110.350046 -39.399972)
		(size 0.508)
		(drill 0.254)
		(layers "F.Cu" "B.Cu")
		(net "GND")
	)
	(via
		(at 144.145 -115.062)
		(size 0.7112)
		(drill 0.4064)
		(layers "F.Cu" "B.Cu")
		(net "GND")
	)
	(via
		(at 314.706 -76.818998)
		(size 0.5588)
		(drill 0.3048)
		(layers "F.Cu" "B.Cu")
		(net "GND")
	)
	(via
		(at 293.171372 -172.710856)
		(size 0.508)
		(drill 0.254)
		(layers "F.Cu" "B.Cu")
		(net "GND")
	)
	(via
		(at 318.389 -80.391)
		(size 0.5588)
		(drill 0.3048)
		(layers "F.Cu" "B.Cu")
		(net "GND")
	)
	(via
		(at 296.418 -82.9183)
		(size 0.5588)
		(drill 0.3048)
		(layers "F.Cu" "B.Cu")
		(net "GND")
	)
	(via
		(at 265.43 -1.27)
		(size 0.5588)
		(drill 0.254)
		(layers "F.Cu" "B.Cu")
		(net "GND")
	)
	(via
		(at 167.005 -210.058)
		(size 0.7112)
		(drill 0.4064)
		(layers "F.Cu" "B.Cu")
		(net "GND")
	)
	(via
		(at 307.721 -16.637)
		(size 0.5588)
		(drill 0.254)
		(layers "F.Cu" "B.Cu")
		(net "GND")
	)
	(via
		(at 128.402842 -94.349824)
		(size 0.508)
		(drill 0.254)
		(layers "F.Cu" "B.Cu")
		(net "GND")
	)
	(via
		(at 223.52 -5.08)
		(size 0.5588)
		(drill 0.254)
		(layers "F.Cu" "B.Cu")
		(net "GND")
	)
	(via
		(at 160.147 -231.648)
		(size 0.7112)
		(drill 0.4064)
		(layers "F.Cu" "B.Cu")
		(net "GND")
	)
	(via
		(at 112.84966 -88.849708)
		(size 0.508)
		(drill 0.254)
		(layers "F.Cu" "B.Cu")
		(net "GND")
	)
	(via
		(at 22.302216 -212.27288)
		(size 0.5588)
		(drill 0.3048)
		(layers "F.Cu" "B.Cu")
		(net "GND")
	)
	(via
		(at 185.800492 -253.111)
		(size 0.508)
		(drill 0.254)
		(layers "F.Cu" "B.Cu")
		(net "GND")
	)
	(via
		(at 103.849678 -105.850182)
		(size 0.508)
		(drill 0.254)
		(layers "F.Cu" "B.Cu")
		(net "GND")
	)
	(via
		(at 84.436966 -53.34)
		(size 0.5588)
		(drill 0.3048)
		(layers "F.Cu" "B.Cu")
		(net "GND")
	)
	(via
		(at 117.850158 -83.849718)
		(size 0.508)
		(drill 0.254)
		(layers "F.Cu" "B.Cu")
		(net "GND")
	)
	(via
		(at 90.69197 -97.79)
		(size 0.5588)
		(drill 0.3048)
		(layers "F.Cu" "B.Cu")
		(net "GND")
	)
	(via
		(at 18.48358 -230.247952)
		(size 0.5588)
		(drill 0.3048)
		(layers "F.Cu" "B.Cu")
		(net "GND")
	)
	(via
		(at 111.849662 -98.850196)
		(size 0.508)
		(drill 0.254)
		(layers "F.Cu" "B.Cu")
		(net "GND")
	)
	(via
		(at 254.254 -195.961)
		(size 0.5588)
		(drill 0.3048)
		(layers "F.Cu" "B.Cu")
		(net "GND")
	)
	(via
		(at 282.14066 -187.6679)
		(size 0.508)
		(drill 0.254)
		(layers "F.Cu" "B.Cu")
		(net "GND")
	)
	(via
		(at 307.721 -9.017)
		(size 0.5588)
		(drill 0.254)
		(layers "F.Cu" "B.Cu")
		(net "GND")
	)
	(via
		(at 108.849668 -100.850192)
		(size 0.508)
		(drill 0.254)
		(layers "F.Cu" "B.Cu")
		(net "GND")
	)
	(via
		(at 128.402842 -84.349844)
		(size 0.508)
		(drill 0.254)
		(layers "F.Cu" "B.Cu")
		(net "GND")
	)
	(via
		(at 117.850158 -90.849704)
		(size 0.508)
		(drill 0.254)
		(layers "F.Cu" "B.Cu")
		(net "GND")
	)
	(via
		(at 291.0332 -71.700136)
		(size 0.5588)
		(drill 0.3048)
		(layers "F.Cu" "B.Cu")
		(net "GND")
	)
	(via
		(at 184.712864 -39.75608)
		(size 0.7112)
		(drill 0.4064)
		(layers "F.Cu" "B.Cu")
		(net "GND")
	)
	(via
		(at 125.10897 -109.5375)
		(size 0.5588)
		(drill 0.3048)
		(layers "F.Cu" "B.Cu")
		(net "GND")
	)
	(via
		(at 189.9412 -12.7508)
		(size 0.5588)
		(drill 0.3048)
		(layers "F.Cu" "B.Cu")
		(net "GND")
	)
	(via
		(at 338.963 -141.478)
		(size 0.5588)
		(drill 0.3048)
		(layers "F.Cu" "B.Cu")
		(net "GND")
	)
	(via
		(at 53.975 -199.644)
		(size 0.5588)
		(drill 0.3048)
		(layers "F.Cu" "B.Cu")
		(net "GND")
	)
	(via
		(at 180.721 -97.79)
		(size 0.7112)
		(drill 0.4064)
		(layers "F.Cu" "B.Cu")
		(net "GND")
	)
	(via
		(at 19.59991 -104.79786)
		(size 0.5588)
		(drill 0.3048)
		(layers "F.Cu" "B.Cu")
		(net "GND")
	)
	(via
		(at 198.374 -222.758)
		(size 0.5588)
		(drill 0.3048)
		(layers "F.Cu" "B.Cu")
		(net "GND")
	)
	(via
		(at 285.226252 -171.84116)
		(size 0.508)
		(drill 0.254)
		(layers "F.Cu" "B.Cu")
		(net "GND")
	)
	(via
		(at 120.58777 -78.3082)
		(size 0.5588)
		(drill 0.3048)
		(layers "F.Cu" "B.Cu")
		(net "GND")
	)
	(via
		(at 251.206 -16.891)
		(size 0.5588)
		(drill 0.3048)
		(layers "F.Cu" "B.Cu")
		(net "GND")
	)
	(via
		(at 189.23 -1.27)
		(size 0.5588)
		(drill 0.254)
		(layers "F.Cu" "B.Cu")
		(net "GND")
	)
	(via
		(at 83.4898 -39.2176)
		(size 0.508)
		(drill 0.254)
		(layers "F.Cu" "B.Cu")
		(net "GND")
	)
	(via
		(at 200.66 -140.843)
		(size 0.5588)
		(drill 0.3048)
		(layers "F.Cu" "B.Cu")
		(net "GND")
	)
	(via
		(at 43.655996 -83.492086)
		(size 0.5588)
		(drill 0.3048)
		(layers "F.Cu" "B.Cu")
		(net "GND")
	)
	(via
		(at 231.14 -40.64)
		(size 0.7112)
		(drill 0.4064)
		(layers "F.Cu" "B.Cu")
		(net "GND")
	)
	(via
		(at 341.376 -110.363)
		(size 0.5588)
		(drill 0.3048)
		(layers "F.Cu" "B.Cu")
		(net "GND")
	)
	(via
		(at 194.339464 -47.665386)
		(size 0.5588)
		(drill 0.3048)
		(layers "F.Cu" "B.Cu")
		(net "GND")
	)
	(via
		(at 117.850158 -99.850194)
		(size 0.508)
		(drill 0.254)
		(layers "F.Cu" "B.Cu")
		(net "GND")
	)
	(via
		(at 298.45 -83.058)
		(size 0.5588)
		(drill 0.3048)
		(layers "F.Cu" "B.Cu")
		(net "GND")
	)
	(via
		(at 11.811 -239.903)
		(size 0.5588)
		(drill 0.3048)
		(layers "F.Cu" "B.Cu")
		(net "GND")
	)
	(via
		(at 87.986616 -66.04)
		(size 0.5588)
		(drill 0.3048)
		(layers "F.Cu" "B.Cu")
		(net "GND")
	)
	(via
		(at 104.749854 -40.199818)
		(size 0.508)
		(drill 0.254)
		(layers "F.Cu" "B.Cu")
		(net "GND")
	)
	(via
		(at 221.107 -168.92524)
		(size 0.5588)
		(drill 0.3048)
		(layers "F.Cu" "B.Cu")
		(net "GND")
	)
	(via
		(at 114.48415 -108.06684)
		(size 0.508)
		(drill 0.254)
		(layers "F.Cu" "B.Cu")
		(net "GND")
	)
	(via
		(at 41.402 -228.854)
		(size 0.5588)
		(drill 0.3048)
		(layers "F.Cu" "B.Cu")
		(net "GND")
	)
	(via
		(at 68.1482 -55.8292)
		(size 0.5588)
		(drill 0.3048)
		(layers "F.Cu" "B.Cu")
		(net "GND")
	)
	(via
		(at 107.156504 -47.397162)
		(size 0.508)
		(drill 0.254)
		(layers "F.Cu" "B.Cu")
		(net "GND")
	)
	(via
		(at 349.758 -99.06)
		(size 0.7112)
		(drill 0.4064)
		(layers "F.Cu" "B.Cu")
		(net "GND")
	)
	(via
		(at 104.267 -224.917)
		(size 0.5588)
		(drill 0.3048)
		(layers "F.Cu" "B.Cu")
		(net "GND")
	)
	(via
		(at 119.850154 -82.84972)
		(size 0.508)
		(drill 0.254)
		(layers "F.Cu" "B.Cu")
		(net "GND")
	)
	(via
		(at 256.159 -138.0998)
		(size 0.5588)
		(drill 0.3048)
		(layers "F.Cu" "B.Cu")
		(net "GND")
	)
	(via
		(at 102.349808 -48.999648)
		(size 0.508)
		(drill 0.254)
		(layers "F.Cu" "B.Cu")
		(net "GND")
	)
	(via
		(at 284.734 -205.359)
		(size 0.508)
		(drill 0.254)
		(layers "F.Cu" "B.Cu")
		(net "GND")
	)
	(via
		(at 283.582872 -221.052136)
		(size 0.5588)
		(drill 0.3048)
		(layers "F.Cu" "B.Cu")
		(net "GND")
	)
	(via
		(at 17.59966 -97.75571)
		(size 0.5588)
		(drill 0.3048)
		(layers "F.Cu" "B.Cu")
		(net "GND")
	)
	(via
		(at 264.024872 -39.442136)
		(size 0.5588)
		(drill 0.3048)
		(layers "F.Cu" "B.Cu")
		(net "GND")
	)
	(via
		(at 183.315864 -29.663136)
		(size 0.5588)
		(drill 0.3048)
		(layers "F.Cu" "B.Cu")
		(net "GND")
	)
	(via
		(at 106.299 -217.805)
		(size 0.5588)
		(drill 0.3048)
		(layers "F.Cu" "B.Cu")
		(net "GND")
	)
	(via
		(at 102.350062 -53.79974)
		(size 0.508)
		(drill 0.254)
		(layers "F.Cu" "B.Cu")
		(net "GND")
	)
	(via
		(at 99.949762 -52.19954)
		(size 0.508)
		(drill 0.254)
		(layers "F.Cu" "B.Cu")
		(net "GND")
	)
	(via
		(at 195.834 -117.856)
		(size 0.5588)
		(drill 0.3048)
		(layers "F.Cu" "B.Cu")
		(net "GND")
	)
	(via
		(at 109.549946 -47.399702)
		(size 0.508)
		(drill 0.254)
		(layers "F.Cu" "B.Cu")
		(net "GND")
	)
	(via
		(at 160.655 -111.7854)
		(size 0.7112)
		(drill 0.3556)
		(layers "F.Cu" "B.Cu")
		(net "GND")
	)
	(via
		(at 177.1015 -222.6945)
		(size 0.5588)
		(drill 0.3048)
		(layers "F.Cu" "B.Cu")
		(net "GND")
	)
	(via
		(at 118.850156 -92.8497)
		(size 0.508)
		(drill 0.254)
		(layers "F.Cu" "B.Cu")
		(net "GND")
	)
	(via
		(at 282.702 -160.147)
		(size 0.508)
		(drill 0.254)
		(layers "F.Cu" "B.Cu")
		(net "GND")
	)
	(via
		(at 303.53 -246.38)
		(size 0.7112)
		(drill 0.4064)
		(layers "F.Cu" "B.Cu")
		(net "GND")
	)
	(via
		(at 77.477366 -37.5158)
		(size 0.508)
		(drill 0.254)
		(layers "F.Cu" "B.Cu")
		(net "GND")
	)
	(via
		(at 44.323 -228.981)
		(size 0.5588)
		(drill 0.3048)
		(layers "F.Cu" "B.Cu")
		(net "GND")
	)
	(via
		(at 320.294 -52.705)
		(size 0.5588)
		(drill 0.3048)
		(layers "F.Cu" "B.Cu")
		(net "GND")
	)
	(via
		(at 45.86097 -142.367)
		(size 0.5588)
		(drill 0.3048)
		(layers "F.Cu" "B.Cu")
		(net "GND")
	)
	(via
		(at 83.801966 -61.341)
		(size 0.5588)
		(drill 0.3048)
		(layers "F.Cu" "B.Cu")
		(net "GND")
	)
	(via
		(at 126.70917 -76.924154)
		(size 0.5588)
		(drill 0.3048)
		(layers "F.Cu" "B.Cu")
		(net "GND")
	)
	(via
		(at 307.467 -186.309)
		(size 0.5588)
		(drill 0.3048)
		(layers "F.Cu" "B.Cu")
		(net "GND")
	)
	(via
		(at 97.54997 -51.399694)
		(size 0.508)
		(drill 0.254)
		(layers "F.Cu" "B.Cu")
		(net "GND")
	)
	(via
		(at 199.3392 -114.1222)
		(size 0.5588)
		(drill 0.3048)
		(layers "F.Cu" "B.Cu")
		(net "GND")
	)
	(via
		(at 125.4252 -43.688)
		(size 0.7112)
		(drill 0.3556)
		(layers "F.Cu" "B.Cu")
		(net "GND")
	)
	(via
		(at 135.636 -80.645)
		(size 0.508)
		(drill 0.254)
		(layers "F.Cu" "B.Cu")
		(net "GND")
	)
	(via
		(at 144.145 -118.491)
		(size 0.7112)
		(drill 0.4064)
		(layers "F.Cu" "B.Cu")
		(net "GND")
	)
	(via
		(at 48.895 -109.601)
		(size 0.5588)
		(drill 0.3048)
		(layers "F.Cu" "B.Cu")
		(net "GND")
	)
	(via
		(at 189.992 -147.193)
		(size 0.5588)
		(drill 0.3048)
		(layers "F.Cu" "B.Cu")
		(net "GND")
	)
	(via
		(at 122.473212 -252.857)
		(size 0.7112)
		(drill 0.4064)
		(layers "F.Cu" "B.Cu")
		(net "GND")
	)
	(via
		(at 319.786 -177.673)
		(size 0.508)
		(drill 0.254)
		(layers "F.Cu" "B.Cu")
		(net "GND")
	)
	(via
		(at 350.2152 -151.1046)
		(size 0.508)
		(drill 0.254)
		(layers "F.Cu" "B.Cu")
		(net "GND")
	)
	(via
		(at 106.849672 -101.85019)
		(size 0.508)
		(drill 0.254)
		(layers "F.Cu" "B.Cu")
		(net "GND")
	)
	(via
		(at 89.897966 -32.639)
		(size 0.5588)
		(drill 0.3048)
		(layers "F.Cu" "B.Cu")
		(net "GND")
	)
	(via
		(at 161.163 -108.458)
		(size 0.7112)
		(drill 0.4064)
		(layers "F.Cu" "B.Cu")
		(net "GND")
	)
	(via
		(at 226.06 -35.56)
		(size 0.7112)
		(drill 0.4064)
		(layers "F.Cu" "B.Cu")
		(net "GND")
	)
	(via
		(at 1.143 -134.441438)
		(size 0.7112)
		(drill 0.4064)
		(layers "F.Cu" "B.Cu")
		(net "GND")
	)
	(via
		(at 43.50893 -81.460086)
		(size 0.5588)
		(drill 0.3048)
		(layers "F.Cu" "B.Cu")
		(net "GND")
	)
	(via
		(at 199.071484 -175.959516)
		(size 0.5588)
		(drill 0.3048)
		(layers "F.Cu" "B.Cu")
		(net "GND")
	)
	(via
		(at 108.749846 -51.399694)
		(size 0.508)
		(drill 0.254)
		(layers "F.Cu" "B.Cu")
		(net "GND")
	)
	(via
		(at 1.143 -144.601438)
		(size 0.7112)
		(drill 0.4064)
		(layers "F.Cu" "B.Cu")
		(net "GND")
	)
	(via
		(at 278.892 -32.131)
		(size 0.5588)
		(drill 0.3048)
		(layers "F.Cu" "B.Cu")
		(net "GND")
	)
	(via
		(at 277.622 -200.914)
		(size 0.5588)
		(drill 0.3048)
		(layers "F.Cu" "B.Cu")
		(net "GND")
	)
	(via
		(at 279.908 -63.5)
		(size 0.508)
		(drill 0.254)
		(layers "F.Cu" "B.Cu")
		(net "GND")
	)
	(via
		(at 81.029556 -38.856158)
		(size 0.508)
		(drill 0.254)
		(layers "F.Cu" "B.Cu")
		(net "GND")
	)
	(via
		(at 321.183 -112.268)
		(size 0.5588)
		(drill 0.3048)
		(layers "F.Cu" "B.Cu")
		(net "GND")
	)
	(via
		(at 95.94977 -48.999648)
		(size 0.508)
		(drill 0.254)
		(layers "F.Cu" "B.Cu")
		(net "GND")
	)
	(via
		(at 273.685 -27.305)
		(size 0.5588)
		(drill 0.3048)
		(layers "F.Cu" "B.Cu")
		(net "GND")
	)
	(via
		(at 80.264 -68.961)
		(size 0.7112)
		(drill 0.4064)
		(layers "F.Cu" "B.Cu")
		(net "GND")
	)
	(via
		(at 79.375 -40.4114)
		(size 0.508)
		(drill 0.254)
		(layers "F.Cu" "B.Cu")
		(net "GND")
	)
	(via
		(at 294.829992 -174.245016)
		(size 0.508)
		(drill 0.254)
		(layers "F.Cu" "B.Cu")
		(net "GND")
	)
	(via
		(at 86.703154 -85.454236)
		(size 0.5588)
		(drill 0.3048)
		(layers "F.Cu" "B.Cu")
		(net "GND")
	)
	(via
		(at 212.598 -91.821)
		(size 0.7112)
		(drill 0.4064)
		(layers "F.Cu" "B.Cu")
		(net "GND")
	)
	(via
		(at 155.829 -189.103)
		(size 0.7112)
		(drill 0.4064)
		(layers "F.Cu" "B.Cu")
		(net "GND")
	)
	(via
		(at 294.132 -226.06)
		(size 0.7112)
		(drill 0.4064)
		(layers "F.Cu" "B.Cu")
		(net "GND")
	)
	(via
		(at 263.148826 -51.606958)
		(size 0.5588)
		(drill 0.3048)
		(layers "F.Cu" "B.Cu")
		(net "GND")
	)
	(via
		(at 293.46906 -207.772)
		(size 0.508)
		(drill 0.254)
		(layers "F.Cu" "B.Cu")
		(net "GND")
	)
	(via
		(at 48.989996 -82.857086)
		(size 0.5588)
		(drill 0.3048)
		(layers "F.Cu" "B.Cu")
		(net "GND")
	)
	(via
		(at 269.3924 -77.0001)
		(size 0.7112)
		(drill 0.4064)
		(layers "F.Cu" "B.Cu")
		(net "GND")
	)
	(via
		(at 320.294 -42.291)
		(size 0.5588)
		(drill 0.3048)
		(layers "F.Cu" "B.Cu")
		(net "GND")
	)
	(via
		(at 52.197 -228.854)
		(size 0.5588)
		(drill 0.3048)
		(layers "F.Cu" "B.Cu")
		(net "GND")
	)
	(via
		(at 191.8462 -124.2822)
		(size 0.5588)
		(drill 0.3048)
		(layers "F.Cu" "B.Cu")
		(net "GND")
	)
	(via
		(at 263.2202 -63.1952)
		(size 0.7112)
		(drill 0.4064)
		(layers "F.Cu" "B.Cu")
		(net "GND")
	)
	(via
		(at 122.473212 -225.044)
		(size 0.5588)
		(drill 0.3048)
		(layers "F.Cu" "B.Cu")
		(net "GND")
	)
	(via
		(at 269.2146 -74.9808)
		(size 0.7112)
		(drill 0.4064)
		(layers "F.Cu" "B.Cu")
		(net "GND")
	)
	(via
		(at 169.672 -84.836)
		(size 0.7112)
		(drill 0.4064)
		(layers "F.Cu" "B.Cu")
		(net "GND")
	)
	(via
		(at 102.349808 -47.399702)
		(size 0.508)
		(drill 0.254)
		(layers "F.Cu" "B.Cu")
		(net "GND")
	)
	(via
		(at 168.529 -116.967)
		(size 0.5588)
		(drill 0.3048)
		(layers "F.Cu" "B.Cu")
		(net "GND")
	)
	(via
		(at 263.124188 -53.232812)
		(size 0.5588)
		(drill 0.3048)
		(layers "F.Cu" "B.Cu")
		(net "GND")
	)
	(via
		(at 314.579 -73.66)
		(size 0.5588)
		(drill 0.3048)
		(layers "F.Cu" "B.Cu")
		(net "GND")
	)
	(via
		(at 328.549 -120.65)
		(size 0.7112)
		(drill 0.4064)
		(layers "F.Cu" "B.Cu")
		(net "GND")
	)
	(via
		(at 110.350046 -50.599848)
		(size 0.508)
		(drill 0.254)
		(layers "F.Cu" "B.Cu")
		(net "GND")
	)
	(via
		(at 117.850158 -95.850202)
		(size 0.508)
		(drill 0.254)
		(layers "F.Cu" "B.Cu")
		(net "GND")
	)
	(via
		(at 84.709 -242.316)
		(size 0.5588)
		(drill 0.3048)
		(layers "F.Cu" "B.Cu")
		(net "GND")
	)
	(via
		(at 96.750378 -36.20008)
		(size 0.508)
		(drill 0.254)
		(layers "F.Cu" "B.Cu")
		(net "GND")
	)
	(via
		(at 109.474 -181.229)
		(size 0.7112)
		(drill 0.4064)
		(layers "F.Cu" "B.Cu")
		(net "GND")
	)
	(via
		(at 109.849666 -100.850192)
		(size 0.508)
		(drill 0.254)
		(layers "F.Cu" "B.Cu")
		(net "GND")
	)
	(via
		(at 144.145 -117.348)
		(size 0.7112)
		(drill 0.4064)
		(layers "F.Cu" "B.Cu")
		(net "GND")
	)
	(via
		(at 119.850154 -99.850194)
		(size 0.508)
		(drill 0.254)
		(layers "F.Cu" "B.Cu")
		(net "GND")
	)
	(via
		(at 234.95 -1.27)
		(size 0.5588)
		(drill 0.254)
		(layers "F.Cu" "B.Cu")
		(net "GND")
	)
	(via
		(at 104.756966 -34.59734)
		(size 0.508)
		(drill 0.254)
		(layers "F.Cu" "B.Cu")
		(net "GND")
	)
	(via
		(at 178.997864 -39.75608)
		(size 0.7112)
		(drill 0.4064)
		(layers "F.Cu" "B.Cu")
		(net "GND")
	)
	(via
		(at 282.829 -156.0195)
		(size 0.508)
		(drill 0.254)
		(layers "F.Cu" "B.Cu")
		(net "GND")
	)
	(via
		(at 293.230046 -175.844962)
		(size 0.508)
		(drill 0.254)
		(layers "F.Cu" "B.Cu")
		(net "GND")
	)
	(via
		(at 107.84967 -91.849702)
		(size 0.508)
		(drill 0.254)
		(layers "F.Cu" "B.Cu")
		(net "GND")
	)
	(via
		(at 210.439 -91.821)
		(size 0.7112)
		(drill 0.4064)
		(layers "F.Cu" "B.Cu")
		(net "GND")
	)
	(via
		(at 300.355 -103.378)
		(size 0.5588)
		(drill 0.3048)
		(layers "F.Cu" "B.Cu")
		(net "GND")
	)
	(via
		(at 284.898084 -203.180696)
		(size 0.508)
		(drill 0.254)
		(layers "F.Cu" "B.Cu")
		(net "GND")
	)
	(via
		(at 293.230046 -176.644808)
		(size 0.508)
		(drill 0.254)
		(layers "F.Cu" "B.Cu")
		(net "GND")
	)
	(via
		(at 12.40028 -104.75849)
		(size 0.5588)
		(drill 0.3048)
		(layers "F.Cu" "B.Cu")
		(net "GND")
	)
	(via
		(at 113.849658 -86.849712)
		(size 0.508)
		(drill 0.254)
		(layers "F.Cu" "B.Cu")
		(net "GND")
	)
	(via
		(at 186.182 -49.022)
		(size 0.5588)
		(drill 0.3048)
		(layers "F.Cu" "B.Cu")
		(net "GND")
	)
	(via
		(at 15.317216 -168.45788)
		(size 0.5588)
		(drill 0.3048)
		(layers "F.Cu" "B.Cu")
		(net "GND")
	)
	(via
		(at 253.111 -42.418)
		(size 0.5588)
		(drill 0.3048)
		(layers "F.Cu" "B.Cu")
		(net "GND")
	)
	(via
		(at 1.143 -88.721438)
		(size 0.7112)
		(drill 0.4064)
		(layers "F.Cu" "B.Cu")
		(net "GND")
	)
	(via
		(at 100.457 -220.218)
		(size 0.5588)
		(drill 0.3048)
		(layers "F.Cu" "B.Cu")
		(net "GND")
	)
	(via
		(at 301.371 -58.928)
		(size 0.5588)
		(drill 0.3048)
		(layers "F.Cu" "B.Cu")
		(net "GND")
	)
	(via
		(at 293.230046 -173.444916)
		(size 0.508)
		(drill 0.254)
		(layers "F.Cu" "B.Cu")
		(net "GND")
	)
	(via
		(at 104.749854 -38.599618)
		(size 0.508)
		(drill 0.254)
		(layers "F.Cu" "B.Cu")
		(net "GND")
	)
	(via
		(at 132.5372 -81.788)
		(size 0.508)
		(drill 0.254)
		(layers "F.Cu" "B.Cu")
		(net "GND")
	)
	(via
		(at 88.500966 -33.02)
		(size 0.5588)
		(drill 0.3048)
		(layers "F.Cu" "B.Cu")
		(net "GND")
	)
	(via
		(at 74.657966 -86.868)
		(size 0.5588)
		(drill 0.3048)
		(layers "F.Cu" "B.Cu")
		(net "GND")
	)
	(via
		(at 103.849678 -90.849704)
		(size 0.508)
		(drill 0.254)
		(layers "F.Cu" "B.Cu")
		(net "GND")
	)
	(via
		(at 80.264 -12.7)
		(size 0.7112)
		(drill 0.3556)
		(layers "F.Cu" "B.Cu")
		(net "GND")
	)
	(via
		(at 292.735 -78.994)
		(size 0.5588)
		(drill 0.3048)
		(layers "F.Cu" "B.Cu")
		(net "GND")
	)
	(via
		(at 183.569864 -39.75608)
		(size 0.7112)
		(drill 0.4064)
		(layers "F.Cu" "B.Cu")
		(net "GND")
	)
	(via
		(at 14.047216 -215.82888)
		(size 0.5588)
		(drill 0.3048)
		(layers "F.Cu" "B.Cu")
		(net "GND")
	)
	(via
		(at 323.85 -248.92)
		(size 0.5588)
		(drill 0.254)
		(layers "F.Cu" "B.Cu")
		(net "GND")
	)
	(via
		(at 290.703 -226.06)
		(size 0.7112)
		(drill 0.4064)
		(layers "F.Cu" "B.Cu")
		(net "GND")
	)
	(via
		(at 215.138 -101.981)
		(size 0.5588)
		(drill 0.3048)
		(layers "F.Cu" "B.Cu")
		(net "GND")
	)
	(via
		(at 133.8072 -91.3384)
		(size 0.508)
		(drill 0.254)
		(layers "F.Cu" "B.Cu")
		(net "GND")
	)
	(via
		(at 325.374 -120.65)
		(size 0.7112)
		(drill 0.4064)
		(layers "F.Cu" "B.Cu")
		(net "GND")
	)
	(via
		(at 208.407 -191.516)
		(size 0.7112)
		(drill 0.4064)
		(layers "F.Cu" "B.Cu")
		(net "GND")
	)
	(via
		(at 342.138 -22.352)
		(size 0.5588)
		(drill 0.3048)
		(layers "F.Cu" "B.Cu")
		(net "GND")
	)
	(via
		(at 47.752 -228.854)
		(size 0.5588)
		(drill 0.3048)
		(layers "F.Cu" "B.Cu")
		(net "GND")
	)
	(via
		(at 257.039364 -226.957636)
		(size 0.5588)
		(drill 0.3048)
		(layers "F.Cu" "B.Cu")
		(net "GND")
	)
	(via
		(at 127.997966 -32.385)
		(size 0.5588)
		(drill 0.3048)
		(layers "F.Cu" "B.Cu")
		(net "GND")
	)
	(via
		(at 187.799472 -253.13894)
		(size 0.508)
		(drill 0.254)
		(layers "F.Cu" "B.Cu")
		(net "GND")
	)
	(via
		(at 269.584424 -191.351916)
		(size 0.508)
		(drill 0.254)
		(layers "F.Cu" "B.Cu")
		(net "GND")
	)
	(via
		(at 349.758 -97.536)
		(size 0.7112)
		(drill 0.4064)
		(layers "F.Cu" "B.Cu")
		(net "GND")
	)
	(via
		(at 305.352958 -66.04)
		(size 0.5588)
		(drill 0.3048)
		(layers "F.Cu" "B.Cu")
		(net "GND")
	)
	(via
		(at 262.0772 -63.1952)
		(size 0.7112)
		(drill 0.4064)
		(layers "F.Cu" "B.Cu")
		(net "GND")
	)
	(via
		(at 107.949746 -50.599594)
		(size 0.508)
		(drill 0.254)
		(layers "F.Cu" "B.Cu")
		(net "GND")
	)
	(via
		(at 153.543 -181.483)
		(size 0.7112)
		(drill 0.4064)
		(layers "F.Cu" "B.Cu")
		(net "GND")
	)
	(via
		(at 181.9275 -218.5035)
		(size 0.5588)
		(drill 0.3048)
		(layers "F.Cu" "B.Cu")
		(net "GND")
	)
	(via
		(at 182.299864 -30.806136)
		(size 0.5588)
		(drill 0.3048)
		(layers "F.Cu" "B.Cu")
		(net "GND")
	)
	(via
		(at 173.49597 -65.659)
		(size 0.5588)
		(drill 0.3048)
		(layers "F.Cu" "B.Cu")
		(net "GND")
	)
	(via
		(at 117.012212 -225.044)
		(size 0.5588)
		(drill 0.3048)
		(layers "F.Cu" "B.Cu")
		(net "GND")
	)
	(via
		(at 124.57557 -81.0768)
		(size 0.508)
		(drill 0.254)
		(layers "F.Cu" "B.Cu")
		(net "GND")
	)
	(via
		(at 107.58297 -109.601)
		(size 0.508)
		(drill 0.254)
		(layers "F.Cu" "B.Cu")
		(net "GND")
	)
	(via
		(at 173.355 -233.045)
		(size 0.7112)
		(drill 0.4064)
		(layers "F.Cu" "B.Cu")
		(net "GND")
	)
	(via
		(at 95.940372 -40.999918)
		(size 0.508)
		(drill 0.254)
		(layers "F.Cu" "B.Cu")
		(net "GND")
	)
	(via
		(at 84.074 -78.236572)
		(size 0.5588)
		(drill 0.3048)
		(layers "F.Cu" "B.Cu")
		(net "GND")
	)
	(via
		(at 102.356158 -44.196762)
		(size 0.508)
		(drill 0.254)
		(layers "F.Cu" "B.Cu")
		(net "GND")
	)
	(via
		(at 103.949754 -42.59961)
		(size 0.508)
		(drill 0.254)
		(layers "F.Cu" "B.Cu")
		(net "GND")
	)
	(via
		(at 327.881996 -8.731504)
		(size 0.5588)
		(drill 0.3048)
		(layers "F.Cu" "B.Cu")
		(net "GND")
	)
	(via
		(at 272.923 -47.117)
		(size 0.5588)
		(drill 0.3048)
		(layers "F.Cu" "B.Cu")
		(net "GND")
	)
	(via
		(at 107.995212 -202.692)
		(size 0.5588)
		(drill 0.3048)
		(layers "F.Cu" "B.Cu")
		(net "GND")
	)
	(via
		(at 306.959 -81.661)
		(size 0.5588)
		(drill 0.3048)
		(layers "F.Cu" "B.Cu")
		(net "GND")
	)
	(via
		(at 155.321 -86.741)
		(size 0.7112)
		(drill 0.4064)
		(layers "F.Cu" "B.Cu")
		(net "GND")
	)
	(via
		(at 315.309758 -69.8246)
		(size 0.5588)
		(drill 0.3048)
		(layers "F.Cu" "B.Cu")
		(net "GND")
	)
	(via
		(at 80.333342 -132.151628)
		(size 0.508)
		(drill 0.254)
		(layers "F.Cu" "B.Cu")
		(net "GND")
	)
	(via
		(at 333.828136 -198.755)
		(size 0.5588)
		(drill 0.3048)
		(layers "F.Cu" "B.Cu")
		(net "GND")
	)
	(via
		(at 129.02057 -90.4494)
		(size 0.508)
		(drill 0.254)
		(layers "F.Cu" "B.Cu")
		(net "GND")
	)
	(via
		(at 95.145606 -39.39794)
		(size 0.508)
		(drill 0.254)
		(layers "F.Cu" "B.Cu")
		(net "GND")
	)
	(via
		(at 275.708872 -227.575872)
		(size 0.5588)
		(drill 0.3048)
		(layers "F.Cu" "B.Cu")
		(net "GND")
	)
	(via
		(at 119.933212 -225.044)
		(size 0.5588)
		(drill 0.3048)
		(layers "F.Cu" "B.Cu")
		(net "GND")
	)
	(via
		(at 81.534 -10.795)
		(size 0.7112)
		(drill 0.4064)
		(layers "F.Cu" "B.Cu")
		(net "GND")
	)
	(via
		(at 284.226 -217.297)
		(size 0.7112)
		(drill 0.4064)
		(layers "F.Cu" "B.Cu")
		(net "GND")
	)
	(via
		(at 116.845842 -103.856282)
		(size 0.508)
		(drill 0.254)
		(layers "F.Cu" "B.Cu")
		(net "GND")
	)
	(via
		(at 296.50182 -202.14082)
		(size 0.508)
		(drill 0.254)
		(layers "F.Cu" "B.Cu")
		(net "GND")
	)
	(via
		(at 292.4302 -173.444916)
		(size 0.508)
		(drill 0.254)
		(layers "F.Cu" "B.Cu")
		(net "GND")
	)
	(via
		(at 262.001 -224.663)
		(size 0.5588)
		(drill 0.3048)
		(layers "F.Cu" "B.Cu")
		(net "GND")
	)
	(via
		(at 331.1525 -219.0115)
		(size 0.5588)
		(drill 0.3048)
		(layers "F.Cu" "B.Cu")
		(net "GND")
	)
	(via
		(at 299.636434 -177.43551)
		(size 0.508)
		(drill 0.254)
		(layers "F.Cu" "B.Cu")
		(net "GND")
	)
	(via
		(at 146.558 -14.732)
		(size 0.5588)
		(drill 0.3048)
		(layers "F.Cu" "B.Cu")
		(net "GND")
	)
	(via
		(at 105.791 -72.3392)
		(size 0.5588)
		(drill 0.3048)
		(layers "F.Cu" "B.Cu")
		(net "GND")
	)
	(via
		(at 313.817 -1.27)
		(size 0.5588)
		(drill 0.254)
		(layers "F.Cu" "B.Cu")
		(net "GND")
	)
	(via
		(at 182.426864 -39.75608)
		(size 0.7112)
		(drill 0.4064)
		(layers "F.Cu" "B.Cu")
		(net "GND")
	)
	(via
		(at 107.84967 -93.849698)
		(size 0.508)
		(drill 0.254)
		(layers "F.Cu" "B.Cu")
		(net "GND")
	)
	(via
		(at 346.2274 -159.258)
		(size 0.5588)
		(drill 0.3048)
		(layers "F.Cu" "B.Cu")
		(net "GND")
	)
	(via
		(at 59.055 -109.474)
		(size 0.5588)
		(drill 0.3048)
		(layers "F.Cu" "B.Cu")
		(net "GND")
	)
	(via
		(at 77.53477 -137.8204)
		(size 0.5588)
		(drill 0.3048)
		(layers "F.Cu" "B.Cu")
		(net "GND")
	)
	(via
		(at 111.849662 -96.8502)
		(size 0.508)
		(drill 0.254)
		(layers "F.Cu" "B.Cu")
		(net "GND")
	)
	(via
		(at 51.943 -207.645)
		(size 0.5588)
		(drill 0.3048)
		(layers "F.Cu" "B.Cu")
		(net "GND")
	)
	(via
		(at 323.215 -180.975)
		(size 0.508)
		(drill 0.254)
		(layers "F.Cu" "B.Cu")
		(net "GND")
	)
	(via
		(at 121.83237 -81.915)
		(size 0.508)
		(drill 0.254)
		(layers "F.Cu" "B.Cu")
		(net "GND")
	)
	(via
		(at 190.4365 -115.316)
		(size 0.5588)
		(drill 0.3048)
		(layers "F.Cu" "B.Cu")
		(net "GND")
	)
	(via
		(at 183.315864 -28.647136)
		(size 0.5588)
		(drill 0.3048)
		(layers "F.Cu" "B.Cu")
		(net "GND")
	)
	(via
		(at 169.545 -115.316)
		(size 0.5588)
		(drill 0.3048)
		(layers "F.Cu" "B.Cu")
		(net "GND")
	)
	(via
		(at 90.69197 -95.631)
		(size 0.5588)
		(drill 0.3048)
		(layers "F.Cu" "B.Cu")
		(net "GND")
	)
	(via
		(at 254.127 -169.545)
		(size 0.7112)
		(drill 0.4064)
		(layers "F.Cu" "B.Cu")
		(net "GND")
	)
	(via
		(at 132.969 -88.265)
		(size 0.508)
		(drill 0.254)
		(layers "F.Cu" "B.Cu")
		(net "GND")
	)
	(via
		(at 195.707 -34.544)
		(size 0.5588)
		(drill 0.3048)
		(layers "F.Cu" "B.Cu")
		(net "GND")
	)
	(via
		(at 109.849666 -101.85019)
		(size 0.508)
		(drill 0.254)
		(layers "F.Cu" "B.Cu")
		(net "GND")
	)
	(via
		(at 328.295 -112.014)
		(size 0.7112)
		(drill 0.4064)
		(layers "F.Cu" "B.Cu")
		(net "GND")
	)
	(via
		(at 85.5218 -1.0922)
		(size 0.5588)
		(drill 0.3048)
		(layers "F.Cu" "B.Cu")
		(net "GND")
	)
	(via
		(at 85.45703 -129.36982)
		(size 0.5588)
		(drill 0.3048)
		(layers "F.Cu" "B.Cu")
		(net "GND")
	)
	(via
		(at 112.858042 -105.888282)
		(size 0.508)
		(drill 0.254)
		(layers "F.Cu" "B.Cu")
		(net "GND")
	)
	(via
		(at 213.868 -94.488)
		(size 0.7112)
		(drill 0.4064)
		(layers "F.Cu" "B.Cu")
		(net "GND")
	)
	(via
		(at 28.6766 -251.079)
		(size 0.508)
		(drill 0.254)
		(layers "F.Cu" "B.Cu")
		(net "GND")
	)
	(via
		(at 77.578966 -55.7276)
		(size 0.5588)
		(drill 0.3048)
		(layers "F.Cu" "B.Cu")
		(net "GND")
	)
	(via
		(at 268.732 -38.227)
		(size 0.5588)
		(drill 0.3048)
		(layers "F.Cu" "B.Cu")
		(net "GND")
	)
	(via
		(at 116.85016 -88.849708)
		(size 0.508)
		(drill 0.254)
		(layers "F.Cu" "B.Cu")
		(net "GND")
	)
	(via
		(at 180.140864 -39.75608)
		(size 0.7112)
		(drill 0.4064)
		(layers "F.Cu" "B.Cu")
		(net "GND")
	)
	(via
		(at 221.234 -162.433)
		(size 0.5588)
		(drill 0.3048)
		(layers "F.Cu" "B.Cu")
		(net "GND")
	)
	(via
		(at 251.46 -169.545)
		(size 0.7112)
		(drill 0.4064)
		(layers "F.Cu" "B.Cu")
		(net "GND")
	)
	(via
		(at 118.917212 -225.044)
		(size 0.5588)
		(drill 0.3048)
		(layers "F.Cu" "B.Cu")
		(net "GND")
	)
	(via
		(at 124.850144 -99.850194)
		(size 0.508)
		(drill 0.254)
		(layers "F.Cu" "B.Cu")
		(net "GND")
	)
	(via
		(at 97.54997 -47.399702)
		(size 0.508)
		(drill 0.254)
		(layers "F.Cu" "B.Cu")
		(net "GND")
	)
	(via
		(at 89.262966 -32.131)
		(size 0.5588)
		(drill 0.3048)
		(layers "F.Cu" "B.Cu")
		(net "GND")
	)
	(via
		(at 122.850148 -103.850186)
		(size 0.508)
		(drill 0.254)
		(layers "F.Cu" "B.Cu")
		(net "GND")
	)
	(via
		(at 268.732 -227.584)
		(size 0.7112)
		(drill 0.4064)
		(layers "F.Cu" "B.Cu")
		(net "GND")
	)
	(via
		(at 126.85014 -105.850182)
		(size 0.508)
		(drill 0.254)
		(layers "F.Cu" "B.Cu")
		(net "GND")
	)
	(via
		(at 196.85 -1.27)
		(size 0.5588)
		(drill 0.254)
		(layers "F.Cu" "B.Cu")
		(net "GND")
	)
	(via
		(at 109.549946 -41.79951)
		(size 0.508)
		(drill 0.254)
		(layers "F.Cu" "B.Cu")
		(net "GND")
	)
	(via
		(at 120.822212 -202.819)
		(size 0.5588)
		(drill 0.3048)
		(layers "F.Cu" "B.Cu")
		(net "GND")
	)
	(via
		(at 38.86073 -83.596226)
		(size 0.5588)
		(drill 0.3048)
		(layers "F.Cu" "B.Cu")
		(net "GND")
	)
	(via
		(at 237.236 -113.9698)
		(size 0.5588)
		(drill 0.3048)
		(layers "F.Cu" "B.Cu")
		(net "GND")
	)
	(via
		(at 90.18397 -98.933)
		(size 0.5588)
		(drill 0.3048)
		(layers "F.Cu" "B.Cu")
		(net "GND")
	)
	(via
		(at 1.143 -149.681438)
		(size 0.7112)
		(drill 0.4064)
		(layers "F.Cu" "B.Cu")
		(net "GND")
	)
	(via
		(at 351.6376 -152.8826)
		(size 0.508)
		(drill 0.254)
		(layers "F.Cu" "B.Cu")
		(net "GND")
	)
	(via
		(at 257.2766 -69.9262)
		(size 0.7112)
		(drill 0.4064)
		(layers "F.Cu" "B.Cu")
		(net "GND")
	)
	(via
		(at 106.242612 -210.312)
		(size 0.5588)
		(drill 0.3048)
		(layers "F.Cu" "B.Cu")
		(net "GND")
	)
	(via
		(at 99.95027 -37.00018)
		(size 0.508)
		(drill 0.254)
		(layers "F.Cu" "B.Cu")
		(net "GND")
	)
	(via
		(at 31.623 -80.264)
		(size 0.5588)
		(drill 0.3048)
		(layers "F.Cu" "B.Cu")
		(net "GND")
	)
	(via
		(at 33.732216 -227.13188)
		(size 0.5588)
		(drill 0.3048)
		(layers "F.Cu" "B.Cu")
		(net "GND")
	)
	(via
		(at 110.849664 -95.850202)
		(size 0.508)
		(drill 0.254)
		(layers "F.Cu" "B.Cu")
		(net "GND")
	)
	(via
		(at 326.771 -144.526)
		(size 0.5588)
		(drill 0.3048)
		(layers "F.Cu" "B.Cu")
		(net "GND")
	)
	(via
		(at 306.959 -91.186)
		(size 0.5588)
		(drill 0.3048)
		(layers "F.Cu" "B.Cu")
		(net "GND")
	)
	(via
		(at 276.4536 -164.460936)
		(size 0.508)
		(drill 0.254)
		(layers "F.Cu" "B.Cu")
		(net "GND")
	)
	(via
		(at 293.241984 -169.442384)
		(size 0.508)
		(drill 0.254)
		(layers "F.Cu" "B.Cu")
		(net "GND")
	)
	(via
		(at 110.350046 -53.79974)
		(size 0.508)
		(drill 0.254)
		(layers "F.Cu" "B.Cu")
		(net "GND")
	)
	(via
		(at 197.222872 -113.6904)
		(size 0.7112)
		(drill 0.4064)
		(layers "F.Cu" "B.Cu")
		(net "GND")
	)
	(via
		(at 99.149916 -42.59961)
		(size 0.508)
		(drill 0.254)
		(layers "F.Cu" "B.Cu")
		(net "GND")
	)
	(via
		(at 130.405378 -79.121508)
		(size 0.508)
		(drill 0.254)
		(layers "F.Cu" "B.Cu")
		(net "GND")
	)
	(via
		(at 264.795 -236.22)
		(size 0.5588)
		(drill 0.3048)
		(layers "F.Cu" "B.Cu")
		(net "GND")
	)
	(via
		(at 119.850154 -104.850184)
		(size 0.508)
		(drill 0.254)
		(layers "F.Cu" "B.Cu")
		(net "GND")
	)
	(via
		(at 314.706 -89.6112)
		(size 0.5588)
		(drill 0.3048)
		(layers "F.Cu" "B.Cu")
		(net "GND")
	)
	(via
		(at 9.145016 -213.233)
		(size 0.5588)
		(drill 0.3048)
		(layers "F.Cu" "B.Cu")
		(net "GND")
	)
	(via
		(at 48.006 -88.2904)
		(size 0.5588)
		(drill 0.3048)
		(layers "F.Cu" "B.Cu")
		(net "GND")
	)
	(via
		(at 306.451 -83.82)
		(size 0.5588)
		(drill 0.3048)
		(layers "F.Cu" "B.Cu")
		(net "GND")
	)
	(via
		(at 295.630092 -175.044862)
		(size 0.508)
		(drill 0.254)
		(layers "F.Cu" "B.Cu")
		(net "GND")
	)
	(via
		(at 65.7352 -46.7868)
		(size 0.7112)
		(drill 0.4064)
		(layers "F.Cu" "B.Cu")
		(net "GND")
	)
	(via
		(at 270.891 -47.117)
		(size 0.5588)
		(drill 0.3048)
		(layers "F.Cu" "B.Cu")
		(net "GND")
	)
	(via
		(at 156.21 -84.582)
		(size 0.7112)
		(drill 0.4064)
		(layers "F.Cu" "B.Cu")
		(net "GND")
	)
	(via
		(at 134.6454 -88.1888)
		(size 0.508)
		(drill 0.254)
		(layers "F.Cu" "B.Cu")
		(net "GND")
	)
	(via
		(at 222.758 -104.013)
		(size 0.5588)
		(drill 0.3048)
		(layers "F.Cu" "B.Cu")
		(net "GND")
	)
	(via
		(at 96.52 -221.488)
		(size 0.5588)
		(drill 0.3048)
		(layers "F.Cu" "B.Cu")
		(net "GND")
	)
	(via
		(at 133.522466 -34.6075)
		(size 0.5588)
		(drill 0.3048)
		(layers "F.Cu" "B.Cu")
		(net "GND")
	)
	(via
		(at 94.88297 -122.555)
		(size 0.5588)
		(drill 0.3048)
		(layers "F.Cu" "B.Cu")
		(net "GND")
	)
	(via
		(at 116.85016 -99.850194)
		(size 0.508)
		(drill 0.254)
		(layers "F.Cu" "B.Cu")
		(net "GND")
	)
	(via
		(at 292.608 -226.06)
		(size 0.7112)
		(drill 0.4064)
		(layers "F.Cu" "B.Cu")
		(net "GND")
	)
	(via
		(at 201.041 -199.009)
		(size 0.5588)
		(drill 0.3048)
		(layers "F.Cu" "B.Cu")
		(net "GND")
	)
	(via
		(at 308.61 -248.92)
		(size 0.5588)
		(drill 0.254)
		(layers "F.Cu" "B.Cu")
		(net "GND")
	)
	(via
		(at 1.143 -225.881438)
		(size 0.7112)
		(drill 0.4064)
		(layers "F.Cu" "B.Cu")
		(net "GND")
	)
	(via
		(at 146.05 -1.27)
		(size 0.5588)
		(drill 0.254)
		(layers "F.Cu" "B.Cu")
		(net "GND")
	)
	(via
		(at 125.850142 -107.850178)
		(size 0.508)
		(drill 0.254)
		(layers "F.Cu" "B.Cu")
		(net "GND")
	)
	(via
		(at 127.850138 -102.850188)
		(size 0.508)
		(drill 0.254)
		(layers "F.Cu" "B.Cu")
		(net "GND")
	)
	(via
		(at 104.013 -196.977)
		(size 0.7112)
		(drill 0.4064)
		(layers "F.Cu" "B.Cu")
		(net "GND")
	)
	(via
		(at 172.974 -115.824)
		(size 0.5588)
		(drill 0.3048)
		(layers "F.Cu" "B.Cu")
		(net "GND")
	)
	(via
		(at 294.132 -78.613)
		(size 0.5588)
		(drill 0.3048)
		(layers "F.Cu" "B.Cu")
		(net "GND")
	)
	(via
		(at 54.59984 -81.545176)
		(size 0.5588)
		(drill 0.3048)
		(layers "F.Cu" "B.Cu")
		(net "GND")
	)
	(via
		(at 313.480958 -96.393)
		(size 0.5588)
		(drill 0.3048)
		(layers "F.Cu" "B.Cu")
		(net "GND")
	)
	(via
		(at 197.2945 -245.0465)
		(size 0.5588)
		(drill 0.3048)
		(layers "F.Cu" "B.Cu")
		(net "GND")
	)
	(via
		(at 21.294852 -215.425782)
		(size 0.5588)
		(drill 0.3048)
		(layers "F.Cu" "B.Cu")
		(net "GND")
	)
	(via
		(at 129.921 -87.63)
		(size 0.7112)
		(drill 0.3556)
		(layers "F.Cu" "B.Cu")
		(net "GND")
	)
	(via
		(at 320.031872 -112.848136)
		(size 0.5588)
		(drill 0.3048)
		(layers "F.Cu" "B.Cu")
		(net "GND")
	)
	(via
		(at 285.242 -63.627)
		(size 0.5588)
		(drill 0.3048)
		(layers "F.Cu" "B.Cu")
		(net "GND")
	)
	(via
		(at 301.752 -193.675)
		(size 0.5588)
		(drill 0.3048)
		(layers "F.Cu" "B.Cu")
		(net "GND")
	)
	(via
		(at 306.832 -78.486)
		(size 0.5588)
		(drill 0.3048)
		(layers "F.Cu" "B.Cu")
		(net "GND")
	)
	(via
		(at 115.850162 -95.850202)
		(size 0.508)
		(drill 0.254)
		(layers "F.Cu" "B.Cu")
		(net "GND")
	)
	(via
		(at 109.5502 -36.20008)
		(size 0.508)
		(drill 0.254)
		(layers "F.Cu" "B.Cu")
		(net "GND")
	)
	(via
		(at 86.659212 -252.984)
		(size 0.7112)
		(drill 0.4064)
		(layers "F.Cu" "B.Cu")
		(net "GND")
	)
	(via
		(at 331.58049 -153.395172)
		(size 0.508)
		(drill 0.254)
		(layers "F.Cu" "B.Cu")
		(net "GND")
	)
	(via
		(at 123.850146 -107.850178)
		(size 0.508)
		(drill 0.254)
		(layers "F.Cu" "B.Cu")
		(net "GND")
	)
	(via
		(at 307.086 -53.975)
		(size 0.5588)
		(drill 0.3048)
		(layers "F.Cu" "B.Cu")
		(net "GND")
	)
	(via
		(at 275.844 -32.131)
		(size 0.5588)
		(drill 0.3048)
		(layers "F.Cu" "B.Cu")
		(net "GND")
	)
	(via
		(at 96.759776 -40.999918)
		(size 0.508)
		(drill 0.254)
		(layers "F.Cu" "B.Cu")
		(net "GND")
	)
	(via
		(at 40.259 -117.221)
		(size 0.5588)
		(drill 0.3048)
		(layers "F.Cu" "B.Cu")
		(net "GND")
	)
	(via
		(at 94.350078 -44.190412)
		(size 0.508)
		(drill 0.254)
		(layers "F.Cu" "B.Cu")
		(net "GND")
	)
	(via
		(at 81.67497 -135.763)
		(size 0.5588)
		(drill 0.3048)
		(layers "F.Cu" "B.Cu")
		(net "GND")
	)
	(via
		(at 1.143 -98.881438)
		(size 0.7112)
		(drill 0.4064)
		(layers "F.Cu" "B.Cu")
		(net "GND")
	)
	(via
		(at 350.4184 -148.3868)
		(size 0.508)
		(drill 0.254)
		(layers "F.Cu" "B.Cu")
		(net "GND")
	)
	(via
		(at 153.289 -55.499)
		(size 0.508)
		(drill 0.254)
		(layers "F.Cu" "B.Cu")
		(net "GND")
	)
	(via
		(at 332.994 -110.49)
		(size 0.5588)
		(drill 0.3048)
		(layers "F.Cu" "B.Cu")
		(net "GND")
	)
	(via
		(at 109.35716 -27.6225)
		(size 0.5588)
		(drill 0.3048)
		(layers "F.Cu" "B.Cu")
		(net "GND")
	)
	(via
		(at 163.068 -85.09)
		(size 0.7112)
		(drill 0.4064)
		(layers "F.Cu" "B.Cu")
		(net "GND")
	)
	(via
		(at 179.959 -92.71)
		(size 0.7112)
		(drill 0.4064)
		(layers "F.Cu" "B.Cu")
		(net "GND")
	)
	(via
		(at 53.975 -110.49)
		(size 0.5588)
		(drill 0.3048)
		(layers "F.Cu" "B.Cu")
		(net "GND")
	)
	(via
		(at 124.841 -181.61)
		(size 0.7112)
		(drill 0.4064)
		(layers "F.Cu" "B.Cu")
		(net "GND")
	)
	(via
		(at 50.038 -228.854)
		(size 0.5588)
		(drill 0.3048)
		(layers "F.Cu" "B.Cu")
		(net "GND")
	)
	(via
		(at 319.405 -180.467)
		(size 0.508)
		(drill 0.254)
		(layers "F.Cu" "B.Cu")
		(net "GND")
	)
	(via
		(at 103.849678 -97.850198)
		(size 0.508)
		(drill 0.254)
		(layers "F.Cu" "B.Cu")
		(net "GND")
	)
	(via
		(at 114.624612 -214.884)
		(size 0.5588)
		(drill 0.3048)
		(layers "F.Cu" "B.Cu")
		(net "GND")
	)
	(via
		(at 302.768 -87.503)
		(size 0.5588)
		(drill 0.3048)
		(layers "F.Cu" "B.Cu")
		(net "GND")
	)
	(via
		(at 314.706 -86.0806)
		(size 0.5588)
		(drill 0.3048)
		(layers "F.Cu" "B.Cu")
		(net "GND")
	)
	(via
		(at 110.419642 -108.275882)
		(size 0.508)
		(drill 0.254)
		(layers "F.Cu" "B.Cu")
		(net "GND")
	)
	(via
		(at 301.23003 -176.63541)
		(size 0.508)
		(drill 0.254)
		(layers "F.Cu" "B.Cu")
		(net "GND")
	)
	(via
		(at 332.096872 -224.671128)
		(size 0.5588)
		(drill 0.3048)
		(layers "F.Cu" "B.Cu")
		(net "GND")
	)
	(via
		(at 232.41 -245.11)
		(size 0.7112)
		(drill 0.4064)
		(layers "F.Cu" "B.Cu")
		(net "GND")
	)
	(via
		(at 160.655 -110.871)
		(size 0.7112)
		(drill 0.4064)
		(layers "F.Cu" "B.Cu")
		(net "GND")
	)
	(via
		(at 117.850158 -92.8497)
		(size 0.508)
		(drill 0.254)
		(layers "F.Cu" "B.Cu")
		(net "GND")
	)
	(via
		(at 183.684672 -196.845936)
		(size 0.5588)
		(drill 0.3048)
		(layers "F.Cu" "B.Cu")
		(net "GND")
	)
	(via
		(at 94.37497 -88.265)
		(size 0.5588)
		(drill 0.3048)
		(layers "F.Cu" "B.Cu")
		(net "GND")
	)
	(via
		(at 107.156504 -42.59707)
		(size 0.508)
		(drill 0.254)
		(layers "F.Cu" "B.Cu")
		(net "GND")
	)
	(via
		(at 99.149916 -55.399686)
		(size 0.508)
		(drill 0.254)
		(layers "F.Cu" "B.Cu")
		(net "GND")
	)
	(via
		(at 304.474372 -203.398628)
		(size 0.5588)
		(drill 0.3048)
		(layers "F.Cu" "B.Cu")
		(net "GND")
	)
	(via
		(at 203.327 -248.285)
		(size 0.7112)
		(drill 0.4064)
		(layers "F.Cu" "B.Cu")
		(net "GND")
	)
	(via
		(at 108.849668 -101.85019)
		(size 0.508)
		(drill 0.254)
		(layers "F.Cu" "B.Cu")
		(net "GND")
	)
	(via
		(at 69.596 -234.061)
		(size 0.5588)
		(drill 0.3048)
		(layers "F.Cu" "B.Cu")
		(net "GND")
	)
	(via
		(at 217.12428 -89.50452)
		(size 0.5588)
		(drill 0.3048)
		(layers "F.Cu" "B.Cu")
		(net "GND")
	)
	(via
		(at 335.652364 -230.386636)
		(size 0.5588)
		(drill 0.3048)
		(layers "F.Cu" "B.Cu")
		(net "GND")
	)
	(via
		(at 9.856216 -230.17988)
		(size 0.5588)
		(drill 0.3048)
		(layers "F.Cu" "B.Cu")
		(net "GND")
	)
	(via
		(at 334.772 -93.853)
		(size 0.7112)
		(drill 0.4064)
		(layers "F.Cu" "B.Cu")
		(net "GND")
	)
	(via
		(at 128.524 -80.645)
		(size 0.508)
		(drill 0.254)
		(layers "F.Cu" "B.Cu")
		(net "GND")
	)
	(via
		(at 320.04 -113.919)
		(size 0.5588)
		(drill 0.3048)
		(layers "F.Cu" "B.Cu")
		(net "GND")
	)
	(via
		(at 89.516966 -70.866)
		(size 0.7112)
		(drill 0.4064)
		(layers "F.Cu" "B.Cu")
		(net "GND")
	)
	(via
		(at 24.825198 -177.457862)
		(size 0.5588)
		(drill 0.3048)
		(layers "F.Cu" "B.Cu")
		(net "GND")
	)
	(via
		(at 10.173716 -209.28838)
		(size 0.5588)
		(drill 0.3048)
		(layers "F.Cu" "B.Cu")
		(net "GND")
	)
	(via
		(at 280.035 -67.183)
		(size 0.508)
		(drill 0.254)
		(layers "F.Cu" "B.Cu")
		(net "GND")
	)
	(via
		(at 349.123 -100.33)
		(size 0.7112)
		(drill 0.4064)
		(layers "F.Cu" "B.Cu")
		(net "GND")
	)
	(via
		(at 180.35397 -65.659)
		(size 0.5588)
		(drill 0.3048)
		(layers "F.Cu" "B.Cu")
		(net "GND")
	)
	(via
		(at 45.72 -193.04)
		(size 0.7112)
		(drill 0.4064)
		(layers "F.Cu" "B.Cu")
		(net "GND")
	)
	(via
		(at 113.849658 -89.849706)
		(size 0.508)
		(drill 0.254)
		(layers "F.Cu" "B.Cu")
		(net "GND")
	)
	(via
		(at 213.1695 -217.043)
		(size 0.5588)
		(drill 0.3048)
		(layers "F.Cu" "B.Cu")
		(net "GND")
	)
	(via
		(at 66.593212 -247.904)
		(size 0.7112)
		(drill 0.4064)
		(layers "F.Cu" "B.Cu")
		(net "GND")
	)
	(via
		(at 110.349792 -47.399702)
		(size 0.508)
		(drill 0.254)
		(layers "F.Cu" "B.Cu")
		(net "GND")
	)
	(via
		(at 94.34957 -37.808916)
		(size 0.508)
		(drill 0.254)
		(layers "F.Cu" "B.Cu")
		(net "GND")
	)
	(via
		(at 37.8714 -167.9194)
		(size 0.5588)
		(drill 0.3048)
		(layers "F.Cu" "B.Cu")
		(net "GND")
	)
	(via
		(at 103.849678 -101.85019)
		(size 0.508)
		(drill 0.254)
		(layers "F.Cu" "B.Cu")
		(net "GND")
	)
	(via
		(at 142.76197 -88.265)
		(size 0.5588)
		(drill 0.3048)
		(layers "F.Cu" "B.Cu")
		(net "GND")
	)
	(via
		(at 113.849658 -93.849698)
		(size 0.508)
		(drill 0.254)
		(layers "F.Cu" "B.Cu")
		(net "GND")
	)
	(via
		(at 289.7251 -198.753984)
		(size 0.508)
		(drill 0.254)
		(layers "F.Cu" "B.Cu")
		(net "GND")
	)
	(via
		(at 304.292 -88.392)
		(size 0.5588)
		(drill 0.3048)
		(layers "F.Cu" "B.Cu")
		(net "GND")
	)
	(via
		(at 127.850138 -103.850186)
		(size 0.508)
		(drill 0.254)
		(layers "F.Cu" "B.Cu")
		(net "GND")
	)
	(via
		(at 284.734 -209.169)
		(size 0.5588)
		(drill 0.3048)
		(layers "F.Cu" "B.Cu")
		(net "GND")
	)
	(via
		(at 320.295524 -77.099922)
		(size 0.5588)
		(drill 0.3048)
		(layers "F.Cu" "B.Cu")
		(net "GND")
	)
	(via
		(at 121.85015 -91.849702)
		(size 0.508)
		(drill 0.254)
		(layers "F.Cu" "B.Cu")
		(net "GND")
	)
	(via
		(at 127.850138 -100.850192)
		(size 0.508)
		(drill 0.254)
		(layers "F.Cu" "B.Cu")
		(net "GND")
	)
	(via
		(at 115.850162 -97.850198)
		(size 0.508)
		(drill 0.254)
		(layers "F.Cu" "B.Cu")
		(net "GND")
	)
	(via
		(at 194.312286 -143.126714)
		(size 0.5588)
		(drill 0.3048)
		(layers "F.Cu" "B.Cu")
		(net "GND")
	)
	(via
		(at 83.058 -78.232)
		(size 0.5588)
		(drill 0.3048)
		(layers "F.Cu" "B.Cu")
		(net "GND")
	)
	(via
		(at 198.755 -89.154)
		(size 0.7112)
		(drill 0.4064)
		(layers "F.Cu" "B.Cu")
		(net "GND")
	)
	(via
		(at 354.106988 -1.493012)
		(size 0.5588)
		(drill 0.254)
		(layers "F.Cu" "B.Cu")
		(net "GND")
	)
	(via
		(at 92.964 -70.485)
		(size 0.7112)
		(drill 0.4064)
		(layers "F.Cu" "B.Cu")
		(net "GND")
	)
	(via
		(at 290.83 -246.38)
		(size 0.7112)
		(drill 0.4064)
		(layers "F.Cu" "B.Cu")
		(net "GND")
	)
	(via
		(at 273.685 -24.638)
		(size 0.5588)
		(drill 0.3048)
		(layers "F.Cu" "B.Cu")
		(net "GND")
	)
	(via
		(at 105.849674 -102.850188)
		(size 0.508)
		(drill 0.254)
		(layers "F.Cu" "B.Cu")
		(net "GND")
	)
	(via
		(at 280.67 -101.727)
		(size 0.7112)
		(drill 0.4064)
		(layers "F.Cu" "B.Cu")
		(net "GND")
	)
	(via
		(at 283.582872 -222.068136)
		(size 0.5588)
		(drill 0.3048)
		(layers "F.Cu" "B.Cu")
		(net "GND")
	)
	(via
		(at 314.833 -92.964)
		(size 0.5588)
		(drill 0.3048)
		(layers "F.Cu" "B.Cu")
		(net "GND")
	)
	(via
		(at 99.159568 -47.399956)
		(size 0.508)
		(drill 0.254)
		(layers "F.Cu" "B.Cu")
		(net "GND")
	)
	(via
		(at 324.104 -176.276)
		(size 0.508)
		(drill 0.254)
		(layers "F.Cu" "B.Cu")
		(net "GND")
	)
	(via
		(at 166.665148 -119.973852)
		(size 0.5588)
		(drill 0.3048)
		(layers "F.Cu" "B.Cu")
		(net "GND")
	)
	(via
		(at 95.943928 -42.596562)
		(size 0.508)
		(drill 0.254)
		(layers "F.Cu" "B.Cu")
		(net "GND")
	)
	(via
		(at 91.000072 -252.857)
		(size 0.7112)
		(drill 0.4064)
		(layers "F.Cu" "B.Cu")
		(net "GND")
	)
	(via
		(at 314.833 -51.816)
		(size 0.5588)
		(drill 0.3048)
		(layers "F.Cu" "B.Cu")
		(net "GND")
	)
	(via
		(at 232.41 -240.03)
		(size 0.7112)
		(drill 0.4064)
		(layers "F.Cu" "B.Cu")
		(net "GND")
	)
	(via
		(at 237.49 -13.081)
		(size 0.508)
		(drill 0.254)
		(layers "F.Cu" "B.Cu")
		(net "GND")
	)
	(via
		(at 189.6745 -145.2245)
		(size 0.5588)
		(drill 0.3048)
		(layers "F.Cu" "B.Cu")
		(net "GND")
	)
	(via
		(at 269.367 -69.85)
		(size 0.7112)
		(drill 0.3556)
		(layers "F.Cu" "B.Cu")
		(net "GND")
	)
	(via
		(at 305.288188 -63.119)
		(size 0.5588)
		(drill 0.3048)
		(layers "F.Cu" "B.Cu")
		(net "GND")
	)
	(via
		(at 160.655 -109.601)
		(size 0.7112)
		(drill 0.4064)
		(layers "F.Cu" "B.Cu")
		(net "GND")
	)
	(via
		(at 273.6215 -25.908)
		(size 0.5588)
		(drill 0.3048)
		(layers "F.Cu" "B.Cu")
		(net "GND")
	)
	(via
		(at 82.468212 -252.857)
		(size 0.7112)
		(drill 0.4064)
		(layers "F.Cu" "B.Cu")
		(net "GND")
	)
	(via
		(at 172.22597 -65.659)
		(size 0.5588)
		(drill 0.3048)
		(layers "F.Cu" "B.Cu")
		(net "GND")
	)
	(via
		(at 126.537212 -252.857)
		(size 0.7112)
		(drill 0.4064)
		(layers "F.Cu" "B.Cu")
		(net "GND")
	)
	(via
		(at 200.8124 -139.0904)
		(size 0.5588)
		(drill 0.3048)
		(layers "F.Cu" "B.Cu")
		(net "GND")
	)
	(via
		(at 82.804 -74.295)
		(size 0.5588)
		(drill 0.254)
		(layers "F.Cu" "B.Cu")
		(net "GND")
	)
	(via
		(at 127.850138 -98.850196)
		(size 0.508)
		(drill 0.254)
		(layers "F.Cu" "B.Cu")
		(net "GND")
	)
	(via
		(at 104.750362 -36.20008)
		(size 0.508)
		(drill 0.254)
		(layers "F.Cu" "B.Cu")
		(net "GND")
	)
	(via
		(at 87.884 -1.1176)
		(size 0.5588)
		(drill 0.3048)
		(layers "F.Cu" "B.Cu")
		(net "GND")
	)
	(via
		(at 314.579 -80.391)
		(size 0.5588)
		(drill 0.3048)
		(layers "F.Cu" "B.Cu")
		(net "GND")
	)
	(via
		(at 262.2804 -220.384878)
		(size 0.5588)
		(drill 0.3048)
		(layers "F.Cu" "B.Cu")
		(net "GND")
	)
	(via
		(at 179.578 -86.487)
		(size 0.7112)
		(drill 0.4064)
		(layers "F.Cu" "B.Cu")
		(net "GND")
	)
	(via
		(at 312.547 -213.614)
		(size 0.5588)
		(drill 0.3048)
		(layers "F.Cu" "B.Cu")
		(net "GND")
	)
	(via
		(at 272.542 -161.925)
		(size 0.5588)
		(drill 0.3048)
		(layers "F.Cu" "B.Cu")
		(net "GND")
	)
	(via
		(at 88.564212 -252.984)
		(size 0.7112)
		(drill 0.4064)
		(layers "F.Cu" "B.Cu")
		(net "GND")
	)
	(via
		(at 19.508216 -168.33088)
		(size 0.5588)
		(drill 0.3048)
		(layers "F.Cu" "B.Cu")
		(net "GND")
	)
	(via
		(at 174.743872 -198.573136)
		(size 0.5588)
		(drill 0.3048)
		(layers "F.Cu" "B.Cu")
		(net "GND")
	)
	(via
		(at 126.73457 -80.4926)
		(size 0.508)
		(drill 0.254)
		(layers "F.Cu" "B.Cu")
		(net "GND")
	)
	(via
		(at 162.179 -103.886)
		(size 0.7112)
		(drill 0.4064)
		(layers "F.Cu" "B.Cu")
		(net "GND")
	)
	(via
		(at 337.82 -248.92)
		(size 0.5588)
		(drill 0.254)
		(layers "F.Cu" "B.Cu")
		(net "GND")
	)
	(via
		(at 91.5416 -1.1176)
		(size 0.5588)
		(drill 0.3048)
		(layers "F.Cu" "B.Cu")
		(net "GND")
	)
	(via
		(at 177.499772 -192.8749)
		(size 0.5588)
		(drill 0.3048)
		(layers "F.Cu" "B.Cu")
		(net "GND")
	)
	(via
		(at 255.786128 -223.511872)
		(size 0.5588)
		(drill 0.3048)
		(layers "F.Cu" "B.Cu")
		(net "GND")
	)
	(via
		(at 121.85015 -93.849698)
		(size 0.508)
		(drill 0.254)
		(layers "F.Cu" "B.Cu")
		(net "GND")
	)
	(via
		(at 1.143 -170.001438)
		(size 0.7112)
		(drill 0.4064)
		(layers "F.Cu" "B.Cu")
		(net "GND")
	)
	(via
		(at 121.285 -181.61)
		(size 0.7112)
		(drill 0.4064)
		(layers "F.Cu" "B.Cu")
		(net "GND")
	)
	(via
		(at 203.835 -147.193)
		(size 0.5588)
		(drill 0.3048)
		(layers "F.Cu" "B.Cu")
		(net "GND")
	)
	(via
		(at 81.534 -7.366)
		(size 0.7112)
		(drill 0.4064)
		(layers "F.Cu" "B.Cu")
		(net "GND")
	)
	(via
		(at 64.389 -154.559)
		(size 0.5588)
		(drill 0.3048)
		(layers "F.Cu" "B.Cu")
		(net "GND")
	)
	(via
		(at 18.238216 -200.58888)
		(size 0.5588)
		(drill 0.3048)
		(layers "F.Cu" "B.Cu")
		(net "GND")
	)
	(via
		(at 144.145 -116.205)
		(size 0.7112)
		(drill 0.4064)
		(layers "F.Cu" "B.Cu")
		(net "GND")
	)
	(via
		(at 317.881 -67.691)
		(size 0.5588)
		(drill 0.3048)
		(layers "F.Cu" "B.Cu")
		(net "GND")
	)
	(via
		(at 213.36 -248.92)
		(size 0.5588)
		(drill 0.254)
		(layers "F.Cu" "B.Cu")
		(net "GND")
	)
	(via
		(at 319.674748 -170.799252)
		(size 0.508)
		(drill 0.254)
		(layers "F.Cu" "B.Cu")
		(net "GND")
	)
	(via
		(at 332.105 -1.27)
		(size 0.5588)
		(drill 0.254)
		(layers "F.Cu" "B.Cu")
		(net "GND")
	)
	(via
		(at 115.850162 -90.849704)
		(size 0.508)
		(drill 0.254)
		(layers "F.Cu" "B.Cu")
		(net "GND")
	)
	(via
		(at 105.549446 -38.60546)
		(size 0.508)
		(drill 0.254)
		(layers "F.Cu" "B.Cu")
		(net "GND")
	)
	(via
		(at 145.796 -68.326)
		(size 0.5588)
		(drill 0.3048)
		(layers "F.Cu" "B.Cu")
		(net "GND")
	)
	(via
		(at 287.629092 -183.038496)
		(size 0.508)
		(drill 0.254)
		(layers "F.Cu" "B.Cu")
		(net "GND")
	)
	(via
		(at 116.656612 -214.884)
		(size 0.5588)
		(drill 0.3048)
		(layers "F.Cu" "B.Cu")
		(net "GND")
	)
	(via
		(at 334.772 -96.901)
		(size 0.7112)
		(drill 0.4064)
		(layers "F.Cu" "B.Cu")
		(net "GND")
	)
	(via
		(at 324.231 -120.65)
		(size 0.7112)
		(drill 0.4064)
		(layers "F.Cu" "B.Cu")
		(net "GND")
	)
	(via
		(at 237.744 -94.869)
		(size 0.5588)
		(drill 0.3048)
		(layers "F.Cu" "B.Cu")
		(net "GND")
	)
	(via
		(at 201.803 -227.838)
		(size 0.5588)
		(drill 0.3048)
		(layers "F.Cu" "B.Cu")
		(net "GND")
	)
	(via
		(at 112.567212 -225.044)
		(size 0.5588)
		(drill 0.3048)
		(layers "F.Cu" "B.Cu")
		(net "GND")
	)
	(via
		(at 41.29913 -75.364086)
		(size 0.5588)
		(drill 0.3048)
		(layers "F.Cu" "B.Cu")
		(net "GND")
	)
	(via
		(at 18.746216 -177.72888)
		(size 0.5588)
		(drill 0.3048)
		(layers "F.Cu" "B.Cu")
		(net "GND")
	)
	(via
		(at 207.899 -91.8464)
		(size 0.7112)
		(drill 0.4064)
		(layers "F.Cu" "B.Cu")
		(net "GND")
	)
	(via
		(at 120.850152 -91.849702)
		(size 0.508)
		(drill 0.254)
		(layers "F.Cu" "B.Cu")
		(net "GND")
	)
	(via
		(at 72.562212 -252.857)
		(size 0.7112)
		(drill 0.4064)
		(layers "F.Cu" "B.Cu")
		(net "GND")
	)
	(via
		(at 96.000062 -252.91415)
		(size 0.7112)
		(drill 0.4064)
		(layers "F.Cu" "B.Cu")
		(net "GND")
	)
	(via
		(at 209.81924 -219.31376)
		(size 0.5588)
		(drill 0.3048)
		(layers "F.Cu" "B.Cu")
		(net "GND")
	)
	(via
		(at 105.849674 -105.850182)
		(size 0.508)
		(drill 0.254)
		(layers "F.Cu" "B.Cu")
		(net "GND")
	)
	(via
		(at 225.7425 -82.46364)
		(size 0.5588)
		(drill 0.3048)
		(layers "F.Cu" "B.Cu")
		(net "GND")
	)
	(via
		(at 295.630092 -175.844962)
		(size 0.508)
		(drill 0.254)
		(layers "F.Cu" "B.Cu")
		(net "GND")
	)
	(via
		(at 257.048 -10.922)
		(size 0.5588)
		(drill 0.3048)
		(layers "F.Cu" "B.Cu")
		(net "GND")
	)
	(via
		(at 127.850138 -96.8502)
		(size 0.508)
		(drill 0.254)
		(layers "F.Cu" "B.Cu")
		(net "GND")
	)
	(via
		(at 88.392 -74.295)
		(size 0.5588)
		(drill 0.254)
		(layers "F.Cu" "B.Cu")
		(net "GND")
	)
	(via
		(at 138.43 -1.27)
		(size 0.5588)
		(drill 0.254)
		(layers "F.Cu" "B.Cu")
		(net "GND")
	)
	(via
		(at 55.19293 -75.364086)
		(size 0.5588)
		(drill 0.3048)
		(layers "F.Cu" "B.Cu")
		(net "GND")
	)
	(via
		(at 104.75341 -37.793676)
		(size 0.508)
		(drill 0.254)
		(layers "F.Cu" "B.Cu")
		(net "GND")
	)
	(via
		(at 79.121 -69.088)
		(size 0.7112)
		(drill 0.4064)
		(layers "F.Cu" "B.Cu")
		(net "GND")
	)
	(via
		(at 319.396872 -121.539)
		(size 0.5588)
		(drill 0.3048)
		(layers "F.Cu" "B.Cu")
		(net "GND")
	)
	(via
		(at 293.230046 -175.044862)
		(size 0.508)
		(drill 0.254)
		(layers "F.Cu" "B.Cu")
		(net "GND")
	)
	(via
		(at 116.85016 -86.849712)
		(size 0.508)
		(drill 0.254)
		(layers "F.Cu" "B.Cu")
		(net "GND")
	)
	(via
		(at 250.19 -1.27)
		(size 0.5588)
		(drill 0.254)
		(layers "F.Cu" "B.Cu")
		(net "GND")
	)
	(via
		(at 200.3552 -115.062)
		(size 0.5588)
		(drill 0.3048)
		(layers "F.Cu" "B.Cu")
		(net "GND")
	)
	(via
		(at 107.84967 -101.85019)
		(size 0.508)
		(drill 0.254)
		(layers "F.Cu" "B.Cu")
		(net "GND")
	)
	(via
		(at 287.77184 -191.2493)
		(size 0.5588)
		(drill 0.3048)
		(layers "F.Cu" "B.Cu")
		(net "GND")
	)
	(via
		(at 220.98 -40.64)
		(size 0.7112)
		(drill 0.4064)
		(layers "F.Cu" "B.Cu")
		(net "GND")
	)
	(via
		(at 100.59797 -115.951)
		(size 0.5588)
		(drill 0.3048)
		(layers "F.Cu" "B.Cu")
		(net "GND")
	)
	(via
		(at 147.530312 -66.047112)
		(size 0.508)
		(drill 0.254)
		(layers "F.Cu" "B.Cu")
		(net "GND")
	)
	(via
		(at 221.361 -122.936)
		(size 0.5588)
		(drill 0.3048)
		(layers "F.Cu" "B.Cu")
		(net "GND")
	)
	(via
		(at 205.994 -109.347)
		(size 0.5588)
		(drill 0.3048)
		(layers "F.Cu" "B.Cu")
		(net "GND")
	)
	(via
		(at 350.032828 -156.023564)
		(size 0.508)
		(drill 0.254)
		(layers "F.Cu" "B.Cu")
		(net "GND")
	)
	(via
		(at 25.350216 -203.12888)
		(size 0.5588)
		(drill 0.3048)
		(layers "F.Cu" "B.Cu")
		(net "GND")
	)
	(via
		(at 115.850162 -101.85019)
		(size 0.508)
		(drill 0.254)
		(layers "F.Cu" "B.Cu")
		(net "GND")
	)
	(via
		(at 83.471766 -37.2872)
		(size 0.508)
		(drill 0.254)
		(layers "F.Cu" "B.Cu")
		(net "GND")
	)
	(via
		(at 185.157364 -16.628364)
		(size 0.5588)
		(drill 0.3048)
		(layers "F.Cu" "B.Cu")
		(net "GND")
	)
	(via
		(at 299.703236 -144.018)
		(size 0.5588)
		(drill 0.3048)
		(layers "F.Cu" "B.Cu")
		(net "GND")
	)
	(via
		(at 49.800002 -81.079086)
		(size 0.5588)
		(drill 0.3048)
		(layers "F.Cu" "B.Cu")
		(net "GND")
	)
	(via
		(at 296.080688 -154.856688)
		(size 0.5588)
		(drill 0.3048)
		(layers "F.Cu" "B.Cu")
		(net "GND")
	)
	(via
		(at 307.721 -224.155)
		(size 0.5588)
		(drill 0.3048)
		(layers "F.Cu" "B.Cu")
		(net "GND")
	)
	(via
		(at 1.143 -154.761438)
		(size 0.7112)
		(drill 0.4064)
		(layers "F.Cu" "B.Cu")
		(net "GND")
	)
	(via
		(at 123.19 -1.27)
		(size 0.5588)
		(drill 0.254)
		(layers "F.Cu" "B.Cu")
		(net "GND")
	)
	(via
		(at 281.178 -192.405)
		(size 0.5588)
		(drill 0.3048)
		(layers "F.Cu" "B.Cu")
		(net "GND")
	)
	(via
		(at 100.749862 -44.19981)
		(size 0.508)
		(drill 0.254)
		(layers "F.Cu" "B.Cu")
		(net "GND")
	)
	(via
		(at 81.896966 -88.7222)
		(size 0.7112)
		(drill 0.4064)
		(layers "F.Cu" "B.Cu")
		(net "GND")
	)
	(via
		(at 14.80058 -104.77119)
		(size 0.5588)
		(drill 0.3048)
		(layers "F.Cu" "B.Cu")
		(net "GND")
	)
	(via
		(at 66.04 -66.04)
		(size 0.7112)
		(drill 0.4064)
		(layers "F.Cu" "B.Cu")
		(net "GND")
	)
	(via
		(at 110.350046 -42.599864)
		(size 0.508)
		(drill 0.254)
		(layers "F.Cu" "B.Cu")
		(net "GND")
	)
	(via
		(at 112.84077 -72.0598)
		(size 0.5588)
		(drill 0.3048)
		(layers "F.Cu" "B.Cu")
		(net "GND")
	)
	(via
		(at 6.35 -248.92)
		(size 0.7112)
		(drill 0.4064)
		(layers "F.Cu" "B.Cu")
		(net "GND")
	)
	(via
		(at 109.549946 -46.599602)
		(size 0.508)
		(drill 0.254)
		(layers "F.Cu" "B.Cu")
		(net "GND")
	)
	(via
		(at 109.849666 -93.849698)
		(size 0.508)
		(drill 0.254)
		(layers "F.Cu" "B.Cu")
		(net "GND")
	)
	(via
		(at 69.342 -171.196)
		(size 0.5588)
		(drill 0.3048)
		(layers "F.Cu" "B.Cu")
		(net "GND")
	)
	(via
		(at 206.629 -93.218)
		(size 0.7112)
		(drill 0.4064)
		(layers "F.Cu" "B.Cu")
		(net "GND")
	)
	(via
		(at 262.89 -246.38)
		(size 0.7112)
		(drill 0.4064)
		(layers "F.Cu" "B.Cu")
		(net "GND")
	)
	(via
		(at 316.23 -248.92)
		(size 0.5588)
		(drill 0.254)
		(layers "F.Cu" "B.Cu")
		(net "GND")
	)
	(via
		(at 116.85016 -98.850196)
		(size 0.508)
		(drill 0.254)
		(layers "F.Cu" "B.Cu")
		(net "GND")
	)
	(via
		(at 107.950254 -36.20008)
		(size 0.508)
		(drill 0.254)
		(layers "F.Cu" "B.Cu")
		(net "GND")
	)
	(via
		(at 335.788 -80.899)
		(size 0.5588)
		(drill 0.3048)
		(layers "F.Cu" "B.Cu")
		(net "GND")
	)
	(via
		(at 193.294 -20.955)
		(size 0.5588)
		(drill 0.3048)
		(layers "F.Cu" "B.Cu")
		(net "GND")
	)
	(via
		(at 264.033 -38.354)
		(size 0.5588)
		(drill 0.3048)
		(layers "F.Cu" "B.Cu")
		(net "GND")
	)
	(via
		(at 19.508216 -215.32088)
		(size 0.5588)
		(drill 0.3048)
		(layers "F.Cu" "B.Cu")
		(net "GND")
	)
	(via
		(at 66.421 -217.805)
		(size 0.5588)
		(drill 0.3048)
		(layers "F.Cu" "B.Cu")
		(net "GND")
	)
	(via
		(at 294.030146 -175.844962)
		(size 0.508)
		(drill 0.254)
		(layers "F.Cu" "B.Cu")
		(net "GND")
	)
	(via
		(at 64.9732 -45.6184)
		(size 0.7112)
		(drill 0.4064)
		(layers "F.Cu" "B.Cu")
		(net "GND")
	)
	(via
		(at 272.415 -53.066696)
		(size 0.5588)
		(drill 0.3048)
		(layers "F.Cu" "B.Cu")
		(net "GND")
	)
	(via
		(at 252.603 -138.1252)
		(size 0.5588)
		(drill 0.3048)
		(layers "F.Cu" "B.Cu")
		(net "GND")
	)
	(via
		(at 268.723872 -39.442136)
		(size 0.5588)
		(drill 0.3048)
		(layers "F.Cu" "B.Cu")
		(net "GND")
	)
	(via
		(at 81.407 -16.764)
		(size 0.5588)
		(drill 0.3048)
		(layers "F.Cu" "B.Cu")
		(net "GND")
	)
	(via
		(at 168.148 -84.836)
		(size 0.7112)
		(drill 0.4064)
		(layers "F.Cu" "B.Cu")
		(net "GND")
	)
	(via
		(at 272.161 -187.706)
		(size 0.5588)
		(drill 0.3048)
		(layers "F.Cu" "B.Cu")
		(net "GND")
	)
	(via
		(at 350.935798 -155.25115)
		(size 0.508)
		(drill 0.254)
		(layers "F.Cu" "B.Cu")
		(net "GND")
	)
	(via
		(at 114.599212 -225.044)
		(size 0.5588)
		(drill 0.3048)
		(layers "F.Cu" "B.Cu")
		(net "GND")
	)
	(via
		(at 341.122 -118.491)
		(size 0.5588)
		(drill 0.3048)
		(layers "F.Cu" "B.Cu")
		(net "GND")
	)
	(via
		(at 191.77 -5.08)
		(size 0.5588)
		(drill 0.254)
		(layers "F.Cu" "B.Cu")
		(net "GND")
	)
	(via
		(at 83.9216 -35.9664)
		(size 0.508)
		(drill 0.254)
		(layers "F.Cu" "B.Cu")
		(net "GND")
	)
	(via
		(at 174.743872 -191.842136)
		(size 0.5588)
		(drill 0.3048)
		(layers "F.Cu" "B.Cu")
		(net "GND")
	)
	(via
		(at 128.86817 -99.2632)
		(size 0.5588)
		(drill 0.3048)
		(layers "F.Cu" "B.Cu")
		(net "GND")
	)
	(via
		(at 292.4302 -175.044862)
		(size 0.508)
		(drill 0.254)
		(layers "F.Cu" "B.Cu")
		(net "GND")
	)
	(segment
		(start 89.35847 -136.779)
		(end 89.35847 -137.795)
		(width 0.508)
		(layer "B.Cu")
		(net "GND")
	)
	(segment
		(start 166.665148 -118.354856)
		(end 166.665148 -119.973852)
		(width 0.508)
		(layer "B.Cu")
		(net "GND")
	)
	(segment
		(start 103.20147 -86.0679)
		(end 103.20147 -86.201504)
		(width 0.3048)
		(layer "B.Cu")
		(net "GND")
	)
	(segment
		(start 106.423206 -53.872892)
		(end 106.350054 -53.79974)
		(width 0.508)
		(layer "B.Cu")
		(net "GND")
	)
	(segment
		(start 133.999732 -256.50444)
		(end 133.999732 -253.49835)
		(width 0.508)
		(layer "B.Cu")
		(net "GND")
	)
	(segment
		(start 305.610514 -179.832254)
		(end 304.894234 -179.832254)
		(width 0.508)
		(layer "B.Cu")
		(net "GND")
	)
	(segment
		(start 113.867946 -86.868)
		(end 113.849658 -86.849712)
		(width 0.3556)
		(layer "B.Cu")
		(net "GND")
	)
	(segment
		(start 122.56897 -96.6724)
		(end 122.02795 -96.6724)
		(width 0.3048)
		(layer "B.Cu")
		(net "GND")
	)
	(segment
		(start 18.682716 -216.14638)
		(end 19.508216 -215.32088)
		(width 0.508)
		(layer "B.Cu")
		(net "GND")
	)
	(segment
		(start 113.01857 -82.931)
		(end 112.85347 -83.0961)
		(width 0.3048)
		(layer "B.Cu")
		(net "GND")
	)
	(segment
		(start 101.010466 -46.113446)
		(end 100.94976 -46.05274)
		(width 0.508)
		(layer "B.Cu")
		(net "GND")
	)
	(segment
		(start 332.359 -155.552648)
		(end 331.525118 -155.552648)
		(width 0.508)
		(layer "B.Cu")
		(net "GND")
	)
	(segment
		(start 118.82247 -94.615)
		(end 118.82247 -93.877384)
		(width 0.508)
		(layer "B.Cu")
		(net "GND")
	)
	(segment
		(start 97.544128 -44.196762)
		(end 97.54489 -44.196)
		(width 0.508)
		(layer "B.Cu")
		(net "GND")
	)
	(segment
		(start 114.472212 -205.1558)
		(end 115.056412 -204.5716)
		(width 0.508)
		(layer "B.Cu")
		(net "GND")
	)
	(segment
		(start 125.13437 -94.361)
		(end 125.36297 -94.361)
		(width 0.3048)
		(layer "B.Cu")
		(net "GND")
	)
	(segment
		(start 125.000512 -253.4793)
		(end 124.378212 -252.857)
		(width 0.508)
		(layer "B.Cu")
		(net "GND")
	)
	(segment
		(start 128.30937 -99.822)
		(end 128.86817 -99.2632)
		(width 0.3048)
		(layer "B.Cu")
		(net "GND")
	)
	(segment
		(start 107.639866 -42.113708)
		(end 107.156504 -42.59707)
		(width 0.508)
		(layer "B.Cu")
		(net "GND")
	)
	(segment
		(start 74.999342 -253.38913)
		(end 74.467212 -252.857)
		(width 0.508)
		(layer "B.Cu")
		(net "GND")
	)
	(segment
		(start 4.895088 -85.79993)
		(end 4.895088 -88.162638)
		(width 0.508)
		(layer "B.Cu")
		(net "GND")
	)
	(segment
		(start 105.03027 -87.9475)
		(end 104.86517 -88.1126)
		(width 0.3048)
		(layer "B.Cu")
		(net "GND")
	)
	(segment
		(start 69.514212 -244.4115)
		(end 69.514212 -243.332)
		(width 0.508)
		(layer "B.Cu")
		(net "GND")
	)
	(segment
		(start 98.909886 -37.69868)
		(end 98.744786 -37.53358)
		(width 0.3556)
		(layer "B.Cu")
		(net "GND")
	)
	(segment
		(start 78.105 -74.803)
		(end 78.105 -75.946)
		(width 0.508)
		(layer "B.Cu")
		(net "GND")
	)
	(segment
		(start 111.57077 -98.1202)
		(end 111.57077 -98.571304)
		(width 0.3556)
		(layer "B.Cu")
		(net "GND")
	)
	(segment
		(start 107.929426 -53.778912)
		(end 107.950254 -53.79974)
		(width 0.508)
		(layer "B.Cu")
		(net "GND")
	)
	(segment
		(start 111.513366 -27.432)
		(end 109.54766 -27.432)
		(width 0.508)
		(layer "B.Cu")
		(net "GND")
	)
	(segment
		(start 4.895088 -85.79993)
		(end 7.257796 -85.79993)
		(width 0.508)
		(layer "B.Cu")
		(net "GND")
	)
	(segment
		(start 284.776418 -205.359)
		(end 284.734 -205.359)
		(width 0.508)
		(layer "B.Cu")
		(net "GND")
	)
	(segment
		(start 103.392478 -93.3069)
		(end 103.849678 -92.8497)
		(width 0.2032)
		(layer "B.Cu")
		(net "GND")
	)
	(segment
		(start 101.35997 -113.77803)
		(end 100.59797 -114.54003)
		(width 0.3048)
		(layer "B.Cu")
		(net "GND")
	)
	(segment
		(start 136.999472 -253.66726)
		(end 136.316212 -252.984)
		(width 0.508)
		(layer "B.Cu")
		(net "GND")
	)
	(segment
		(start 84.6455 -20.32)
		(end 83.8835 -20.32)
		(width 0.508)
		(layer "B.Cu")
		(net "GND")
	)
	(segment
		(start 110.281466 -43.39844)
		(end 110.281466 -44.13123)
		(width 0.508)
		(layer "B.Cu")
		(net "GND")
	)
	(segment
		(start 17.404588 -208.789016)
		(end 18.738088 -208.789016)
		(width 0.381)
		(layer "B.Cu")
		(net "GND")
	)
	(segment
		(start 87.96782 -46.380146)
		(end 87.865966 -46.482)
		(width 0.508)
		(layer "B.Cu")
		(net "GND")
	)
	(segment
		(start 105.549954 -48.999648)
		(end 105.709466 -48.840136)
		(width 0.508)
		(layer "B.Cu")
		(net "GND")
	)
	(segment
		(start 92.031566 -37.718746)
		(end 91.950286 -37.800026)
		(width 0.3048)
		(layer "B.Cu")
		(net "GND")
	)
	(segment
		(start 119.90197 -107.188)
		(end 119.90197 -107.95)
		(width 0.3048)
		(layer "B.Cu")
		(net "GND")
	)
	(segment
		(start 100.94976 -46.05274)
		(end 100.94976 -45.999654)
		(width 0.508)
		(layer "B.Cu")
		(net "GND")
	)
	(segment
		(start 121.862342 -84.907882)
		(end 121.862342 -85.837522)
		(width 0.508)
		(layer "B.Cu")
		(net "GND")
	)
	(segment
		(start 25.040844 -175.387762)
		(end 25.040844 -176.276762)
		(width 0.508)
		(layer "B.Cu")
		(net "GND")
	)
	(segment
		(start 76.8604 -21.3868)
		(end 76.0222 -21.3868)
		(width 0.508)
		(layer "B.Cu")
		(net "GND")
	)
	(segment
		(start 110.360206 -53.05298)
		(end 110.350046 -53.06314)
		(width 0.508)
		(layer "B.Cu")
		(net "GND")
	)
	(segment
		(start 103.804466 -45.645324)
		(end 103.804466 -44.958)
		(width 0.508)
		(layer "B.Cu")
		(net "GND")
	)
	(segment
		(start 115.27917 -96.2406)
		(end 115.48237 -96.2406)
		(width 0.3048)
		(layer "B.Cu")
		(net "GND")
	)
	(segment
		(start 110.281466 -44.13123)
		(end 110.350046 -44.19981)
		(width 0.508)
		(layer "B.Cu")
		(net "GND")
	)
	(segment
		(start 298.7675 -178.1302)
		(end 298.7675 -177.49774)
		(width 0.508)
		(layer "B.Cu")
		(net "GND")
	)
	(segment
		(start 122.090942 -100.6094)
		(end 121.85015 -100.850192)
		(width 0.3048)
		(layer "B.Cu")
		(net "GND")
	)
	(segment
		(start 105.55605 -42.596562)
		(end 105.709466 -42.749978)
		(width 0.508)
		(layer "B.Cu")
		(net "GND")
	)
	(segment
		(start 273.7485 -162.56)
		(end 273.177 -162.56)
		(width 0.508)
		(layer "B.Cu")
		(net "GND")
	)
	(segment
		(start 63.529972 -186.679078)
		(end 63.529972 -187.809886)
		(width 0.508)
		(layer "B.Cu")
		(net "GND")
	)
	(segment
		(start 103.804466 -47.254414)
		(end 103.804466 -46.609)
		(width 0.508)
		(layer "B.Cu")
		(net "GND")
	)
	(segment
		(start 182.612792 -27.944064)
		(end 183.315864 -28.647136)
		(width 0.508)
		(layer "B.Cu")
		(net "GND")
	)
	(segment
		(start 90.778076 -33.399984)
		(end 90.779092 -33.401)
		(width 0.3048)
		(layer "B.Cu")
		(net "GND")
	)
	(segment
		(start 288.439352 -174.971456)
		(end 288.439352 -174.245016)
		(width 0.3556)
		(layer "B.Cu")
		(net "GND")
	)
	(segment
		(start 105.559098 -45.80001)
		(end 105.709466 -45.649642)
		(width 0.508)
		(layer "B.Cu")
		(net "GND")
	)
	(segment
		(start 91.92006 -39.37)
		(end 91.950286 -39.400226)
		(width 0.3048)
		(layer "B.Cu")
		(net "GND")
	)
	(segment
		(start 89.770966 -31.623)
		(end 89.262966 -32.131)
		(width 0.3048)
		(layer "B.Cu")
		(net "GND")
	)
	(segment
		(start 103.20147 -86.201504)
		(end 103.849678 -86.849712)
		(width 0.3048)
		(layer "B.Cu")
		(net "GND")
	)
	(segment
		(start 111.26597 -81.9785)
		(end 111.16437 -82.0801)
		(width 0.3048)
		(layer "B.Cu")
		(net "GND")
	)
	(segment
		(start 115.12677 -90.8812)
		(end 115.818666 -90.8812)
		(width 0.3048)
		(layer "B.Cu")
		(net "GND")
	)
	(segment
		(start 100.950014 -47.652686)
		(end 100.950014 -47.599854)
		(width 0.508)
		(layer "B.Cu")
		(net "GND")
	)
	(segment
		(start 97.9424 -38.217094)
		(end 97.559622 -38.599872)
		(width 0.254)
		(layer "B.Cu")
		(net "GND")
	)
	(segment
		(start 118.82247 -93.877384)
		(end 118.850156 -93.849698)
		(width 0.508)
		(layer "B.Cu")
		(net "GND")
	)
	(segment
		(start 103.486966 -60.489084)
		(end 105.583482 -62.5856)
		(width 0.508)
		(layer "B.Cu")
		(net "GND")
	)
	(segment
		(start 120.63857 -85.979)
		(end 120.63857 -86.63813)
		(width 0.3048)
		(layer "B.Cu")
		(net "GND")
	)
	(segment
		(start 350.393 -82.296)
		(end 349.377 -83.312)
		(width 0.508)
		(layer "B.Cu")
		(net "GND")
	)
	(segment
		(start 105.709466 -42.749978)
		(end 105.709466 -43.307)
		(width 0.508)
		(layer "B.Cu")
		(net "GND")
	)
	(segment
		(start 107.51566 -35.604958)
		(end 107.950254 -36.039552)
		(width 0.508)
		(layer "B.Cu")
		(net "GND")
	)
	(segment
		(start 103.804466 -44.958)
		(end 103.804466 -44.345098)
		(width 0.508)
		(layer "B.Cu")
		(net "GND")
	)
	(segment
		(start 100.749862 -44.19981)
		(end 100.93706 -44.012612)
		(width 0.508)
		(layer "B.Cu")
		(net "GND")
	)
	(segment
		(start 110.268766 -40.918638)
		(end 110.350046 -40.999918)
		(width 0.508)
		(layer "B.Cu")
		(net "GND")
	)
	(segment
		(start 140.34897 -87.6935)
		(end 141.36497 -87.6935)
		(width 0.508)
		(layer "B.Cu")
		(net "GND")
	)
	(segment
		(start 166.249858 -9.863328)
		(end 166.249858 -11.210036)
		(width 0.508)
		(layer "B.Cu")
		(net "GND")
	)
	(segment
		(start 295.148 -163.449)
		(end 294.5638 -162.8648)
		(width 0.508)
		(layer "B.Cu")
		(net "GND")
	)
	(segment
		(start 103.486966 -59.944)
		(end 103.486966 -60.489084)
		(width 0.508)
		(layer "B.Cu")
		(net "GND")
	)
	(segment
		(start 96.000062 -256.50444)
		(end 96.000062 -252.91415)
		(width 0.508)
		(layer "B.Cu")
		(net "GND")
	)
	(segment
		(start 91.47556 -34.417)
		(end 91.47556 -34.097468)
		(width 0.3048)
		(layer "B.Cu")
		(net "GND")
	)
	(segment
		(start 119.13997 -106.426)
		(end 119.90197 -107.188)
		(width 0.3048)
		(layer "B.Cu")
		(net "GND")
	)
	(segment
		(start 115.767612 -222.9739)
		(end 116.224812 -223.4311)
		(width 0.508)
		(layer "B.Cu")
		(net "GND")
	)
	(segment
		(start 76.000102 -256.50444)
		(end 76.000102 -253.35611)
		(width 0.508)
		(layer "B.Cu")
		(net "GND")
	)
	(segment
		(start 107.614466 -48.26)
		(end 107.614466 -48.472598)
		(width 0.4572)
		(layer "B.Cu")
		(net "GND")
	)
	(segment
		(start 91.000072 -256.50444)
		(end 91.000072 -252.857)
		(width 0.508)
		(layer "B.Cu")
		(net "GND")
	)
	(segment
		(start 100.711 -81.7118)
		(end 101.05517 -81.7118)
		(width 0.3048)
		(layer "B.Cu")
		(net "GND")
	)
	(segment
		(start 50.829972 -186.679078)
		(end 50.829972 -187.809886)
		(width 0.508)
		(layer "B.Cu")
		(net "GND")
	)
	(segment
		(start 120.66397 -92.6846)
		(end 120.66397 -92.035884)
		(width 0.3048)
		(layer "B.Cu")
		(net "GND")
	)
	(segment
		(start 66.069972 -186.679078)
		(end 66.069972 -187.809886)
		(width 0.508)
		(layer "B.Cu")
		(net "GND")
	)
	(segment
		(start 120.53697 -107.536996)
		(end 120.850152 -107.850178)
		(width 0.3048)
		(layer "B.Cu")
		(net "GND")
	)
	(segment
		(start 115.60556 -98.0948)
		(end 115.850162 -97.850198)
		(width 0.3048)
		(layer "B.Cu")
		(net "GND")
	)
	(segment
		(start 101.010466 -43.87977)
		(end 101.010466 -43.307)
		(width 0.508)
		(layer "B.Cu")
		(net "GND")
	)
	(segment
		(start 331.851 -164.7825)
		(end 332.5495 -164.7825)
		(width 0.508)
		(layer "B.Cu")
		(net "GND")
	)
	(segment
		(start 319.309496 -170.434)
		(end 319.674748 -170.799252)
		(width 0.508)
		(layer "B.Cu")
		(net "GND")
	)
	(segment
		(start 110.362746 -51.42992)
		(end 110.341156 -51.45151)
		(width 0.508)
		(layer "B.Cu")
		(net "GND")
	)
	(segment
		(start 106.677206 -54.5211)
		(end 106.423206 -53.872892)
		(width 0.508)
		(layer "B.Cu")
		(net "GND")
	)
	(segment
		(start 110.58017 -88.119204)
		(end 110.849664 -87.84971)
		(width 0.3048)
		(layer "B.Cu")
		(net "GND")
	)
	(segment
		(start 90.96756 -41.148)
		(end 91.80576 -41.148)
		(width 0.3048)
		(layer "B.Cu")
		(net "GND")
	)
	(segment
		(start 304.894234 -179.832254)
		(end 304.89398 -179.832)
		(width 0.508)
		(layer "B.Cu")
		(net "GND")
	)
	(segment
		(start 345.059 -72.263508)
		(end 345.059 -73.384664)
		(width 0.508)
		(layer "B.Cu")
		(net "GND")
	)
	(segment
		(start 122.44197 -94.441518)
		(end 121.85015 -93.849698)
		(width 0.3048)
		(layer "B.Cu")
		(net "GND")
	)
	(segment
		(start 353.734878 -24.45004)
		(end 353.734878 -25.517348)
		(width 0.508)
		(layer "B.Cu")
		(net "GND")
	)
	(segment
		(start 87.1855 -73.0885)
		(end 88.392 -74.295)
		(width 0.508)
		(layer "B.Cu")
		(net "GND")
	)
	(segment
		(start 109.69117 -91.27998)
		(end 109.69117 -91.691206)
		(width 0.3048)
		(layer "B.Cu")
		(net "GND")
	)
	(segment
		(start 71.999602 -256.50444)
		(end 71.999602 -253.41961)
		(width 0.508)
		(layer "B.Cu")
		(net "GND")
	)
	(segment
		(start 136.87425 -36.1315)
		(end 136.87425 -35.052)
		(width 0.508)
		(layer "B.Cu")
		(net "GND")
	)
	(segment
		(start 58.449972 -186.679078)
		(end 58.449972 -187.809886)
		(width 0.508)
		(layer "B.Cu")
		(net "GND")
	)
	(segment
		(start 100.692966 -54.49824)
		(end 100.692966 -53.85689)
		(width 0.508)
		(layer "B.Cu")
		(net "GND")
	)
	(segment
		(start 113.000282 -256.50444)
		(end 113.000282 -253.41707)
		(width 0.508)
		(layer "B.Cu")
		(net "GND")
	)
	(segment
		(start 100.93706 -44.458636)
		(end 100.93706 -44.387008)
		(width 0.508)
		(layer "B.Cu")
		(net "GND")
	)
	(segment
		(start 93.896434 -47.85868)
		(end 93.557344 -48.19777)
		(width 0.508)
		(layer "B.Cu")
		(net "GND")
	)
	(segment
		(start 100.94976 -45.999654)
		(end 100.749862 -45.799756)
		(width 0.508)
		(layer "B.Cu")
		(net "GND")
	)
	(segment
		(start 120.58777 -95.58782)
		(end 120.850152 -95.850202)
		(width 0.3048)
		(layer "B.Cu")
		(net "GND")
	)
	(segment
		(start 107.156504 -44.19727)
		(end 107.614466 -44.655232)
		(width 0.508)
		(layer "B.Cu")
		(net "GND")
	)
	(segment
		(start 125.000512 -256.50444)
		(end 125.000512 -253.4793)
		(width 0.508)
		(layer "B.Cu")
		(net "GND")
	)
	(segment
		(start 38.15969 -60.680092)
		(end 39.099998 -60.680092)
		(width 0.508)
		(layer "B.Cu")
		(net "GND")
	)
	(segment
		(start 48.289972 -187.809886)
		(end 49.42078 -187.809886)
		(width 0.508)
		(layer "B.Cu")
		(net "GND")
	)
	(segment
		(start 20.579588 -180.467508)
		(end 20.651216 -180.39588)
		(width 0.508)
		(layer "B.Cu")
		(net "GND")
	)
	(segment
		(start 120.53697 -106.7054)
		(end 120.53697 -107.536996)
		(width 0.3048)
		(layer "B.Cu")
		(net "GND")
	)
	(segment
		(start 120.00357 -104.14)
		(end 120.00357 -104.696768)
		(width 0.3048)
		(layer "B.Cu")
		(net "GND")
	)
	(segment
		(start 90.634566 -31.623)
		(end 89.770966 -31.623)
		(width 0.3048)
		(layer "B.Cu")
		(net "GND")
	)
	(segment
		(start 39.099998 -60.680092)
		(end 39.099998 -61.6204)
		(width 0.508)
		(layer "B.Cu")
		(net "GND")
	)
	(segment
		(start 95.966534 -39.39286)
		(end 95.95231 -39.407084)
		(width 0.3556)
		(layer "B.Cu")
		(net "GND")
	)
	(segment
		(start 83.999832 -256.50444)
		(end 83.999832 -253.35738)
		(width 0.508)
		(layer "B.Cu")
		(net "GND")
	)
	(segment
		(start 115.90147 -83.79841)
		(end 115.850162 -83.849718)
		(width 0.3048)
		(layer "B.Cu")
		(net "GND")
	)
	(segment
		(start 25.104852 -85.79993)
		(end 25.104852 -88.162638)
		(width 0.508)
		(layer "B.Cu")
		(net "GND")
	)
	(segment
		(start 64.939164 -185.269886)
		(end 66.069972 -185.269886)
		(width 0.508)
		(layer "B.Cu")
		(net "GND")
	)
	(segment
		(start 112.85347 -83.0961)
		(end 112.85347 -83.845908)
		(width 0.3048)
		(layer "B.Cu")
		(net "GND")
	)
	(segment
		(start 136.999472 -256.50444)
		(end 136.999472 -253.66726)
		(width 0.508)
		(layer "B.Cu")
		(net "GND")
	)
	(segment
		(start 28.6766 -252.603)
		(end 28.6766 -251.079)
		(width 0.508)
		(layer "B.Cu")
		(net "GND")
	)
	(segment
		(start 92.031566 -37.084)
		(end 92.031566 -37.718746)
		(width 0.3048)
		(layer "B.Cu")
		(net "GND")
	)
	(segment
		(start 94.294706 -47.85868)
		(end 93.896434 -47.85868)
		(width 0.508)
		(layer "B.Cu")
		(net "GND")
	)
	(segment
		(start 111.32566 -36.024566)
		(end 111.150146 -36.20008)
		(width 0.508)
		(layer "B.Cu")
		(net "GND")
	)
	(segment
		(start 121.127266 -90.849704)
		(end 120.850152 -90.849704)
		(width 0.3048)
		(layer "B.Cu")
		(net "GND")
	)
	(segment
		(start 117.928898 -76.890118)
		(end 117.928898 -76.762102)
		(width 0.508)
		(layer "B.Cu")
		(net "GND")
	)
	(segment
		(start 60.989972 -187.809886)
		(end 60.989972 -188.940694)
		(width 0.508)
		(layer "B.Cu")
		(net "GND")
	)
	(segment
		(start 50.829972 -187.809886)
		(end 50.829972 -188.940694)
		(width 0.508)
		(layer "B.Cu")
		(net "GND")
	)
	(segment
		(start 55.959502 -66.179954)
		(end 56.89981 -66.179954)
		(width 0.508)
		(layer "B.Cu")
		(net "GND")
	)
	(segment
		(start 148.67001 -9.863328)
		(end 148.67001 -11.210036)
		(width 0.508)
		(layer "B.Cu")
		(net "GND")
	)
	(segment
		(start 124.34697 -109.5375)
		(end 125.10897 -109.5375)
		(width 0.508)
		(layer "B.Cu")
		(net "GND")
	)
	(segment
		(start 116.999512 -253.4793)
		(end 116.504212 -252.984)
		(width 0.508)
		(layer "B.Cu")
		(net "GND")
	)
	(segment
		(start 122.18797 -103.6574)
		(end 122.657362 -103.6574)
		(width 0.3048)
		(layer "B.Cu")
		(net "GND")
	)
	(segment
		(start 103.804466 -43.307)
		(end 103.804466 -42.744898)
		(width 0.508)
		(layer "B.Cu")
		(net "GND")
	)
	(segment
		(start 110.281466 -45.731176)
		(end 110.350046 -45.799756)
		(width 0.508)
		(layer "B.Cu")
		(net "GND")
	)
	(segment
		(start 133.000242 -253.47803)
		(end 132.379212 -252.857)
		(width 0.508)
		(layer "B.Cu")
		(net "GND")
	)
	(segment
		(start 183.642 -253.238)
		(end 183.642 -253.111)
		(width 0.508)
		(layer "B.Cu")
		(net "GND")
	)
	(segment
		(start 68.609972 -187.809886)
		(end 68.609972 -188.940694)
		(width 0.508)
		(layer "B.Cu")
		(net "GND")
	)
	(segment
		(start 353.734878 -23.382732)
		(end 353.734878 -24.45004)
		(width 0.508)
		(layer "B.Cu")
		(net "GND")
	)
	(segment
		(start 107.614466 -47.855124)
		(end 107.614466 -48.26)
		(width 0.508)
		(layer "B.Cu")
		(net "GND")
	)
	(segment
		(start 352.66757 -24.45004)
		(end 353.734878 -24.45004)
		(width 0.508)
		(layer "B.Cu")
		(net "GND")
	)
	(segment
		(start 112.84077 -99.6696)
		(end 113.669064 -99.6696)
		(width 0.3048)
		(layer "B.Cu")
		(net "GND")
	)
	(segment
		(start 116.999512 -256.50444)
		(end 116.999512 -253.4793)
		(width 0.508)
		(layer "B.Cu")
		(net "GND")
	)
	(segment
		(start 313.817 -51.816)
		(end 314.833 -51.816)
		(width 0.508)
		(layer "B.Cu")
		(net "GND")
	)
	(segment
		(start 25.040844 -177.242216)
		(end 24.825198 -177.457862)
		(width 0.508)
		(layer "B.Cu")
		(net "GND")
	)
	(segment
		(start 333.375 -155.2575)
		(end 332.654148 -155.2575)
		(width 0.508)
		(layer "B.Cu")
		(net "GND")
	)
	(segment
		(start 64.939164 -187.809886)
		(end 66.069972 -187.809886)
		(width 0.508)
		(layer "B.Cu")
		(net "GND")
	)
	(segment
		(start 101.962966 -56.199786)
		(end 101.549962 -56.199786)
		(width 0.508)
		(layer "B.Cu")
		(net "GND")
	)
	(segment
		(start 117.588792 -89.58834)
		(end 116.85016 -88.849708)
		(width 0.3048)
		(layer "B.Cu")
		(net "GND")
	)
	(segment
		(start 106.368342 -83.368388)
		(end 106.849672 -83.849718)
		(width 0.508)
		(layer "B.Cu")
		(net "GND")
	)
	(segment
		(start 107.614466 -45.339254)
		(end 107.156504 -45.797216)
		(width 0.508)
		(layer "B.Cu")
		(net "GND")
	)
	(segment
		(start 107.156504 -47.397162)
		(end 107.614466 -46.9392)
		(width 0.508)
		(layer "B.Cu")
		(net "GND")
	)
	(segment
		(start 110.849664 -83.79333)
		(end 110.849664 -83.849718)
		(width 0.3048)
		(layer "B.Cu")
		(net "GND")
	)
	(segment
		(start 120.58777 -88.2142)
		(end 120.58777 -88.587326)
		(width 0.3556)
		(layer "B.Cu")
		(net "GND")
	)
	(segment
		(start 107.614466 -46.255178)
		(end 107.156504 -45.797216)
		(width 0.508)
		(layer "B.Cu")
		(net "GND")
	)
	(segment
		(start 117.93347 -83.0961)
		(end 117.93347 -83.766406)
		(width 0.3048)
		(layer "B.Cu")
		(net "GND")
	)
	(segment
		(start 275.500084 -9.94791)
		(end 275.500084 -10.989818)
		(width 0.508)
		(layer "B.Cu")
		(net "GND")
	)
	(segment
		(start 122.44197 -94.7166)
		(end 122.44197 -94.441518)
		(width 0.3048)
		(layer "B.Cu")
		(net "GND")
	)
	(segment
		(start 103.392478 -94.039182)
		(end 103.392478 -93.3069)
		(width 0.2032)
		(layer "B.Cu")
		(net "GND")
	)
	(segment
		(start 54.779164 -187.809886)
		(end 55.909972 -187.809886)
		(width 0.508)
		(layer "B.Cu")
		(net "GND")
	)
	(segment
		(start 101.035866 -42.25417)
		(end 100.946458 -42.343578)
		(width 0.508)
		(layer "B.Cu")
		(net "GND")
	)
	(segment
		(start 121.01957 -87.01913)
		(end 120.850152 -86.849712)
		(width 0.3048)
		(layer "B.Cu")
		(net "GND")
	)
	(segment
		(start 109.352842 -82.177382)
		(end 108.336842 -82.177382)
		(width 0.508)
		(layer "B.Cu")
		(net "GND")
	)
	(segment
		(start 78.999842 -256.50444)
		(end 78.999842 -253.19863)
		(width 0.508)
		(layer "B.Cu")
		(net "GND")
	)
	(segment
		(start 285.157418 -205.74)
		(end 284.776418 -205.359)
		(width 0.508)
		(layer "B.Cu")
		(net "GND")
	)
	(segment
		(start 101.962966 -56.18734)
		(end 101.962966 -56.199786)
		(width 0.508)
		(layer "B.Cu")
		(net "GND")
	)
	(segment
		(start 39.099998 -62.680088)
		(end 39.099998 -63.620396)
		(width 0.508)
		(layer "B.Cu")
		(net "GND")
	)
	(segment
		(start 109.69117 -91.691206)
		(end 109.849666 -91.849702)
		(width 0.3048)
		(layer "B.Cu")
		(net "GND")
	)
	(segment
		(start 101.010466 -45.486574)
		(end 101.010466 -44.958)
		(width 0.508)
		(layer "B.Cu")
		(net "GND")
	)
	(segment
		(start 116.91747 -94.615)
		(end 116.91747 -93.917008)
		(width 0.508)
		(layer "B.Cu")
		(net "GND")
	)
	(segment
		(start 128.86817 -102.5398)
		(end 128.53797 -102.87)
		(width 0.3048)
		(layer "B.Cu")
		(net "GND")
	)
	(segment
		(start 96.550226 -39.39286)
		(end 95.966534 -39.39286)
		(width 0.3556)
		(layer "B.Cu")
		(net "GND")
	)
	(segment
		(start 94.990666 -44.1833)
		(end 94.35719 -44.1833)
		(width 0.3556)
		(layer "B.Cu")
		(net "GND")
	)
	(segment
		(start 332.5495 -164.7825)
		(end 332.994 -165.227)
		(width 0.508)
		(layer "B.Cu")
		(net "GND")
	)
	(segment
		(start 98.343466 -44.196)
		(end 98.343466 -43.307)
		(width 0.508)
		(layer "B.Cu")
		(net "GND")
	)
	(segment
		(start 124.09297 -104.1146)
		(end 124.58573 -104.1146)
		(width 0.3048)
		(layer "B.Cu")
		(net "GND")
	)
	(segment
		(start 105.709466 -47.240444)
		(end 105.709466 -46.609)
		(width 0.508)
		(layer "B.Cu")
		(net "GND")
	)
	(segment
		(start 109.54766 -27.432)
		(end 109.35716 -27.6225)
		(width 0.508)
		(layer "B.Cu")
		(net "GND")
	)
	(segment
		(start 323.342 -184.8485)
		(end 323.342 -185.42)
		(width 0.508)
		(layer "B.Cu")
		(net "GND")
	)
	(segment
		(start 68.498212 -243.078)
		(end 68.117212 -242.697)
		(width 0.508)
		(layer "B.Cu")
		(net "GND")
	)
	(segment
		(start 49.699164 -187.809886)
		(end 50.829972 -187.809886)
		(width 0.508)
		(layer "B.Cu")
		(net "GND")
	)
	(segment
		(start 105.734866 -41.91)
		(end 105.734866 -42.417746)
		(width 0.508)
		(layer "B.Cu")
		(net "GND")
	)
	(segment
		(start 120.58777 -97.4852)
		(end 120.58777 -97.112582)
		(width 0.3048)
		(layer "B.Cu")
		(net "GND")
	)
	(segment
		(start 148.67001 -11.210036)
		(end 150.016718 -11.210036)
		(width 0.508)
		(layer "B.Cu")
		(net "GND")
	)
	(segment
		(start 106.241342 -82.875882)
		(end 106.368342 -83.002882)
		(width 0.508)
		(layer "B.Cu")
		(net "GND")
	)
	(segment
		(start 162.97275 -116.5225)
		(end 162.97275 -118.20525)
		(width 0.508)
		(layer "B.Cu")
		(net "GND")
	)
	(segment
		(start 114.726466 -43.561)
		(end 116.186966 -43.561)
		(width 0.508)
		(layer "B.Cu")
		(net "GND")
	)
	(segment
		(start 39.099998 -62.680088)
		(end 40.040306 -62.680088)
		(width 0.508)
		(layer "B.Cu")
		(net "GND")
	)
	(segment
		(start 39.099998 -66.179954)
		(end 39.099998 -67.120262)
		(width 0.508)
		(layer "B.Cu")
		(net "GND")
	)
	(segment
		(start 120.86717 -90.832686)
		(end 120.850152 -90.849704)
		(width 0.3048)
		(layer "B.Cu")
		(net "GND")
	)
	(segment
		(start 273.177 -162.56)
		(end 272.542 -161.925)
		(width 0.508)
		(layer "B.Cu")
		(net "GND")
	)
	(segment
		(start 48.289972 -187.809886)
		(end 48.289972 -188.940694)
		(width 0.508)
		(layer "B.Cu")
		(net "GND")
	)
	(segment
		(start 324.358 -185.42)
		(end 323.85 -185.928)
		(width 0.508)
		(layer "B.Cu")
		(net "GND")
	)
	(segment
		(start 353.734878 -14.182598)
		(end 353.734878 -15.249906)
		(width 0.508)
		(layer "B.Cu")
		(net "GND")
	)
	(segment
		(start 114.56797 -96.9645)
		(end 113.963958 -96.9645)
		(width 0.508)
		(layer "B.Cu")
		(net "GND")
	)
	(segment
		(start 121.862342 -85.837522)
		(end 121.85015 -85.849714)
		(width 0.508)
		(layer "B.Cu")
		(net "GND")
	)
	(segment
		(start 97.9424 -37.973)
		(end 97.9424 -38.217094)
		(width 0.254)
		(layer "B.Cu")
		(net "GND")
	)
	(segment
		(start 133.522466 -35.814)
		(end 133.522466 -34.6075)
		(width 0.508)
		(layer "B.Cu")
		(net "GND")
	)
	(segment
		(start 182.799482 -254.080518)
		(end 183.642 -253.238)
		(width 0.508)
		(layer "B.Cu")
		(net "GND")
	)
	(segment
		(start 105.137966 -34.21634)
		(end 104.756966 -34.59734)
		(width 0.3048)
		(layer "B.Cu")
		(net "GND")
	)
	(segment
		(start 124.681742 -98.0186)
		(end 124.850144 -97.850198)
		(width 0.3048)
		(layer "B.Cu")
		(net "GND")
	)
	(segment
		(start 121.67997 -90.297)
		(end 121.127266 -90.849704)
		(width 0.3048)
		(layer "B.Cu")
		(net "GND")
	)
	(segment
		(start 146.999452 -253.50724)
		(end 146.476212 -252.984)
		(width 0.508)
		(layer "B.Cu")
		(net "GND")
	)
	(segment
		(start 121.000012 -253.4158)
		(end 120.441212 -252.857)
		(width 0.508)
		(layer "B.Cu")
		(net "GND")
	)
	(segment
		(start 55.909972 -186.679078)
		(end 55.909972 -187.809886)
		(width 0.508)
		(layer "B.Cu")
		(net "GND")
	)
	(segment
		(start 103.43007 -94.488)
		(end 103.43007 -94.076774)
		(width 0.2032)
		(layer "B.Cu")
		(net "GND")
	)
	(segment
		(start 24.905716 -169.28338)
		(end 24.207216 -168.58488)
		(width 0.508)
		(layer "B.Cu")
		(net "GND")
	)
	(segment
		(start 22.742144 -85.79993)
		(end 25.104852 -85.79993)
		(width 0.508)
		(layer "B.Cu")
		(net "GND")
	)
	(segment
		(start 89.154 -99.7585)
		(end 89.86647 -99.7585)
		(width 0.508)
		(layer "B.Cu")
		(net "GND")
	)
	(segment
		(start 120.66397 -92.035884)
		(end 120.850152 -91.849702)
		(width 0.3048)
		(layer "B.Cu")
		(net "GND")
	)
	(segment
		(start 104.744266 -54.52872)
		(end 104.744266 -53.805582)
		(width 0.508)
		(layer "B.Cu")
		(net "GND")
	)
	(segment
		(start 147.323302 -11.210036)
		(end 148.67001 -11.210036)
		(width 0.508)
		(layer "B.Cu")
		(net "GND")
	)
	(segment
		(start 101.150166 -37.533834)
		(end 101.550216 -37.133784)
		(width 0.3556)
		(layer "B.Cu")
		(net "GND")
	)
	(segment
		(start 304.6603 -177.42408)
		(end 305.689 -177.42408)
		(width 0.3556)
		(layer "B.Cu")
		(net "GND")
	)
	(segment
		(start 96.618806 -41.140888)
		(end 96.759776 -40.999918)
		(width 0.254)
		(layer "B.Cu")
		(net "GND")
	)
	(segment
		(start 67.479164 -185.269886)
		(end 68.609972 -185.269886)
		(width 0.508)
		(layer "B.Cu")
		(net "GND")
	)
	(segment
		(start 117.329966 -46.6725)
		(end 116.758466 -46.6725)
		(width 0.508)
		(layer "B.Cu")
		(net "GND")
	)
	(segment
		(start 111.16437 -83.1088)
		(end 111.16437 -83.478624)
		(width 0.3048)
		(layer "B.Cu")
		(net "GND")
	)
	(segment
		(start 120.58777 -88.587326)
		(end 120.850152 -88.849708)
		(width 0.3556)
		(layer "B.Cu")
		(net "GND")
	)
	(segment
		(start 114.64417 -99.7712)
		(end 113.928652 -99.7712)
		(width 0.3048)
		(layer "B.Cu")
		(net "GND")
	)
	(segment
		(start 107.614466 -44.655232)
		(end 107.614466 -44.958)
		(width 0.508)
		(layer "B.Cu")
		(net "GND")
	)
	(segment
		(start 110.000542 -256.50444)
		(end 110.000542 -253.64567)
		(width 0.508)
		(layer "B.Cu")
		(net "GND")
	)
	(segment
		(start 16.277844 -177.419508)
		(end 16.333216 -177.47488)
		(width 0.508)
		(layer "B.Cu")
		(net "GND")
	)
	(segment
		(start 53.369972 -187.809886)
		(end 53.369972 -188.940694)
		(width 0.508)
		(layer "B.Cu")
		(net "GND")
	)
	(segment
		(start 319.8495 -182.753)
		(end 319.8495 -183.8325)
		(width 0.508)
		(layer "B.Cu")
		(net "GND")
	)
	(segment
		(start 107.614466 -43.307)
		(end 107.614466 -43.739308)
		(width 0.508)
		(layer "B.Cu")
		(net "GND")
	)
	(segment
		(start 116.758466 -46.6725)
		(end 116.440966 -46.99)
		(width 0.508)
		(layer "B.Cu")
		(net "GND")
	)
	(segment
		(start 63.529972 -187.809886)
		(end 64.66078 -187.809886)
		(width 0.508)
		(layer "B.Cu")
		(net "GND")
	)
	(segment
		(start 103.804466 -42.744898)
		(end 103.949754 -42.59961)
		(width 0.508)
		(layer "B.Cu")
		(net "GND")
	)
	(segment
		(start 106.368342 -83.002882)
		(end 106.368342 -83.368388)
		(width 0.508)
		(layer "B.Cu")
		(net "GND")
	)
	(segment
		(start 62.399164 -187.809886)
		(end 63.529972 -187.809886)
		(width 0.508)
		(layer "B.Cu")
		(net "GND")
	)
	(segment
		(start 100.59797 -114.54003)
		(end 100.59797 -115.951)
		(width 0.3048)
		(layer "B.Cu")
		(net "GND")
	)
	(segment
		(start 113.669064 -99.6696)
		(end 113.849658 -99.850194)
		(width 0.3048)
		(layer "B.Cu")
		(net "GND")
	)
	(segment
		(start 60.989972 -186.679078)
		(end 60.989972 -187.809886)
		(width 0.508)
		(layer "B.Cu")
		(net "GND")
	)
	(segment
		(start 102.389686 -55.76062)
		(end 101.962966 -56.18734)
		(width 0.508)
		(layer "B.Cu")
		(net "GND")
	)
	(segment
		(start 294.5638 -162.8648)
		(end 294.513 -162.8648)
		(width 0.508)
		(layer "B.Cu")
		(net "GND")
	)
	(segment
		(start 68.609972 -186.679078)
		(end 68.609972 -187.809886)
		(width 0.508)
		(layer "B.Cu")
		(net "GND")
	)
	(segment
		(start 318.4525 -170.434)
		(end 319.309496 -170.434)
		(width 0.508)
		(layer "B.Cu")
		(net "GND")
	)
	(segment
		(start 110.281466 -48.1965)
		(end 110.281466 -48.931322)
		(width 0.508)
		(layer "B.Cu")
		(net "GND")
	)
	(segment
		(start 107.639866 -41.91)
		(end 107.639866 -42.113708)
		(width 0.508)
		(layer "B.Cu")
		(net "GND")
	)
	(segment
		(start 95.26016 -37.9984)
		(end 95.12046 -37.9984)
		(width 0.3556)
		(layer "B.Cu")
		(net "GND")
	)
	(segment
		(start 105.549954 -48.100488)
		(end 105.549954 -47.399956)
		(width 0.508)
		(layer "B.Cu")
		(net "GND")
	)
	(segment
		(start 109.7026 -94.488)
		(end 109.7026 -93.996764)
		(width 0.3048)
		(layer "B.Cu")
		(net "GND")
	)
	(segment
		(start 187.799472 -256.50444)
		(end 187.799472 -253.13894)
		(width 0.508)
		(layer "B.Cu")
		(net "GND")
	)
	(segment
		(start 83.000342 -256.50444)
		(end 83.000342 -253.38913)
		(width 0.508)
		(layer "B.Cu")
		(net "GND")
	)
	(segment
		(start 113.928652 -99.7712)
		(end 113.849658 -99.850194)
		(width 0.3048)
		(layer "B.Cu")
		(net "GND")
	)
	(segment
		(start 50.829972 -187.809886)
		(end 51.96078 -187.809886)
		(width 0.508)
		(layer "B.Cu")
		(net "GND")
	)
	(segment
		(start 150.999952 -256.00914)
		(end 150.999952 -250.828048)
		(width 0.508)
		(layer "B.Cu")
		(net "GND")
	)
	(segment
		(start 120.58777 -95.1992)
		(end 120.58777 -95.58782)
		(width 0.3048)
		(layer "B.Cu")
		(net "GND")
	)
	(segment
		(start 113.868962 -98.8695)
		(end 113.849658 -98.850196)
		(width 0.508)
		(layer "B.Cu")
		(net "GND")
	)
	(segment
		(start 110.83417 -99.568)
		(end 110.13186 -99.568)
		(width 0.3556)
		(layer "B.Cu")
		(net "GND")
	)
	(segment
		(start 124.58573 -104.1146)
		(end 124.850144 -103.850186)
		(width 0.3048)
		(layer "B.Cu")
		(net "GND")
	)
	(segment
		(start 39.099998 -61.73978)
		(end 39.099998 -62.680088)
		(width 0.508)
		(layer "B.Cu")
		(net "GND")
	)
	(segment
		(start 122.69597 -100.6094)
		(end 122.090942 -100.6094)
		(width 0.3048)
		(layer "B.Cu")
		(net "GND")
	)
	(segment
		(start 101.010466 -48.68037)
		(end 101.010466 -48.26)
		(width 0.508)
		(layer "B.Cu")
		(net "GND")
	)
	(segment
		(start 111.57077 -97.129092)
		(end 111.849662 -96.8502)
		(width 0.3556)
		(layer "B.Cu")
		(net "GND")
	)
	(segment
		(start 114.41557 -92.1004)
		(end 114.100356 -92.1004)
		(width 0.3048)
		(layer "B.Cu")
		(net "GND")
	)
	(segment
		(start 121.860056 -108.860082)
		(end 120.850152 -107.850178)
		(width 0.3048)
		(layer "B.Cu")
		(net "GND")
	)
	(segment
		(start 120.63857 -86.63813)
		(end 120.850152 -86.849712)
		(width 0.3048)
		(layer "B.Cu")
		(net "GND")
	)
	(segment
		(start 94.35719 -44.1833)
		(end 94.350078 -44.190412)
		(width 0.3556)
		(layer "B.Cu")
		(net "GND")
	)
	(segment
		(start 345.080336 -72.242172)
		(end 345.059 -72.263508)
		(width 0.508)
		(layer "B.Cu")
		(net "GND")
	)
	(segment
		(start 127.29337 -99.822)
		(end 128.30937 -99.822)
		(width 0.3048)
		(layer "B.Cu")
		(net "GND")
	)
	(segment
		(start 103.804466 -44.054522)
		(end 103.804466 -43.307)
		(width 0.508)
		(layer "B.Cu")
		(net "GND")
	)
	(segment
		(start 100.950014 -47.147226)
		(end 101.010466 -47.086774)
		(width 0.508)
		(layer "B.Cu")
		(net "GND")
	)
	(segment
		(start 143.999712 -253.5555)
		(end 144.571212 -252.984)
		(width 0.508)
		(layer "B.Cu")
		(net "GND")
	)
	(segment
		(start 117.93347 -83.766406)
		(end 117.850158 -83.849718)
		(width 0.3048)
		(layer "B.Cu")
		(net "GND")
	)
	(segment
		(start 121.01957 -87.503)
		(end 121.01957 -87.01913)
		(width 0.3048)
		(layer "B.Cu")
		(net "GND")
	)
	(segment
		(start 103.959152 -45.80001)
		(end 103.804466 -45.645324)
		(width 0.508)
		(layer "B.Cu")
		(net "GND")
	)
	(segment
		(start 95.12046 -37.9984)
		(end 94.930976 -37.808916)
		(width 0.3556)
		(layer "B.Cu")
		(net "GND")
	)
	(segment
		(start 66.069972 -185.269886)
		(end 67.20078 -185.269886)
		(width 0.508)
		(layer "B.Cu")
		(net "GND")
	)
	(segment
		(start 347.472 -115.4176)
		(end 347.472 -114.427)
		(width 0.508)
		(layer "B.Cu")
		(net "GND")
	)
	(segment
		(start 304.89398 -179.832)
		(end 304.89398 -179.86502)
		(width 0.508)
		(layer "B.Cu")
		(net "GND")
	)
	(segment
		(start 323.342 -185.42)
		(end 323.85 -185.928)
		(width 0.508)
		(layer "B.Cu")
		(net "GND")
	)
	(segment
		(start 82.05724 -74.1045)
		(end 82.24774 -74.295)
		(width 0.3048)
		(layer "B.Cu")
		(net "GND")
	)
	(segment
		(start 66.069972 -187.809886)
		(end 67.20078 -187.809886)
		(width 0.508)
		(layer "B.Cu")
		(net "GND")
	)
	(segment
		(start 110.332266 -47.382176)
		(end 110.349792 -47.399702)
		(width 0.508)
		(layer "B.Cu")
		(net "GND")
	)
	(segment
		(start 55.959502 -59.680094)
		(end 56.89981 -59.680094)
		(width 0.508)
		(layer "B.Cu")
		(net "GND")
	)
	(segment
		(start 128.999742 -253.41453)
		(end 128.442212 -252.857)
		(width 0.508)
		(layer "B.Cu")
		(net "GND")
	)
	(segment
		(start 113.000282 -253.41707)
		(end 112.567212 -252.984)
		(width 0.508)
		(layer "B.Cu")
		(net "GND")
	)
	(segment
		(start 317.0555 -182.753)
		(end 317.0555 -183.515)
		(width 0.508)
		(layer "B.Cu")
		(net "GND")
	)
	(segment
		(start 110.304326 -41.8719)
		(end 110.304326 -42.554144)
		(width 0.508)
		(layer "B.Cu")
		(net "GND")
	)
	(segment
		(start 350.393 -81.9785)
		(end 350.393 -82.296)
		(width 0.508)
		(layer "B.Cu")
		(net "GND")
	)
	(segment
		(start 111.32566 -35.306)
		(end 111.32566 -36.024566)
		(width 0.508)
		(layer "B.Cu")
		(net "GND")
	)
	(segment
		(start 89.35847 -137.795)
		(end 89.35847 -138.90498)
		(width 0.508)
		(layer "B.Cu")
		(net "GND")
	)
	(segment
		(start 21.294852 -216.726008)
		(end 21.294852 -215.425782)
		(width 0.508)
		(layer "B.Cu")
		(net "GND")
	)
	(segment
		(start 79.999332 -256.50444)
		(end 79.999332 -253.42088)
		(width 0.508)
		(layer "B.Cu")
		(net "GND")
	)
	(segment
		(start 294.513 -162.8648)
		(end 294.4114 -162.7632)
		(width 0.508)
		(layer "B.Cu")
		(net "GND")
	)
	(segment
		(start 58.449972 -187.809886)
		(end 59.58078 -187.809886)
		(width 0.508)
		(layer "B.Cu")
		(net "GND")
	)
	(segment
		(start 126.619 -220.345)
		(end 125.495812 -220.345)
		(width 0.508)
		(layer "B.Cu")
		(net "GND")
	)
	(segment
		(start 91.777566 -36.02736)
		(end 91.950286 -36.20008)
		(width 0.3048)
		(layer "B.Cu")
		(net "GND")
	)
	(segment
		(start 276.225 -164.8206)
		(end 276.4536 -164.592)
		(width 0.508)
		(layer "B.Cu")
		(net "GND")
	)
	(segment
		(start 39.099998 -59.739784)
		(end 39.099998 -60.680092)
		(width 0.508)
		(layer "B.Cu")
		(net "GND")
	)
	(segment
		(start 128.53797 -102.87)
		(end 127.86995 -102.87)
		(width 0.3048)
		(layer "B.Cu")
		(net "GND")
	)
	(segment
		(start 103.804466 -46.609)
		(end 103.804466 -45.954696)
		(width 0.508)
		(layer "B.Cu")
		(net "GND")
	)
	(segment
		(start 115.48237 -96.2406)
		(end 115.850162 -95.872808)
		(width 0.3048)
		(layer "B.Cu")
		(net "GND")
	)
	(segment
		(start 91.648026 -52.65166)
		(end 92.645992 -51.399694)
		(width 0.508)
		(layer "B.Cu")
		(net "GND")
	)
	(segment
		(start 27.999436 -256.50444)
		(end 27.999436 -253.280164)
		(width 0.508)
		(layer "B.Cu")
		(net "GND")
	)
	(segment
		(start 96.794066 -40.4495)
		(end 96.794066 -40.965628)
		(width 0.3556)
		(layer "B.Cu")
		(net "GND")
	)
	(segment
		(start 101.010466 -44.532042)
		(end 100.93706 -44.458636)
		(width 0.508)
		(layer "B.Cu")
		(net "GND")
	)
	(segment
		(start 53.369972 -186.679078)
		(end 53.369972 -187.809886)
		(width 0.508)
		(layer "B.Cu")
		(net "GND")
	)
	(segment
		(start 29.922216 -202.36688)
		(end 29.414216 -202.87488)
		(width 0.508)
		(layer "B.Cu")
		(net "GND")
	)
	(segment
		(start 104.744266 -53.805582)
		(end 104.750108 -53.79974)
		(width 0.508)
		(layer "B.Cu")
		(net "GND")
	)
	(segment
		(start 113.999772 -256.50444)
		(end 113.999772 -253.32944)
		(width 0.508)
		(layer "B.Cu")
		(net "GND")
	)
	(segment
		(start 100.93706 -43.953176)
		(end 101.010466 -43.87977)
		(width 0.508)
		(layer "B.Cu")
		(net "GND")
	)
	(segment
		(start 164.90315 -11.210036)
		(end 166.249858 -11.210036)
		(width 0.508)
		(layer "B.Cu")
		(net "GND")
	)
	(segment
		(start 112.58677 -92.58681)
		(end 112.84966 -92.8497)
		(width 0.3048)
		(layer "B.Cu")
		(net "GND")
	)
	(segment
		(start 105.709466 -46.609)
		(end 105.709466 -45.950378)
		(width 0.508)
		(layer "B.Cu")
		(net "GND")
	)
	(segment
		(start 83.000342 -253.38913)
		(end 82.468212 -252.857)
		(width 0.508)
		(layer "B.Cu")
		(net "GND")
	)
	(segment
		(start 332.654148 -155.2575)
		(end 332.359 -155.552648)
		(width 0.508)
		(layer "B.Cu")
		(net "GND")
	)
	(segment
		(start 143.999712 -256.50444)
		(end 143.999712 -253.5555)
		(width 0.508)
		(layer "B.Cu")
		(net "GND")
	)
	(segment
		(start 100.937314 -48.812196)
		(end 100.937314 -48.753522)
		(width 0.508)
		(layer "B.Cu")
		(net "GND")
	)
	(segment
		(start 121.925842 -108.860082)
		(end 121.860056 -108.860082)
		(width 0.3048)
		(layer "B.Cu")
		(net "GND")
	)
	(segment
		(start 112.58677 -91.5416)
		(end 112.58677 -91.112594)
		(width 0.3048)
		(layer "B.Cu")
		(net "GND")
	)
	(segment
		(start 60.989972 -187.809886)
		(end 62.12078 -187.809886)
		(width 0.508)
		(layer "B.Cu")
		(net "GND")
	)
	(segment
		(start 311.3405 -182.499)
		(end 311.3405 -181.5465)
		(width 0.508)
		(layer "B.Cu")
		(net "GND")
	)
	(segment
		(start 98.744786 -37.53358)
		(end 98.744786 -37.394642)
		(width 0.3556)
		(layer "B.Cu")
		(net "GND")
	)
	(segment
		(start 127.877824 -103.8225)
		(end 127.850138 -103.850186)
		(width 0.508)
		(layer "B.Cu")
		(net "GND")
	)
	(segment
		(start 29.922216 -203.38288)
		(end 29.414216 -202.87488)
		(width 0.508)
		(layer "B.Cu")
		(net "GND")
	)
	(segment
		(start 111.59617 -94.10319)
		(end 111.849662 -93.849698)
		(width 0.3556)
		(layer "B.Cu")
		(net "GND")
	)
	(segment
		(start 104.72166 -36.171378)
		(end 104.750362 -36.20008)
		(width 0.508)
		(layer "B.Cu")
		(net "GND")
	)
	(segment
		(start 53.369972 -187.809886)
		(end 54.50078 -187.809886)
		(width 0.508)
		(layer "B.Cu")
		(net "GND")
	)
	(segment
		(start 55.909972 -187.809886)
		(end 55.909972 -188.940694)
		(width 0.508)
		(layer "B.Cu")
		(net "GND")
	)
	(segment
		(start 105.709466 -45.950378)
		(end 105.559098 -45.80001)
		(width 0.508)
		(layer "B.Cu")
		(net "GND")
	)
	(segment
		(start 304.89398 -179.86502)
		(end 304.292 -180.467)
		(width 0.508)
		(layer "B.Cu")
		(net "GND")
	)
	(segment
		(start 113.74247 -94.615)
		(end 113.74247 -93.956886)
		(width 0.508)
		(layer "B.Cu")
		(net "GND")
	)
	(segment
		(start 107.944666 -52.1208)
		(end 107.944666 -51.404774)
		(width 0.508)
		(layer "B.Cu")
		(net "GND")
	)
	(segment
		(start 115.767612 -222.4405)
		(end 115.767612 -222.9739)
		(width 0.508)
		(layer "B.Cu")
		(net "GND")
	)
	(segment
		(start 128.86817 -101.727)
		(end 128.86817 -102.5398)
		(width 0.3048)
		(layer "B.Cu")
		(net "GND")
	)
	(segment
		(start 100.535486 -54.65572)
		(end 100.692966 -54.49824)
		(width 0.508)
		(layer "B.Cu")
		(net "GND")
	)
	(segment
		(start 103.829866 -41.91)
		(end 103.829866 -42.479722)
		(width 0.508)
		(layer "B.Cu")
		(net "GND")
	)
	(segment
		(start 116.631466 -29.972)
		(end 116.631466 -30.307534)
		(width 0.508)
		(layer "B.Cu")
		(net "GND")
	)
	(segment
		(start 104.86517 -88.1126)
		(end 104.86517 -88.85428)
		(width 0.3048)
		(layer "B.Cu")
		(net "GND")
	)
	(segment
		(start 25.104852 -83.437222)
		(end 25.104852 -85.79993)
		(width 0.508)
		(layer "B.Cu")
		(net "GND")
	)
	(segment
		(start 103.804466 -44.345098)
		(end 103.949754 -44.19981)
		(width 0.508)
		(layer "B.Cu")
		(net "GND")
	)
	(segment
		(start 115.659662 -92.6592)
		(end 115.850162 -92.8497)
		(width 0.3048)
		(layer "B.Cu")
		(net "GND")
	)
	(segment
		(start 98.744786 -37.394642)
		(end 98.350324 -37.00018)
		(width 0.3556)
		(layer "B.Cu")
		(net "GND")
	)
	(segment
		(start 56.89981 -66.179954)
		(end 56.89981 -67.120262)
		(width 0.508)
		(layer "B.Cu")
		(net "GND")
	)
	(segment
		(start 105.709466 -43.307)
		(end 105.709466 -44.040298)
		(width 0.508)
		(layer "B.Cu")
		(net "GND")
	)
	(segment
		(start 101.010466 -47.086774)
		(end 101.010466 -46.609)
		(width 0.508)
		(layer "B.Cu")
		(net "GND")
	)
	(segment
		(start 98.3615 -48.26)
		(end 98.289618 -48.26)
		(width 0.254)
		(layer "B.Cu")
		(net "GND")
	)
	(segment
		(start 105.709466 -45.649642)
		(end 105.709466 -44.958)
		(width 0.508)
		(layer "B.Cu")
		(net "GND")
	)
	(segment
		(start 166.249858 -11.210036)
		(end 166.249858 -12.556744)
		(width 0.508)
		(layer "B.Cu")
		(net "GND")
	)
	(segment
		(start 131.490466 -30.89275)
		(end 131.490466 -31.9405)
		(width 0.508)
		(layer "B.Cu")
		(net "GND")
	)
	(segment
		(start 79.999332 -253.42088)
		(end 80.563212 -252.857)
		(width 0.508)
		(layer "B.Cu")
		(net "GND")
	)
	(segment
		(start 107.614466 -43.739308)
		(end 107.156504 -44.19727)
		(width 0.508)
		(layer "B.Cu")
		(net "GND")
	)
	(segment
		(start 82.24774 -74.295)
		(end 82.804 -74.295)
		(width 0.3048)
		(layer "B.Cu")
		(net "GND")
	)
	(segment
		(start 197.2945 -245.999)
		(end 197.2945 -245.0465)
		(width 0.508)
		(layer "B.Cu")
		(net "GND")
	)
	(segment
		(start 100.749862 -45.799756)
		(end 100.94976 -45.599858)
		(width 0.508)
		(layer "B.Cu")
		(net "GND")
	)
	(segment
		(start 101.35997 -112.6744)
		(end 101.35997 -113.77803)
		(width 0.3048)
		(layer "B.Cu")
		(net "GND")
	)
	(segment
		(start 110.341156 -51.45151)
		(end 110.341156 -52.200556)
		(width 0.508)
		(layer "B.Cu")
		(net "GND")
	)
	(segment
		(start 100.93706 -44.012612)
		(end 100.93706 -43.953176)
		(width 0.508)
		(layer "B.Cu")
		(net "GND")
	)
	(segment
		(start 78.0415 -21.36775)
		(end 76.87945 -21.36775)
		(width 0.508)
		(layer "B.Cu")
		(net "GND")
	)
	(segment
		(start 107.614466 -46.609)
		(end 107.614466 -46.255178)
		(width 0.508)
		(layer "B.Cu")
		(net "GND")
	)
	(segment
		(start 111.57077 -97.5106)
		(end 111.57077 -97.129092)
		(width 0.3556)
		(layer "B.Cu")
		(net "GND")
	)
	(segment
		(start 39.099998 -60.680092)
		(end 40.040306 -60.680092)
		(width 0.508)
		(layer "B.Cu")
		(net "GND")
	)
	(segment
		(start 110.408466 -49.784)
		(end 110.408466 -50.541428)
		(width 0.508)
		(layer "B.Cu")
		(net "GND")
	)
	(segment
		(start 109.352842 -81.496154)
		(end 109.352842 -82.177382)
		(width 0.3048)
		(layer "B.Cu")
		(net "GND")
	)
	(segment
		(start 117.928898 -76.762102)
		(end 119.0498 -75.6412)
		(width 0.508)
		(layer "B.Cu")
		(net "GND")
	)
	(segment
		(start 353.734878 -15.249906)
		(end 353.734878 -16.317214)
		(width 0.508)
		(layer "B.Cu")
		(net "GND")
	)
	(segment
		(start 319.8495 -183.8325)
		(end 319.913 -183.896)
		(width 0.508)
		(layer "B.Cu")
		(net "GND")
	)
	(segment
		(start 63.529972 -187.809886)
		(end 63.529972 -188.940694)
		(width 0.508)
		(layer "B.Cu")
		(net "GND")
	)
	(segment
		(start 109.350302 -81.493614)
		(end 109.352842 -81.496154)
		(width 0.3048)
		(layer "B.Cu")
		(net "GND")
	)
	(segment
		(start 76.87945 -21.36775)
		(end 76.8604 -21.3868)
		(width 0.508)
		(layer "B.Cu")
		(net "GND")
	)
	(segment
		(start 56.89981 -62.680088)
		(end 57.840118 -62.680088)
		(width 0.508)
		(layer "B.Cu")
		(net "GND")
	)
	(segment
		(start 101.05517 -81.7118)
		(end 101.99497 -80.772)
		(width 0.3048)
		(layer "B.Cu")
		(net "GND")
	)
	(segment
		(start 16.277844 -176.149762)
		(end 16.277844 -177.419508)
		(width 0.508)
		(layer "B.Cu")
		(net "GND")
	)
	(segment
		(start 109.42066 -36.07054)
		(end 109.5502 -36.20008)
		(width 0.508)
		(layer "B.Cu")
		(net "GND")
	)
	(segment
		(start 24.905716 -170.10888)
		(end 24.905716 -169.28338)
		(width 0.508)
		(layer "B.Cu")
		(net "GND")
	)
	(segment
		(start 352.66757 -15.249906)
		(end 353.734878 -15.249906)
		(width 0.508)
		(layer "B.Cu")
		(net "GND")
	)
	(segment
		(start 295.148 -163.7665)
		(end 295.148 -163.449)
		(width 0.508)
		(layer "B.Cu")
		(net "GND")
	)
	(segment
		(start 114.472212 -205.4225)
		(end 114.472212 -205.1558)
		(width 0.508)
		(layer "B.Cu")
		(net "GND")
	)
	(segment
		(start 109.7026 -93.996764)
		(end 109.849666 -93.849698)
		(width 0.3048)
		(layer "B.Cu")
		(net "GND")
	)
	(segment
		(start 115.818666 -90.8812)
		(end 115.850162 -90.849704)
		(width 0.3048)
		(layer "B.Cu")
		(net "GND")
	)
	(segment
		(start 112.85347 -83.845908)
		(end 112.84966 -83.849718)
		(width 0.3048)
		(layer "B.Cu")
		(net "GND")
	)
	(segment
		(start 55.959502 -62.680088)
		(end 56.89981 -62.680088)
		(width 0.508)
		(layer "B.Cu")
		(net "GND")
	)
	(segment
		(start 126.000002 -256.50444)
		(end 126.000002 -253.39421)
		(width 0.508)
		(layer "B.Cu")
		(net "GND")
	)
	(segment
		(start 121.999502 -253.33071)
		(end 122.473212 -252.857)
		(width 0.508)
		(layer "B.Cu")
		(net "GND")
	)
	(segment
		(start 110.510066 -38.53434)
		(end 110.510066 -39.239952)
		(width 0.508)
		(layer "B.Cu")
		(net "GND")
	)
	(segment
		(start 124.649738 -100.0506)
		(end 124.850144 -99.850194)
		(width 0.3048)
		(layer "B.Cu")
		(net "GND")
	)
	(segment
		(start 101.010466 -43.307)
		(end 101.010466 -43.1165)
		(width 0.508)
		(layer "B.Cu")
		(net "GND")
	)
	(segment
		(start 116.631466 -30.307534)
		(end 116.205 -30.734)
		(width 0.508)
		(layer "B.Cu")
		(net "GND")
	)
	(segment
		(start 109.42066 -35.306)
		(end 109.42066 -36.07054)
		(width 0.508)
		(layer "B.Cu")
		(net "GND")
	)
	(segment
		(start 100.749862 -48.999648)
		(end 100.937314 -48.812196)
		(width 0.508)
		(layer "B.Cu")
		(net "GND")
	)
	(segment
		(start 112.58677 -92.1258)
		(end 112.58677 -92.58681)
		(width 0.3048)
		(layer "B.Cu")
		(net "GND")
	)
	(segment
		(start 56.89981 -65.239646)
		(end 56.89981 -66.179954)
		(width 0.508)
		(layer "B.Cu")
		(net "GND")
	)
	(segment
		(start 16.277844 -176.149762)
		(end 16.277844 -175.260762)
		(width 0.508)
		(layer "B.Cu")
		(net "GND")
	)
	(segment
		(start 111.13897 -95.1738)
		(end 111.13897 -95.560896)
		(width 0.3556)
		(layer "B.Cu")
		(net "GND")
	)
	(segment
		(start 94.309946 -49.78146)
		(end 93.568266 -49.78146)
		(width 0.508)
		(layer "B.Cu")
		(net "GND")
	)
	(segment
		(start 311.3405 -181.5465)
		(end 311.277 -181.483)
		(width 0.508)
		(layer "B.Cu")
		(net "GND")
	)
	(segment
		(start 109.601 -63.627)
		(end 110.49 -63.627)
		(width 0.508)
		(layer "B.Cu")
		(net "GND")
	)
	(segment
		(start 120.58777 -97.112582)
		(end 120.850152 -96.8502)
		(width 0.3048)
		(layer "B.Cu")
		(net "GND")
	)
	(segment
		(start 110.332266 -46.6852)
		(end 110.332266 -47.382176)
		(width 0.508)
		(layer "B.Cu")
		(net "GND")
	)
	(segment
		(start 90.96756 -39.37)
		(end 91.92006 -39.37)
		(width 0.3048)
		(layer "B.Cu")
		(net "GND")
	)
	(segment
		(start 114.100356 -92.1004)
		(end 113.849658 -91.849702)
		(width 0.3048)
		(layer "B.Cu")
		(net "GND")
	)
	(segment
		(start 84.836 -20.5105)
		(end 84.6455 -20.32)
		(width 0.508)
		(layer "B.Cu")
		(net "GND")
	)
	(segment
		(start 107.614466 -44.958)
		(end 107.614466 -45.339254)
		(width 0.508)
		(layer "B.Cu")
		(net "GND")
	)
	(segment
		(start 143.000222 -253.57201)
		(end 142.412212 -252.984)
		(width 0.508)
		(layer "B.Cu")
		(net "GND")
	)
	(segment
		(start 130.000502 -256.50444)
		(end 130.000502 -253.33071)
		(width 0.508)
		(layer "B.Cu")
		(net "GND")
	)
	(segment
		(start 16.015716 -170.10888)
		(end 16.015716 -169.15638)
		(width 0.508)
		(layer "B.Cu")
		(net "GND")
	)
	(segment
		(start 112.58677 -91.112594)
		(end 112.84966 -90.849704)
		(width 0.3048)
		(layer "B.Cu")
		(net "GND")
	)
	(segment
		(start 20.008088 -193.041016)
		(end 19.373088 -193.676016)
		(width 0.508)
		(layer "B.Cu")
		(net "GND")
	)
	(segment
		(start 96.618806 -41.81602)
		(end 96.618806 -41.140888)
		(width 0.254)
		(layer "B.Cu")
		(net "GND")
	)
	(segment
		(start 128.999742 -256.50444)
		(end 128.999742 -253.41453)
		(width 0.508)
		(layer "B.Cu")
		(net "GND")
	)
	(segment
		(start 113.999772 -253.32944)
		(end 114.345212 -252.984)
		(width 0.508)
		(layer "B.Cu")
		(net "GND")
	)
	(segment
		(start 119.615966 -102.616)
		(end 118.850156 -101.85019)
		(width 0.3048)
		(layer "B.Cu")
		(net "GND")
	)
	(segment
		(start 104.86517 -88.85428)
		(end 104.85501 -88.86444)
		(width 0.3048)
		(layer "B.Cu")
		(net "GND")
	)
	(segment
		(start 103.804466 -47.54499)
		(end 103.949754 -47.399702)
		(width 0.508)
		(layer "B.Cu")
		(net "GND")
	)
	(segment
		(start 166.249858 -11.210036)
		(end 167.596566 -11.210036)
		(width 0.508)
		(layer "B.Cu")
		(net "GND")
	)
	(segment
		(start 110.49 -63.627)
		(end 111.506 -64.643)
		(width 0.508)
		(layer "B.Cu")
		(net "GND")
	)
	(segment
		(start 4.895088 -100.7999)
		(end 4.895088 -103.162608)
		(width 0.508)
		(layer "B.Cu")
		(net "GND")
	)
	(segment
		(start 118.000272 -256.50444)
		(end 118.000272 -253.39294)
		(width 0.508)
		(layer "B.Cu")
		(net "GND")
	)
	(segment
		(start 110.510066 -39.239952)
		(end 110.350046 -39.399972)
		(width 0.508)
		(layer "B.Cu")
		(net "GND")
	)
	(segment
		(start 118.09857 -82.931)
		(end 117.93347 -83.0961)
		(width 0.3048)
		(layer "B.Cu")
		(net "GND")
	)
	(segment
		(start 86.999572 -256.50444)
		(end 86.999572 -253.32436)
		(width 0.508)
		(layer "B.Cu")
		(net "GND")
	)
	(segment
		(start 52.239164 -187.809886)
		(end 53.369972 -187.809886)
		(width 0.508)
		(layer "B.Cu")
		(net "GND")
	)
	(segment
		(start 67.479164 -187.809886)
		(end 68.609972 -187.809886)
		(width 0.508)
		(layer "B.Cu")
		(net "GND")
	)
	(segment
		(start 103.949754 -48.999648)
		(end 103.804466 -48.85436)
		(width 0.508)
		(layer "B.Cu")
		(net "GND")
	)
	(segment
		(start 38.15969 -66.179954)
		(end 39.099998 -66.179954)
		(width 0.508)
		(layer "B.Cu")
		(net "GND")
	)
	(segment
		(start 110.268766 -40.28948)
		(end 110.268766 -40.918638)
		(width 0.508)
		(layer "B.Cu")
		(net "GND")
	)
	(segment
		(start 141.36497 -87.6935)
		(end 142.19047 -87.6935)
		(width 0.508)
		(layer "B.Cu")
		(net "GND")
	)
	(segment
		(start 114.61877 -101.6762)
		(end 114.023648 -101.6762)
		(width 0.3048)
		(layer "B.Cu")
		(net "GND")
	)
	(segment
		(start 103.359966 -59.817)
		(end 103.486966 -59.944)
		(width 0.508)
		(layer "B.Cu")
		(net "GND")
	)
	(segment
		(start 98.23577 -112.014)
		(end 98.23577 -113.6142)
		(width 0.508)
		(layer "B.Cu")
		(net "GND")
	)
	(segment
		(start 126.27737 -103.422958)
		(end 125.850142 -103.850186)
		(width 0.3048)
		(layer "B.Cu")
		(net "GND")
	)
	(segment
		(start 120.58777 -94.11208)
		(end 120.850152 -93.849698)
		(width 0.3048)
		(layer "B.Cu")
		(net "GND")
	)
	(segment
		(start 105.549954 -47.399956)
		(end 105.709466 -47.240444)
		(width 0.508)
		(layer "B.Cu")
		(net "GND")
	)
	(segment
		(start 287.3502 -205.74)
		(end 288.29 -205.74)
		(width 0.508)
		(layer "B.Cu")
		(net "GND")
	)
	(segment
		(start 119.74957 -102.616)
		(end 119.615966 -102.616)
		(width 0.3048)
		(layer "B.Cu")
		(net "GND")
	)
	(segment
		(start 115.20297 -92.6592)
		(end 115.659662 -92.6592)
		(width 0.3048)
		(layer "B.Cu")
		(net "GND")
	)
	(segment
		(start 96.628966 -40.2844)
		(end 96.794066 -40.4495)
		(width 0.3556)
		(layer "B.Cu")
		(net "GND")
	)
	(segment
		(start 122.657362 -103.6574)
		(end 122.850148 -103.850186)
		(width 0.3048)
		(layer "B.Cu")
		(net "GND")
	)
	(segment
		(start 74.999342 -256.50444)
		(end 74.999342 -253.38913)
		(width 0.508)
		(layer "B.Cu")
		(net "GND")
	)
	(segment
		(start 68.609972 -185.269886)
		(end 68.609972 -186.400694)
		(width 0.508)
		(layer "B.Cu")
		(net "GND")
	)
	(segment
		(start 293.1922 -204.7875)
		(end 293.1922 -205.64094)
		(width 0.508)
		(layer "B.Cu")
		(net "GND")
	)
	(segment
		(start 324.358 -184.8485)
		(end 324.358 -185.42)
		(width 0.508)
		(layer "B.Cu")
		(net "GND")
	)
	(segment
		(start 115.676172 -101.6762)
		(end 115.850162 -101.85019)
		(width 0.3048)
		(layer "B.Cu")
		(net "GND")
	)
	(segment
		(start 96.794066 -40.965628)
		(end 96.759776 -40.999918)
		(width 0.3556)
		(layer "B.Cu")
		(net "GND")
	)
	(segment
		(start 98.94316 -34.393378)
		(end 99.149916 -34.600134)
		(width 0.3048)
		(layer "B.Cu")
		(net "GND")
	)
	(segment
		(start 66.069972 -187.809886)
		(end 66.069972 -188.940694)
		(width 0.508)
		(layer "B.Cu")
		(net "GND")
	)
	(segment
		(start 100.94976 -45.599858)
		(end 100.94976 -45.54728)
		(width 0.508)
		(layer "B.Cu")
		(net "GND")
	)
	(segment
		(start 103.829866 -42.479722)
		(end 103.949754 -42.59961)
		(width 0.508)
		(layer "B.Cu")
		(net "GND")
	)
	(segment
		(start 121.999502 -256.50444)
		(end 121.999502 -253.33071)
		(width 0.508)
		(layer "B.Cu")
		(net "GND")
	)
	(segment
		(start 89.48166 -28.64866)
		(end 87.884 -28.64866)
		(width 0.508)
		(layer "B.Cu")
		(net "GND")
	)
	(segment
		(start 105.137966 -33.9344)
		(end 105.137966 -34.21634)
		(width 0.3048)
		(layer "B.Cu")
		(net "GND")
	)
	(segment
		(start 103.804466 -48.85436)
		(end 103.804466 -48.26)
		(width 0.508)
		(layer "B.Cu")
		(net "GND")
	)
	(segment
		(start 93.568266 -49.78146)
		(end 93.549978 -49.799748)
		(width 0.508)
		(layer "B.Cu")
		(net "GND")
	)
	(segment
		(start 125.36297 -94.361)
		(end 125.87097 -93.853)
		(width 0.3048)
		(layer "B.Cu")
		(net "GND")
	)
	(segment
		(start 108.3945 -62.23)
		(end 108.3945 -62.4205)
		(width 0.508)
		(layer "B.Cu")
		(net "GND")
	)
	(segment
		(start 104.72166 -35.306)
		(end 104.72166 -36.171378)
		(width 0.508)
		(layer "B.Cu")
		(net "GND")
	)
	(segment
		(start 27.999436 -253.280164)
		(end 28.6766 -252.603)
		(width 0.508)
		(layer "B.Cu")
		(net "GND")
	)
	(segment
		(start 107.944666 -51.404774)
		(end 107.949746 -51.399694)
		(width 0.508)
		(layer "B.Cu")
		(net "GND")
	)
	(segment
		(start 128.79197 -103.8225)
		(end 127.877824 -103.8225)
		(width 0.508)
		(layer "B.Cu")
		(net "GND")
	)
	(segment
		(start 98.709226 -54.958996)
		(end 99.149916 -55.399686)
		(width 0.508)
		(layer "B.Cu")
		(net "GND")
	)
	(segment
		(start 92.0496 -34.417)
		(end 91.47556 -34.417)
		(width 0.254)
		(layer "B.Cu")
		(net "GND")
	)
	(segment
		(start 116.224812 -223.4311)
		(end 116.224812 -223.4438)
		(width 0.508)
		(layer "B.Cu")
		(net "GND")
	)
	(segment
		(start 4.895088 -98.437192)
		(end 4.895088 -100.7999)
		(width 0.508)
		(layer "B.Cu")
		(net "GND")
	)
	(segment
		(start 332.994 -165.227)
		(end 332.994 -165.5826)
		(width 0.508)
		(layer "B.Cu")
		(net "GND")
	)
	(segment
		(start 56.89981 -61.73978)
		(end 56.89981 -62.680088)
		(width 0.508)
		(layer "B.Cu")
		(net "GND")
	)
	(segment
		(start 143.000222 -256.50444)
		(end 143.000222 -253.57201)
		(width 0.508)
		(layer "B.Cu")
		(net "GND")
	)
	(segment
		(start 101.150166 -37.719)
		(end 101.150166 -37.533834)
		(width 0.3556)
		(layer "B.Cu")
		(net "GND")
	)
	(segment
		(start 91.80576 -41.148)
		(end 91.956636 -40.997124)
		(width 0.3048)
		(layer "B.Cu")
		(net "GND")
	)
	(segment
		(start 56.89981 -62.680088)
		(end 56.89981 -63.620396)
		(width 0.508)
		(layer "B.Cu")
		(net "GND")
	)
	(segment
		(start 107.614466 -48.472598)
		(end 107.340146 -48.746918)
		(width 0.4572)
		(layer "B.Cu")
		(net "GND")
	)
	(segment
		(start 116.57457 -102.616)
		(end 116.57457 -102.12578)
		(width 0.3048)
		(layer "B.Cu")
		(net "GND")
	)
	(segment
		(start 87.884 -28.64866)
		(end 86.614 -28.64866)
		(width 0.508)
		(layer "B.Cu")
		(net "GND")
	)
	(segment
		(start 107.340146 -48.746918)
		(end 107.340146 -48.813466)
		(width 0.4572)
		(layer "B.Cu")
		(net "GND")
	)
	(segment
		(start 290.0553 -204.51064)
		(end 290.07054 -204.52588)
		(width 0.508)
		(layer "B.Cu")
		(net "GND")
	)
	(segment
		(start 120.58777 -94.615)
		(end 120.58777 -94.11208)
		(width 0.3048)
		(layer "B.Cu")
		(net "GND")
	)
	(segment
		(start 92.686886 -49.191926)
		(end 93.294708 -49.799748)
		(width 0.508)
		(layer "B.Cu")
		(net "GND")
	)
	(segment
		(start 107.950254 -36.039552)
		(end 107.950254 -36.20008)
		(width 0.508)
		(layer "B.Cu")
		(net "GND")
	)
	(segment
		(start 276.4536 -164.592)
		(end 276.4536 -164.460936)
		(width 0.508)
		(layer "B.Cu")
		(net "GND")
	)
	(segment
		(start 257.048 -12.827)
		(end 257.048 -10.922)
		(width 0.508)
		(layer "B.Cu")
		(net "GND")
	)
	(segment
		(start 124.21997 -100.0506)
		(end 124.649738 -100.0506)
		(width 0.3048)
		(layer "B.Cu")
		(net "GND")
	)
	(segment
		(start 148.000212 -253.111)
		(end 148.508212 -252.603)
		(width 0.508)
		(layer "B.Cu")
		(net "GND")
	)
	(segment
		(start 100.937314 -48.753522)
		(end 101.010466 -48.68037)
		(width 0.508)
		(layer "B.Cu")
		(net "GND")
	)
	(segment
		(start 89.35847 -138.90498)
		(end 89.36101 -138.90752)
		(width 0.508)
		(layer "B.Cu")
		(net "GND")
	)
	(segment
		(start 148.67001 -11.210036)
		(end 148.67001 -12.556744)
		(width 0.508)
		(layer "B.Cu")
		(net "GND")
	)
	(segment
		(start 105.583482 -62.5856)
		(end 106.788966 -62.5856)
		(width 0.508)
		(layer "B.Cu")
		(net "GND")
	)
	(segment
		(start 111.16437 -83.478624)
		(end 110.849664 -83.79333)
		(width 0.3048)
		(layer "B.Cu")
		(net "GND")
	)
	(segment
		(start 110.58017 -88.6206)
		(end 110.58017 -88.119204)
		(width 0.3048)
		(layer "B.Cu")
		(net "GND")
	)
	(segment
		(start 114.56797 -98.8695)
		(end 113.868962 -98.8695)
		(width 0.508)
		(layer "B.Cu")
		(net "GND")
	)
	(segment
		(start 98.999802 -256.50444)
		(end 98.999802 -253.00559)
		(width 0.508)
		(layer "B.Cu")
		(net "GND")
	)
	(segment
		(start 56.89981 -66.179954)
		(end 57.840118 -66.179954)
		(width 0.508)
		(layer "B.Cu")
		(net "GND")
	)
	(segment
		(start 105.709466 -44.040298)
		(end 105.549954 -44.19981)
		(width 0.508)
		(layer "B.Cu")
		(net "GND")
	)
	(segment
		(start 105.709466 -44.958)
		(end 105.709466 -44.359322)
		(width 0.508)
		(layer "B.Cu")
		(net "GND")
	)
	(segment
		(start 93.294708 -49.799748)
		(end 93.549978 -49.799748)
		(width 0.508)
		(layer "B.Cu")
		(net "GND")
	)
	(segment
		(start 2.53238 -85.79993)
		(end 4.895088 -85.79993)
		(width 0.508)
		(layer "B.Cu")
		(net "GND")
	)
	(segment
		(start 107.929426 -53.00218)
		(end 107.929426 -53.778912)
		(width 0.508)
		(layer "B.Cu")
		(net "GND")
	)
	(segment
		(start 105.709466 -48.840136)
		(end 105.709466 -48.26)
		(width 0.508)
		(layer "B.Cu")
		(net "GND")
	)
	(segment
		(start 120.00357 -104.696768)
		(end 119.850154 -104.850184)
		(width 0.3048)
		(layer "B.Cu")
		(net "GND")
	)
	(segment
		(start 285.6992 -205.74)
		(end 285.157418 -205.74)
		(width 0.508)
		(layer "B.Cu")
		(net "GND")
	)
	(segment
		(start 122.02795 -96.6724)
		(end 121.85015 -96.8502)
		(width 0.3048)
		(layer "B.Cu")
		(net "GND")
	)
	(segment
		(start 100.93706 -44.387008)
		(end 100.749862 -44.19981)
		(width 0.508)
		(layer "B.Cu")
		(net "GND")
	)
	(segment
		(start 98.289618 -48.26)
		(end 97.54997 -48.999648)
		(width 0.254)
		(layer "B.Cu")
		(net "GND")
	)
	(segment
		(start 107.13847 -94.615)
		(end 107.13847 -94.560898)
		(width 0.3048)
		(layer "B.Cu")
		(net "GND")
	)
	(segment
		(start 92.3036 -34.163)
		(end 92.0496 -34.417)
		(width 0.254)
		(layer "B.Cu")
		(net "GND")
	)
	(segment
		(start 100.749862 -42.855896)
		(end 100.749862 -42.59961)
		(width 0.508)
		(layer "B.Cu")
		(net "GND")
	)
	(segment
		(start 118.000272 -253.39294)
		(end 118.409212 -252.984)
		(width 0.508)
		(layer "B.Cu")
		(net "GND")
	)
	(segment
		(start 124.09297 -98.0186)
		(end 124.681742 -98.0186)
		(width 0.3048)
		(layer "B.Cu")
		(net "GND")
	)
	(segment
		(start 116.91747 -93.917008)
		(end 116.85016 -93.849698)
		(width 0.508)
		(layer "B.Cu")
		(net "GND")
	)
	(segment
		(start 107.156504 -47.397162)
		(end 107.614466 -47.855124)
		(width 0.508)
		(layer "B.Cu")
		(net "GND")
	)
	(segment
		(start 97.54489 -44.196)
		(end 98.343466 -44.196)
		(width 0.508)
		(layer "B.Cu")
		(net "GND")
	)
	(segment
		(start 116.57457 -102.12578)
		(end 116.85016 -101.85019)
		(width 0.3048)
		(layer "B.Cu")
		(net "GND")
	)
	(segment
		(start 103.078534 -37.719)
		(end 103.15575 -37.796216)
		(width 0.254)
		(layer "B.Cu")
		(net "GND")
	)
	(segment
		(start 295.9862 -204.4065)
		(end 295.9862 -205.64094)
		(width 0.508)
		(layer "B.Cu")
		(net "GND")
	)
	(segment
		(start 182.799482 -256.50444)
		(end 182.799482 -254.080518)
		(width 0.508)
		(layer "B.Cu")
		(net "GND")
	)
	(segment
		(start 58.449972 -187.809886)
		(end 58.449972 -188.940694)
		(width 0.508)
		(layer "B.Cu")
		(net "GND")
	)
	(segment
		(start 39.099998 -66.179954)
		(end 40.040306 -66.179954)
		(width 0.508)
		(layer "B.Cu")
		(net "GND")
	)
	(segment
		(start 96.758506 -53.808122)
		(end 96.750124 -53.79974)
		(width 0.508)
		(layer "B.Cu")
		(net "GND")
	)
	(segment
		(start 78.999842 -253.19863)
		(end 78.658212 -252.857)
		(width 0.508)
		(layer "B.Cu")
		(net "GND")
	)
	(segment
		(start 110.304326 -42.554144)
		(end 110.350046 -42.599864)
		(width 0.508)
		(layer "B.Cu")
		(net "GND")
	)
	(segment
		(start 102.37597 -82.2706)
		(end 102.37597 -81.153)
		(width 0.3048)
		(layer "B.Cu")
		(net "GND")
	)
	(segment
		(start 71.999602 -253.41961)
		(end 72.562212 -252.857)
		(width 0.508)
		(layer "B.Cu")
		(net "GND")
	)
	(segment
		(start 110.281466 -45.0596)
		(end 110.281466 -45.731176)
		(width 0.508)
		(layer "B.Cu")
		(net "GND")
	)
	(segment
		(start 39.099998 -65.239646)
		(end 39.099998 -66.179954)
		(width 0.508)
		(layer "B.Cu")
		(net "GND")
	)
	(segment
		(start 114.54257 -86.868)
		(end 113.867946 -86.868)
		(width 0.3556)
		(layer "B.Cu")
		(net "GND")
	)
	(segment
		(start 76.000102 -253.35611)
		(end 76.499212 -252.857)
		(width 0.508)
		(layer "B.Cu")
		(net "GND")
	)
	(segment
		(start 56.89981 -59.680094)
		(end 57.840118 -59.680094)
		(width 0.508)
		(layer "B.Cu")
		(net "GND")
	)
	(segment
		(start 100.946458 -42.403014)
		(end 100.749862 -42.59961)
		(width 0.508)
		(layer "B.Cu")
		(net "GND")
	)
	(segment
		(start 30.366716 -202.36688)
		(end 29.922216 -202.36688)
		(width 0.508)
		(layer "B.Cu")
		(net "GND")
	)
	(segment
		(start 113.74247 -93.956886)
		(end 113.849658 -93.849698)
		(width 0.508)
		(layer "B.Cu")
		(net "GND")
	)
	(segment
		(start 2.53238 -100.7999)
		(end 4.895088 -100.7999)
		(width 0.508)
		(layer "B.Cu")
		(net "GND")
	)
	(segment
		(start 105.709466 -48.26)
		(end 105.549954 -48.100488)
		(width 0.508)
		(layer "B.Cu")
		(net "GND")
	)
	(segment
		(start 115.27917 -98.0948)
		(end 115.60556 -98.0948)
		(width 0.3048)
		(layer "B.Cu")
		(net "GND")
	)
	(segment
		(start 55.909972 -187.809886)
		(end 57.04078 -187.809886)
		(width 0.508)
		(layer "B.Cu")
		(net "GND")
	)
	(segment
		(start 30.366716 -203.38288)
		(end 29.922216 -203.38288)
		(width 0.508)
		(layer "B.Cu")
		(net "GND")
	)
	(segment
		(start 142.19047 -87.6935)
		(end 142.76197 -88.265)
		(width 0.508)
		(layer "B.Cu")
		(net "GND")
	)
	(segment
		(start 98.94316 -33.6804)
		(end 98.94316 -34.393378)
		(width 0.3048)
		(layer "B.Cu")
		(net "GND")
	)
	(segment
		(start 115.90147 -82.931)
		(end 115.90147 -83.79841)
		(width 0.3048)
		(layer "B.Cu")
		(net "GND")
	)
	(segment
		(start 275.500084 -10.989818)
		(end 276.541992 -10.989818)
		(width 0.508)
		(layer "B.Cu")
		(net "GND")
	)
	(segment
		(start 105.709466 -44.359322)
		(end 105.549954 -44.19981)
		(width 0.508)
		(layer "B.Cu")
		(net "GND")
	)
	(segment
		(start 150.999952 -250.828048)
		(end 151.937212 -249.890788)
		(width 0.508)
		(layer "B.Cu")
		(net "GND")
	)
	(segment
		(start 113.963958 -96.9645)
		(end 113.849658 -96.8502)
		(width 0.508)
		(layer "B.Cu")
		(net "GND")
	)
	(segment
		(start 90.58656 -37.084)
		(end 92.031566 -37.084)
		(width 0.3048)
		(layer "B.Cu")
		(net "GND")
	)
	(segment
		(start 88.000332 -253.54788)
		(end 88.564212 -252.984)
		(width 0.508)
		(layer "B.Cu")
		(net "GND")
	)
	(segment
		(start 59.859164 -187.809886)
		(end 60.989972 -187.809886)
		(width 0.508)
		(layer "B.Cu")
		(net "GND")
	)
	(segment
		(start 94.930976 -37.808916)
		(end 94.34957 -37.808916)
		(width 0.3556)
		(layer "B.Cu")
		(net "GND")
	)
	(segment
		(start 108.3945 -62.4205)
		(end 109.601 -63.627)
		(width 0.508)
		(layer "B.Cu")
		(net "GND")
	)
	(segment
		(start 100.950014 -47.200058)
		(end 100.950014 -47.147226)
		(width 0.508)
		(layer "B.Cu")
		(net "GND")
	)
	(segment
		(start 105.734866 -42.417746)
		(end 105.55605 -42.596562)
		(width 0.508)
		(layer "B.Cu")
		(net "GND")
	)
	(segment
		(start 276.225 -165.187884)
		(end 276.225 -164.8206)
		(width 0.508)
		(layer "B.Cu")
		(net "GND")
	)
	(segment
		(start 274.458176 -10.989818)
		(end 275.500084 -10.989818)
		(width 0.508)
		(layer "B.Cu")
		(net "GND")
	)
	(segment
		(start 111.13897 -95.560896)
		(end 110.849664 -95.850202)
		(width 0.3556)
		(layer "B.Cu")
		(net "GND")
	)
	(segment
		(start 119.742966 -32.9565)
		(end 119.742966 -33.909)
		(width 0.508)
		(layer "B.Cu")
		(net "GND")
	)
	(segment
		(start 96.715326 -39.22776)
		(end 96.550226 -39.39286)
		(width 0.3556)
		(layer "B.Cu")
		(net "GND")
	)
	(segment
		(start 107.51566 -35.306)
		(end 107.51566 -35.604958)
		(width 0.508)
		(layer "B.Cu")
		(net "GND")
	)
	(segment
		(start 304.292 -180.467)
		(end 303.784 -180.467)
		(width 0.508)
		(layer "B.Cu")
		(net "GND")
	)
	(segment
		(start 66.069972 -185.269886)
		(end 66.069972 -186.400694)
		(width 0.508)
		(layer "B.Cu")
		(net "GND")
	)
	(segment
		(start 90.634566 -32.639)
		(end 89.897966 -32.639)
		(width 0.3048)
		(layer "B.Cu")
		(net "GND")
	)
	(segment
		(start 89.86647 -99.7585)
		(end 90.18397 -100.076)
		(width 0.508)
		(layer "B.Cu")
		(net "GND")
	)
	(segment
		(start 110.408466 -50.541428)
		(end 110.350046 -50.599848)
		(width 0.508)
		(layer "B.Cu")
		(net "GND")
	)
	(segment
		(start 19.817588 -191.136016)
		(end 20.008088 -191.326516)
		(width 0.508)
		(layer "B.Cu")
		(net "GND")
	)
	(segment
		(start 111.59617 -94.488)
		(end 111.59617 -94.10319)
		(width 0.3556)
		(layer "B.Cu")
		(net "GND")
	)
	(segment
		(start 297.2562 -204.4065)
		(end 297.2562 -205.64094)
		(width 0.508)
		(layer "B.Cu")
		(net "GND")
	)
	(segment
		(start 101.035866 -41.91)
		(end 101.035866 -42.25417)
		(width 0.508)
		(layer "B.Cu")
		(net "GND")
	)
	(segment
		(start 98.709226 -54.7116)
		(end 98.709226 -54.958996)
		(width 0.508)
		(layer "B.Cu")
		(net "GND")
	)
	(segment
		(start 4.895088 -83.437222)
		(end 4.895088 -85.79993)
		(width 0.508)
		(layer "B.Cu")
		(net "GND")
	)
	(segment
		(start 130.000502 -253.33071)
		(end 130.474212 -252.857)
		(width 0.508)
		(layer "B.Cu")
		(net "GND")
	)
	(segment
		(start 101.010466 -46.609)
		(end 101.010466 -46.113446)
		(width 0.508)
		(layer "B.Cu")
		(net "GND")
	)
	(segment
		(start 83.999832 -253.35738)
		(end 84.500212 -252.857)
		(width 0.508)
		(layer "B.Cu")
		(net "GND")
	)
	(segment
		(start 56.89981 -59.680094)
		(end 56.89981 -60.620402)
		(width 0.508)
		(layer "B.Cu")
		(net "GND")
	)
	(segment
		(start 96.758506 -54.70906)
		(end 96.758506 -53.808122)
		(width 0.508)
		(layer "B.Cu")
		(net "GND")
	)
	(segment
		(start 20.008088 -191.326516)
		(end 20.008088 -193.041016)
		(width 0.508)
		(layer "B.Cu")
		(net "GND")
	)
	(segment
		(start 101.010466 -43.1165)
		(end 100.749862 -42.855896)
		(width 0.508)
		(layer "B.Cu")
		(net "GND")
	)
	(segment
		(start 102.37597 -81.153)
		(end 101.99497 -80.772)
		(width 0.3048)
		(layer "B.Cu")
		(net "GND")
	)
	(segment
		(start 103.804466 -45.954696)
		(end 103.959152 -45.80001)
		(width 0.508)
		(layer "B.Cu")
		(net "GND")
	)
	(segment
		(start 91.47556 -34.097468)
		(end 90.779092 -33.401)
		(width 0.3048)
		(layer "B.Cu")
		(net "GND")
	)
	(segment
		(start 110.000542 -253.64567)
		(end 110.662212 -252.984)
		(width 0.508)
		(layer "B.Cu")
		(net "GND")
	)
	(segment
		(start 100.94976 -45.54728)
		(end 101.010466 -45.486574)
		(width 0.508)
		(layer "B.Cu")
		(net "GND")
	)
	(segment
		(start 126.000002 -253.39421)
		(end 126.537212 -252.857)
		(width 0.508)
		(layer "B.Cu")
		(net "GND")
	)
	(segment
		(start 317.0555 -183.515)
		(end 317.246 -183.7055)
		(width 0.508)
		(layer "B.Cu")
		(net "GND")
	)
	(segment
		(start 103.949754 -44.19981)
		(end 103.804466 -44.054522)
		(width 0.508)
		(layer "B.Cu")
		(net "GND")
	)
	(segment
		(start 92.285566 -33.401)
		(end 90.779092 -33.401)
		(width 0.3048)
		(layer "B.Cu")
		(net "GND")
	)
	(segment
		(start 117.73789 -89.58834)
		(end 117.588792 -89.58834)
		(width 0.3048)
		(layer "B.Cu")
		(net "GND")
	)
	(segment
		(start 119.0498 -75.6412)
		(end 119.16537 -75.6412)
		(width 0.508)
		(layer "B.Cu")
		(net "GND")
	)
	(segment
		(start 92.645992 -51.399694)
		(end 93.549978 -51.399694)
		(width 0.508)
		(layer "B.Cu")
		(net "GND")
	)
	(segment
		(start 18.682716 -216.71788)
		(end 18.682716 -216.14638)
		(width 0.508)
		(layer "B.Cu")
		(net "GND")
	)
	(segment
		(start 111.57077 -98.571304)
		(end 111.849662 -98.850196)
		(width 0.3556)
		(layer "B.Cu")
		(net "GND")
	)
	(segment
		(start 100.946458 -42.343578)
		(end 100.946458 -42.403014)
		(width 0.508)
		(layer "B.Cu")
		(net "GND")
	)
	(segment
		(start 151.937212 -249.890788)
		(end 151.937212 -249.809)
		(width 0.508)
		(layer "B.Cu")
		(net "GND")
	)
	(segment
		(start 20.579588 -185.421016)
		(end 20.579588 -180.467508)
		(width 0.508)
		(layer "B.Cu")
		(net "GND")
	)
	(segment
		(start 107.614466 -46.9392)
		(end 107.614466 -46.609)
		(width 0.508)
		(layer "B.Cu")
		(net "GND")
	)
	(segment
		(start 95.155766 -44.0182)
		(end 94.990666 -44.1833)
		(width 0.3556)
		(layer "B.Cu")
		(net "GND")
	)
	(segment
		(start 133.000242 -256.50444)
		(end 133.000242 -253.47803)
		(width 0.508)
		(layer "B.Cu")
		(net "GND")
	)
	(segment
		(start 107.340146 -48.813466)
		(end 107.156504 -48.997108)
		(width 0.4572)
		(layer "B.Cu")
		(net "GND")
	)
	(segment
		(start 133.999732 -253.49835)
		(end 134.641082 -252.857)
		(width 0.508)
		(layer "B.Cu")
		(net "GND")
	)
	(segment
		(start 115.850162 -95.872808)
		(end 115.850162 -95.850202)
		(width 0.3048)
		(layer "B.Cu")
		(net "GND")
	)
	(segment
		(start 290.068 -204.597)
		(end 290.0553 -204.51064)
		(width 0.508)
		(layer "B.Cu")
		(net "GND")
	)
	(segment
		(start 86.532466 -51.181)
		(end 86.532466 -52.0446)
		(width 0.508)
		(layer "B.Cu")
		(net "GND")
	)
	(segment
		(start 121.000012 -256.50444)
		(end 121.000012 -253.4158)
		(width 0.508)
		(layer "B.Cu")
		(net "GND")
	)
	(segment
		(start 101.550216 -37.133784)
		(end 101.550216 -37.00018)
		(width 0.3556)
		(layer "B.Cu")
		(net "GND")
	)
	(segment
		(start 127.519938 -96.52)
		(end 127.850138 -96.8502)
		(width 0.3048)
		(layer "B.Cu")
		(net "GND")
	)
	(segment
		(start 87.1855 -73.05675)
		(end 87.1855 -73.0885)
		(width 0.508)
		(layer "B.Cu")
		(net "GND")
	)
	(segment
		(start 48.289972 -186.679078)
		(end 48.289972 -187.809886)
		(width 0.508)
		(layer "B.Cu")
		(net "GND")
	)
	(segment
		(start 25.104852 -85.79993)
		(end 27.46756 -85.79993)
		(width 0.508)
		(layer "B.Cu")
		(net "GND")
	)
	(segment
		(start 86.999572 -253.32436)
		(end 86.659212 -252.984)
		(width 0.508)
		(layer "B.Cu")
		(net "GND")
	)
	(segment
		(start 100.692966 -53.85689)
		(end 100.750116 -53.79974)
		(width 0.508)
		(layer "B.Cu")
		(net "GND")
	)
	(segment
		(start 100.950014 -47.599854)
		(end 100.750116 -47.399956)
		(width 0.508)
		(layer "B.Cu")
		(net "GND")
	)
	(segment
		(start 305.91506 -180.1368)
		(end 305.610514 -179.832254)
		(width 0.508)
		(layer "B.Cu")
		(net "GND")
	)
	(segment
		(start 184.799732 -256.50444)
		(end 184.799732 -253.111)
		(width 0.508)
		(layer "B.Cu")
		(net "GND")
	)
	(segment
		(start 127.86995 -102.87)
		(end 127.850138 -102.850188)
		(width 0.3048)
		(layer "B.Cu")
		(net "GND")
	)
	(segment
		(start 111.16437 -82.0801)
		(end 111.16437 -83.1088)
		(width 0.3048)
		(layer "B.Cu")
		(net "GND")
	)
	(segment
		(start 121.67997 -90.1954)
		(end 121.67997 -90.297)
		(width 0.3048)
		(layer "B.Cu")
		(net "GND")
	)
	(segment
		(start 311.702958 -52.2732)
		(end 313.3598 -52.2732)
		(width 0.508)
		(layer "B.Cu")
		(net "GND")
	)
	(segment
		(start 119.13997 -106.1974)
		(end 119.13997 -106.426)
		(width 0.3048)
		(layer "B.Cu")
		(net "GND")
	)
	(segment
		(start 276.285452 -165.248336)
		(end 276.225 -165.187884)
		(width 0.508)
		(layer "B.Cu")
		(net "GND")
	)
	(segment
		(start 290.07054 -204.52588)
		(end 290.07054 -205.613)
		(width 0.508)
		(layer "B.Cu")
		(net "GND")
	)
	(segment
		(start 103.43007 -94.076774)
		(end 103.392478 -94.039182)
		(width 0.2032)
		(layer "B.Cu")
		(net "GND")
	)
	(segment
		(start 68.609972 -185.269886)
		(end 69.74078 -185.269886)
		(width 0.508)
		(layer "B.Cu")
		(net "GND")
	)
	(segment
		(start 275.500084 -10.989818)
		(end 275.500084 -12.031726)
		(width 0.508)
		(layer "B.Cu")
		(net "GND")
	)
	(segment
		(start 38.15969 -62.680088)
		(end 39.099998 -62.680088)
		(width 0.508)
		(layer "B.Cu")
		(net "GND")
	)
	(segment
		(start 115.17757 -101.6762)
		(end 115.676172 -101.6762)
		(width 0.3048)
		(layer "B.Cu")
		(net "GND")
	)
	(segment
		(start 110.13186 -99.568)
		(end 109.849666 -99.850194)
		(width 0.3556)
		(layer "B.Cu")
		(net "GND")
	)
	(segment
		(start 146.999452 -256.50444)
		(end 146.999452 -253.50724)
		(width 0.508)
		(layer "B.Cu")
		(net "GND")
	)
	(segment
		(start 87.96782 -45.6692)
		(end 87.96782 -46.380146)
		(width 0.508)
		(layer "B.Cu")
		(net "GND")
	)
	(segment
		(start 110.350046 -53.06314)
		(end 110.350046 -53.79974)
		(width 0.508)
		(layer "B.Cu")
		(net "GND")
	)
	(segment
		(start 91.777566 -35.433)
		(end 91.777566 -36.02736)
		(width 0.3048)
		(layer "B.Cu")
		(net "GND")
	)
	(segment
		(start 182.612792 -27.305)
		(end 182.612792 -27.944064)
		(width 0.508)
		(layer "B.Cu")
		(net "GND")
	)
	(segment
		(start 88.000332 -256.50444)
		(end 88.000332 -253.54788)
		(width 0.508)
		(layer "B.Cu")
		(net "GND")
	)
	(segment
		(start 101.010466 -44.958)
		(end 101.010466 -44.532042)
		(width 0.508)
		(layer "B.Cu")
		(net "GND")
	)
	(segment
		(start 298.7675 -177.49774)
		(end 298.829984 -177.435256)
		(width 0.508)
		(layer "B.Cu")
		(net "GND")
	)
	(segment
		(start 16.015716 -169.15638)
		(end 15.317216 -168.45788)
		(width 0.508)
		(layer "B.Cu")
		(net "GND")
	)
	(segment
		(start 313.3598 -52.2732)
		(end 313.817 -51.816)
		(width 0.508)
		(layer "B.Cu")
		(net "GND")
	)
	(segment
		(start 57.319164 -187.809886)
		(end 58.449972 -187.809886)
		(width 0.508)
		(layer "B.Cu")
		(net "GND")
	)
	(segment
		(start 103.949754 -47.399702)
		(end 103.804466 -47.254414)
		(width 0.508)
		(layer "B.Cu")
		(net "GND")
	)
	(segment
		(start 126.91237 -96.52)
		(end 127.519938 -96.52)
		(width 0.3048)
		(layer "B.Cu")
		(net "GND")
	)
	(segment
		(start 103.359966 -59.3725)
		(end 103.359966 -59.817)
		(width 0.508)
		(layer "B.Cu")
		(net "GND")
	)
	(segment
		(start 126.27737 -102.997)
		(end 126.27737 -103.422958)
		(width 0.3048)
		(layer "B.Cu")
		(net "GND")
	)
	(segment
		(start 114.023648 -101.6762)
		(end 113.849658 -101.85019)
		(width 0.3048)
		(layer "B.Cu")
		(net "GND")
	)
	(segment
		(start 101.010466 -48.26)
		(end 101.010466 -47.713138)
		(width 0.508)
		(layer "B.Cu")
		(net "GND")
	)
	(segment
		(start 103.804466 -48.26)
		(end 103.804466 -47.54499)
		(width 0.508)
		(layer "B.Cu")
		(net "GND")
	)
	(segment
		(start 294.7162 -204.4065)
		(end 294.7162 -205.64094)
		(width 0.508)
		(layer "B.Cu")
		(net "GND")
	)
	(segment
		(start 288.439352 -174.245016)
		(end 288.429954 -174.235618)
		(width 0.3556)
		(layer "B.Cu")
		(net "GND")
	)
	(segment
		(start 101.010466 -47.713138)
		(end 100.950014 -47.652686)
		(width 0.508)
		(layer "B.Cu")
		(net "GND")
	)
	(segment
		(start 120.86717 -90.1446)
		(end 120.86717 -90.832686)
		(width 0.3048)
		(layer "B.Cu")
		(net "GND")
	)
	(segment
		(start 110.281466 -48.931322)
		(end 110.350046 -48.999902)
		(width 0.508)
		(layer "B.Cu")
		(net "GND")
	)
	(segment
		(start 164.36975 -110.4265)
		(end 164.36975 -109.06125)
		(width 0.508)
		(layer "B.Cu")
		(net "GND")
	)
	(segment
		(start 148.000212 -256.50444)
		(end 148.000212 -253.111)
		(width 0.508)
		(layer "B.Cu")
		(net "GND")
	)
	(segment
		(start 89.535 -28.702)
		(end 89.48166 -28.64866)
		(width 0.508)
		(layer "B.Cu")
		(net "GND")
	)
	(segment
		(start 107.13847 -94.560898)
		(end 107.84967 -93.849698)
		(width 0.3048)
		(layer "B.Cu")
		(net "GND")
	)
	(segment
		(start 128.86817 -97.917)
		(end 128.86817 -99.2632)
		(width 0.3048)
		(layer "B.Cu")
		(net "GND")
	)
	(segment
		(start 100.750116 -47.399956)
		(end 100.950014 -47.200058)
		(width 0.508)
		(layer "B.Cu")
		(net "GND")
	)
	(segment
		(start 25.040844 -176.276762)
		(end 25.040844 -177.242216)
		(width 0.508)
		(layer "B.Cu")
		(net "GND")
	)
	(segment
		(start 68.609972 -187.809886)
		(end 69.74078 -187.809886)
		(width 0.508)
		(layer "B.Cu")
		(net "GND")
	)
	(segment
		(start 102.5144 -37.719)
		(end 103.078534 -37.719)
		(width 0.254)
		(layer "B.Cu")
		(net "GND")
	)
	(segment
		(start 68.498212 -244.4115)
		(end 68.498212 -243.078)
		(width 0.508)
		(layer "B.Cu")
		(net "GND")
	)
	(segment
		(start 60.989972 -187.809886)
		(end 62.12078 -187.809886)
		(width 0.508)
		(layer "In2.Cu")
		(net "GND")
	)
	(segment
		(start 25.104852 -98.983292)
		(end 25.104852 -100.7999)
		(width 0.508)
		(layer "In2.Cu")
		(net "GND")
	)
	(segment
		(start 4.895088 -85.79993)
		(end 6.711696 -85.79993)
		(width 0.508)
		(layer "In2.Cu")
		(net "GND")
	)
	(segment
		(start 55.909972 -186.679078)
		(end 55.909972 -187.809886)
		(width 0.508)
		(layer "In2.Cu")
		(net "GND")
	)
	(segment
		(start 166.249858 -11.210036)
		(end 166.249858 -12.556744)
		(width 0.508)
		(layer "In2.Cu")
		(net "GND")
	)
	(segment
		(start 66.069972 -186.679078)
		(end 66.069972 -187.809886)
		(width 0.508)
		(layer "In2.Cu")
		(net "GND")
	)
	(segment
		(start 147.323302 -11.210036)
		(end 148.67001 -11.210036)
		(width 0.508)
		(layer "In2.Cu")
		(net "GND")
	)
	(segment
		(start 58.449972 -187.809886)
		(end 58.449972 -188.940694)
		(width 0.508)
		(layer "In2.Cu")
		(net "GND")
	)
	(segment
		(start 347.235018 -24.45004)
		(end 348.302326 -24.45004)
		(width 0.508)
		(layer "In2.Cu")
		(net "GND")
	)
	(segment
		(start 39.099998 -66.179954)
		(end 40.040306 -66.179954)
		(width 0.508)
		(layer "In2.Cu")
		(net "GND")
	)
	(segment
		(start 68.609972 -187.809886)
		(end 68.609972 -188.940694)
		(width 0.508)
		(layer "In2.Cu")
		(net "GND")
	)
	(segment
		(start 59.859164 -187.809886)
		(end 60.989972 -187.809886)
		(width 0.508)
		(layer "In2.Cu")
		(net "GND")
	)
	(segment
		(start 53.369972 -187.809886)
		(end 54.50078 -187.809886)
		(width 0.508)
		(layer "In2.Cu")
		(net "GND")
	)
	(segment
		(start 4.895088 -98.983292)
		(end 4.895088 -100.7999)
		(width 0.508)
		(layer "In2.Cu")
		(net "GND")
	)
	(segment
		(start 39.099998 -60.680092)
		(end 39.099998 -61.6204)
		(width 0.508)
		(layer "In2.Cu")
		(net "GND")
	)
	(segment
		(start 54.779164 -187.809886)
		(end 55.909972 -187.809886)
		(width 0.508)
		(layer "In2.Cu")
		(net "GND")
	)
	(segment
		(start 49.699164 -187.809886)
		(end 50.829972 -187.809886)
		(width 0.508)
		(layer "In2.Cu")
		(net "GND")
	)
	(segment
		(start 353.734878 -14.182598)
		(end 353.734878 -15.249906)
		(width 0.508)
		(layer "In2.Cu")
		(net "GND")
	)
	(segment
		(start 55.909972 -187.809886)
		(end 55.909972 -188.940694)
		(width 0.508)
		(layer "In2.Cu")
		(net "GND")
	)
	(segment
		(start 39.099998 -60.680092)
		(end 40.040306 -60.680092)
		(width 0.508)
		(layer "In2.Cu")
		(net "GND")
	)
	(segment
		(start 346.16771 -24.45004)
		(end 347.235018 -24.45004)
		(width 0.508)
		(layer "In2.Cu")
		(net "GND")
	)
	(segment
		(start 25.104852 -100.7999)
		(end 26.92146 -100.7999)
		(width 0.508)
		(layer "In2.Cu")
		(net "GND")
	)
	(segment
		(start 50.829972 -187.809886)
		(end 50.829972 -188.940694)
		(width 0.508)
		(layer "In2.Cu")
		(net "GND")
	)
	(segment
		(start 53.369972 -186.679078)
		(end 53.369972 -187.809886)
		(width 0.508)
		(layer "In2.Cu")
		(net "GND")
	)
	(segment
		(start 25.104852 -85.79993)
		(end 26.92146 -85.79993)
		(width 0.508)
		(layer "In2.Cu")
		(net "GND")
	)
	(segment
		(start 56.89981 -65.239646)
		(end 56.89981 -66.179954)
		(width 0.508)
		(layer "In2.Cu")
		(net "GND")
	)
	(segment
		(start 66.069972 -187.809886)
		(end 67.20078 -187.809886)
		(width 0.508)
		(layer "In2.Cu")
		(net "GND")
	)
	(segment
		(start 67.479164 -187.809886)
		(end 68.609972 -187.809886)
		(width 0.508)
		(layer "In2.Cu")
		(net "GND")
	)
	(segment
		(start 60.989972 -186.679078)
		(end 60.989972 -187.809886)
		(width 0.508)
		(layer "In2.Cu")
		(net "GND")
	)
	(segment
		(start 52.239164 -187.809886)
		(end 53.369972 -187.809886)
		(width 0.508)
		(layer "In2.Cu")
		(net "GND")
	)
	(segment
		(start 55.909972 -187.809886)
		(end 57.04078 -187.809886)
		(width 0.508)
		(layer "In2.Cu")
		(net "GND")
	)
	(segment
		(start 4.895088 -100.7999)
		(end 6.711696 -100.7999)
		(width 0.508)
		(layer "In2.Cu")
		(net "GND")
	)
	(segment
		(start 38.15969 -62.680088)
		(end 39.099998 -62.680088)
		(width 0.508)
		(layer "In2.Cu")
		(net "GND")
	)
	(segment
		(start 68.609972 -185.269886)
		(end 69.74078 -185.269886)
		(width 0.508)
		(layer "In2.Cu")
		(net "GND")
	)
	(segment
		(start 48.289972 -187.809886)
		(end 49.42078 -187.809886)
		(width 0.508)
		(layer "In2.Cu")
		(net "GND")
	)
	(segment
		(start 275.500084 -10.989818)
		(end 276.541992 -10.989818)
		(width 0.508)
		(layer "In2.Cu")
		(net "GND")
	)
	(segment
		(start 4.895088 -100.7999)
		(end 4.895088 -102.616508)
		(width 0.508)
		(layer "In2.Cu")
		(net "GND")
	)
	(segment
		(start 353.734878 -23.382732)
		(end 353.734878 -24.45004)
		(width 0.508)
		(layer "In2.Cu")
		(net "GND")
	)
	(segment
		(start 23.288244 -100.7999)
		(end 25.104852 -100.7999)
		(width 0.508)
		(layer "In2.Cu")
		(net "GND")
	)
	(segment
		(start 67.479164 -185.269886)
		(end 68.609972 -185.269886)
		(width 0.508)
		(layer "In2.Cu")
		(net "GND")
	)
	(segment
		(start 63.529972 -187.809886)
		(end 64.66078 -187.809886)
		(width 0.508)
		(layer "In2.Cu")
		(net "GND")
	)
	(segment
		(start 3.07848 -100.7999)
		(end 4.895088 -100.7999)
		(width 0.508)
		(layer "In2.Cu")
		(net "GND")
	)
	(segment
		(start 47.159164 -187.809886)
		(end 48.289972 -187.809886)
		(width 0.508)
		(layer "In2.Cu")
		(net "GND")
	)
	(segment
		(start 275.500084 -9.94791)
		(end 275.500084 -10.989818)
		(width 0.508)
		(layer "In2.Cu")
		(net "GND")
	)
	(segment
		(start 56.89981 -59.680094)
		(end 56.89981 -60.620402)
		(width 0.508)
		(layer "In2.Cu")
		(net "GND")
	)
	(segment
		(start 66.069972 -187.809886)
		(end 66.069972 -188.940694)
		(width 0.508)
		(layer "In2.Cu")
		(net "GND")
	)
	(segment
		(start 50.829972 -187.809886)
		(end 51.96078 -187.809886)
		(width 0.508)
		(layer "In2.Cu")
		(net "GND")
	)
	(segment
		(start 148.67001 -9.863328)
		(end 148.67001 -11.210036)
		(width 0.508)
		(layer "In2.Cu")
		(net "GND")
	)
	(segment
		(start 60.989972 -187.809886)
		(end 60.989972 -188.940694)
		(width 0.508)
		(layer "In2.Cu")
		(net "GND")
	)
	(segment
		(start 68.609972 -184.139078)
		(end 68.609972 -185.269886)
		(width 0.508)
		(layer "In2.Cu")
		(net "GND")
	)
	(segment
		(start 275.500084 -10.989818)
		(end 275.500084 -12.031726)
		(width 0.508)
		(layer "In2.Cu")
		(net "GND")
	)
	(segment
		(start 38.15969 -60.680092)
		(end 39.099998 -60.680092)
		(width 0.508)
		(layer "In2.Cu")
		(net "GND")
	)
	(segment
		(start 58.449972 -185.269886)
		(end 59.58078 -185.269886)
		(width 0.508)
		(layer "In2.Cu")
		(net "GND")
	)
	(segment
		(start 57.319164 -185.269886)
		(end 58.449972 -185.269886)
		(width 0.508)
		(layer "In2.Cu")
		(net "GND")
	)
	(segment
		(start 56.89981 -62.680088)
		(end 56.89981 -63.620396)
		(width 0.508)
		(layer "In2.Cu")
		(net "GND")
	)
	(segment
		(start 58.449972 -186.679078)
		(end 58.449972 -187.809886)
		(width 0.508)
		(layer "In2.Cu")
		(net "GND")
	)
	(segment
		(start 58.449972 -187.809886)
		(end 59.58078 -187.809886)
		(width 0.508)
		(layer "In2.Cu")
		(net "GND")
	)
	(segment
		(start 3.07848 -85.79993)
		(end 4.895088 -85.79993)
		(width 0.508)
		(layer "In2.Cu")
		(net "GND")
	)
	(segment
		(start 347.235018 -15.249906)
		(end 347.235018 -16.317214)
		(width 0.508)
		(layer "In2.Cu")
		(net "GND")
	)
	(segment
		(start 25.104852 -85.79993)
		(end 25.104852 -87.616538)
		(width 0.508)
		(layer "In2.Cu")
		(net "GND")
	)
	(segment
		(start 55.959502 -59.680094)
		(end 56.89981 -59.680094)
		(width 0.508)
		(layer "In2.Cu")
		(net "GND")
	)
	(segment
		(start 148.67001 -11.210036)
		(end 150.016718 -11.210036)
		(width 0.508)
		(layer "In2.Cu")
		(net "GND")
	)
	(segment
		(start 39.099998 -62.680088)
		(end 39.099998 -63.620396)
		(width 0.508)
		(layer "In2.Cu")
		(net "GND")
	)
	(segment
		(start 39.099998 -59.739784)
		(end 39.099998 -60.680092)
		(width 0.508)
		(layer "In2.Cu")
		(net "GND")
	)
	(segment
		(start 39.099998 -65.239646)
		(end 39.099998 -66.179954)
		(width 0.508)
		(layer "In2.Cu")
		(net "GND")
	)
	(segment
		(start 339.985604 -7.499604)
		(end 339.985604 -8.490712)
		(width 0.508)
		(layer "In2.Cu")
		(net "GND")
	)
	(segment
		(start 56.89981 -66.179954)
		(end 57.840118 -66.179954)
		(width 0.508)
		(layer "In2.Cu")
		(net "GND")
	)
	(segment
		(start 66.069972 -185.269886)
		(end 66.069972 -186.400694)
		(width 0.508)
		(layer "In2.Cu")
		(net "GND")
	)
	(segment
		(start 56.89981 -62.680088)
		(end 57.840118 -62.680088)
		(width 0.508)
		(layer "In2.Cu")
		(net "GND")
	)
	(segment
		(start 164.90315 -11.210036)
		(end 166.249858 -11.210036)
		(width 0.508)
		(layer "In2.Cu")
		(net "GND")
	)
	(segment
		(start 55.959502 -62.680088)
		(end 56.89981 -62.680088)
		(width 0.508)
		(layer "In2.Cu")
		(net "GND")
	)
	(segment
		(start 4.895088 -83.983322)
		(end 4.895088 -85.79993)
		(width 0.508)
		(layer "In2.Cu")
		(net "GND")
	)
	(segment
		(start 68.609972 -185.269886)
		(end 68.609972 -186.400694)
		(width 0.508)
		(layer "In2.Cu")
		(net "GND")
	)
	(segment
		(start 56.89981 -61.73978)
		(end 56.89981 -62.680088)
		(width 0.508)
		(layer "In2.Cu")
		(net "GND")
	)
	(segment
		(start 274.458176 -10.989818)
		(end 275.500084 -10.989818)
		(width 0.508)
		(layer "In2.Cu")
		(net "GND")
	)
	(segment
		(start 25.104852 -83.983322)
		(end 25.104852 -85.79993)
		(width 0.508)
		(layer "In2.Cu")
		(net "GND")
	)
	(segment
		(start 58.449972 -185.269886)
		(end 58.449972 -186.400694)
		(width 0.508)
		(layer "In2.Cu")
		(net "GND")
	)
	(segment
		(start 347.235018 -15.249906)
		(end 348.302326 -15.249906)
		(width 0.508)
		(layer "In2.Cu")
		(net "GND")
	)
	(segment
		(start 353.734878 -15.249906)
		(end 353.734878 -16.317214)
		(width 0.508)
		(layer "In2.Cu")
		(net "GND")
	)
	(segment
		(start 48.289972 -186.679078)
		(end 48.289972 -187.809886)
		(width 0.508)
		(layer "In2.Cu")
		(net "GND")
	)
	(segment
		(start 148.67001 -11.210036)
		(end 148.67001 -12.556744)
		(width 0.508)
		(layer "In2.Cu")
		(net "GND")
	)
	(segment
		(start 25.104852 -100.7999)
		(end 25.104852 -102.616508)
		(width 0.508)
		(layer "In2.Cu")
		(net "GND")
	)
	(segment
		(start 352.66757 -15.249906)
		(end 353.734878 -15.249906)
		(width 0.508)
		(layer "In2.Cu")
		(net "GND")
	)
	(segment
		(start 68.609972 -187.809886)
		(end 69.74078 -187.809886)
		(width 0.508)
		(layer "In2.Cu")
		(net "GND")
	)
	(segment
		(start 4.895088 -85.79993)
		(end 4.895088 -87.616538)
		(width 0.508)
		(layer "In2.Cu")
		(net "GND")
	)
	(segment
		(start 48.289972 -187.809886)
		(end 48.289972 -188.940694)
		(width 0.508)
		(layer "In2.Cu")
		(net "GND")
	)
	(segment
		(start 57.319164 -187.809886)
		(end 58.449972 -187.809886)
		(width 0.508)
		(layer "In2.Cu")
		(net "GND")
	)
	(segment
		(start 68.609972 -186.679078)
		(end 68.609972 -187.809886)
		(width 0.508)
		(layer "In2.Cu")
		(net "GND")
	)
	(segment
		(start 56.89981 -59.680094)
		(end 57.840118 -59.680094)
		(width 0.508)
		(layer "In2.Cu")
		(net "GND")
	)
	(segment
		(start 63.529972 -186.679078)
		(end 63.529972 -187.809886)
		(width 0.508)
		(layer "In2.Cu")
		(net "GND")
	)
	(segment
		(start 64.939164 -187.809886)
		(end 66.069972 -187.809886)
		(width 0.508)
		(layer "In2.Cu")
		(net "GND")
	)
	(segment
		(start 166.249858 -11.210036)
		(end 167.596566 -11.210036)
		(width 0.508)
		(layer "In2.Cu")
		(net "GND")
	)
	(segment
		(start 63.529972 -187.809886)
		(end 63.529972 -188.940694)
		(width 0.508)
		(layer "In2.Cu")
		(net "GND")
	)
	(segment
		(start 23.288244 -85.79993)
		(end 25.104852 -85.79993)
		(width 0.508)
		(layer "In2.Cu")
		(net "GND")
	)
	(segment
		(start 347.235018 -14.182598)
		(end 347.235018 -15.249906)
		(width 0.508)
		(layer "In2.Cu")
		(net "GND")
	)
	(segment
		(start 39.099998 -66.179954)
		(end 39.099998 -67.120262)
		(width 0.508)
		(layer "In2.Cu")
		(net "GND")
	)
	(segment
		(start 62.399164 -187.809886)
		(end 63.529972 -187.809886)
		(width 0.508)
		(layer "In2.Cu")
		(net "GND")
	)
	(segment
		(start 56.89981 -66.179954)
		(end 56.89981 -67.120262)
		(width 0.508)
		(layer "In2.Cu")
		(net "GND")
	)
	(segment
		(start 353.734878 -24.45004)
		(end 353.734878 -25.517348)
		(width 0.508)
		(layer "In2.Cu")
		(net "GND")
	)
	(segment
		(start 66.069972 -184.139078)
		(end 66.069972 -185.269886)
		(width 0.508)
		(layer "In2.Cu")
		(net "GND")
	)
	(segment
		(start 55.959502 -66.179954)
		(end 56.89981 -66.179954)
		(width 0.508)
		(layer "In2.Cu")
		(net "GND")
	)
	(segment
		(start 166.249858 -9.863328)
		(end 166.249858 -11.210036)
		(width 0.508)
		(layer "In2.Cu")
		(net "GND")
	)
	(segment
		(start 347.235018 -23.382732)
		(end 347.235018 -24.45004)
		(width 0.508)
		(layer "In2.Cu")
		(net "GND")
	)
	(segment
		(start 64.939164 -185.269886)
		(end 66.069972 -185.269886)
		(width 0.508)
		(layer "In2.Cu")
		(net "GND")
	)
	(segment
		(start 50.829972 -186.679078)
		(end 50.829972 -187.809886)
		(width 0.508)
		(layer "In2.Cu")
		(net "GND")
	)
	(segment
		(start 53.369972 -187.809886)
		(end 53.369972 -188.940694)
		(width 0.508)
		(layer "In2.Cu")
		(net "GND")
	)
	(segment
		(start 352.66757 -24.45004)
		(end 353.734878 -24.45004)
		(width 0.508)
		(layer "In2.Cu")
		(net "GND")
	)
	(segment
		(start 338.994496 -7.499604)
		(end 339.985604 -7.499604)
		(width 0.508)
		(layer "In2.Cu")
		(net "GND")
	)
	(segment
		(start 39.099998 -62.680088)
		(end 40.040306 -62.680088)
		(width 0.508)
		(layer "In2.Cu")
		(net "GND")
	)
	(segment
		(start 38.15969 -66.179954)
		(end 39.099998 -66.179954)
		(width 0.508)
		(layer "In2.Cu")
		(net "GND")
	)
	(segment
		(start 58.449972 -184.139078)
		(end 58.449972 -185.269886)
		(width 0.508)
		(layer "In2.Cu")
		(net "GND")
	)
	(segment
		(start 347.235018 -24.45004)
		(end 347.235018 -25.517348)
		(width 0.508)
		(layer "In2.Cu")
		(net "GND")
	)
	(segment
		(start 346.16771 -15.249906)
		(end 347.235018 -15.249906)
		(width 0.508)
		(layer "In2.Cu")
		(net "GND")
	)
	(segment
		(start 66.069972 -185.269886)
		(end 67.20078 -185.269886)
		(width 0.508)
		(layer "In2.Cu")
		(net "GND")
	)
	(segment
		(start 39.099998 -61.73978)
		(end 39.099998 -62.680088)
		(width 0.508)
		(layer "In2.Cu")
		(net "GND")
	)
	(segment
		(start 56.89981 -62.680088)
		(end 57.840118 -62.680088)
		(width 0.508)
		(layer "In5.Cu")
		(net "GND")
	)
	(segment
		(start 55.909972 -187.809886)
		(end 57.04078 -187.809886)
		(width 0.508)
		(layer "In5.Cu")
		(net "GND")
	)
	(segment
		(start 166.249858 -9.863328)
		(end 166.249858 -11.210036)
		(width 0.508)
		(layer "In5.Cu")
		(net "GND")
	)
	(segment
		(start 352.66757 -15.249906)
		(end 353.734878 -15.249906)
		(width 0.508)
		(layer "In5.Cu")
		(net "GND")
	)
	(segment
		(start 3.07848 -85.79993)
		(end 4.895088 -85.79993)
		(width 0.508)
		(layer "In5.Cu")
		(net "GND")
	)
	(segment
		(start 47.159164 -187.809886)
		(end 48.289972 -187.809886)
		(width 0.508)
		(layer "In5.Cu")
		(net "GND")
	)
	(segment
		(start 4.895088 -85.79993)
		(end 6.711696 -85.79993)
		(width 0.508)
		(layer "In5.Cu")
		(net "GND")
	)
	(segment
		(start 55.959502 -62.680088)
		(end 56.89981 -62.680088)
		(width 0.508)
		(layer "In5.Cu")
		(net "GND")
	)
	(segment
		(start 25.104852 -85.79993)
		(end 25.104852 -87.616538)
		(width 0.508)
		(layer "In5.Cu")
		(net "GND")
	)
	(segment
		(start 58.449972 -185.269886)
		(end 59.58078 -185.269886)
		(width 0.508)
		(layer "In5.Cu")
		(net "GND")
	)
	(segment
		(start 67.479164 -185.269886)
		(end 68.609972 -185.269886)
		(width 0.508)
		(layer "In5.Cu")
		(net "GND")
	)
	(segment
		(start 56.89981 -59.680094)
		(end 57.840118 -59.680094)
		(width 0.508)
		(layer "In5.Cu")
		(net "GND")
	)
	(segment
		(start 60.989972 -187.809886)
		(end 60.989972 -188.940694)
		(width 0.508)
		(layer "In5.Cu")
		(net "GND")
	)
	(segment
		(start 56.89981 -61.73978)
		(end 56.89981 -62.680088)
		(width 0.508)
		(layer "In5.Cu")
		(net "GND")
	)
	(segment
		(start 25.104852 -98.983292)
		(end 25.104852 -100.7999)
		(width 0.508)
		(layer "In5.Cu")
		(net "GND")
	)
	(segment
		(start 54.779164 -187.809886)
		(end 55.909972 -187.809886)
		(width 0.508)
		(layer "In5.Cu")
		(net "GND")
	)
	(segment
		(start 58.449972 -184.139078)
		(end 58.449972 -185.269886)
		(width 0.508)
		(layer "In5.Cu")
		(net "GND")
	)
	(segment
		(start 274.458176 -10.989818)
		(end 275.500084 -10.989818)
		(width 0.508)
		(layer "In5.Cu")
		(net "GND")
	)
	(segment
		(start 56.89981 -59.680094)
		(end 56.89981 -60.620402)
		(width 0.508)
		(layer "In5.Cu")
		(net "GND")
	)
	(segment
		(start 55.959502 -59.680094)
		(end 56.89981 -59.680094)
		(width 0.508)
		(layer "In5.Cu")
		(net "GND")
	)
	(segment
		(start 66.069972 -187.809886)
		(end 67.20078 -187.809886)
		(width 0.508)
		(layer "In5.Cu")
		(net "GND")
	)
	(segment
		(start 56.89981 -65.239646)
		(end 56.89981 -66.179954)
		(width 0.508)
		(layer "In5.Cu")
		(net "GND")
	)
	(segment
		(start 63.529972 -187.809886)
		(end 64.66078 -187.809886)
		(width 0.508)
		(layer "In5.Cu")
		(net "GND")
	)
	(segment
		(start 68.609972 -185.269886)
		(end 69.74078 -185.269886)
		(width 0.508)
		(layer "In5.Cu")
		(net "GND")
	)
	(segment
		(start 55.959502 -66.179954)
		(end 56.89981 -66.179954)
		(width 0.508)
		(layer "In5.Cu")
		(net "GND")
	)
	(segment
		(start 53.369972 -187.809886)
		(end 54.50078 -187.809886)
		(width 0.508)
		(layer "In5.Cu")
		(net "GND")
	)
	(segment
		(start 60.989972 -187.809886)
		(end 62.12078 -187.809886)
		(width 0.508)
		(layer "In5.Cu")
		(net "GND")
	)
	(segment
		(start 68.609972 -187.809886)
		(end 69.74078 -187.809886)
		(width 0.508)
		(layer "In5.Cu")
		(net "GND")
	)
	(segment
		(start 3.07848 -100.7999)
		(end 4.895088 -100.7999)
		(width 0.508)
		(layer "In5.Cu")
		(net "GND")
	)
	(segment
		(start 39.099998 -66.179954)
		(end 39.099998 -67.120262)
		(width 0.508)
		(layer "In5.Cu")
		(net "GND")
	)
	(segment
		(start 55.909972 -186.679078)
		(end 55.909972 -187.809886)
		(width 0.508)
		(layer "In5.Cu")
		(net "GND")
	)
	(segment
		(start 66.069972 -184.139078)
		(end 66.069972 -185.269886)
		(width 0.508)
		(layer "In5.Cu")
		(net "GND")
	)
	(segment
		(start 66.069972 -185.269886)
		(end 66.069972 -186.400694)
		(width 0.508)
		(layer "In5.Cu")
		(net "GND")
	)
	(segment
		(start 58.449972 -186.679078)
		(end 58.449972 -187.809886)
		(width 0.508)
		(layer "In5.Cu")
		(net "GND")
	)
	(segment
		(start 56.89981 -62.680088)
		(end 56.89981 -63.620396)
		(width 0.508)
		(layer "In5.Cu")
		(net "GND")
	)
	(segment
		(start 68.609972 -187.809886)
		(end 68.609972 -188.940694)
		(width 0.508)
		(layer "In5.Cu")
		(net "GND")
	)
	(segment
		(start 275.500084 -10.989818)
		(end 275.500084 -12.031726)
		(width 0.508)
		(layer "In5.Cu")
		(net "GND")
	)
	(segment
		(start 53.369972 -186.679078)
		(end 53.369972 -187.809886)
		(width 0.508)
		(layer "In5.Cu")
		(net "GND")
	)
	(segment
		(start 64.939164 -187.809886)
		(end 66.069972 -187.809886)
		(width 0.508)
		(layer "In5.Cu")
		(net "GND")
	)
	(segment
		(start 50.829972 -187.809886)
		(end 51.96078 -187.809886)
		(width 0.508)
		(layer "In5.Cu")
		(net "GND")
	)
	(segment
		(start 23.288244 -85.79993)
		(end 25.104852 -85.79993)
		(width 0.508)
		(layer "In5.Cu")
		(net "GND")
	)
	(segment
		(start 68.609972 -186.679078)
		(end 68.609972 -187.809886)
		(width 0.508)
		(layer "In5.Cu")
		(net "GND")
	)
	(segment
		(start 48.289972 -186.679078)
		(end 48.289972 -187.809886)
		(width 0.508)
		(layer "In5.Cu")
		(net "GND")
	)
	(segment
		(start 39.099998 -59.739784)
		(end 39.099998 -60.680092)
		(width 0.508)
		(layer "In5.Cu")
		(net "GND")
	)
	(segment
		(start 353.734878 -15.249906)
		(end 353.734878 -16.317214)
		(width 0.508)
		(layer "In5.Cu")
		(net "GND")
	)
	(segment
		(start 4.895088 -100.7999)
		(end 6.711696 -100.7999)
		(width 0.508)
		(layer "In5.Cu")
		(net "GND")
	)
	(segment
		(start 39.099998 -65.239646)
		(end 39.099998 -66.179954)
		(width 0.508)
		(layer "In5.Cu")
		(net "GND")
	)
	(segment
		(start 275.500084 -9.94791)
		(end 275.500084 -10.989818)
		(width 0.508)
		(layer "In5.Cu")
		(net "GND")
	)
	(segment
		(start 64.939164 -185.269886)
		(end 66.069972 -185.269886)
		(width 0.508)
		(layer "In5.Cu")
		(net "GND")
	)
	(segment
		(start 67.479164 -187.809886)
		(end 68.609972 -187.809886)
		(width 0.508)
		(layer "In5.Cu")
		(net "GND")
	)
	(segment
		(start 58.449972 -187.809886)
		(end 58.449972 -188.940694)
		(width 0.508)
		(layer "In5.Cu")
		(net "GND")
	)
	(segment
		(start 148.67001 -9.863328)
		(end 148.67001 -11.210036)
		(width 0.508)
		(layer "In5.Cu")
		(net "GND")
	)
	(segment
		(start 166.249858 -11.210036)
		(end 167.596566 -11.210036)
		(width 0.508)
		(layer "In5.Cu")
		(net "GND")
	)
	(segment
		(start 39.099998 -60.680092)
		(end 39.099998 -61.6204)
		(width 0.508)
		(layer "In5.Cu")
		(net "GND")
	)
	(segment
		(start 57.319164 -187.809886)
		(end 58.449972 -187.809886)
		(width 0.508)
		(layer "In5.Cu")
		(net "GND")
	)
	(segment
		(start 4.895088 -98.983292)
		(end 4.895088 -100.7999)
		(width 0.508)
		(layer "In5.Cu")
		(net "GND")
	)
	(segment
		(start 38.15969 -60.680092)
		(end 39.099998 -60.680092)
		(width 0.508)
		(layer "In5.Cu")
		(net "GND")
	)
	(segment
		(start 25.104852 -83.983322)
		(end 25.104852 -85.79993)
		(width 0.508)
		(layer "In5.Cu")
		(net "GND")
	)
	(segment
		(start 39.099998 -66.179954)
		(end 40.040306 -66.179954)
		(width 0.508)
		(layer "In5.Cu")
		(net "GND")
	)
	(segment
		(start 56.89981 -66.179954)
		(end 56.89981 -67.120262)
		(width 0.508)
		(layer "In5.Cu")
		(net "GND")
	)
	(segment
		(start 148.67001 -11.210036)
		(end 150.016718 -11.210036)
		(width 0.508)
		(layer "In5.Cu")
		(net "GND")
	)
	(segment
		(start 4.895088 -83.983322)
		(end 4.895088 -85.79993)
		(width 0.508)
		(layer "In5.Cu")
		(net "GND")
	)
	(segment
		(start 63.529972 -186.679078)
		(end 63.529972 -187.809886)
		(width 0.508)
		(layer "In5.Cu")
		(net "GND")
	)
	(segment
		(start 48.289972 -187.809886)
		(end 49.42078 -187.809886)
		(width 0.508)
		(layer "In5.Cu")
		(net "GND")
	)
	(segment
		(start 23.288244 -100.7999)
		(end 25.104852 -100.7999)
		(width 0.508)
		(layer "In5.Cu")
		(net "GND")
	)
	(segment
		(start 66.069972 -186.679078)
		(end 66.069972 -187.809886)
		(width 0.508)
		(layer "In5.Cu")
		(net "GND")
	)
	(segment
		(start 25.104852 -100.7999)
		(end 26.92146 -100.7999)
		(width 0.508)
		(layer "In5.Cu")
		(net "GND")
	)
	(segment
		(start 52.239164 -187.809886)
		(end 53.369972 -187.809886)
		(width 0.508)
		(layer "In5.Cu")
		(net "GND")
	)
	(segment
		(start 58.449972 -187.809886)
		(end 59.58078 -187.809886)
		(width 0.508)
		(layer "In5.Cu")
		(net "GND")
	)
	(segment
		(start 25.104852 -100.7999)
		(end 25.104852 -102.616508)
		(width 0.508)
		(layer "In5.Cu")
		(net "GND")
	)
	(segment
		(start 50.829972 -187.809886)
		(end 50.829972 -188.940694)
		(width 0.508)
		(layer "In5.Cu")
		(net "GND")
	)
	(segment
		(start 25.104852 -85.79993)
		(end 26.92146 -85.79993)
		(width 0.508)
		(layer "In5.Cu")
		(net "GND")
	)
	(segment
		(start 39.099998 -60.680092)
		(end 40.040306 -60.680092)
		(width 0.508)
		(layer "In5.Cu")
		(net "GND")
	)
	(segment
		(start 147.323302 -11.210036)
		(end 148.67001 -11.210036)
		(width 0.508)
		(layer "In5.Cu")
		(net "GND")
	)
	(segment
		(start 59.859164 -187.809886)
		(end 60.989972 -187.809886)
		(width 0.508)
		(layer "In5.Cu")
		(net "GND")
	)
	(segment
		(start 56.89981 -66.179954)
		(end 57.840118 -66.179954)
		(width 0.508)
		(layer "In5.Cu")
		(net "GND")
	)
	(segment
		(start 38.15969 -62.680088)
		(end 39.099998 -62.680088)
		(width 0.508)
		(layer "In5.Cu")
		(net "GND")
	)
	(segment
		(start 66.069972 -185.269886)
		(end 67.20078 -185.269886)
		(width 0.508)
		(layer "In5.Cu")
		(net "GND")
	)
	(segment
		(start 66.069972 -187.809886)
		(end 66.069972 -188.940694)
		(width 0.508)
		(layer "In5.Cu")
		(net "GND")
	)
	(segment
		(start 63.529972 -187.809886)
		(end 63.529972 -188.940694)
		(width 0.508)
		(layer "In5.Cu")
		(net "GND")
	)
	(segment
		(start 353.734878 -24.45004)
		(end 353.734878 -25.517348)
		(width 0.508)
		(layer "In5.Cu")
		(net "GND")
	)
	(segment
		(start 57.319164 -185.269886)
		(end 58.449972 -185.269886)
		(width 0.508)
		(layer "In5.Cu")
		(net "GND")
	)
	(segment
		(start 164.90315 -11.210036)
		(end 166.249858 -11.210036)
		(width 0.508)
		(layer "In5.Cu")
		(net "GND")
	)
	(segment
		(start 53.369972 -187.809886)
		(end 53.369972 -188.940694)
		(width 0.508)
		(layer "In5.Cu")
		(net "GND")
	)
	(segment
		(start 48.289972 -187.809886)
		(end 48.289972 -188.940694)
		(width 0.508)
		(layer "In5.Cu")
		(net "GND")
	)
	(segment
		(start 38.15969 -66.179954)
		(end 39.099998 -66.179954)
		(width 0.508)
		(layer "In5.Cu")
		(net "GND")
	)
	(segment
		(start 39.099998 -61.73978)
		(end 39.099998 -62.680088)
		(width 0.508)
		(layer "In5.Cu")
		(net "GND")
	)
	(segment
		(start 353.734878 -23.382732)
		(end 353.734878 -24.45004)
		(width 0.508)
		(layer "In5.Cu")
		(net "GND")
	)
	(segment
		(start 68.609972 -184.139078)
		(end 68.609972 -185.269886)
		(width 0.508)
		(layer "In5.Cu")
		(net "GND")
	)
	(segment
		(start 50.829972 -186.679078)
		(end 50.829972 -187.809886)
		(width 0.508)
		(layer "In5.Cu")
		(net "GND")
	)
	(segment
		(start 4.895088 -100.7999)
		(end 4.895088 -102.616508)
		(width 0.508)
		(layer "In5.Cu")
		(net "GND")
	)
	(segment
		(start 352.66757 -24.45004)
		(end 353.734878 -24.45004)
		(width 0.508)
		(layer "In5.Cu")
		(net "GND")
	)
	(segment
		(start 39.099998 -62.680088)
		(end 40.040306 -62.680088)
		(width 0.508)
		(layer "In5.Cu")
		(net "GND")
	)
	(segment
		(start 166.249858 -11.210036)
		(end 166.249858 -12.556744)
		(width 0.508)
		(layer "In5.Cu")
		(net "GND")
	)
	(segment
		(start 62.399164 -187.809886)
		(end 63.529972 -187.809886)
		(width 0.508)
		(layer "In5.Cu")
		(net "GND")
	)
	(segment
		(start 4.895088 -85.79993)
		(end 4.895088 -87.616538)
		(width 0.508)
		(layer "In5.Cu")
		(net "GND")
	)
	(segment
		(start 148.67001 -11.210036)
		(end 148.67001 -12.556744)
		(width 0.508)
		(layer "In5.Cu")
		(net "GND")
	)
	(segment
		(start 60.989972 -186.679078)
		(end 60.989972 -187.809886)
		(width 0.508)
		(layer "In5.Cu")
		(net "GND")
	)
	(segment
		(start 275.500084 -10.989818)
		(end 276.541992 -10.989818)
		(width 0.508)
		(layer "In5.Cu")
		(net "GND")
	)
	(segment
		(start 353.734878 -14.182598)
		(end 353.734878 -15.249906)
		(width 0.508)
		(layer "In5.Cu")
		(net "GND")
	)
	(segment
		(start 39.099998 -62.680088)
		(end 39.099998 -63.620396)
		(width 0.508)
		(layer "In5.Cu")
		(net "GND")
	)
	(segment
		(start 58.449972 -185.269886)
		(end 58.449972 -186.400694)
		(width 0.508)
		(layer "In5.Cu")
		(net "GND")
	)
	(segment
		(start 55.909972 -187.809886)
		(end 55.909972 -188.940694)
		(width 0.508)
		(layer "In5.Cu")
		(net "GND")
	)
	(segment
		(start 49.699164 -187.809886)
		(end 50.829972 -187.809886)
		(width 0.508)
		(layer "In5.Cu")
		(net "GND")
	)
	(segment
		(start 68.609972 -185.269886)
		(end 68.609972 -186.400694)
		(width 0.508)
		(layer "In5.Cu")
		(net "GND")
	)
	(segment
		(start 300.834806 -169.040048)
		(end 300.986952 -169.040048)
		(width 0.1143)
		(layer "F.Cu")
		(net "BMC0_SMB3_DAT")
	)
	(segment
		(start 301.371 -168.656)
		(end 302.26 -168.656)
		(width 0.1143)
		(layer "F.Cu")
		(net "BMC0_SMB3_DAT")
	)
	(segment
		(start 300.986952 -169.040048)
		(end 301.371 -168.656)
		(width 0.1143)
		(layer "F.Cu")
		(net "BMC0_SMB3_DAT")
	)
	(segment
		(start 302.26 -168.656)
		(end 302.514 -168.402)
		(width 0.1143)
		(layer "F.Cu")
		(net "BMC0_SMB3_DAT")
	)
	(via
		(at 302.514 -168.402)
		(size 0.5588)
		(drill 0.3048)
		(layers "F.Cu" "B.Cu")
		(net "BMC0_SMB3_DAT")
	)
	(via
		(at 313.944 -167.767)
		(size 0.7112)
		(drill 0.3556)
		(layers "F.Cu" "B.Cu")
		(net "BMC0_SMB3_DAT")
	)
	(segment
		(start 308.350412 -168.49725)
		(end 308.756812 -168.09085)
		(width 0.1143)
		(layer "B.Cu")
		(net "BMC0_SMB3_DAT")
	)
	(segment
		(start 302.514 -168.402)
		(end 303.188624 -168.402)
		(width 0.1143)
		(layer "B.Cu")
		(net "BMC0_SMB3_DAT")
	)
	(segment
		(start 313.62015 -168.09085)
		(end 313.944 -167.767)
		(width 0.1143)
		(layer "B.Cu")
		(net "BMC0_SMB3_DAT")
	)
	(segment
		(start 308.756812 -168.09085)
		(end 313.62015 -168.09085)
		(width 0.1143)
		(layer "B.Cu")
		(net "BMC0_SMB3_DAT")
	)
	(segment
		(start 305.017424 -168.49725)
		(end 308.350412 -168.49725)
		(width 0.1143)
		(layer "B.Cu")
		(net "BMC0_SMB3_DAT")
	)
	(segment
		(start 313.944 -167.767)
		(end 314.54725 -167.16375)
		(width 0.1143)
		(layer "B.Cu")
		(net "BMC0_SMB3_DAT")
	)
	(segment
		(start 303.188624 -168.402)
		(end 303.537874 -168.05275)
		(width 0.1143)
		(layer "B.Cu")
		(net "BMC0_SMB3_DAT")
	)
	(segment
		(start 304.572924 -168.05275)
		(end 305.017424 -168.49725)
		(width 0.1143)
		(layer "B.Cu")
		(net "BMC0_SMB3_DAT")
	)
	(segment
		(start 315.75375 -167.16375)
		(end 317.5635 -165.354)
		(width 0.1143)
		(layer "B.Cu")
		(net "BMC0_SMB3_DAT")
	)
	(segment
		(start 303.537874 -168.05275)
		(end 304.572924 -168.05275)
		(width 0.1143)
		(layer "B.Cu")
		(net "BMC0_SMB3_DAT")
	)
	(segment
		(start 314.54725 -167.16375)
		(end 315.75375 -167.16375)
		(width 0.1143)
		(layer "B.Cu")
		(net "BMC0_SMB3_DAT")
	)
	(segment
		(start 313.125104 -82.00009)
		(end 314.251848 -82.00009)
		(width 0.1397)
		(layer "F.Cu")
		(net "PCIE_10G_CPU_RX3_N")
	)
	(segment
		(start 316.028578 -82.042)
		(end 317.754 -82.042)
		(width 0.1397)
		(layer "F.Cu")
		(net "PCIE_10G_CPU_RX3_N")
	)
	(segment
		(start 318.04737 -82.163666)
		(end 318.306958 -82.423)
		(width 0.1397)
		(layer "F.Cu")
		(net "PCIE_10G_CPU_RX3_N")
	)
	(segment
		(start 314.596272 -81.77149)
		(end 315.375544 -81.77149)
		(width 0.1397)
		(layer "F.Cu")
		(net "PCIE_10G_CPU_RX3_N")
	)
	(segment
		(start 314.350654 -81.959196)
		(end 314.497466 -81.812384)
		(width 0.1397)
		(layer "F.Cu")
		(net "PCIE_10G_CPU_RX3_N")
	)
	(via
		(at 318.306958 -82.423)
		(size 0.5588)
		(drill 0.3048)
		(layers "F.Cu" "B.Cu")
		(net "PCIE_10G_CPU_RX3_N")
	)
	(arc
		(start 314.497466 -81.812384)
		(mid 314.542799 -81.782094)
		(end 314.596272 -81.77149)
		(width 0.1397)
		(layer "F.Cu")
		(net "PCIE_10G_CPU_RX3_N")
	)
	(arc
		(start 315.375544 -81.77149)
		(mid 315.563046 -81.808786)
		(end 315.722 -81.915)
		(width 0.1397)
		(layer "F.Cu")
		(net "PCIE_10G_CPU_RX3_N")
	)
	(arc
		(start 317.754 -82.042)
		(mid 317.912774 -82.073676)
		(end 318.04737 -82.163666)
		(width 0.1397)
		(layer "F.Cu")
		(net "PCIE_10G_CPU_RX3_N")
	)
	(arc
		(start 314.251848 -82.00009)
		(mid 314.305309 -81.989456)
		(end 314.350654 -81.959196)
		(width 0.1397)
		(layer "F.Cu")
		(net "PCIE_10G_CPU_RX3_N")
	)
	(arc
		(start 315.722 -81.915)
		(mid 315.862659 -82.008985)
		(end 316.028578 -82.042)
		(width 0.1397)
		(layer "F.Cu")
		(net "PCIE_10G_CPU_RX3_N")
	)
	(segment
		(start 145.318988 -82.199734)
		(end 145.892266 -82.773266)
		(width 0.127)
		(layer "In5.Cu")
		(net "PCIE_10G_CPU_RX3_N")
	)
	(segment
		(start 151.765 -85.979254)
		(end 151.765254 -85.979)
		(width 0.127)
		(layer "In5.Cu")
		(net "PCIE_10G_CPU_RX3_N")
	)
	(segment
		(start 151.765254 -85.979)
		(end 177.865278 -85.979)
		(width 0.127)
		(layer "In5.Cu")
		(net "PCIE_10G_CPU_RX3_N")
	)
	(segment
		(start 178.537616 -85.700616)
		(end 178.809396 -85.428836)
		(width 0.127)
		(layer "In5.Cu")
		(net "PCIE_10G_CPU_RX3_N")
	)
	(segment
		(start 314.354464 -84.357718)
		(end 316.42177 -82.290412)
		(width 0.127)
		(layer "In5.Cu")
		(net "PCIE_10G_CPU_RX3_N")
	)
	(segment
		(start 148.590254 -83.565746)
		(end 150.368 -85.343492)
		(width 0.127)
		(layer "In5.Cu")
		(net "PCIE_10G_CPU_RX3_N")
	)
	(segment
		(start 150.368 -85.343492)
		(end 150.464774 -85.440774)
		(width 0.127)
		(layer "In5.Cu")
		(net "PCIE_10G_CPU_RX3_N")
	)
	(segment
		(start 317.082932 -82.0166)
		(end 317.996062 -82.0166)
		(width 0.127)
		(layer "In5.Cu")
		(net "PCIE_10G_CPU_RX3_N")
	)
	(segment
		(start 178.952906 -85.3694)
		(end 299.971968 -85.3694)
		(width 0.127)
		(layer "In5.Cu")
		(net "PCIE_10G_CPU_RX3_N")
	)
	(segment
		(start 147.193 -83.312)
		(end 147.977606 -83.312)
		(width 0.127)
		(layer "In5.Cu")
		(net "PCIE_10G_CPU_RX3_N")
	)
	(segment
		(start 318.306958 -82.399378)
		(end 318.306958 -82.423)
		(width 0.127)
		(layer "In5.Cu")
		(net "PCIE_10G_CPU_RX3_N")
	)
	(segment
		(start 141.23797 -80.085946)
		(end 141.23797 -80.264)
		(width 0.127)
		(layer "In5.Cu")
		(net "PCIE_10G_CPU_RX3_N")
	)
	(segment
		(start 300.99 -84.92744)
		(end 312.9788 -84.92744)
		(width 0.127)
		(layer "In5.Cu")
		(net "PCIE_10G_CPU_RX3_N")
	)
	(segment
		(start 142.27937 -74.163428)
		(end 142.27937 -78.5114)
		(width 0.127)
		(layer "In5.Cu")
		(net "PCIE_10G_CPU_RX3_N")
	)
	(segment
		(start 142.63497 -81.661)
		(end 144.018 -81.661)
		(width 0.127)
		(layer "In5.Cu")
		(net "PCIE_10G_CPU_RX3_N")
	)
	(segment
		(start 142.127732 -78.877414)
		(end 141.463014 -79.542132)
		(width 0.127)
		(layer "In5.Cu")
		(net "PCIE_10G_CPU_RX3_N")
	)
	(segment
		(start 300.53026 -85.13826)
		(end 300.565058 -85.103462)
		(width 0.127)
		(layer "In5.Cu")
		(net "PCIE_10G_CPU_RX3_N")
	)
	(arc
		(start 144.018 -81.661)
		(mid 144.722085 -81.800958)
		(end 145.318988 -82.199734)
		(width 0.127)
		(layer "In5.Cu")
		(net "PCIE_10G_CPU_RX3_N")
	)
	(arc
		(start 145.892266 -82.773266)
		(mid 146.489062 -83.171969)
		(end 147.193 -83.312)
		(width 0.127)
		(layer "In5.Cu")
		(net "PCIE_10G_CPU_RX3_N")
	)
	(arc
		(start 312.9788 -84.92744)
		(mid 313.723267 -84.779356)
		(end 314.354464 -84.357718)
		(width 0.127)
		(layer "In5.Cu")
		(net "PCIE_10G_CPU_RX3_N")
	)
	(arc
		(start 177.865278 -85.979)
		(mid 178.229157 -85.906714)
		(end 178.537616 -85.700616)
		(width 0.127)
		(layer "In5.Cu")
		(net "PCIE_10G_CPU_RX3_N")
	)
	(arc
		(start 299.971968 -85.3694)
		(mid 300.274124 -85.309391)
		(end 300.53026 -85.13826)
		(width 0.127)
		(layer "In5.Cu")
		(net "PCIE_10G_CPU_RX3_N")
	)
	(arc
		(start 141.463014 -79.542132)
		(mid 141.296515 -79.791693)
		(end 141.23797 -80.085946)
		(width 0.127)
		(layer "In5.Cu")
		(net "PCIE_10G_CPU_RX3_N")
	)
	(arc
		(start 142.450566 -73.75017)
		(mid 142.323876 -73.939774)
		(end 142.27937 -74.163428)
		(width 0.127)
		(layer "In5.Cu")
		(net "PCIE_10G_CPU_RX3_N")
	)
	(arc
		(start 147.977606 -83.312)
		(mid 148.309161 -83.37795)
		(end 148.590254 -83.565746)
		(width 0.127)
		(layer "In5.Cu")
		(net "PCIE_10G_CPU_RX3_N")
	)
	(arc
		(start 317.996062 -82.0166)
		(mid 318.095596 -82.036399)
		(end 318.179958 -82.0928)
		(width 0.127)
		(layer "In5.Cu")
		(net "PCIE_10G_CPU_RX3_N")
	)
	(arc
		(start 300.565058 -85.103462)
		(mid 300.760023 -84.973191)
		(end 300.99 -84.92744)
		(width 0.127)
		(layer "In5.Cu")
		(net "PCIE_10G_CPU_RX3_N")
	)
	(arc
		(start 141.23797 -80.264)
		(mid 141.647142 -81.251828)
		(end 142.63497 -81.661)
		(width 0.127)
		(layer "In5.Cu")
		(net "PCIE_10G_CPU_RX3_N")
	)
	(arc
		(start 318.179958 -82.0928)
		(mid 318.273943 -82.233459)
		(end 318.306958 -82.399378)
		(width 0.127)
		(layer "In5.Cu")
		(net "PCIE_10G_CPU_RX3_N")
	)
	(arc
		(start 150.464774 -85.440774)
		(mid 151.061324 -85.839346)
		(end 151.765 -85.979254)
		(width 0.127)
		(layer "In5.Cu")
		(net "PCIE_10G_CPU_RX3_N")
	)
	(arc
		(start 142.27937 -78.5114)
		(mid 142.239966 -78.709497)
		(end 142.127732 -78.877414)
		(width 0.127)
		(layer "In5.Cu")
		(net "PCIE_10G_CPU_RX3_N")
	)
	(arc
		(start 178.809396 -85.428836)
		(mid 178.875239 -85.384841)
		(end 178.952906 -85.3694)
		(width 0.127)
		(layer "In5.Cu")
		(net "PCIE_10G_CPU_RX3_N")
	)
	(arc
		(start 316.42177 -82.290412)
		(mid 316.725114 -82.087724)
		(end 317.082932 -82.0166)
		(width 0.127)
		(layer "In5.Cu")
		(net "PCIE_10G_CPU_RX3_N")
	)
	(segment
		(start 76.748386 -107.868212)
		(end 75.493626 -107.868212)
		(width 0.254)
		(layer "F.Cu")
		(net "P1V8_EN_LV")
	)
	(segment
		(start 75.493626 -107.868212)
		(end 74.919586 -108.442252)
		(width 0.254)
		(layer "F.Cu")
		(net "P1V8_EN_LV")
	)
	(segment
		(start 74.906886 -106.598212)
		(end 74.952098 -106.553)
		(width 0.254)
		(layer "F.Cu")
		(net "P1V8_EN_LV")
	)
	(segment
		(start 74.467974 -107.99064)
		(end 74.919586 -108.442252)
		(width 0.254)
		(layer "F.Cu")
		(net "P1V8_EN_LV")
	)
	(segment
		(start 70.715886 -108.937044)
		(end 71.66229 -107.99064)
		(width 0.254)
		(layer "F.Cu")
		(net "P1V8_EN_LV")
	)
	(segment
		(start 70.715886 -109.392212)
		(end 70.715886 -108.937044)
		(width 0.254)
		(layer "F.Cu")
		(net "P1V8_EN_LV")
	)
	(segment
		(start 71.66229 -107.99064)
		(end 74.467974 -107.99064)
		(width 0.254)
		(layer "F.Cu")
		(net "P1V8_EN_LV")
	)
	(segment
		(start 74.952098 -106.553)
		(end 75.95997 -106.553)
		(width 0.254)
		(layer "F.Cu")
		(net "P1V8_EN_LV")
	)
	(segment
		(start 74.919586 -106.610912)
		(end 74.906886 -106.598212)
		(width 0.254)
		(layer "F.Cu")
		(net "P1V8_EN_LV")
	)
	(segment
		(start 74.919586 -108.442252)
		(end 74.919586 -106.610912)
		(width 0.254)
		(layer "F.Cu")
		(net "P1V8_EN_LV")
	)
	(via
		(at 75.95997 -106.553)
		(size 0.7112)
		(drill 0.3556)
		(layers "F.Cu" "B.Cu")
		(net "P1V8_EN_LV")
	)
	(segment
		(start 318.387476 -78.456028)
		(end 318.408558 -78.4352)
		(width 0.1397)
		(layer "F.Cu")
		(net "PCIE_10G_CPU_RX2_P")
	)
	(segment
		(start 316.834266 -78.6765)
		(end 317.8556 -78.6765)
		(width 0.1397)
		(layer "F.Cu")
		(net "PCIE_10G_CPU_RX2_P")
	)
	(segment
		(start 314.350654 -78.040992)
		(end 314.497466 -78.187804)
		(width 0.1397)
		(layer "F.Cu")
		(net "PCIE_10G_CPU_RX2_P")
	)
	(segment
		(start 314.596272 -78.228698)
		(end 315.75375 -78.228698)
		(width 0.1397)
		(layer "F.Cu")
		(net "PCIE_10G_CPU_RX2_P")
	)
	(segment
		(start 313.125104 -78.000098)
		(end 314.251848 -78.000098)
		(width 0.1397)
		(layer "F.Cu")
		(net "PCIE_10G_CPU_RX2_P")
	)
	(via
		(at 318.408558 -78.4352)
		(size 0.5588)
		(drill 0.3048)
		(layers "F.Cu" "B.Cu")
		(net "PCIE_10G_CPU_RX2_P")
	)
	(arc
		(start 314.251848 -78.000098)
		(mid 314.305309 -78.010732)
		(end 314.350654 -78.040992)
		(width 0.1397)
		(layer "F.Cu")
		(net "PCIE_10G_CPU_RX2_P")
	)
	(arc
		(start 317.8556 -78.6765)
		(mid 318.143457 -78.619148)
		(end 318.387476 -78.456028)
		(width 0.1397)
		(layer "F.Cu")
		(net "PCIE_10G_CPU_RX2_P")
	)
	(arc
		(start 314.497466 -78.187804)
		(mid 314.542799 -78.218094)
		(end 314.596272 -78.228698)
		(width 0.1397)
		(layer "F.Cu")
		(net "PCIE_10G_CPU_RX2_P")
	)
	(arc
		(start 316.21857 -78.42123)
		(mid 316.501038 -78.610092)
		(end 316.834266 -78.6765)
		(width 0.1397)
		(layer "F.Cu")
		(net "PCIE_10G_CPU_RX2_P")
	)
	(arc
		(start 315.75375 -78.228698)
		(mid 316.005322 -78.278721)
		(end 316.21857 -78.42123)
		(width 0.1397)
		(layer "F.Cu")
		(net "PCIE_10G_CPU_RX2_P")
	)
	(segment
		(start 318.051942 -78.766416)
		(end 318.383158 -78.4352)
		(width 0.127)
		(layer "In5.Cu")
		(net "PCIE_10G_CPU_RX2_P")
	)
	(segment
		(start 147.709382 -80.650588)
		(end 148.014182 -80.955388)
		(width 0.127)
		(layer "In5.Cu")
		(net "PCIE_10G_CPU_RX2_P")
	)
	(segment
		(start 146.49577 -75.27036)
		(end 146.49577 -78.290928)
		(width 0.127)
		(layer "In5.Cu")
		(net "PCIE_10G_CPU_RX2_P")
	)
	(segment
		(start 301.743618 -80.13954)
		(end 302.124618 -80.13954)
		(width 0.127)
		(layer "In5.Cu")
		(net "PCIE_10G_CPU_RX2_P")
	)
	(segment
		(start 312.268108 -79.51089)
		(end 313.39663 -79.51089)
		(width 0.127)
		(layer "In5.Cu")
		(net "PCIE_10G_CPU_RX2_P")
	)
	(segment
		(start 153.144474 -81.7372)
		(end 220.565726 -81.7372)
		(width 0.127)
		(layer "In5.Cu")
		(net "PCIE_10G_CPU_RX2_P")
	)
	(segment
		(start 231.422448 -81.294224)
		(end 231.655112 -81.526888)
		(width 0.127)
		(layer "In5.Cu")
		(net "PCIE_10G_CPU_RX2_P")
	)
	(segment
		(start 302.424338 -80.2894)
		(end 302.805338 -80.2894)
		(width 0.127)
		(layer "In5.Cu")
		(net "PCIE_10G_CPU_RX2_P")
	)
	(segment
		(start 146.983196 -75.036172)
		(end 146.72437 -75.036172)
		(width 0.127)
		(layer "In5.Cu")
		(net "PCIE_10G_CPU_RX2_P")
	)
	(segment
		(start 146.534886 -75.114658)
		(end 146.534632 -75.114912)
		(width 0.127)
		(layer "In5.Cu")
		(net "PCIE_10G_CPU_RX2_P")
	)
	(segment
		(start 308.278276 -80.2894)
		(end 310.56834 -80.2894)
		(width 0.127)
		(layer "In5.Cu")
		(net "PCIE_10G_CPU_RX2_P")
	)
	(segment
		(start 303.105058 -80.13954)
		(end 303.486058 -80.13954)
		(width 0.127)
		(layer "In5.Cu")
		(net "PCIE_10G_CPU_RX2_P")
	)
	(segment
		(start 314.850272 -78.8035)
		(end 317.96228 -78.8035)
		(width 0.127)
		(layer "In5.Cu")
		(net "PCIE_10G_CPU_RX2_P")
	)
	(segment
		(start 147.58797 -80.047846)
		(end 147.58797 -80.357472)
		(width 0.127)
		(layer "In5.Cu")
		(net "PCIE_10G_CPU_RX2_P")
	)
	(segment
		(start 297.18 -80.2894)
		(end 298.721018 -80.2894)
		(width 0.127)
		(layer "In5.Cu")
		(net "PCIE_10G_CPU_RX2_P")
	)
	(segment
		(start 152.4635 -81.3435)
		(end 152.654 -81.534)
		(width 0.127)
		(layer "In5.Cu")
		(net "PCIE_10G_CPU_RX2_P")
	)
	(segment
		(start 310.9976 -80.1116)
		(end 311.1246 -79.9846)
		(width 0.127)
		(layer "In5.Cu")
		(net "PCIE_10G_CPU_RX2_P")
	)
	(segment
		(start 299.701458 -80.2894)
		(end 300.082458 -80.2894)
		(width 0.127)
		(layer "In5.Cu")
		(net "PCIE_10G_CPU_RX2_P")
	)
	(segment
		(start 299.020738 -80.13954)
		(end 299.401738 -80.13954)
		(width 0.127)
		(layer "In5.Cu")
		(net "PCIE_10G_CPU_RX2_P")
	)
	(segment
		(start 147.20443 -75.155806)
		(end 147.15617 -75.1078)
		(width 0.127)
		(layer "In5.Cu")
		(net "PCIE_10G_CPU_RX2_P")
	)
	(segment
		(start 307.597556 -80.13954)
		(end 307.978556 -80.13954)
		(width 0.127)
		(layer "In5.Cu")
		(net "PCIE_10G_CPU_RX2_P")
	)
	(segment
		(start 303.785778 -80.2894)
		(end 305.936396 -80.2894)
		(width 0.127)
		(layer "In5.Cu")
		(net "PCIE_10G_CPU_RX2_P")
	)
	(segment
		(start 306.236116 -80.13954)
		(end 306.617116 -80.13954)
		(width 0.127)
		(layer "In5.Cu")
		(net "PCIE_10G_CPU_RX2_P")
	)
	(segment
		(start 146.731482 -78.859888)
		(end 147.353782 -79.482188)
		(width 0.127)
		(layer "In5.Cu")
		(net "PCIE_10G_CPU_RX2_P")
	)
	(segment
		(start 314.07481 -79.229966)
		(end 314.254388 -79.050388)
		(width 0.127)
		(layer "In5.Cu")
		(net "PCIE_10G_CPU_RX2_P")
	)
	(segment
		(start 295.31056 -81.473802)
		(end 295.389808 -81.394808)
		(width 0.127)
		(layer "In5.Cu")
		(net "PCIE_10G_CPU_RX2_P")
	)
	(segment
		(start 148.42998 -81.1276)
		(end 151.942038 -81.1276)
		(width 0.127)
		(layer "In5.Cu")
		(net "PCIE_10G_CPU_RX2_P")
	)
	(segment
		(start 220.709236 -81.677764)
		(end 220.96476 -81.42224)
		(width 0.127)
		(layer "In5.Cu")
		(net "PCIE_10G_CPU_RX2_P")
	)
	(segment
		(start 221.615 -81.153)
		(end 231.081326 -81.153)
		(width 0.127)
		(layer "In5.Cu")
		(net "PCIE_10G_CPU_RX2_P")
	)
	(segment
		(start 232.07091 -81.6991)
		(end 294.767 -81.6991)
		(width 0.127)
		(layer "In5.Cu")
		(net "PCIE_10G_CPU_RX2_P")
	)
	(segment
		(start 295.389808 -81.394808)
		(end 296.011092 -80.773524)
		(width 0.127)
		(layer "In5.Cu")
		(net "PCIE_10G_CPU_RX2_P")
	)
	(segment
		(start 306.916836 -80.2894)
		(end 307.297836 -80.2894)
		(width 0.127)
		(layer "In5.Cu")
		(net "PCIE_10G_CPU_RX2_P")
	)
	(segment
		(start 300.382178 -80.13954)
		(end 300.763178 -80.13954)
		(width 0.127)
		(layer "In5.Cu")
		(net "PCIE_10G_CPU_RX2_P")
	)
	(segment
		(start 318.383158 -78.4352)
		(end 318.408558 -78.4352)
		(width 0.127)
		(layer "In5.Cu")
		(net "PCIE_10G_CPU_RX2_P")
	)
	(segment
		(start 301.062898 -80.2894)
		(end 301.443898 -80.2894)
		(width 0.127)
		(layer "In5.Cu")
		(net "PCIE_10G_CPU_RX2_P")
	)
	(arc
		(start 146.534632 -75.114912)
		(mid 146.505652 -75.19025)
		(end 146.49577 -75.27036)
		(width 0.127)
		(layer "In5.Cu")
		(net "PCIE_10G_CPU_RX2_P")
	)
	(arc
		(start 317.96228 -78.8035)
		(mid 318.010798 -78.793867)
		(end 318.051942 -78.766416)
		(width 0.127)
		(layer "In5.Cu")
		(net "PCIE_10G_CPU_RX2_P")
	)
	(arc
		(start 302.805338 -80.2894)
		(mid 302.888453 -80.268317)
		(end 302.955198 -80.21447)
		(width 0.127)
		(layer "In5.Cu")
		(net "PCIE_10G_CPU_RX2_P")
	)
	(arc
		(start 300.232318 -80.21447)
		(mid 300.299063 -80.160646)
		(end 300.382178 -80.13954)
		(width 0.127)
		(layer "In5.Cu")
		(net "PCIE_10G_CPU_RX2_P")
	)
	(arc
		(start 302.955198 -80.21447)
		(mid 303.021943 -80.160646)
		(end 303.105058 -80.13954)
		(width 0.127)
		(layer "In5.Cu")
		(net "PCIE_10G_CPU_RX2_P")
	)
	(arc
		(start 302.274478 -80.21447)
		(mid 302.341223 -80.268294)
		(end 302.424338 -80.2894)
		(width 0.127)
		(layer "In5.Cu")
		(net "PCIE_10G_CPU_RX2_P")
	)
	(arc
		(start 301.443898 -80.2894)
		(mid 301.527013 -80.268317)
		(end 301.593758 -80.21447)
		(width 0.127)
		(layer "In5.Cu")
		(net "PCIE_10G_CPU_RX2_P")
	)
	(arc
		(start 303.635918 -80.21447)
		(mid 303.702663 -80.268294)
		(end 303.785778 -80.2894)
		(width 0.127)
		(layer "In5.Cu")
		(net "PCIE_10G_CPU_RX2_P")
	)
	(arc
		(start 147.58797 -80.357472)
		(mid 147.619524 -80.516105)
		(end 147.709382 -80.650588)
		(width 0.127)
		(layer "In5.Cu")
		(net "PCIE_10G_CPU_RX2_P")
	)
	(arc
		(start 220.565726 -81.7372)
		(mid 220.64339 -81.721752)
		(end 220.709236 -81.677764)
		(width 0.127)
		(layer "In5.Cu")
		(net "PCIE_10G_CPU_RX2_P")
	)
	(arc
		(start 231.081326 -81.153)
		(mid 231.265926 -81.189701)
		(end 231.422448 -81.294224)
		(width 0.127)
		(layer "In5.Cu")
		(net "PCIE_10G_CPU_RX2_P")
	)
	(arc
		(start 310.56834 -80.2894)
		(mid 310.800652 -80.24319)
		(end 310.9976 -80.1116)
		(width 0.127)
		(layer "In5.Cu")
		(net "PCIE_10G_CPU_RX2_P")
	)
	(arc
		(start 307.297836 -80.2894)
		(mid 307.380972 -80.268336)
		(end 307.447696 -80.21447)
		(width 0.127)
		(layer "In5.Cu")
		(net "PCIE_10G_CPU_RX2_P")
	)
	(arc
		(start 298.721018 -80.2894)
		(mid 298.804154 -80.268336)
		(end 298.870878 -80.21447)
		(width 0.127)
		(layer "In5.Cu")
		(net "PCIE_10G_CPU_RX2_P")
	)
	(arc
		(start 148.014182 -80.955388)
		(mid 148.204952 -81.082856)
		(end 148.42998 -81.1276)
		(width 0.127)
		(layer "In5.Cu")
		(net "PCIE_10G_CPU_RX2_P")
	)
	(arc
		(start 300.913038 -80.21447)
		(mid 300.979783 -80.268294)
		(end 301.062898 -80.2894)
		(width 0.127)
		(layer "In5.Cu")
		(net "PCIE_10G_CPU_RX2_P")
	)
	(arc
		(start 147.15617 -75.1078)
		(mid 147.076809 -75.054773)
		(end 146.983196 -75.036172)
		(width 0.127)
		(layer "In5.Cu")
		(net "PCIE_10G_CPU_RX2_P")
	)
	(arc
		(start 301.593758 -80.21447)
		(mid 301.660503 -80.160646)
		(end 301.743618 -80.13954)
		(width 0.127)
		(layer "In5.Cu")
		(net "PCIE_10G_CPU_RX2_P")
	)
	(arc
		(start 294.767 -81.6991)
		(mid 295.061176 -81.640491)
		(end 295.31056 -81.473802)
		(width 0.127)
		(layer "In5.Cu")
		(net "PCIE_10G_CPU_RX2_P")
	)
	(arc
		(start 307.978556 -80.13954)
		(mid 308.061692 -80.160604)
		(end 308.128416 -80.21447)
		(width 0.127)
		(layer "In5.Cu")
		(net "PCIE_10G_CPU_RX2_P")
	)
	(arc
		(start 306.617116 -80.13954)
		(mid 306.700252 -80.160604)
		(end 306.766976 -80.21447)
		(width 0.127)
		(layer "In5.Cu")
		(net "PCIE_10G_CPU_RX2_P")
	)
	(arc
		(start 302.124618 -80.13954)
		(mid 302.207733 -80.160623)
		(end 302.274478 -80.21447)
		(width 0.127)
		(layer "In5.Cu")
		(net "PCIE_10G_CPU_RX2_P")
	)
	(arc
		(start 300.082458 -80.2894)
		(mid 300.165573 -80.268317)
		(end 300.232318 -80.21447)
		(width 0.127)
		(layer "In5.Cu")
		(net "PCIE_10G_CPU_RX2_P")
	)
	(arc
		(start 147.353782 -79.482188)
		(mid 147.527109 -79.741729)
		(end 147.58797 -80.047846)
		(width 0.127)
		(layer "In5.Cu")
		(net "PCIE_10G_CPU_RX2_P")
	)
	(arc
		(start 147.450556 -75.75042)
		(mid 147.386641 -75.428629)
		(end 147.20443 -75.155806)
		(width 0.127)
		(layer "In5.Cu")
		(net "PCIE_10G_CPU_RX2_P")
	)
	(arc
		(start 146.49577 -78.290928)
		(mid 146.557022 -78.598863)
		(end 146.731482 -78.859888)
		(width 0.127)
		(layer "In5.Cu")
		(net "PCIE_10G_CPU_RX2_P")
	)
	(arc
		(start 306.086256 -80.21447)
		(mid 306.153001 -80.160646)
		(end 306.236116 -80.13954)
		(width 0.127)
		(layer "In5.Cu")
		(net "PCIE_10G_CPU_RX2_P")
	)
	(arc
		(start 314.254388 -79.050388)
		(mid 314.527781 -78.867683)
		(end 314.850272 -78.8035)
		(width 0.127)
		(layer "In5.Cu")
		(net "PCIE_10G_CPU_RX2_P")
	)
	(arc
		(start 300.763178 -80.13954)
		(mid 300.846293 -80.160623)
		(end 300.913038 -80.21447)
		(width 0.127)
		(layer "In5.Cu")
		(net "PCIE_10G_CPU_RX2_P")
	)
	(arc
		(start 299.401738 -80.13954)
		(mid 299.484874 -80.160604)
		(end 299.551598 -80.21447)
		(width 0.127)
		(layer "In5.Cu")
		(net "PCIE_10G_CPU_RX2_P")
	)
	(arc
		(start 311.1246 -79.9846)
		(mid 311.649245 -79.634014)
		(end 312.268108 -79.51089)
		(width 0.127)
		(layer "In5.Cu")
		(net "PCIE_10G_CPU_RX2_P")
	)
	(arc
		(start 307.447696 -80.21447)
		(mid 307.514441 -80.160646)
		(end 307.597556 -80.13954)
		(width 0.127)
		(layer "In5.Cu")
		(net "PCIE_10G_CPU_RX2_P")
	)
	(arc
		(start 151.942038 -81.1276)
		(mid 152.224214 -81.183728)
		(end 152.4635 -81.3435)
		(width 0.127)
		(layer "In5.Cu")
		(net "PCIE_10G_CPU_RX2_P")
	)
	(arc
		(start 296.011092 -80.773524)
		(mid 296.547406 -80.415234)
		(end 297.18 -80.2894)
		(width 0.127)
		(layer "In5.Cu")
		(net "PCIE_10G_CPU_RX2_P")
	)
	(arc
		(start 152.654 -81.534)
		(mid 152.879031 -81.684361)
		(end 153.144474 -81.7372)
		(width 0.127)
		(layer "In5.Cu")
		(net "PCIE_10G_CPU_RX2_P")
	)
	(arc
		(start 313.39663 -79.51089)
		(mid 313.763688 -79.437935)
		(end 314.07481 -79.229966)
		(width 0.127)
		(layer "In5.Cu")
		(net "PCIE_10G_CPU_RX2_P")
	)
	(arc
		(start 306.766976 -80.21447)
		(mid 306.833721 -80.268294)
		(end 306.916836 -80.2894)
		(width 0.127)
		(layer "In5.Cu")
		(net "PCIE_10G_CPU_RX2_P")
	)
	(arc
		(start 146.72437 -75.036172)
		(mid 146.621822 -75.05657)
		(end 146.534886 -75.114658)
		(width 0.127)
		(layer "In5.Cu")
		(net "PCIE_10G_CPU_RX2_P")
	)
	(arc
		(start 305.936396 -80.2894)
		(mid 306.019532 -80.268336)
		(end 306.086256 -80.21447)
		(width 0.127)
		(layer "In5.Cu")
		(net "PCIE_10G_CPU_RX2_P")
	)
	(arc
		(start 220.96476 -81.42224)
		(mid 221.263107 -81.222954)
		(end 221.615 -81.153)
		(width 0.127)
		(layer "In5.Cu")
		(net "PCIE_10G_CPU_RX2_P")
	)
	(arc
		(start 231.655112 -81.526888)
		(mid 231.845882 -81.654356)
		(end 232.07091 -81.6991)
		(width 0.127)
		(layer "In5.Cu")
		(net "PCIE_10G_CPU_RX2_P")
	)
	(arc
		(start 308.128416 -80.21447)
		(mid 308.195161 -80.268294)
		(end 308.278276 -80.2894)
		(width 0.127)
		(layer "In5.Cu")
		(net "PCIE_10G_CPU_RX2_P")
	)
	(arc
		(start 299.551598 -80.21447)
		(mid 299.618343 -80.268294)
		(end 299.701458 -80.2894)
		(width 0.127)
		(layer "In5.Cu")
		(net "PCIE_10G_CPU_RX2_P")
	)
	(arc
		(start 303.486058 -80.13954)
		(mid 303.569173 -80.160623)
		(end 303.635918 -80.21447)
		(width 0.127)
		(layer "In5.Cu")
		(net "PCIE_10G_CPU_RX2_P")
	)
	(arc
		(start 298.870878 -80.21447)
		(mid 298.937623 -80.160646)
		(end 299.020738 -80.13954)
		(width 0.127)
		(layer "In5.Cu")
		(net "PCIE_10G_CPU_RX2_P")
	)
	(segment
		(start 298.43476 -182.640224)
		(end 298.43476 -182.63108)
		(width 0.1143)
		(layer "F.Cu")
		(net "HB0_R_IN1")
	)
	(segment
		(start 298.43476 -182.63108)
		(end 298.0436 -182.23992)
		(width 0.1143)
		(layer "F.Cu")
		(net "HB0_R_IN1")
	)
	(via
		(at 306.324 -185.674)
		(size 0.7112)
		(drill 0.3556)
		(layers "F.Cu" "B.Cu")
		(net "HB0_R_IN1")
	)
	(via
		(at 298.0436 -182.23992)
		(size 0.508)
		(drill 0.254)
		(layers "F.Cu" "B.Cu")
		(net "HB0_R_IN1")
	)
	(segment
		(start 301.752 -184.912)
		(end 299.847 -184.912)
		(width 0.1143)
		(layer "B.Cu")
		(net "HB0_R_IN1")
	)
	(segment
		(start 310.4515 -185.674)
		(end 310.29402 -185.83148)
		(width 0.1143)
		(layer "B.Cu")
		(net "HB0_R_IN1")
	)
	(segment
		(start 298.430696 -182.868824)
		(end 298.45 -182.84952)
		(width 0.0889)
		(layer "B.Cu")
		(net "HB0_R_IN1")
	)
	(segment
		(start 299.847 -184.912)
		(end 299.085 -184.15)
		(width 0.1143)
		(layer "B.Cu")
		(net "HB0_R_IN1")
	)
	(segment
		(start 307.264308 -185.82005)
		(end 307.252878 -185.83148)
		(width 0.1143)
		(layer "B.Cu")
		(net "HB0_R_IN1")
	)
	(segment
		(start 299.085 -183.854852)
		(end 298.430696 -183.200548)
		(width 0.0889)
		(layer "B.Cu")
		(net "HB0_R_IN1")
	)
	(segment
		(start 298.45 -182.84952)
		(end 298.45 -182.64632)
		(width 0.0889)
		(layer "B.Cu")
		(net "HB0_R_IN1")
	)
	(segment
		(start 307.669692 -185.82005)
		(end 307.264308 -185.82005)
		(width 0.1143)
		(layer "B.Cu")
		(net "HB0_R_IN1")
	)
	(segment
		(start 298.45 -182.64632)
		(end 298.0436 -182.23992)
		(width 0.0889)
		(layer "B.Cu")
		(net "HB0_R_IN1")
	)
	(segment
		(start 306.48148 -185.83148)
		(end 306.324 -185.674)
		(width 0.1143)
		(layer "B.Cu")
		(net "HB0_R_IN1")
	)
	(segment
		(start 306.324 -185.674)
		(end 302.514 -185.674)
		(width 0.1143)
		(layer "B.Cu")
		(net "HB0_R_IN1")
	)
	(segment
		(start 302.514 -185.674)
		(end 301.752 -184.912)
		(width 0.1143)
		(layer "B.Cu")
		(net "HB0_R_IN1")
	)
	(segment
		(start 310.29402 -185.83148)
		(end 307.681122 -185.83148)
		(width 0.1143)
		(layer "B.Cu")
		(net "HB0_R_IN1")
	)
	(segment
		(start 307.252878 -185.83148)
		(end 306.48148 -185.83148)
		(width 0.1143)
		(layer "B.Cu")
		(net "HB0_R_IN1")
	)
	(segment
		(start 307.681122 -185.83148)
		(end 307.669692 -185.82005)
		(width 0.1143)
		(layer "B.Cu")
		(net "HB0_R_IN1")
	)
	(segment
		(start 299.085 -184.15)
		(end 299.085 -183.854852)
		(width 0.0889)
		(layer "B.Cu")
		(net "HB0_R_IN1")
	)
	(segment
		(start 298.430696 -183.200548)
		(end 298.430696 -182.868824)
		(width 0.0889)
		(layer "B.Cu")
		(net "HB0_R_IN1")
	)
	(segment
		(start 271.482312 -50.165)
		(end 271.609312 -50.292)
		(width 0.254)
		(layer "F.Cu")
		(net "P3V3_S_LV")
	)
	(segment
		(start 273.2532 -51.146964)
		(end 273.2532 -52.0446)
		(width 0.254)
		(layer "F.Cu")
		(net "P3V3_S_LV")
	)
	(segment
		(start 270.959072 -51.187096)
		(end 270.959072 -50.292)
		(width 0.254)
		(layer "F.Cu")
		(net "P3V3_S_LV")
	)
	(segment
		(start 273.105372 -50.999136)
		(end 273.2532 -51.146964)
		(width 0.254)
		(layer "F.Cu")
		(net "P3V3_S_LV")
	)
	(segment
		(start 272.917412 -51.187096)
		(end 273.105372 -50.999136)
		(width 0.254)
		(layer "F.Cu")
		(net "P3V3_S_LV")
	)
	(segment
		(start 270.959072 -50.292)
		(end 271.086072 -50.165)
		(width 0.254)
		(layer "F.Cu")
		(net "P3V3_S_LV")
	)
	(segment
		(start 271.609312 -51.187096)
		(end 272.917412 -51.187096)
		(width 0.254)
		(layer "F.Cu")
		(net "P3V3_S_LV")
	)
	(segment
		(start 271.086072 -50.165)
		(end 271.482312 -50.165)
		(width 0.254)
		(layer "F.Cu")
		(net "P3V3_S_LV")
	)
	(segment
		(start 271.609312 -50.292)
		(end 271.609312 -51.187096)
		(width 0.254)
		(layer "F.Cu")
		(net "P3V3_S_LV")
	)
	(via
		(at 273.2532 -52.0446)
		(size 0.7112)
		(drill 0.3556)
		(layers "F.Cu" "B.Cu")
		(net "P3V3_S_LV")
	)
	(segment
		(start 298.43476 -173.844204)
		(end 298.041568 -174.237396)
		(width 0.1143)
		(layer "F.Cu")
		(net "LOW_HEX_0")
	)
	(segment
		(start 298.43476 -173.84014)
		(end 298.43476 -173.844204)
		(width 0.1143)
		(layer "F.Cu")
		(net "LOW_HEX_0")
	)
	(via
		(at 306.522374 -173.736762)
		(size 0.5588)
		(drill 0.3048)
		(layers "F.Cu" "B.Cu")
		(net "LOW_HEX_0")
	)
	(via
		(at 298.041568 -174.237396)
		(size 0.508)
		(drill 0.254)
		(layers "F.Cu" "B.Cu")
		(net "LOW_HEX_0")
	)
	(segment
		(start 306.450238 -173.736762)
		(end 305.44643 -174.74057)
		(width 0.127)
		(layer "In2.Cu")
		(net "LOW_HEX_0")
	)
	(segment
		(start 299.47235 -174.634144)
		(end 299.470064 -174.63643)
		(width 0.0889)
		(layer "In2.Cu")
		(net "LOW_HEX_0")
	)
	(segment
		(start 306.522374 -173.736762)
		(end 306.450238 -173.736762)
		(width 0.127)
		(layer "In2.Cu")
		(net "LOW_HEX_0")
	)
	(segment
		(start 298.46143 -174.63643)
		(end 298.062396 -174.237396)
		(width 0.0889)
		(layer "In2.Cu")
		(net "LOW_HEX_0")
	)
	(segment
		(start 301.17415 -174.643034)
		(end 299.812964 -174.643034)
		(width 0.0889)
		(layer "In2.Cu")
		(net "LOW_HEX_0")
	)
	(segment
		(start 299.804074 -174.634144)
		(end 299.47235 -174.634144)
		(width 0.0889)
		(layer "In2.Cu")
		(net "LOW_HEX_0")
	)
	(segment
		(start 299.470064 -174.63643)
		(end 298.46143 -174.63643)
		(width 0.0889)
		(layer "In2.Cu")
		(net "LOW_HEX_0")
	)
	(segment
		(start 301.271686 -174.74057)
		(end 301.250604 -174.719488)
		(width 0.127)
		(layer "In2.Cu")
		(net "LOW_HEX_0")
	)
	(segment
		(start 305.44643 -174.74057)
		(end 301.271686 -174.74057)
		(width 0.127)
		(layer "In2.Cu")
		(net "LOW_HEX_0")
	)
	(segment
		(start 301.250604 -174.719488)
		(end 301.17415 -174.643034)
		(width 0.0889)
		(layer "In2.Cu")
		(net "LOW_HEX_0")
	)
	(segment
		(start 298.062396 -174.237396)
		(end 298.041568 -174.237396)
		(width 0.0889)
		(layer "In2.Cu")
		(net "LOW_HEX_0")
	)
	(segment
		(start 299.812964 -174.643034)
		(end 299.804074 -174.634144)
		(width 0.0889)
		(layer "In2.Cu")
		(net "LOW_HEX_0")
	)
	(segment
		(start 310.028082 -173.938692)
		(end 306.724304 -173.938692)
		(width 0.127)
		(layer "In5.Cu")
		(net "LOW_HEX_0")
	)
	(segment
		(start 333.248 -84.328)
		(end 333.248 -89.789)
		(width 0.127)
		(layer "In5.Cu")
		(net "LOW_HEX_0")
	)
	(segment
		(start 333.248 -89.789)
		(end 324.1167 -98.9203)
		(width 0.127)
		(layer "In5.Cu")
		(net "LOW_HEX_0")
	)
	(segment
		(start 345.987624 -13.462)
		(end 336.169 -23.280624)
		(width 0.127)
		(layer "In5.Cu")
		(net "LOW_HEX_0")
	)
	(segment
		(start 327.1393 -114.681)
		(end 327.1393 -135.416036)
		(width 0.127)
		(layer "In5.Cu")
		(net "LOW_HEX_0")
	)
	(segment
		(start 351.984564 -7.499604)
		(end 351.984564 -8.712962)
		(width 0.127)
		(layer "In5.Cu")
		(net "LOW_HEX_0")
	)
	(segment
		(start 318.851534 -173.4566)
		(end 317.556134 -174.752)
		(width 0.127)
		(layer "In5.Cu")
		(net "LOW_HEX_0")
	)
	(segment
		(start 334.992218 -82.583782)
		(end 333.248 -84.328)
		(width 0.127)
		(layer "In5.Cu")
		(net "LOW_HEX_0")
	)
	(segment
		(start 326.009 -113.5507)
		(end 327.1393 -114.681)
		(width 0.127)
		(layer "In5.Cu")
		(net "LOW_HEX_0")
	)
	(segment
		(start 336.169 -23.280624)
		(end 336.169 -32.909002)
		(width 0.127)
		(layer "In5.Cu")
		(net "LOW_HEX_0")
	)
	(segment
		(start 329.184762 -173.4566)
		(end 318.851534 -173.4566)
		(width 0.127)
		(layer "In5.Cu")
		(net "LOW_HEX_0")
	)
	(segment
		(start 334.992218 -34.085784)
		(end 334.992218 -82.583782)
		(width 0.127)
		(layer "In5.Cu")
		(net "LOW_HEX_0")
	)
	(segment
		(start 306.724304 -173.938692)
		(end 306.522374 -173.736762)
		(width 0.127)
		(layer "In5.Cu")
		(net "LOW_HEX_0")
	)
	(segment
		(start 310.84139 -174.752)
		(end 310.028082 -173.938692)
		(width 0.127)
		(layer "In5.Cu")
		(net "LOW_HEX_0")
	)
	(segment
		(start 324.1167 -98.9203)
		(end 324.1167 -108.9787)
		(width 0.127)
		(layer "In5.Cu")
		(net "LOW_HEX_0")
	)
	(segment
		(start 324.1167 -108.9787)
		(end 326.009 -110.871)
		(width 0.127)
		(layer "In5.Cu")
		(net "LOW_HEX_0")
	)
	(segment
		(start 335.2673 -167.374062)
		(end 329.184762 -173.4566)
		(width 0.127)
		(layer "In5.Cu")
		(net "LOW_HEX_0")
	)
	(segment
		(start 326.009 -110.871)
		(end 326.009 -113.5507)
		(width 0.127)
		(layer "In5.Cu")
		(net "LOW_HEX_0")
	)
	(segment
		(start 317.556134 -174.752)
		(end 310.84139 -174.752)
		(width 0.127)
		(layer "In5.Cu")
		(net "LOW_HEX_0")
	)
	(segment
		(start 347.235526 -13.462)
		(end 345.987624 -13.462)
		(width 0.127)
		(layer "In5.Cu")
		(net "LOW_HEX_0")
	)
	(segment
		(start 351.984564 -8.712962)
		(end 347.235526 -13.462)
		(width 0.127)
		(layer "In5.Cu")
		(net "LOW_HEX_0")
	)
	(segment
		(start 327.1393 -135.416036)
		(end 335.2673 -143.544036)
		(width 0.127)
		(layer "In5.Cu")
		(net "LOW_HEX_0")
	)
	(segment
		(start 336.169 -32.909002)
		(end 334.992218 -34.085784)
		(width 0.127)
		(layer "In5.Cu")
		(net "LOW_HEX_0")
	)
	(segment
		(start 335.2673 -143.544036)
		(end 335.2673 -167.374062)
		(width 0.127)
		(layer "In5.Cu")
		(net "LOW_HEX_0")
	)
	(segment
		(start 314.596272 -78.571598)
		(end 315.753496 -78.571598)
		(width 0.1397)
		(layer "F.Cu")
		(net "PCIE_10G_CPU_RX2_N")
	)
	(segment
		(start 314.350654 -78.759304)
		(end 314.497466 -78.612492)
		(width 0.1397)
		(layer "F.Cu")
		(net "PCIE_10G_CPU_RX2_N")
	)
	(segment
		(start 316.83452 -79.0194)
		(end 317.8556 -79.0194)
		(width 0.1397)
		(layer "F.Cu")
		(net "PCIE_10G_CPU_RX2_N")
	)
	(segment
		(start 313.125104 -78.800198)
		(end 314.251848 -78.800198)
		(width 0.1397)
		(layer "F.Cu")
		(net "PCIE_10G_CPU_RX2_N")
	)
	(segment
		(start 318.018922 -79.087218)
		(end 318.383158 -79.4512)
		(width 0.1397)
		(layer "F.Cu")
		(net "PCIE_10G_CPU_RX2_N")
	)
	(via
		(at 318.383158 -79.4512)
		(size 0.5588)
		(drill 0.3048)
		(layers "F.Cu" "B.Cu")
		(net "PCIE_10G_CPU_RX2_N")
	)
	(arc
		(start 314.497466 -78.612492)
		(mid 314.542799 -78.582202)
		(end 314.596272 -78.571598)
		(width 0.1397)
		(layer "F.Cu")
		(net "PCIE_10G_CPU_RX2_N")
	)
	(arc
		(start 315.976 -78.6638)
		(mid 316.369892 -78.92699)
		(end 316.83452 -79.0194)
		(width 0.1397)
		(layer "F.Cu")
		(net "PCIE_10G_CPU_RX2_N")
	)
	(arc
		(start 317.8556 -79.0194)
		(mid 317.944 -79.037077)
		(end 318.018922 -79.087218)
		(width 0.1397)
		(layer "F.Cu")
		(net "PCIE_10G_CPU_RX2_N")
	)
	(arc
		(start 314.251848 -78.800198)
		(mid 314.305309 -78.789564)
		(end 314.350654 -78.759304)
		(width 0.1397)
		(layer "F.Cu")
		(net "PCIE_10G_CPU_RX2_N")
	)
	(arc
		(start 315.753496 -78.571598)
		(mid 315.873929 -78.595554)
		(end 315.976 -78.6638)
		(width 0.1397)
		(layer "F.Cu")
		(net "PCIE_10G_CPU_RX2_N")
	)
	(segment
		(start 220.906848 -81.875376)
		(end 221.162372 -81.619852)
		(width 0.127)
		(layer "In5.Cu")
		(net "PCIE_10G_CPU_RX2_N")
	)
	(segment
		(start 152.265888 -81.541112)
		(end 152.456388 -81.731612)
		(width 0.127)
		(layer "In5.Cu")
		(net "PCIE_10G_CPU_RX2_N")
	)
	(segment
		(start 312.268362 -79.79029)
		(end 313.396884 -79.79029)
		(width 0.127)
		(layer "In5.Cu")
		(net "PCIE_10G_CPU_RX2_N")
	)
	(segment
		(start 297.18 -80.5688)
		(end 310.56834 -80.5688)
		(width 0.127)
		(layer "In5.Cu")
		(net "PCIE_10G_CPU_RX2_N")
	)
	(segment
		(start 232.071164 -81.9785)
		(end 294.767254 -81.9785)
		(width 0.127)
		(layer "In5.Cu")
		(net "PCIE_10G_CPU_RX2_N")
	)
	(segment
		(start 318.051942 -79.119984)
		(end 318.383158 -79.4512)
		(width 0.127)
		(layer "In5.Cu")
		(net "PCIE_10G_CPU_RX2_N")
	)
	(segment
		(start 147.51177 -80.8482)
		(end 147.81657 -81.153)
		(width 0.127)
		(layer "In5.Cu")
		(net "PCIE_10G_CPU_RX2_N")
	)
	(segment
		(start 221.615 -81.4324)
		(end 231.081326 -81.4324)
		(width 0.127)
		(layer "In5.Cu")
		(net "PCIE_10G_CPU_RX2_N")
	)
	(segment
		(start 311.195212 -80.309212)
		(end 311.322212 -80.182212)
		(width 0.127)
		(layer "In5.Cu")
		(net "PCIE_10G_CPU_RX2_N")
	)
	(segment
		(start 146.449796 -73.75017)
		(end 146.449796 -74.331068)
		(width 0.127)
		(layer "In5.Cu")
		(net "PCIE_10G_CPU_RX2_N")
	)
	(segment
		(start 153.14422 -82.0166)
		(end 220.565726 -82.0166)
		(width 0.127)
		(layer "In5.Cu")
		(net "PCIE_10G_CPU_RX2_N")
	)
	(segment
		(start 148.42998 -81.407)
		(end 151.942038 -81.407)
		(width 0.127)
		(layer "In5.Cu")
		(net "PCIE_10G_CPU_RX2_N")
	)
	(segment
		(start 295.508172 -81.671668)
		(end 296.208704 -80.971136)
		(width 0.127)
		(layer "In5.Cu")
		(net "PCIE_10G_CPU_RX2_N")
	)
	(segment
		(start 146.21637 -75.270106)
		(end 146.21637 -78.291182)
		(width 0.127)
		(layer "In5.Cu")
		(net "PCIE_10G_CPU_RX2_N")
	)
	(segment
		(start 314.850526 -79.0829)
		(end 317.96228 -79.0829)
		(width 0.127)
		(layer "In5.Cu")
		(net "PCIE_10G_CPU_RX2_N")
	)
	(segment
		(start 147.30857 -80.047846)
		(end 147.30857 -80.357472)
		(width 0.127)
		(layer "In5.Cu")
		(net "PCIE_10G_CPU_RX2_N")
	)
	(segment
		(start 146.53387 -79.0575)
		(end 147.15617 -79.6798)
		(width 0.127)
		(layer "In5.Cu")
		(net "PCIE_10G_CPU_RX2_N")
	)
	(segment
		(start 231.224836 -81.491836)
		(end 231.4575 -81.7245)
		(width 0.127)
		(layer "In5.Cu")
		(net "PCIE_10G_CPU_RX2_N")
	)
	(segment
		(start 314.272422 -79.427578)
		(end 314.452 -79.248)
		(width 0.127)
		(layer "In5.Cu")
		(net "PCIE_10G_CPU_RX2_N")
	)
	(arc
		(start 231.4575 -81.7245)
		(mid 231.739052 -81.912597)
		(end 232.071164 -81.9785)
		(width 0.127)
		(layer "In5.Cu")
		(net "PCIE_10G_CPU_RX2_N")
	)
	(arc
		(start 310.56834 -80.5688)
		(mid 310.907574 -80.501322)
		(end 311.195212 -80.309212)
		(width 0.127)
		(layer "In5.Cu")
		(net "PCIE_10G_CPU_RX2_N")
	)
	(arc
		(start 221.162372 -81.619852)
		(mid 221.370039 -81.481093)
		(end 221.615 -81.4324)
		(width 0.127)
		(layer "In5.Cu")
		(net "PCIE_10G_CPU_RX2_N")
	)
	(arc
		(start 294.767254 -81.9785)
		(mid 295.168239 -81.898775)
		(end 295.508172 -81.671668)
		(width 0.127)
		(layer "In5.Cu")
		(net "PCIE_10G_CPU_RX2_N")
	)
	(arc
		(start 220.565726 -82.0166)
		(mid 220.750326 -81.979899)
		(end 220.906848 -81.875376)
		(width 0.127)
		(layer "In5.Cu")
		(net "PCIE_10G_CPU_RX2_N")
	)
	(arc
		(start 146.28749 -74.983848)
		(mid 146.234385 -75.122618)
		(end 146.21637 -75.270106)
		(width 0.127)
		(layer "In5.Cu")
		(net "PCIE_10G_CPU_RX2_N")
	)
	(arc
		(start 314.452 -79.248)
		(mid 314.634845 -79.125827)
		(end 314.850526 -79.0829)
		(width 0.127)
		(layer "In5.Cu")
		(net "PCIE_10G_CPU_RX2_N")
	)
	(arc
		(start 146.449796 -74.331068)
		(mid 146.4086 -74.66739)
		(end 146.28749 -74.983848)
		(width 0.127)
		(layer "In5.Cu")
		(net "PCIE_10G_CPU_RX2_N")
	)
	(arc
		(start 147.30857 -80.357472)
		(mid 147.361392 -80.623027)
		(end 147.51177 -80.8482)
		(width 0.127)
		(layer "In5.Cu")
		(net "PCIE_10G_CPU_RX2_N")
	)
	(arc
		(start 317.96228 -79.0829)
		(mid 318.010798 -79.092533)
		(end 318.051942 -79.119984)
		(width 0.127)
		(layer "In5.Cu")
		(net "PCIE_10G_CPU_RX2_N")
	)
	(arc
		(start 311.322212 -80.182212)
		(mid 311.756309 -79.892157)
		(end 312.268362 -79.79029)
		(width 0.127)
		(layer "In5.Cu")
		(net "PCIE_10G_CPU_RX2_N")
	)
	(arc
		(start 147.15617 -79.6798)
		(mid 147.268999 -79.848661)
		(end 147.30857 -80.047846)
		(width 0.127)
		(layer "In5.Cu")
		(net "PCIE_10G_CPU_RX2_N")
	)
	(arc
		(start 147.81657 -81.153)
		(mid 148.098005 -81.341049)
		(end 148.42998 -81.407)
		(width 0.127)
		(layer "In5.Cu")
		(net "PCIE_10G_CPU_RX2_N")
	)
	(arc
		(start 296.208704 -80.971136)
		(mid 296.654338 -80.673373)
		(end 297.18 -80.5688)
		(width 0.127)
		(layer "In5.Cu")
		(net "PCIE_10G_CPU_RX2_N")
	)
	(arc
		(start 313.396884 -79.79029)
		(mid 313.870728 -79.696019)
		(end 314.272422 -79.427578)
		(width 0.127)
		(layer "In5.Cu")
		(net "PCIE_10G_CPU_RX2_N")
	)
	(arc
		(start 146.21637 -78.291182)
		(mid 146.298939 -78.705902)
		(end 146.53387 -79.0575)
		(width 0.127)
		(layer "In5.Cu")
		(net "PCIE_10G_CPU_RX2_N")
	)
	(arc
		(start 152.456388 -81.731612)
		(mid 152.771967 -81.942505)
		(end 153.14422 -82.0166)
		(width 0.127)
		(layer "In5.Cu")
		(net "PCIE_10G_CPU_RX2_N")
	)
	(arc
		(start 231.081326 -81.4324)
		(mid 231.15899 -81.447848)
		(end 231.224836 -81.491836)
		(width 0.127)
		(layer "In5.Cu")
		(net "PCIE_10G_CPU_RX2_N")
	)
	(arc
		(start 151.942038 -81.407)
		(mid 152.117292 -81.44186)
		(end 152.265888 -81.541112)
		(width 0.127)
		(layer "In5.Cu")
		(net "PCIE_10G_CPU_RX2_N")
	)
	(segment
		(start 270.818864 -56.714136)
		(end 271.145 -56.388)
		(width 0.254)
		(layer "F.Cu")
		(net "P3V3_EN_B")
	)
	(segment
		(start 270.1925 -54.61)
		(end 270.959072 -53.843428)
		(width 0.254)
		(layer "F.Cu")
		(net "P3V3_EN_B")
	)
	(segment
		(start 270.184372 -55.698136)
		(end 270.184372 -56.714136)
		(width 0.254)
		(layer "F.Cu")
		(net "P3V3_EN_B")
	)
	(segment
		(start 270.184372 -56.714136)
		(end 270.818864 -56.714136)
		(width 0.254)
		(layer "F.Cu")
		(net "P3V3_EN_B")
	)
	(segment
		(start 270.184372 -55.698136)
		(end 270.1925 -55.690008)
		(width 0.254)
		(layer "F.Cu")
		(net "P3V3_EN_B")
	)
	(segment
		(start 272.546572 -54.986428)
		(end 271.145 -56.388)
		(width 0.254)
		(layer "F.Cu")
		(net "P3V3_EN_B")
	)
	(segment
		(start 272.546572 -54.952646)
		(end 272.546572 -54.986428)
		(width 0.254)
		(layer "F.Cu")
		(net "P3V3_EN_B")
	)
	(segment
		(start 270.959072 -53.843428)
		(end 270.959072 -53.066696)
		(width 0.254)
		(layer "F.Cu")
		(net "P3V3_EN_B")
	)
	(segment
		(start 270.1925 -55.690008)
		(end 270.1925 -54.61)
		(width 0.254)
		(layer "F.Cu")
		(net "P3V3_EN_B")
	)
	(via
		(at 271.145 -56.388)
		(size 0.7112)
		(drill 0.3556)
		(layers "F.Cu" "B.Cu")
		(net "P3V3_EN_B")
	)
	(segment
		(start 302.056038 -168.240202)
		(end 301.634906 -168.240202)
		(width 0.1143)
		(layer "F.Cu")
		(net "BMC0_SMB4_CLK")
	)
	(segment
		(start 305.943 -167.513)
		(end 305.49215 -167.96385)
		(width 0.1143)
		(layer "F.Cu")
		(net "BMC0_SMB4_CLK")
	)
	(segment
		(start 305.49215 -167.96385)
		(end 302.33239 -167.96385)
		(width 0.1143)
		(layer "F.Cu")
		(net "BMC0_SMB4_CLK")
	)
	(segment
		(start 302.33239 -167.96385)
		(end 302.056038 -168.240202)
		(width 0.1143)
		(layer "F.Cu")
		(net "BMC0_SMB4_CLK")
	)
	(via
		(at 311.277 -165.862)
		(size 0.7112)
		(drill 0.3556)
		(layers "F.Cu" "B.Cu")
		(net "BMC0_SMB4_CLK")
	)
	(via
		(at 305.943 -167.513)
		(size 0.5588)
		(drill 0.3048)
		(layers "F.Cu" "B.Cu")
		(net "BMC0_SMB4_CLK")
	)
	(segment
		(start 317.5635 -162.814)
		(end 315.05525 -165.32225)
		(width 0.1143)
		(layer "B.Cu")
		(net "BMC0_SMB4_CLK")
	)
	(segment
		(start 305.943 -167.513)
		(end 306.540662 -166.915338)
		(width 0.1143)
		(layer "B.Cu")
		(net "BMC0_SMB4_CLK")
	)
	(segment
		(start 311.81675 -165.32225)
		(end 311.277 -165.862)
		(width 0.1143)
		(layer "B.Cu")
		(net "BMC0_SMB4_CLK")
	)
	(segment
		(start 315.05525 -165.32225)
		(end 311.81675 -165.32225)
		(width 0.1143)
		(layer "B.Cu")
		(net "BMC0_SMB4_CLK")
	)
	(segment
		(start 306.540662 -166.915338)
		(end 310.223662 -166.915338)
		(width 0.1143)
		(layer "B.Cu")
		(net "BMC0_SMB4_CLK")
	)
	(segment
		(start 310.223662 -166.915338)
		(end 311.277 -165.862)
		(width 0.1143)
		(layer "B.Cu")
		(net "BMC0_SMB4_CLK")
	)
	(segment
		(start 67.159886 -108.122212)
		(end 68.525136 -108.122212)
		(width 0.254)
		(layer "F.Cu")
		(net "P1V8_EN_S")
	)
	(segment
		(start 67.183 -107.315)
		(end 67.159886 -107.338114)
		(width 0.254)
		(layer "F.Cu")
		(net "P1V8_EN_S")
	)
	(segment
		(start 67.159886 -107.338114)
		(end 67.159886 -108.122212)
		(width 0.254)
		(layer "F.Cu")
		(net "P1V8_EN_S")
	)
	(segment
		(start 67.183 -107.207812)
		(end 67.183 -107.315)
		(width 0.254)
		(layer "F.Cu")
		(net "P1V8_EN_S")
	)
	(segment
		(start 67.159886 -109.265212)
		(end 67.159886 -108.122212)
		(width 0.254)
		(layer "F.Cu")
		(net "P1V8_EN_S")
	)
	(segment
		(start 68.525136 -108.122212)
		(end 68.810886 -108.407962)
		(width 0.254)
		(layer "F.Cu")
		(net "P1V8_EN_S")
	)
	(via
		(at 67.183 -107.207812)
		(size 0.7112)
		(drill 0.3556)
		(layers "F.Cu" "B.Cu")
		(net "P1V8_EN_S")
	)
	(segment
		(start 298.03598 -171.045124)
		(end 298.020486 -171.045124)
		(width 0.1143)
		(layer "F.Cu")
		(net "BMC0_SMB4_DAT")
	)
	(segment
		(start 298.43095 -171.440094)
		(end 298.03598 -171.045124)
		(width 0.1143)
		(layer "F.Cu")
		(net "BMC0_SMB4_DAT")
	)
	(segment
		(start 298.43476 -171.440094)
		(end 298.43095 -171.440094)
		(width 0.1143)
		(layer "F.Cu")
		(net "BMC0_SMB4_DAT")
	)
	(via
		(at 298.020486 -171.045124)
		(size 0.508)
		(drill 0.254)
		(layers "F.Cu" "B.Cu")
		(net "BMC0_SMB4_DAT")
	)
	(via
		(at 315.341 -166.116)
		(size 0.7112)
		(drill 0.3556)
		(layers "F.Cu" "B.Cu")
		(net "BMC0_SMB4_DAT")
	)
	(segment
		(start 308.55158 -167.59555)
		(end 308.14518 -168.00195)
		(width 0.1143)
		(layer "B.Cu")
		(net "BMC0_SMB4_DAT")
	)
	(segment
		(start 311.95645 -167.59555)
		(end 308.55158 -167.59555)
		(width 0.1143)
		(layer "B.Cu")
		(net "BMC0_SMB4_DAT")
	)
	(segment
		(start 315.7855 -166.116)
		(end 315.341 -166.116)
		(width 0.1143)
		(layer "B.Cu")
		(net "BMC0_SMB4_DAT")
	)
	(segment
		(start 300.779942 -169.392854)
		(end 300.380146 -169.392854)
		(width 0.1143)
		(layer "B.Cu")
		(net "BMC0_SMB4_DAT")
	)
	(segment
		(start 308.14518 -168.00195)
		(end 305.222656 -168.00195)
		(width 0.1143)
		(layer "B.Cu")
		(net "BMC0_SMB4_DAT")
	)
	(segment
		(start 298.997624 -170.635422)
		(end 298.502578 -170.635422)
		(width 0.0889)
		(layer "B.Cu")
		(net "BMC0_SMB4_DAT")
	)
	(segment
		(start 299.466 -169.839386)
		(end 299.231812 -170.073574)
		(width 0.0889)
		(layer "B.Cu")
		(net "BMC0_SMB4_DAT")
	)
	(segment
		(start 299.231812 -170.401234)
		(end 298.997624 -170.635422)
		(width 0.0889)
		(layer "B.Cu")
		(net "BMC0_SMB4_DAT")
	)
	(segment
		(start 315.341 -166.116)
		(end 313.436 -166.116)
		(width 0.1143)
		(layer "B.Cu")
		(net "BMC0_SMB4_DAT")
	)
	(segment
		(start 300.371256 -169.392854)
		(end 299.924724 -169.839386)
		(width 0.0889)
		(layer "B.Cu")
		(net "BMC0_SMB4_DAT")
	)
	(segment
		(start 298.502578 -170.635422)
		(end 298.092876 -171.045124)
		(width 0.0889)
		(layer "B.Cu")
		(net "BMC0_SMB4_DAT")
	)
	(segment
		(start 313.436 -166.116)
		(end 311.95645 -167.59555)
		(width 0.1143)
		(layer "B.Cu")
		(net "BMC0_SMB4_DAT")
	)
	(segment
		(start 300.380146 -169.392854)
		(end 300.371256 -169.392854)
		(width 0.0889)
		(layer "B.Cu")
		(net "BMC0_SMB4_DAT")
	)
	(segment
		(start 304.778156 -167.55745)
		(end 302.615346 -167.55745)
		(width 0.1143)
		(layer "B.Cu")
		(net "BMC0_SMB4_DAT")
	)
	(segment
		(start 317.5635 -164.338)
		(end 315.7855 -166.116)
		(width 0.1143)
		(layer "B.Cu")
		(net "BMC0_SMB4_DAT")
	)
	(segment
		(start 298.092876 -171.045124)
		(end 298.020486 -171.045124)
		(width 0.0889)
		(layer "B.Cu")
		(net "BMC0_SMB4_DAT")
	)
	(segment
		(start 302.615346 -167.55745)
		(end 300.779942 -169.392854)
		(width 0.1143)
		(layer "B.Cu")
		(net "BMC0_SMB4_DAT")
	)
	(segment
		(start 305.222656 -168.00195)
		(end 304.778156 -167.55745)
		(width 0.1143)
		(layer "B.Cu")
		(net "BMC0_SMB4_DAT")
	)
	(segment
		(start 299.231812 -170.073574)
		(end 299.231812 -170.401234)
		(width 0.0889)
		(layer "B.Cu")
		(net "BMC0_SMB4_DAT")
	)
	(segment
		(start 299.924724 -169.839386)
		(end 299.466 -169.839386)
		(width 0.0889)
		(layer "B.Cu")
		(net "BMC0_SMB4_DAT")
	)
	(segment
		(start 317.274956 -75.4888)
		(end 319.7098 -75.4888)
		(width 0.1397)
		(layer "F.Cu")
		(net "PCIE_10G_CPU_RX1_P")
	)
	(segment
		(start 314.596272 -75.028806)
		(end 316.164468 -75.028806)
		(width 0.1397)
		(layer "F.Cu")
		(net "PCIE_10G_CPU_RX1_P")
	)
	(segment
		(start 314.350654 -74.8411)
		(end 314.497466 -74.987912)
		(width 0.1397)
		(layer "F.Cu")
		(net "PCIE_10G_CPU_RX1_P")
	)
	(segment
		(start 320.04762 -75.348846)
		(end 320.186558 -75.209908)
		(width 0.1397)
		(layer "F.Cu")
		(net "PCIE_10G_CPU_RX1_P")
	)
	(segment
		(start 313.125104 -74.800206)
		(end 314.251848 -74.800206)
		(width 0.1397)
		(layer "F.Cu")
		(net "PCIE_10G_CPU_RX1_P")
	)
	(via
		(at 320.186558 -75.209908)
		(size 0.5588)
		(drill 0.3048)
		(layers "F.Cu" "B.Cu")
		(net "PCIE_10G_CPU_RX1_P")
	)
	(arc
		(start 316.164468 -75.028806)
		(mid 316.433619 -75.082344)
		(end 316.6618 -75.2348)
		(width 0.1397)
		(layer "F.Cu")
		(net "PCIE_10G_CPU_RX1_P")
	)
	(arc
		(start 316.6618 -75.2348)
		(mid 316.943118 -75.422771)
		(end 317.274956 -75.4888)
		(width 0.1397)
		(layer "F.Cu")
		(net "PCIE_10G_CPU_RX1_P")
	)
	(arc
		(start 319.7098 -75.4888)
		(mid 319.892636 -75.452432)
		(end 320.04762 -75.348846)
		(width 0.1397)
		(layer "F.Cu")
		(net "PCIE_10G_CPU_RX1_P")
	)
	(arc
		(start 314.251848 -74.800206)
		(mid 314.305309 -74.81084)
		(end 314.350654 -74.8411)
		(width 0.1397)
		(layer "F.Cu")
		(net "PCIE_10G_CPU_RX1_P")
	)
	(arc
		(start 314.497466 -74.987912)
		(mid 314.542799 -75.018202)
		(end 314.596272 -75.028806)
		(width 0.1397)
		(layer "F.Cu")
		(net "PCIE_10G_CPU_RX1_P")
	)
	(segment
		(start 150.749 -75.184)
		(end 150.437596 -75.184)
		(width 0.127)
		(layer "In5.Cu")
		(net "PCIE_10G_CPU_RX1_P")
	)
	(segment
		(start 156.390848 -67.1703)
		(end 180.23713 -67.1703)
		(width 0.127)
		(layer "In5.Cu")
		(net "PCIE_10G_CPU_RX1_P")
	)
	(segment
		(start 152.07234 -69.988176)
		(end 153.829258 -68.231258)
		(width 0.127)
		(layer "In5.Cu")
		(net "PCIE_10G_CPU_RX1_P")
	)
	(segment
		(start 230.880412 -66.528188)
		(end 234.17784 -69.825616)
		(width 0.127)
		(layer "In5.Cu")
		(net "PCIE_10G_CPU_RX1_P")
	)
	(segment
		(start 149.549358 -73.157588)
		(end 150.242016 -72.46493)
		(width 0.127)
		(layer "In5.Cu")
		(net "PCIE_10G_CPU_RX1_P")
	)
	(segment
		(start 318.80937 -70.871588)
		(end 319.19037 -71.252588)
		(width 0.127)
		(layer "In5.Cu")
		(net "PCIE_10G_CPU_RX1_P")
	)
	(segment
		(start 301.117 -74.9046)
		(end 306.039012 -74.9046)
		(width 0.127)
		(layer "In5.Cu")
		(net "PCIE_10G_CPU_RX1_P")
	)
	(segment
		(start 149.841458 -74.937112)
		(end 149.549358 -74.645012)
		(width 0.127)
		(layer "In5.Cu")
		(net "PCIE_10G_CPU_RX1_P")
	)
	(segment
		(start 150.35911 -72.182228)
		(end 150.35911 -71.939658)
		(width 0.127)
		(layer "In5.Cu")
		(net "PCIE_10G_CPU_RX1_P")
	)
	(segment
		(start 152.07234 -69.98843)
		(end 152.07234 -69.988176)
		(width 0.127)
		(layer "In5.Cu")
		(net "PCIE_10G_CPU_RX1_P")
	)
	(segment
		(start 310.600852 -71.079106)
		(end 310.737758 -70.942454)
		(width 0.127)
		(layer "In5.Cu")
		(net "PCIE_10G_CPU_RX1_P")
	)
	(segment
		(start 319.475358 -74.1934)
		(end 319.473072 -74.19594)
		(width 0.127)
		(layer "In5.Cu")
		(net "PCIE_10G_CPU_RX1_P")
	)
	(segment
		(start 300.609 -74.549)
		(end 300.85665 -74.796904)
		(width 0.127)
		(layer "In5.Cu")
		(net "PCIE_10G_CPU_RX1_P")
	)
	(segment
		(start 319.678558 -72.431148)
		(end 319.678558 -73.702926)
		(width 0.127)
		(layer "In5.Cu")
		(net "PCIE_10G_CPU_RX1_P")
	)
	(segment
		(start 183.06288 -65.7352)
		(end 228.96576 -65.7352)
		(width 0.127)
		(layer "In5.Cu")
		(net "PCIE_10G_CPU_RX1_P")
	)
	(segment
		(start 150.527258 -71.533512)
		(end 152.07234 -69.98843)
		(width 0.127)
		(layer "In5.Cu")
		(net "PCIE_10G_CPU_RX1_P")
	)
	(segment
		(start 311.658 -70.5612)
		(end 318.059816 -70.5612)
		(width 0.127)
		(layer "In5.Cu")
		(net "PCIE_10G_CPU_RX1_P")
	)
	(segment
		(start 236.3216 -70.7136)
		(end 297.713146 -70.7136)
		(width 0.127)
		(layer "In5.Cu")
		(net "PCIE_10G_CPU_RX1_P")
	)
	(segment
		(start 319.337182 -74.5236)
		(end 319.337182 -74.840592)
		(width 0.127)
		(layer "In5.Cu")
		(net "PCIE_10G_CPU_RX1_P")
	)
	(segment
		(start 307.296058 -74.3839)
		(end 310.600852 -71.079106)
		(width 0.127)
		(layer "In5.Cu")
		(net "PCIE_10G_CPU_RX1_P")
	)
	(segment
		(start 300.3804 -73.532746)
		(end 300.3804 -73.997058)
		(width 0.127)
		(layer "In5.Cu")
		(net "PCIE_10G_CPU_RX1_P")
	)
	(segment
		(start 181.494176 -66.6496)
		(end 181.945788 -66.197988)
		(width 0.127)
		(layer "In5.Cu")
		(net "PCIE_10G_CPU_RX1_P")
	)
	(segment
		(start 298.301664 -70.95744)
		(end 300.029372 -72.685148)
		(width 0.127)
		(layer "In5.Cu")
		(net "PCIE_10G_CPU_RX1_P")
	)
	(segment
		(start 320.085466 -75.311)
		(end 320.186558 -75.209908)
		(width 0.127)
		(layer "In5.Cu")
		(net "PCIE_10G_CPU_RX1_P")
	)
	(segment
		(start 151.449786 -75.75042)
		(end 150.978362 -75.278996)
		(width 0.127)
		(layer "In5.Cu")
		(net "PCIE_10G_CPU_RX1_P")
	)
	(arc
		(start 306.039012 -74.9046)
		(mid 306.719326 -74.769277)
		(end 307.296058 -74.3839)
		(width 0.127)
		(layer "In5.Cu")
		(net "PCIE_10G_CPU_RX1_P")
	)
	(arc
		(start 319.828672 -75.425046)
		(mid 319.96767 -75.391882)
		(end 320.085466 -75.311)
		(width 0.127)
		(layer "In5.Cu")
		(net "PCIE_10G_CPU_RX1_P")
	)
	(arc
		(start 319.19037 -71.252588)
		(mid 319.551673 -71.793316)
		(end 319.678558 -72.431148)
		(width 0.127)
		(layer "In5.Cu")
		(net "PCIE_10G_CPU_RX1_P")
	)
	(arc
		(start 297.713146 -70.7136)
		(mid 298.031636 -70.777027)
		(end 298.301664 -70.95744)
		(width 0.127)
		(layer "In5.Cu")
		(net "PCIE_10G_CPU_RX1_P")
	)
	(arc
		(start 150.242016 -72.46493)
		(mid 150.328682 -72.335225)
		(end 150.35911 -72.182228)
		(width 0.127)
		(layer "In5.Cu")
		(net "PCIE_10G_CPU_RX1_P")
	)
	(arc
		(start 319.337182 -74.840592)
		(mid 319.387819 -75.095163)
		(end 319.532 -75.311)
		(width 0.127)
		(layer "In5.Cu")
		(net "PCIE_10G_CPU_RX1_P")
	)
	(arc
		(start 150.978362 -75.278996)
		(mid 150.87313 -75.208682)
		(end 150.749 -75.184)
		(width 0.127)
		(layer "In5.Cu")
		(net "PCIE_10G_CPU_RX1_P")
	)
	(arc
		(start 181.945788 -66.197988)
		(mid 182.458313 -65.8555)
		(end 183.06288 -65.7352)
		(width 0.127)
		(layer "In5.Cu")
		(net "PCIE_10G_CPU_RX1_P")
	)
	(arc
		(start 153.829258 -68.231258)
		(mid 155.004525 -67.445969)
		(end 156.390848 -67.1703)
		(width 0.127)
		(layer "In5.Cu")
		(net "PCIE_10G_CPU_RX1_P")
	)
	(arc
		(start 319.678558 -73.702926)
		(mid 319.625755 -73.968384)
		(end 319.475358 -74.1934)
		(width 0.127)
		(layer "In5.Cu")
		(net "PCIE_10G_CPU_RX1_P")
	)
	(arc
		(start 300.85665 -74.796904)
		(mid 300.976115 -74.876635)
		(end 301.117 -74.9046)
		(width 0.127)
		(layer "In5.Cu")
		(net "PCIE_10G_CPU_RX1_P")
	)
	(arc
		(start 318.059816 -70.5612)
		(mid 318.465438 -70.641883)
		(end 318.80937 -70.871588)
		(width 0.127)
		(layer "In5.Cu")
		(net "PCIE_10G_CPU_RX1_P")
	)
	(arc
		(start 228.96576 -65.7352)
		(mid 230.001929 -65.941307)
		(end 230.880412 -66.528188)
		(width 0.127)
		(layer "In5.Cu")
		(net "PCIE_10G_CPU_RX1_P")
	)
	(arc
		(start 150.437596 -75.184)
		(mid 150.114984 -75.119828)
		(end 149.841458 -74.937112)
		(width 0.127)
		(layer "In5.Cu")
		(net "PCIE_10G_CPU_RX1_P")
	)
	(arc
		(start 149.549358 -74.645012)
		(mid 149.241302 -73.9013)
		(end 149.549358 -73.157588)
		(width 0.127)
		(layer "In5.Cu")
		(net "PCIE_10G_CPU_RX1_P")
	)
	(arc
		(start 300.3804 -73.997058)
		(mid 300.439815 -74.295758)
		(end 300.609 -74.549)
		(width 0.127)
		(layer "In5.Cu")
		(net "PCIE_10G_CPU_RX1_P")
	)
	(arc
		(start 300.029372 -72.685148)
		(mid 300.28919 -73.074043)
		(end 300.3804 -73.532746)
		(width 0.127)
		(layer "In5.Cu")
		(net "PCIE_10G_CPU_RX1_P")
	)
	(arc
		(start 234.17784 -69.825616)
		(mid 235.161405 -70.482813)
		(end 236.3216 -70.7136)
		(width 0.127)
		(layer "In5.Cu")
		(net "PCIE_10G_CPU_RX1_P")
	)
	(arc
		(start 319.532 -75.311)
		(mid 319.668243 -75.399463)
		(end 319.828672 -75.425046)
		(width 0.127)
		(layer "In5.Cu")
		(net "PCIE_10G_CPU_RX1_P")
	)
	(arc
		(start 180.23713 -67.1703)
		(mid 180.917458 -67.034992)
		(end 181.494176 -66.6496)
		(width 0.127)
		(layer "In5.Cu")
		(net "PCIE_10G_CPU_RX1_P")
	)
	(arc
		(start 150.35911 -71.939658)
		(mid 150.402826 -71.719885)
		(end 150.527258 -71.533512)
		(width 0.127)
		(layer "In5.Cu")
		(net "PCIE_10G_CPU_RX1_P")
	)
	(arc
		(start 310.737758 -70.942454)
		(mid 311.159954 -70.660288)
		(end 311.658 -70.5612)
		(width 0.127)
		(layer "In5.Cu")
		(net "PCIE_10G_CPU_RX1_P")
	)
	(arc
		(start 319.473072 -74.19594)
		(mid 319.372541 -74.346257)
		(end 319.337182 -74.5236)
		(width 0.127)
		(layer "In5.Cu")
		(net "PCIE_10G_CPU_RX1_P")
	)
	(segment
		(start 289.932872 -61.332872)
		(end 289.932872 -62.429136)
		(width 0.254)
		(layer "F.Cu")
		(net "P3V3_EN_LV")
	)
	(segment
		(start 276.352 -56.007)
		(end 276.281896 -55.936896)
		(width 0.254)
		(layer "F.Cu")
		(net "P3V3_EN_LV")
	)
	(segment
		(start 281.051 -60.706)
		(end 289.306 -60.706)
		(width 0.254)
		(layer "F.Cu")
		(net "P3V3_EN_LV")
	)
	(segment
		(start 272.522696 -52.304696)
		(end 270.528034 -52.304696)
		(width 0.254)
		(layer "F.Cu")
		(net "P3V3_EN_LV")
	)
	(segment
		(start 270.528034 -52.304696)
		(end 270.308832 -52.523898)
		(width 0.254)
		(layer "F.Cu")
		(net "P3V3_EN_LV")
	)
	(segment
		(start 273.820636 -53.602636)
		(end 272.522696 -52.304696)
		(width 0.254)
		(layer "F.Cu")
		(net "P3V3_EN_LV")
	)
	(segment
		(start 274.438872 -55.924196)
		(end 274.438872 -53.602636)
		(width 0.254)
		(layer "F.Cu")
		(net "P3V3_EN_LV")
	)
	(segment
		(start 289.306 -60.706)
		(end 289.932872 -61.332872)
		(width 0.254)
		(layer "F.Cu")
		(net "P3V3_EN_LV")
	)
	(segment
		(start 274.451572 -55.936896)
		(end 274.438872 -55.924196)
		(width 0.254)
		(layer "F.Cu")
		(net "P3V3_EN_LV")
	)
	(segment
		(start 289.932872 -63.826136)
		(end 289.932872 -62.429136)
		(width 0.254)
		(layer "F.Cu")
		(net "P3V3_EN_LV")
	)
	(segment
		(start 274.438872 -53.602636)
		(end 273.820636 -53.602636)
		(width 0.254)
		(layer "F.Cu")
		(net "P3V3_EN_LV")
	)
	(segment
		(start 270.308832 -52.523898)
		(end 270.308832 -53.066696)
		(width 0.254)
		(layer "F.Cu")
		(net "P3V3_EN_LV")
	)
	(segment
		(start 276.352 -56.007)
		(end 281.051 -60.706)
		(width 0.254)
		(layer "F.Cu")
		(net "P3V3_EN_LV")
	)
	(segment
		(start 276.281896 -55.936896)
		(end 274.451572 -55.936896)
		(width 0.254)
		(layer "F.Cu")
		(net "P3V3_EN_LV")
	)
	(segment
		(start 289.551872 -64.207136)
		(end 289.932872 -63.826136)
		(width 0.254)
		(layer "F.Cu")
		(net "P3V3_EN_LV")
	)
	(via
		(at 276.352 -56.007)
		(size 0.7112)
		(drill 0.3556)
		(layers "F.Cu" "B.Cu")
		(net "P3V3_EN_LV")
	)
	(segment
		(start 301.22495 -185.259472)
		(end 301.22495 -185.193178)
		(width 0.1143)
		(layer "F.Cu")
		(net "HB0_R_IN2")
	)
	(segment
		(start 305.17465 -187.44565)
		(end 305.152806 -187.44565)
		(width 0.1143)
		(layer "F.Cu")
		(net "HB0_R_IN2")
	)
	(segment
		(start 299.522896 -183.44007)
		(end 299.23486 -183.44007)
		(width 0.1143)
		(layer "F.Cu")
		(net "HB0_R_IN2")
	)
	(segment
		(start 299.961046 -183.87822)
		(end 299.522896 -183.44007)
		(width 0.1143)
		(layer "F.Cu")
		(net "HB0_R_IN2")
	)
	(segment
		(start 302.739806 -186.59475)
		(end 302.733202 -186.588146)
		(width 0.1143)
		(layer "F.Cu")
		(net "HB0_R_IN2")
	)
	(segment
		(start 308.864 -188.214)
		(end 305.943 -188.214)
		(width 0.1143)
		(layer "F.Cu")
		(net "HB0_R_IN2")
	)
	(segment
		(start 301.22495 -185.193178)
		(end 300.472856 -184.441084)
		(width 0.1143)
		(layer "F.Cu")
		(net "HB0_R_IN2")
	)
	(segment
		(start 300.472856 -184.166002)
		(end 300.185074 -183.87822)
		(width 0.1143)
		(layer "F.Cu")
		(net "HB0_R_IN2")
	)
	(segment
		(start 300.185074 -183.87822)
		(end 299.961046 -183.87822)
		(width 0.1143)
		(layer "F.Cu")
		(net "HB0_R_IN2")
	)
	(segment
		(start 310.3245 -188.214)
		(end 308.864 -188.214)
		(width 0.1143)
		(layer "F.Cu")
		(net "HB0_R_IN2")
	)
	(segment
		(start 302.733202 -186.588146)
		(end 302.553624 -186.588146)
		(width 0.1143)
		(layer "F.Cu")
		(net "HB0_R_IN2")
	)
	(segment
		(start 304.301906 -186.59475)
		(end 302.739806 -186.59475)
		(width 0.1143)
		(layer "F.Cu")
		(net "HB0_R_IN2")
	)
	(segment
		(start 305.943 -188.214)
		(end 305.17465 -187.44565)
		(width 0.1143)
		(layer "F.Cu")
		(net "HB0_R_IN2")
	)
	(segment
		(start 305.152806 -187.44565)
		(end 304.301906 -186.59475)
		(width 0.1143)
		(layer "F.Cu")
		(net "HB0_R_IN2")
	)
	(segment
		(start 300.472856 -184.441084)
		(end 300.472856 -184.166002)
		(width 0.1143)
		(layer "F.Cu")
		(net "HB0_R_IN2")
	)
	(segment
		(start 302.553624 -186.588146)
		(end 301.22495 -185.259472)
		(width 0.1143)
		(layer "F.Cu")
		(net "HB0_R_IN2")
	)
	(segment
		(start 310.4515 -188.087)
		(end 310.3245 -188.214)
		(width 0.1143)
		(layer "F.Cu")
		(net "HB0_R_IN2")
	)
	(via
		(at 308.864 -188.214)
		(size 0.7112)
		(drill 0.3556)
		(layers "F.Cu" "B.Cu")
		(net "HB0_R_IN2")
	)
	(segment
		(start 295.47058 -200.762616)
		(end 295.47058 -199.860662)
		(width 0.1143)
		(layer "F.Cu")
		(net "MEMDQ_11")
	)
	(segment
		(start 295.806622 -199.52462)
		(end 296.52214 -199.52462)
		(width 0.1143)
		(layer "F.Cu")
		(net "MEMDQ_11")
	)
	(segment
		(start 295.298114 -200.935082)
		(end 295.47058 -200.762616)
		(width 0.1143)
		(layer "F.Cu")
		(net "MEMDQ_11")
	)
	(segment
		(start 295.234868 -182.640224)
		(end 295.630092 -183.035448)
		(width 0.1143)
		(layer "F.Cu")
		(net "MEMDQ_11")
	)
	(segment
		(start 295.47058 -199.860662)
		(end 295.806622 -199.52462)
		(width 0.1143)
		(layer "F.Cu")
		(net "MEMDQ_11")
	)
	(via
		(at 297.2562 -200.14819)
		(size 0.7112)
		(drill 0.3556)
		(layers "F.Cu" "B.Cu")
		(net "MEMDQ_11")
	)
	(via
		(at 295.630092 -183.035448)
		(size 0.508)
		(drill 0.254)
		(layers "F.Cu" "B.Cu")
		(net "MEMDQ_11")
	)
	(via
		(at 296.52214 -199.52462)
		(size 0.508)
		(drill 0.254)
		(layers "F.Cu" "B.Cu")
		(net "MEMDQ_11")
	)
	(segment
		(start 297.2562 -200.14819)
		(end 297.14571 -200.14819)
		(width 0.1143)
		(layer "B.Cu")
		(net "MEMDQ_11")
	)
	(segment
		(start 297.14571 -200.14819)
		(end 296.52214 -199.52462)
		(width 0.1143)
		(layer "B.Cu")
		(net "MEMDQ_11")
	)
	(segment
		(start 297.645582 -197.895972)
		(end 297.495722 -197.895972)
		(width 0.127)
		(layer "In5.Cu")
		(net "MEMDQ_11")
	)
	(segment
		(start 299.0596 -186.455558)
		(end 299.0596 -196.464174)
		(width 0.127)
		(layer "In5.Cu")
		(net "MEMDQ_11")
	)
	(segment
		(start 299.0596 -196.464174)
		(end 297.905932 -197.617842)
		(width 0.127)
		(layer "In5.Cu")
		(net "MEMDQ_11")
	)
	(segment
		(start 296.52214 -198.869554)
		(end 296.52214 -199.52462)
		(width 0.127)
		(layer "In5.Cu")
		(net "MEMDQ_11")
	)
	(segment
		(start 297.905932 -197.617842)
		(end 297.905932 -197.635622)
		(width 0.127)
		(layer "In5.Cu")
		(net "MEMDQ_11")
	)
	(segment
		(start 297.905932 -197.635622)
		(end 297.645582 -197.895972)
		(width 0.127)
		(layer "In5.Cu")
		(net "MEMDQ_11")
	)
	(segment
		(start 295.630092 -183.035448)
		(end 296.114724 -183.52008)
		(width 0.127)
		(layer "In5.Cu")
		(net "MEMDQ_11")
	)
	(segment
		(start 297.495722 -197.895972)
		(end 296.52214 -198.869554)
		(width 0.127)
		(layer "In5.Cu")
		(net "MEMDQ_11")
	)
	(segment
		(start 296.124122 -183.52008)
		(end 299.0596 -186.455558)
		(width 0.127)
		(layer "In5.Cu")
		(net "MEMDQ_11")
	)
	(segment
		(start 296.114724 -183.52008)
		(end 296.124122 -183.52008)
		(width 0.127)
		(layer "In5.Cu")
		(net "MEMDQ_11")
	)
	(segment
		(start 313.125104 -75.600052)
		(end 314.251848 -75.600052)
		(width 0.1397)
		(layer "F.Cu")
		(net "PCIE_10G_CPU_RX1_N")
	)
	(segment
		(start 319.908682 -75.91425)
		(end 320.186558 -76.191872)
		(width 0.1397)
		(layer "F.Cu")
		(net "PCIE_10G_CPU_RX1_N")
	)
	(segment
		(start 314.596018 -75.371706)
		(end 316.164468 -75.371706)
		(width 0.1397)
		(layer "F.Cu")
		(net "PCIE_10G_CPU_RX1_N")
	)
	(segment
		(start 314.350654 -75.559158)
		(end 314.497212 -75.4126)
		(width 0.1397)
		(layer "F.Cu")
		(net "PCIE_10G_CPU_RX1_N")
	)
	(segment
		(start 317.274702 -75.8317)
		(end 319.7098 -75.8317)
		(width 0.1397)
		(layer "F.Cu")
		(net "PCIE_10G_CPU_RX1_N")
	)
	(via
		(at 320.186558 -76.191872)
		(size 0.5588)
		(drill 0.3048)
		(layers "F.Cu" "B.Cu")
		(net "PCIE_10G_CPU_RX1_N")
	)
	(arc
		(start 319.7098 -75.8317)
		(mid 319.817446 -75.853206)
		(end 319.908682 -75.91425)
		(width 0.1397)
		(layer "F.Cu")
		(net "PCIE_10G_CPU_RX1_N")
	)
	(arc
		(start 314.251848 -75.600052)
		(mid 314.305309 -75.589418)
		(end 314.350654 -75.559158)
		(width 0.1397)
		(layer "F.Cu")
		(net "PCIE_10G_CPU_RX1_N")
	)
	(arc
		(start 316.164468 -75.371706)
		(mid 316.302343 -75.399225)
		(end 316.41923 -75.47737)
		(width 0.1397)
		(layer "F.Cu")
		(net "PCIE_10G_CPU_RX1_N")
	)
	(arc
		(start 316.41923 -75.47737)
		(mid 316.811738 -75.739572)
		(end 317.274702 -75.8317)
		(width 0.1397)
		(layer "F.Cu")
		(net "PCIE_10G_CPU_RX1_N")
	)
	(arc
		(start 314.497212 -75.4126)
		(mid 314.542545 -75.38231)
		(end 314.596018 -75.371706)
		(width 0.1397)
		(layer "F.Cu")
		(net "PCIE_10G_CPU_RX1_N")
	)
	(segment
		(start 302.254412 -75.33386)
		(end 302.635412 -75.33386)
		(width 0.127)
		(layer "In5.Cu")
		(net "PCIE_10G_CPU_RX1_N")
	)
	(segment
		(start 303.615852 -75.33386)
		(end 303.996852 -75.33386)
		(width 0.127)
		(layer "In5.Cu")
		(net "PCIE_10G_CPU_RX1_N")
	)
	(segment
		(start 150.72487 -71.731124)
		(end 152.35174 -70.104254)
		(width 0.127)
		(layer "In5.Cu")
		(net "PCIE_10G_CPU_RX1_N")
	)
	(segment
		(start 236.3216 -70.993)
		(end 297.712892 -70.993)
		(width 0.127)
		(layer "In5.Cu")
		(net "PCIE_10G_CPU_RX1_N")
	)
	(segment
		(start 309.41899 -72.656192)
		(end 309.688484 -72.386698)
		(width 0.127)
		(layer "In5.Cu")
		(net "PCIE_10G_CPU_RX1_N")
	)
	(segment
		(start 318.611758 -71.0692)
		(end 318.992758 -71.4502)
		(width 0.127)
		(layer "In5.Cu")
		(net "PCIE_10G_CPU_RX1_N")
	)
	(segment
		(start 156.390848 -67.4497)
		(end 180.23713 -67.4497)
		(width 0.127)
		(layer "In5.Cu")
		(net "PCIE_10G_CPU_RX1_N")
	)
	(segment
		(start 310.38165 -71.693532)
		(end 310.798464 -71.276718)
		(width 0.127)
		(layer "In5.Cu")
		(net "PCIE_10G_CPU_RX1_N")
	)
	(segment
		(start 302.935132 -75.184)
		(end 303.316132 -75.184)
		(width 0.127)
		(layer "In5.Cu")
		(net "PCIE_10G_CPU_RX1_N")
	)
	(segment
		(start 310.798464 -71.276718)
		(end 310.93537 -71.140066)
		(width 0.127)
		(layer "In5.Cu")
		(net "PCIE_10G_CPU_RX1_N")
	)
	(segment
		(start 298.104052 -71.155052)
		(end 299.72 -72.771)
		(width 0.127)
		(layer "In5.Cu")
		(net "PCIE_10G_CPU_RX1_N")
	)
	(segment
		(start 313.019186 -70.8406)
		(end 313.400186 -70.8406)
		(width 0.127)
		(layer "In5.Cu")
		(net "PCIE_10G_CPU_RX1_N")
	)
	(segment
		(start 150.450296 -73.75017)
		(end 150.579328 -73.879202)
		(width 0.127)
		(layer "In5.Cu")
		(net "PCIE_10G_CPU_RX1_N")
	)
	(segment
		(start 301.117 -75.184254)
		(end 301.117 -75.184)
		(width 0.127)
		(layer "In5.Cu")
		(net "PCIE_10G_CPU_RX1_N")
	)
	(segment
		(start 307.49367 -74.581512)
		(end 307.763164 -74.312018)
		(width 0.127)
		(layer "In5.Cu")
		(net "PCIE_10G_CPU_RX1_N")
	)
	(segment
		(start 310.006238 -72.28078)
		(end 310.275732 -72.011286)
		(width 0.127)
		(layer "In5.Cu")
		(net "PCIE_10G_CPU_RX1_N")
	)
	(segment
		(start 315.061346 -70.99046)
		(end 315.442346 -70.99046)
		(width 0.127)
		(layer "In5.Cu")
		(net "PCIE_10G_CPU_RX1_N")
	)
	(segment
		(start 304.977292 -75.33386)
		(end 305.358292 -75.33386)
		(width 0.127)
		(layer "In5.Cu")
		(net "PCIE_10G_CPU_RX1_N")
	)
	(segment
		(start 315.742066 -70.8406)
		(end 318.059816 -70.8406)
		(width 0.127)
		(layer "In5.Cu")
		(net "PCIE_10G_CPU_RX1_N")
	)
	(segment
		(start 149.854158 -74.554588)
		(end 149.74697 -74.4474)
		(width 0.127)
		(layer "In5.Cu")
		(net "PCIE_10G_CPU_RX1_N")
	)
	(segment
		(start 319.057782 -74.523346)
		(end 319.057782 -74.840592)
		(width 0.127)
		(layer "In5.Cu")
		(net "PCIE_10G_CPU_RX1_N")
	)
	(segment
		(start 183.063134 -66.0146)
		(end 228.96576 -66.0146)
		(width 0.127)
		(layer "In5.Cu")
		(net "PCIE_10G_CPU_RX1_N")
	)
	(segment
		(start 301.117 -75.184)
		(end 301.954692 -75.184)
		(width 0.127)
		(layer "In5.Cu")
		(net "PCIE_10G_CPU_RX1_N")
	)
	(segment
		(start 149.74697 -73.3552)
		(end 150.439628 -72.662542)
		(width 0.127)
		(layer "In5.Cu")
		(net "PCIE_10G_CPU_RX1_N")
	)
	(segment
		(start 311.658 -70.8406)
		(end 312.038746 -70.8406)
		(width 0.127)
		(layer "In5.Cu")
		(net "PCIE_10G_CPU_RX1_N")
	)
	(segment
		(start 299.72 -72.771)
		(end 299.831506 -72.88276)
		(width 0.127)
		(layer "In5.Cu")
		(net "PCIE_10G_CPU_RX1_N")
	)
	(segment
		(start 312.338466 -70.99046)
		(end 312.719466 -70.99046)
		(width 0.127)
		(layer "In5.Cu")
		(net "PCIE_10G_CPU_RX1_N")
	)
	(segment
		(start 150.579328 -74.464672)
		(end 150.489412 -74.554588)
		(width 0.127)
		(layer "In5.Cu")
		(net "PCIE_10G_CPU_RX1_N")
	)
	(segment
		(start 319.269872 -74.003662)
		(end 319.269618 -74.003916)
		(width 0.127)
		(layer "In5.Cu")
		(net "PCIE_10G_CPU_RX1_N")
	)
	(segment
		(start 230.6828 -66.7258)
		(end 233.980228 -70.023228)
		(width 0.127)
		(layer "In5.Cu")
		(net "PCIE_10G_CPU_RX1_N")
	)
	(segment
		(start 314.380626 -70.8406)
		(end 314.761626 -70.8406)
		(width 0.127)
		(layer "In5.Cu")
		(net "PCIE_10G_CPU_RX1_N")
	)
	(segment
		(start 305.658012 -75.184)
		(end 306.039012 -75.184)
		(width 0.127)
		(layer "In5.Cu")
		(net "PCIE_10G_CPU_RX1_N")
	)
	(segment
		(start 320.186558 -76.03109)
		(end 320.186558 -76.191872)
		(width 0.127)
		(layer "In5.Cu")
		(net "PCIE_10G_CPU_RX1_N")
	)
	(segment
		(start 300.101 -73.533)
		(end 300.101 -73.996804)
		(width 0.127)
		(layer "In5.Cu")
		(net "PCIE_10G_CPU_RX1_N")
	)
	(segment
		(start 304.296572 -75.184)
		(end 304.677572 -75.184)
		(width 0.127)
		(layer "In5.Cu")
		(net "PCIE_10G_CPU_RX1_N")
	)
	(segment
		(start 308.080918 -74.2061)
		(end 308.350412 -73.936606)
		(width 0.127)
		(layer "In5.Cu")
		(net "PCIE_10G_CPU_RX1_N")
	)
	(segment
		(start 181.691788 -66.847212)
		(end 182.1434 -66.3956)
		(width 0.127)
		(layer "In5.Cu")
		(net "PCIE_10G_CPU_RX1_N")
	)
	(segment
		(start 309.043578 -73.24344)
		(end 309.313072 -72.973946)
		(width 0.127)
		(layer "In5.Cu")
		(net "PCIE_10G_CPU_RX1_N")
	)
	(segment
		(start 300.411388 -74.746612)
		(end 300.659038 -74.994516)
		(width 0.127)
		(layer "In5.Cu")
		(net "PCIE_10G_CPU_RX1_N")
	)
	(segment
		(start 152.35174 -70.104)
		(end 154.02687 -68.42887)
		(width 0.127)
		(layer "In5.Cu")
		(net "PCIE_10G_CPU_RX1_N")
	)
	(segment
		(start 152.35174 -70.104254)
		(end 152.35174 -70.104)
		(width 0.127)
		(layer "In5.Cu")
		(net "PCIE_10G_CPU_RX1_N")
	)
	(segment
		(start 319.277746 -73.995788)
		(end 319.274952 -73.998328)
		(width 0.127)
		(layer "In5.Cu")
		(net "PCIE_10G_CPU_RX1_N")
	)
	(segment
		(start 150.63851 -72.182228)
		(end 150.63851 -71.939658)
		(width 0.127)
		(layer "In5.Cu")
		(net "PCIE_10G_CPU_RX1_N")
	)
	(segment
		(start 319.399158 -72.431402)
		(end 319.399158 -73.702672)
		(width 0.127)
		(layer "In5.Cu")
		(net "PCIE_10G_CPU_RX1_N")
	)
	(segment
		(start 308.45633 -73.618852)
		(end 308.725824 -73.349358)
		(width 0.127)
		(layer "In5.Cu")
		(net "PCIE_10G_CPU_RX1_N")
	)
	(segment
		(start 313.699906 -70.99046)
		(end 314.080906 -70.99046)
		(width 0.127)
		(layer "In5.Cu")
		(net "PCIE_10G_CPU_RX1_N")
	)
	(arc
		(start 310.275732 -72.011286)
		(mid 310.319624 -71.937714)
		(end 310.328818 -71.852536)
		(width 0.127)
		(layer "In5.Cu")
		(net "PCIE_10G_CPU_RX1_N")
	)
	(arc
		(start 312.719466 -70.99046)
		(mid 312.802602 -70.969396)
		(end 312.869326 -70.91553)
		(width 0.127)
		(layer "In5.Cu")
		(net "PCIE_10G_CPU_RX1_N")
	)
	(arc
		(start 315.442346 -70.99046)
		(mid 315.525482 -70.969396)
		(end 315.592206 -70.91553)
		(width 0.127)
		(layer "In5.Cu")
		(net "PCIE_10G_CPU_RX1_N")
	)
	(arc
		(start 310.93537 -71.140066)
		(mid 311.266887 -70.918427)
		(end 311.658 -70.8406)
		(width 0.127)
		(layer "In5.Cu")
		(net "PCIE_10G_CPU_RX1_N")
	)
	(arc
		(start 314.911486 -70.91553)
		(mid 314.978231 -70.969354)
		(end 315.061346 -70.99046)
		(width 0.127)
		(layer "In5.Cu")
		(net "PCIE_10G_CPU_RX1_N")
	)
	(arc
		(start 308.884828 -73.296526)
		(mid 308.970009 -73.287343)
		(end 309.043578 -73.24344)
		(width 0.127)
		(layer "In5.Cu")
		(net "PCIE_10G_CPU_RX1_N")
	)
	(arc
		(start 318.059816 -70.8406)
		(mid 318.358516 -70.900015)
		(end 318.611758 -71.0692)
		(width 0.127)
		(layer "In5.Cu")
		(net "PCIE_10G_CPU_RX1_N")
	)
	(arc
		(start 154.02687 -68.42887)
		(mid 155.111472 -67.704162)
		(end 156.390848 -67.4497)
		(width 0.127)
		(layer "In5.Cu")
		(net "PCIE_10G_CPU_RX1_N")
	)
	(arc
		(start 297.712892 -70.993)
		(mid 297.924597 -71.035111)
		(end 298.104052 -71.155052)
		(width 0.127)
		(layer "In5.Cu")
		(net "PCIE_10G_CPU_RX1_N")
	)
	(arc
		(start 300.659038 -74.994516)
		(mid 300.869153 -75.13491)
		(end 301.117 -75.184254)
		(width 0.127)
		(layer "In5.Cu")
		(net "PCIE_10G_CPU_RX1_N")
	)
	(arc
		(start 182.1434 -66.3956)
		(mid 182.565378 -66.113644)
		(end 183.063134 -66.0146)
		(width 0.127)
		(layer "In5.Cu")
		(net "PCIE_10G_CPU_RX1_N")
	)
	(arc
		(start 309.688484 -72.386698)
		(mid 309.762208 -72.342913)
		(end 309.847488 -72.333866)
		(width 0.127)
		(layer "In5.Cu")
		(net "PCIE_10G_CPU_RX1_N")
	)
	(arc
		(start 150.489412 -74.554588)
		(mid 150.171822 -74.686101)
		(end 149.854158 -74.554588)
		(width 0.127)
		(layer "In5.Cu")
		(net "PCIE_10G_CPU_RX1_N")
	)
	(arc
		(start 302.635412 -75.33386)
		(mid 302.718548 -75.312796)
		(end 302.785272 -75.25893)
		(width 0.127)
		(layer "In5.Cu")
		(net "PCIE_10G_CPU_RX1_N")
	)
	(arc
		(start 312.188606 -70.91553)
		(mid 312.255351 -70.969354)
		(end 312.338466 -70.99046)
		(width 0.127)
		(layer "In5.Cu")
		(net "PCIE_10G_CPU_RX1_N")
	)
	(arc
		(start 308.350412 -73.936606)
		(mid 308.394158 -73.863001)
		(end 308.403244 -73.777856)
		(width 0.127)
		(layer "In5.Cu")
		(net "PCIE_10G_CPU_RX1_N")
	)
	(arc
		(start 319.399158 -73.702672)
		(mid 319.367589 -73.861291)
		(end 319.277746 -73.995788)
		(width 0.127)
		(layer "In5.Cu")
		(net "PCIE_10G_CPU_RX1_N")
	)
	(arc
		(start 314.230766 -70.91553)
		(mid 314.297511 -70.861706)
		(end 314.380626 -70.8406)
		(width 0.127)
		(layer "In5.Cu")
		(net "PCIE_10G_CPU_RX1_N")
	)
	(arc
		(start 228.96576 -66.0146)
		(mid 229.895007 -66.199439)
		(end 230.6828 -66.7258)
		(width 0.127)
		(layer "In5.Cu")
		(net "PCIE_10G_CPU_RX1_N")
	)
	(arc
		(start 304.677572 -75.184)
		(mid 304.760708 -75.205064)
		(end 304.827432 -75.25893)
		(width 0.127)
		(layer "In5.Cu")
		(net "PCIE_10G_CPU_RX1_N")
	)
	(arc
		(start 314.080906 -70.99046)
		(mid 314.164042 -70.969396)
		(end 314.230766 -70.91553)
		(width 0.127)
		(layer "In5.Cu")
		(net "PCIE_10G_CPU_RX1_N")
	)
	(arc
		(start 309.366158 -72.815196)
		(mid 309.375152 -72.729899)
		(end 309.41899 -72.656192)
		(width 0.127)
		(layer "In5.Cu")
		(net "PCIE_10G_CPU_RX1_N")
	)
	(arc
		(start 319.274952 -73.998328)
		(mid 319.272366 -74.000951)
		(end 319.269872 -74.003662)
		(width 0.127)
		(layer "In5.Cu")
		(net "PCIE_10G_CPU_RX1_N")
	)
	(arc
		(start 180.23713 -67.4497)
		(mid 181.02438 -67.293124)
		(end 181.691788 -66.847212)
		(width 0.127)
		(layer "In5.Cu")
		(net "PCIE_10G_CPU_RX1_N")
	)
	(arc
		(start 150.579328 -73.879202)
		(mid 150.70071 -74.171974)
		(end 150.579328 -74.464672)
		(width 0.127)
		(layer "In5.Cu")
		(net "PCIE_10G_CPU_RX1_N")
	)
	(arc
		(start 149.74697 -74.4474)
		(mid 149.520768 -73.9013)
		(end 149.74697 -73.3552)
		(width 0.127)
		(layer "In5.Cu")
		(net "PCIE_10G_CPU_RX1_N")
	)
	(arc
		(start 150.439628 -72.662542)
		(mid 150.586821 -72.442158)
		(end 150.63851 -72.182228)
		(width 0.127)
		(layer "In5.Cu")
		(net "PCIE_10G_CPU_RX1_N")
	)
	(arc
		(start 304.146712 -75.25893)
		(mid 304.213457 -75.205106)
		(end 304.296572 -75.184)
		(width 0.127)
		(layer "In5.Cu")
		(net "PCIE_10G_CPU_RX1_N")
	)
	(arc
		(start 309.847488 -72.333866)
		(mid 309.93268 -72.324691)
		(end 310.006238 -72.28078)
		(width 0.127)
		(layer "In5.Cu")
		(net "PCIE_10G_CPU_RX1_N")
	)
	(arc
		(start 302.104552 -75.25893)
		(mid 302.171297 -75.312754)
		(end 302.254412 -75.33386)
		(width 0.127)
		(layer "In5.Cu")
		(net "PCIE_10G_CPU_RX1_N")
	)
	(arc
		(start 233.980228 -70.023228)
		(mid 235.054473 -70.740952)
		(end 236.3216 -70.993)
		(width 0.127)
		(layer "In5.Cu")
		(net "PCIE_10G_CPU_RX1_N")
	)
	(arc
		(start 318.992758 -71.4502)
		(mid 319.293529 -71.90038)
		(end 319.399158 -72.431402)
		(width 0.127)
		(layer "In5.Cu")
		(net "PCIE_10G_CPU_RX1_N")
	)
	(arc
		(start 313.400186 -70.8406)
		(mid 313.483322 -70.861664)
		(end 313.550046 -70.91553)
		(width 0.127)
		(layer "In5.Cu")
		(net "PCIE_10G_CPU_RX1_N")
	)
	(arc
		(start 304.827432 -75.25893)
		(mid 304.894177 -75.312754)
		(end 304.977292 -75.33386)
		(width 0.127)
		(layer "In5.Cu")
		(net "PCIE_10G_CPU_RX1_N")
	)
	(arc
		(start 313.550046 -70.91553)
		(mid 313.616791 -70.969354)
		(end 313.699906 -70.99046)
		(width 0.127)
		(layer "In5.Cu")
		(net "PCIE_10G_CPU_RX1_N")
	)
	(arc
		(start 301.954692 -75.184)
		(mid 302.037828 -75.205064)
		(end 302.104552 -75.25893)
		(width 0.127)
		(layer "In5.Cu")
		(net "PCIE_10G_CPU_RX1_N")
	)
	(arc
		(start 302.785272 -75.25893)
		(mid 302.852017 -75.205106)
		(end 302.935132 -75.184)
		(width 0.127)
		(layer "In5.Cu")
		(net "PCIE_10G_CPU_RX1_N")
	)
	(arc
		(start 307.763164 -74.312018)
		(mid 307.836769 -74.268272)
		(end 307.921914 -74.259186)
		(width 0.127)
		(layer "In5.Cu")
		(net "PCIE_10G_CPU_RX1_N")
	)
	(arc
		(start 314.761626 -70.8406)
		(mid 314.844762 -70.861664)
		(end 314.911486 -70.91553)
		(width 0.127)
		(layer "In5.Cu")
		(net "PCIE_10G_CPU_RX1_N")
	)
	(arc
		(start 299.831506 -72.88276)
		(mid 300.030928 -73.181078)
		(end 300.101 -73.533)
		(width 0.127)
		(layer "In5.Cu")
		(net "PCIE_10G_CPU_RX1_N")
	)
	(arc
		(start 312.869326 -70.91553)
		(mid 312.936071 -70.861706)
		(end 313.019186 -70.8406)
		(width 0.127)
		(layer "In5.Cu")
		(net "PCIE_10G_CPU_RX1_N")
	)
	(arc
		(start 310.328818 -71.852536)
		(mid 310.337812 -71.767239)
		(end 310.38165 -71.693532)
		(width 0.127)
		(layer "In5.Cu")
		(net "PCIE_10G_CPU_RX1_N")
	)
	(arc
		(start 300.101 -73.996804)
		(mid 300.181635 -74.402563)
		(end 300.411388 -74.746612)
		(width 0.127)
		(layer "In5.Cu")
		(net "PCIE_10G_CPU_RX1_N")
	)
	(arc
		(start 312.038746 -70.8406)
		(mid 312.121882 -70.861664)
		(end 312.188606 -70.91553)
		(width 0.127)
		(layer "In5.Cu")
		(net "PCIE_10G_CPU_RX1_N")
	)
	(arc
		(start 308.403244 -73.777856)
		(mid 308.412353 -73.692521)
		(end 308.45633 -73.618852)
		(width 0.127)
		(layer "In5.Cu")
		(net "PCIE_10G_CPU_RX1_N")
	)
	(arc
		(start 315.592206 -70.91553)
		(mid 315.658951 -70.861706)
		(end 315.742066 -70.8406)
		(width 0.127)
		(layer "In5.Cu")
		(net "PCIE_10G_CPU_RX1_N")
	)
	(arc
		(start 150.63851 -71.939658)
		(mid 150.660957 -71.826807)
		(end 150.72487 -71.731124)
		(width 0.127)
		(layer "In5.Cu")
		(net "PCIE_10G_CPU_RX1_N")
	)
	(arc
		(start 319.842896 -75.704446)
		(mid 320.08476 -75.794058)
		(end 320.186558 -76.03109)
		(width 0.127)
		(layer "In5.Cu")
		(net "PCIE_10G_CPU_RX1_N")
	)
	(arc
		(start 305.508152 -75.25893)
		(mid 305.574897 -75.205106)
		(end 305.658012 -75.184)
		(width 0.127)
		(layer "In5.Cu")
		(net "PCIE_10G_CPU_RX1_N")
	)
	(arc
		(start 306.039012 -75.184)
		(mid 306.826248 -75.027409)
		(end 307.49367 -74.581512)
		(width 0.127)
		(layer "In5.Cu")
		(net "PCIE_10G_CPU_RX1_N")
	)
	(arc
		(start 303.996852 -75.33386)
		(mid 304.079988 -75.312796)
		(end 304.146712 -75.25893)
		(width 0.127)
		(layer "In5.Cu")
		(net "PCIE_10G_CPU_RX1_N")
	)
	(arc
		(start 308.725824 -73.349358)
		(mid 308.799548 -73.305573)
		(end 308.884828 -73.296526)
		(width 0.127)
		(layer "In5.Cu")
		(net "PCIE_10G_CPU_RX1_N")
	)
	(arc
		(start 305.358292 -75.33386)
		(mid 305.441428 -75.312796)
		(end 305.508152 -75.25893)
		(width 0.127)
		(layer "In5.Cu")
		(net "PCIE_10G_CPU_RX1_N")
	)
	(arc
		(start 303.316132 -75.184)
		(mid 303.399268 -75.205064)
		(end 303.465992 -75.25893)
		(width 0.127)
		(layer "In5.Cu")
		(net "PCIE_10G_CPU_RX1_N")
	)
	(arc
		(start 309.313072 -72.973946)
		(mid 309.356964 -72.900374)
		(end 309.366158 -72.815196)
		(width 0.127)
		(layer "In5.Cu")
		(net "PCIE_10G_CPU_RX1_N")
	)
	(arc
		(start 319.269618 -74.003916)
		(mid 319.112818 -74.242874)
		(end 319.057782 -74.523346)
		(width 0.127)
		(layer "In5.Cu")
		(net "PCIE_10G_CPU_RX1_N")
	)
	(arc
		(start 307.921914 -74.259186)
		(mid 308.007238 -74.250069)
		(end 308.080918 -74.2061)
		(width 0.127)
		(layer "In5.Cu")
		(net "PCIE_10G_CPU_RX1_N")
	)
	(arc
		(start 319.057782 -74.840592)
		(mid 319.129687 -75.202085)
		(end 319.334388 -75.508612)
		(width 0.127)
		(layer "In5.Cu")
		(net "PCIE_10G_CPU_RX1_N")
	)
	(arc
		(start 319.334388 -75.508612)
		(mid 319.567871 -75.660438)
		(end 319.842896 -75.704446)
		(width 0.127)
		(layer "In5.Cu")
		(net "PCIE_10G_CPU_RX1_N")
	)
	(arc
		(start 303.465992 -75.25893)
		(mid 303.532737 -75.312754)
		(end 303.615852 -75.33386)
		(width 0.127)
		(layer "In5.Cu")
		(net "PCIE_10G_CPU_RX1_N")
	)
	(segment
		(start 283.697426 -185.088022)
		(end 283.697426 -185.447178)
		(width 0.1143)
		(layer "F.Cu")
		(net "OSC0_AS_CLKIN")
	)
	(segment
		(start 283.697426 -185.447178)
		(end 283.0703 -186.074304)
		(width 0.1143)
		(layer "F.Cu")
		(net "OSC0_AS_CLKIN")
	)
	(segment
		(start 282.413202 -188.374274)
		(end 283.0703 -187.717176)
		(width 0.1143)
		(layer "F.Cu")
		(net "OSC0_AS_CLKIN")
	)
	(segment
		(start 284.293818 -184.24017)
		(end 283.862526 -184.671462)
		(width 0.1143)
		(layer "F.Cu")
		(net "OSC0_AS_CLKIN")
	)
	(segment
		(start 283.862526 -184.671462)
		(end 283.862526 -184.922922)
		(width 0.1143)
		(layer "F.Cu")
		(net "OSC0_AS_CLKIN")
	)
	(segment
		(start 282.351226 -188.374274)
		(end 282.413202 -188.374274)
		(width 0.1143)
		(layer "F.Cu")
		(net "OSC0_AS_CLKIN")
	)
	(segment
		(start 284.834838 -184.24017)
		(end 284.293818 -184.24017)
		(width 0.1143)
		(layer "F.Cu")
		(net "OSC0_AS_CLKIN")
	)
	(segment
		(start 283.0703 -186.074304)
		(end 283.0703 -186.8297)
		(width 0.1143)
		(layer "F.Cu")
		(net "OSC0_AS_CLKIN")
	)
	(segment
		(start 283.0703 -187.717176)
		(end 283.0703 -186.8297)
		(width 0.1143)
		(layer "F.Cu")
		(net "OSC0_AS_CLKIN")
	)
	(segment
		(start 283.862526 -184.922922)
		(end 283.697426 -185.088022)
		(width 0.1143)
		(layer "F.Cu")
		(net "OSC0_AS_CLKIN")
	)
	(segment
		(start 282.194 -188.5315)
		(end 282.351226 -188.374274)
		(width 0.1143)
		(layer "F.Cu")
		(net "OSC0_AS_CLKIN")
	)
	(via
		(at 283.0703 -186.8297)
		(size 0.7112)
		(drill 0.3556)
		(layers "F.Cu" "B.Cu")
		(net "OSC0_AS_CLKIN")
	)
	(segment
		(start 296.276522 -186.21375)
		(end 296.390822 -186.32805)
		(width 0.1143)
		(layer "F.Cu")
		(net "MEMDQ_10")
	)
	(segment
		(start 296.733722 -187.6552)
		(end 296.848022 -187.5409)
		(width 0.1143)
		(layer "F.Cu")
		(net "MEMDQ_10")
	)
	(segment
		(start 296.018204 -186.21375)
		(end 296.276522 -186.21375)
		(width 0.1143)
		(layer "F.Cu")
		(net "MEMDQ_10")
	)
	(segment
		(start 297.222672 -185.9534)
		(end 297.74642 -185.9534)
		(width 0.1143)
		(layer "F.Cu")
		(net "MEMDQ_10")
	)
	(segment
		(start 295.234868 -183.44007)
		(end 295.529 -183.44007)
		(width 0.1143)
		(layer "F.Cu")
		(net "MEMDQ_10")
	)
	(segment
		(start 296.390822 -186.32805)
		(end 296.390822 -187.5409)
		(width 0.1143)
		(layer "F.Cu")
		(net "MEMDQ_10")
	)
	(segment
		(start 296.89806 -197.73519)
		(end 297.12793 -197.73519)
		(width 0.1143)
		(layer "F.Cu")
		(net "MEMDQ_10")
	)
	(segment
		(start 297.74642 -185.9534)
		(end 298.45 -186.65698)
		(width 0.1143)
		(layer "F.Cu")
		(net "MEMDQ_10")
	)
	(segment
		(start 296.848022 -186.32805)
		(end 297.222672 -185.9534)
		(width 0.1143)
		(layer "F.Cu")
		(net "MEMDQ_10")
	)
	(segment
		(start 297.411648 -197.451472)
		(end 297.461432 -197.451472)
		(width 0.1143)
		(layer "F.Cu")
		(net "MEMDQ_10")
	)
	(segment
		(start 295.656 -185.851546)
		(end 296.018204 -186.21375)
		(width 0.1143)
		(layer "F.Cu")
		(net "MEMDQ_10")
	)
	(segment
		(start 295.656 -183.56707)
		(end 295.656 -185.851546)
		(width 0.1143)
		(layer "F.Cu")
		(net "MEMDQ_10")
	)
	(segment
		(start 296.848022 -187.5409)
		(end 296.848022 -186.32805)
		(width 0.1143)
		(layer "F.Cu")
		(net "MEMDQ_10")
	)
	(segment
		(start 297.12793 -197.73519)
		(end 297.411648 -197.451472)
		(width 0.1143)
		(layer "F.Cu")
		(net "MEMDQ_10")
	)
	(segment
		(start 296.505122 -187.6552)
		(end 296.733722 -187.6552)
		(width 0.1143)
		(layer "F.Cu")
		(net "MEMDQ_10")
	)
	(segment
		(start 296.390822 -187.5409)
		(end 296.505122 -187.6552)
		(width 0.1143)
		(layer "F.Cu")
		(net "MEMDQ_10")
	)
	(segment
		(start 295.529 -183.44007)
		(end 295.656 -183.56707)
		(width 0.1143)
		(layer "F.Cu")
		(net "MEMDQ_10")
	)
	(via
		(at 297.461432 -197.451472)
		(size 0.508)
		(drill 0.254)
		(layers "F.Cu" "B.Cu")
		(net "MEMDQ_10")
	)
	(via
		(at 298.45 -186.65698)
		(size 0.508)
		(drill 0.254)
		(layers "F.Cu" "B.Cu")
		(net "MEMDQ_10")
	)
	(via
		(at 298.2214 -196.8246)
		(size 0.7112)
		(drill 0.3556)
		(layers "F.Cu" "B.Cu")
		(net "MEMDQ_10")
	)
	(segment
		(start 297.461432 -197.451472)
		(end 297.594528 -197.451472)
		(width 0.1143)
		(layer "B.Cu")
		(net "MEMDQ_10")
	)
	(segment
		(start 297.594528 -197.451472)
		(end 298.2214 -196.8246)
		(width 0.1143)
		(layer "B.Cu")
		(net "MEMDQ_10")
	)
	(segment
		(start 298.6278 -196.285104)
		(end 297.461432 -197.451472)
		(width 0.127)
		(layer "In5.Cu")
		(net "MEMDQ_10")
	)
	(segment
		(start 298.45 -186.65698)
		(end 298.6278 -186.83478)
		(width 0.127)
		(layer "In5.Cu")
		(net "MEMDQ_10")
	)
	(segment
		(start 298.6278 -186.83478)
		(end 298.6278 -196.285104)
		(width 0.127)
		(layer "In5.Cu")
		(net "MEMDQ_10")
	)
	(segment
		(start 307.090318 -76.6318)
		(end 298.6278 -76.6318)
		(width 0.1397)
		(layer "F.Cu")
		(net "PCIE_10G_CPU_TX2_P")
	)
	(segment
		(start 307.25237 -76.54163)
		(end 307.213 -76.581)
		(width 0.1397)
		(layer "F.Cu")
		(net "PCIE_10G_CPU_TX2_P")
	)
	(segment
		(start 297.207432 -82.073496)
		(end 297.05681 -82.223864)
		(width 0.1397)
		(layer "F.Cu")
		(net "PCIE_10G_CPU_TX2_P")
	)
	(segment
		(start 297.37812 -77.88148)
		(end 297.37812 -81.661)
		(width 0.1397)
		(layer "F.Cu")
		(net "PCIE_10G_CPU_TX2_P")
	)
	(segment
		(start 308.675024 -76.400152)
		(end 307.594 -76.400152)
		(width 0.1397)
		(layer "F.Cu")
		(net "PCIE_10G_CPU_TX2_P")
	)
	(via
		(at 297.05681 -82.223864)
		(size 0.5588)
		(drill 0.3048)
		(layers "F.Cu" "B.Cu")
		(net "PCIE_10G_CPU_TX2_P")
	)
	(arc
		(start 297.37812 -81.661)
		(mid 297.333811 -81.884229)
		(end 297.207432 -82.073496)
		(width 0.1397)
		(layer "F.Cu")
		(net "PCIE_10G_CPU_TX2_P")
	)
	(arc
		(start 307.594 -76.400152)
		(mid 307.409123 -76.436926)
		(end 307.25237 -76.54163)
		(width 0.1397)
		(layer "F.Cu")
		(net "PCIE_10G_CPU_TX2_P")
	)
	(arc
		(start 298.6278 -76.6318)
		(mid 297.744143 -76.997823)
		(end 297.37812 -77.88148)
		(width 0.1397)
		(layer "F.Cu")
		(net "PCIE_10G_CPU_TX2_P")
	)
	(arc
		(start 307.213 -76.581)
		(mid 307.156713 -76.61861)
		(end 307.090318 -76.6318)
		(width 0.1397)
		(layer "F.Cu")
		(net "PCIE_10G_CPU_TX2_P")
	)
	(segment
		(start 297.124374 -83.240626)
		(end 297.307 -83.058)
		(width 0.127)
		(layer "In5.Cu")
		(net "PCIE_10G_CPU_TX2_P")
	)
	(segment
		(start 145.126964 -79.18196)
		(end 145.239994 -79.238602)
		(width 0.127)
		(layer "In5.Cu")
		(net "PCIE_10G_CPU_TX2_P")
	)
	(segment
		(start 147.477734 -82.042)
		(end 149.225 -82.042)
		(width 0.127)
		(layer "In5.Cu")
		(net "PCIE_10G_CPU_TX2_P")
	)
	(segment
		(start 145.450306 -78.24978)
		(end 145.069306 -79.011018)
		(width 0.127)
		(layer "In5.Cu")
		(net "PCIE_10G_CPU_TX2_P")
	)
	(segment
		(start 145.239994 -79.238602)
		(end 145.276824 -79.257144)
		(width 0.127)
		(layer "In5.Cu")
		(net "PCIE_10G_CPU_TX2_P")
	)
	(segment
		(start 145.126202 -79.181452)
		(end 145.126964 -79.18196)
		(width 0.127)
		(layer "In5.Cu")
		(net "PCIE_10G_CPU_TX2_P")
	)
	(segment
		(start 297.280584 -82.447638)
		(end 297.05681 -82.223864)
		(width 0.127)
		(layer "In5.Cu")
		(net "PCIE_10G_CPU_TX2_P")
	)
	(segment
		(start 146.05 -81.153)
		(end 146.558 -81.661)
		(width 0.127)
		(layer "In5.Cu")
		(net "PCIE_10G_CPU_TX2_P")
	)
	(segment
		(start 297.37558 -82.892392)
		(end 297.37558 -82.677)
		(width 0.127)
		(layer "In5.Cu")
		(net "PCIE_10G_CPU_TX2_P")
	)
	(segment
		(start 145.788888 -80.891634)
		(end 146.05 -81.153)
		(width 0.127)
		(layer "In5.Cu")
		(net "PCIE_10G_CPU_TX2_P")
	)
	(segment
		(start 151.561546 -83.4136)
		(end 296.706798 -83.4136)
		(width 0.127)
		(layer "In5.Cu")
		(net "PCIE_10G_CPU_TX2_P")
	)
	(segment
		(start 145.58137 -79.94015)
		(end 145.58137 -80.391)
		(width 0.127)
		(layer "In5.Cu")
		(net "PCIE_10G_CPU_TX2_P")
	)
	(segment
		(start 145.125948 -79.181452)
		(end 145.126202 -79.181452)
		(width 0.127)
		(layer "In5.Cu")
		(net "PCIE_10G_CPU_TX2_P")
	)
	(segment
		(start 150.289514 -82.482944)
		(end 150.97887 -83.1723)
		(width 0.127)
		(layer "In5.Cu")
		(net "PCIE_10G_CPU_TX2_P")
	)
	(arc
		(start 296.706798 -83.4136)
		(mid 296.932792 -83.368647)
		(end 297.124374 -83.240626)
		(width 0.127)
		(layer "In5.Cu")
		(net "PCIE_10G_CPU_TX2_P")
	)
	(arc
		(start 297.307 -83.058)
		(mid 297.357769 -82.982018)
		(end 297.37558 -82.892392)
		(width 0.127)
		(layer "In5.Cu")
		(net "PCIE_10G_CPU_TX2_P")
	)
	(arc
		(start 145.58137 -80.391)
		(mid 145.635358 -80.661944)
		(end 145.788888 -80.891634)
		(width 0.127)
		(layer "In5.Cu")
		(net "PCIE_10G_CPU_TX2_P")
	)
	(arc
		(start 145.312384 -79.290926)
		(mid 145.511441 -79.588792)
		(end 145.58137 -79.94015)
		(width 0.127)
		(layer "In5.Cu")
		(net "PCIE_10G_CPU_TX2_P")
	)
	(arc
		(start 149.225 -82.042)
		(mid 149.801114 -82.156596)
		(end 150.289514 -82.482944)
		(width 0.127)
		(layer "In5.Cu")
		(net "PCIE_10G_CPU_TX2_P")
	)
	(arc
		(start 146.558 -81.661)
		(mid 146.979978 -81.942956)
		(end 147.477734 -82.042)
		(width 0.127)
		(layer "In5.Cu")
		(net "PCIE_10G_CPU_TX2_P")
	)
	(arc
		(start 150.97887 -83.1723)
		(mid 151.246204 -83.350927)
		(end 151.561546 -83.4136)
		(width 0.127)
		(layer "In5.Cu")
		(net "PCIE_10G_CPU_TX2_P")
	)
	(arc
		(start 145.276824 -79.257144)
		(mid 145.294828 -79.273799)
		(end 145.312384 -79.290926)
		(width 0.127)
		(layer "In5.Cu")
		(net "PCIE_10G_CPU_TX2_P")
	)
	(arc
		(start 297.37558 -82.677)
		(mid 297.35089 -82.552874)
		(end 297.280584 -82.447638)
		(width 0.127)
		(layer "In5.Cu")
		(net "PCIE_10G_CPU_TX2_P")
	)
	(arc
		(start 145.069306 -79.011018)
		(mid 145.062329 -79.107966)
		(end 145.125948 -79.181452)
		(width 0.127)
		(layer "In5.Cu")
		(net "PCIE_10G_CPU_TX2_P")
	)
	(segment
		(start 67.159886 -111.595916)
		(end 67.159886 -110.408212)
		(width 0.254)
		(layer "F.Cu")
		(net "P1V8_EN_G")
	)
	(segment
		(start 67.159886 -110.408212)
		(end 67.191636 -110.376462)
		(width 0.254)
		(layer "F.Cu")
		(net "P1V8_EN_G")
	)
	(segment
		(start 67.191636 -110.376462)
		(end 68.810886 -110.376462)
		(width 0.254)
		(layer "F.Cu")
		(net "P1V8_EN_G")
	)
	(via
		(at 67.159886 -111.595916)
		(size 0.7112)
		(drill 0.3556)
		(layers "F.Cu" "B.Cu")
		(net "P1V8_EN_G")
	)
	(segment
		(start 306.937156 -76.9747)
		(end 298.6278 -76.9747)
		(width 0.1397)
		(layer "F.Cu")
		(net "PCIE_10G_CPU_TX2_N")
	)
	(segment
		(start 297.940222 -82.19059)
		(end 297.97375 -82.223864)
		(width 0.1397)
		(layer "F.Cu")
		(net "PCIE_10G_CPU_TX2_N")
	)
	(segment
		(start 297.72102 -77.88148)
		(end 297.72102 -81.661)
		(width 0.1397)
		(layer "F.Cu")
		(net "PCIE_10G_CPU_TX2_N")
	)
	(segment
		(start 308.675024 -77.199998)
		(end 307.48097 -77.199998)
		(width 0.1397)
		(layer "F.Cu")
		(net "PCIE_10G_CPU_TX2_N")
	)
	(via
		(at 297.97375 -82.223864)
		(size 0.5588)
		(drill 0.3048)
		(layers "F.Cu" "B.Cu")
		(net "PCIE_10G_CPU_TX2_N")
	)
	(arc
		(start 307.48097 -77.199998)
		(mid 307.335945 -77.171151)
		(end 307.213 -77.089)
		(width 0.1397)
		(layer "F.Cu")
		(net "PCIE_10G_CPU_TX2_N")
	)
	(arc
		(start 298.6278 -76.9747)
		(mid 297.98661 -77.24029)
		(end 297.72102 -77.88148)
		(width 0.1397)
		(layer "F.Cu")
		(net "PCIE_10G_CPU_TX2_N")
	)
	(arc
		(start 297.72102 -81.661)
		(mid 297.777935 -81.947604)
		(end 297.940222 -82.19059)
		(width 0.1397)
		(layer "F.Cu")
		(net "PCIE_10G_CPU_TX2_N")
	)
	(arc
		(start 307.213 -77.089)
		(mid 307.086442 -77.004436)
		(end 306.937156 -76.9747)
		(width 0.1397)
		(layer "F.Cu")
		(net "PCIE_10G_CPU_TX2_N")
	)
	(segment
		(start 150.091902 -82.680556)
		(end 150.781258 -83.369912)
		(width 0.127)
		(layer "In5.Cu")
		(net "PCIE_10G_CPU_TX2_N")
	)
	(segment
		(start 147.47748 -82.3214)
		(end 149.225 -82.3214)
		(width 0.127)
		(layer "In5.Cu")
		(net "PCIE_10G_CPU_TX2_N")
	)
	(segment
		(start 297.321986 -83.438238)
		(end 297.504612 -83.255612)
		(width 0.127)
		(layer "In5.Cu")
		(net "PCIE_10G_CPU_TX2_N")
	)
	(segment
		(start 145.852388 -81.350612)
		(end 146.360388 -81.858612)
		(width 0.127)
		(layer "In5.Cu")
		(net "PCIE_10G_CPU_TX2_N")
	)
	(segment
		(start 297.65498 -82.892392)
		(end 297.65498 -82.677)
		(width 0.127)
		(layer "In5.Cu")
		(net "PCIE_10G_CPU_TX2_N")
	)
	(segment
		(start 144.449546 -80.25003)
		(end 144.8308 -79.488284)
		(width 0.127)
		(layer "In5.Cu")
		(net "PCIE_10G_CPU_TX2_N")
	)
	(segment
		(start 145.001488 -79.431642)
		(end 145.114518 -79.488538)
		(width 0.127)
		(layer "In5.Cu")
		(net "PCIE_10G_CPU_TX2_N")
	)
	(segment
		(start 145.591276 -81.089246)
		(end 145.852388 -81.350612)
		(width 0.127)
		(layer "In5.Cu")
		(net "PCIE_10G_CPU_TX2_N")
	)
	(segment
		(start 145.001234 -79.431642)
		(end 145.001488 -79.431642)
		(width 0.127)
		(layer "In5.Cu")
		(net "PCIE_10G_CPU_TX2_N")
	)
	(segment
		(start 297.749976 -82.447638)
		(end 297.97375 -82.223864)
		(width 0.127)
		(layer "In5.Cu")
		(net "PCIE_10G_CPU_TX2_N")
	)
	(segment
		(start 151.561546 -83.693)
		(end 296.707052 -83.693)
		(width 0.127)
		(layer "In5.Cu")
		(net "PCIE_10G_CPU_TX2_N")
	)
	(segment
		(start 145.30197 -79.940404)
		(end 145.30197 -80.391254)
		(width 0.127)
		(layer "In5.Cu")
		(net "PCIE_10G_CPU_TX2_N")
	)
	(arc
		(start 297.504612 -83.255612)
		(mid 297.615962 -83.088965)
		(end 297.65498 -82.892392)
		(width 0.127)
		(layer "In5.Cu")
		(net "PCIE_10G_CPU_TX2_N")
	)
	(arc
		(start 145.114518 -79.488538)
		(mid 145.25318 -79.695827)
		(end 145.30197 -79.940404)
		(width 0.127)
		(layer "In5.Cu")
		(net "PCIE_10G_CPU_TX2_N")
	)
	(arc
		(start 150.781258 -83.369912)
		(mid 151.139272 -83.609036)
		(end 151.561546 -83.693)
		(width 0.127)
		(layer "In5.Cu")
		(net "PCIE_10G_CPU_TX2_N")
	)
	(arc
		(start 145.30197 -80.391254)
		(mid 145.377191 -80.769037)
		(end 145.591276 -81.089246)
		(width 0.127)
		(layer "In5.Cu")
		(net "PCIE_10G_CPU_TX2_N")
	)
	(arc
		(start 144.8308 -79.488284)
		(mid 144.904286 -79.424665)
		(end 145.001234 -79.431642)
		(width 0.127)
		(layer "In5.Cu")
		(net "PCIE_10G_CPU_TX2_N")
	)
	(arc
		(start 296.707052 -83.693)
		(mid 297.039831 -83.62673)
		(end 297.321986 -83.438238)
		(width 0.127)
		(layer "In5.Cu")
		(net "PCIE_10G_CPU_TX2_N")
	)
	(arc
		(start 297.65498 -82.677)
		(mid 297.67967 -82.552874)
		(end 297.749976 -82.447638)
		(width 0.127)
		(layer "In5.Cu")
		(net "PCIE_10G_CPU_TX2_N")
	)
	(arc
		(start 146.360388 -81.858612)
		(mid 146.872913 -82.2011)
		(end 147.47748 -82.3214)
		(width 0.127)
		(layer "In5.Cu")
		(net "PCIE_10G_CPU_TX2_N")
	)
	(arc
		(start 149.225 -82.3214)
		(mid 149.694178 -82.414743)
		(end 150.091902 -82.680556)
		(width 0.127)
		(layer "In5.Cu")
		(net "PCIE_10G_CPU_TX2_N")
	)
	(segment
		(start 295.5544 -188.5696)
		(end 295.40835 -188.42355)
		(width 0.1143)
		(layer "F.Cu")
		(net "MEMDQ_9")
	)
	(segment
		(start 295.8338 -187.538614)
		(end 295.7195 -187.424314)
		(width 0.1143)
		(layer "F.Cu")
		(net "MEMDQ_9")
	)
	(segment
		(start 295.40835 -187.310014)
		(end 295.40835 -187.081414)
		(width 0.1143)
		(layer "F.Cu")
		(net "MEMDQ_9")
	)
	(segment
		(start 295.7195 -186.509914)
		(end 295.52265 -186.509914)
		(width 0.1143)
		(layer "F.Cu")
		(net "MEMDQ_9")
	)
	(segment
		(start 295.8338 -186.624214)
		(end 295.7195 -186.509914)
		(width 0.1143)
		(layer "F.Cu")
		(net "MEMDQ_9")
	)
	(segment
		(start 295.52265 -187.881514)
		(end 295.7195 -187.881514)
		(width 0.1143)
		(layer "F.Cu")
		(net "MEMDQ_9")
	)
	(segment
		(start 295.52265 -187.424314)
		(end 295.40835 -187.310014)
		(width 0.1143)
		(layer "F.Cu")
		(net "MEMDQ_9")
	)
	(segment
		(start 295.7195 -187.881514)
		(end 295.8338 -187.767214)
		(width 0.1143)
		(layer "F.Cu")
		(net "MEMDQ_9")
	)
	(segment
		(start 296.640758 -188.5696)
		(end 295.5544 -188.5696)
		(width 0.1143)
		(layer "F.Cu")
		(net "MEMDQ_9")
	)
	(segment
		(start 295.40835 -187.995814)
		(end 295.52265 -187.881514)
		(width 0.1143)
		(layer "F.Cu")
		(net "MEMDQ_9")
	)
	(segment
		(start 297.5483 -187.653168)
		(end 297.319446 -187.882022)
		(width 0.1143)
		(layer "F.Cu")
		(net "MEMDQ_9")
	)
	(segment
		(start 297.561 -186.36615)
		(end 297.5483 -186.37885)
		(width 0.1143)
		(layer "F.Cu")
		(net "MEMDQ_9")
	)
	(segment
		(start 295.8338 -187.767214)
		(end 295.8338 -187.538614)
		(width 0.1143)
		(layer "F.Cu")
		(net "MEMDQ_9")
	)
	(segment
		(start 296.48404 -197.32498)
		(end 296.500804 -197.341744)
		(width 0.1143)
		(layer "F.Cu")
		(net "MEMDQ_9")
	)
	(segment
		(start 297.319446 -187.890912)
		(end 296.640758 -188.5696)
		(width 0.1143)
		(layer "F.Cu")
		(net "MEMDQ_9")
	)
	(segment
		(start 295.52265 -186.967114)
		(end 295.7195 -186.967114)
		(width 0.1143)
		(layer "F.Cu")
		(net "MEMDQ_9")
	)
	(segment
		(start 295.7195 -186.967114)
		(end 295.8338 -186.852814)
		(width 0.1143)
		(layer "F.Cu")
		(net "MEMDQ_9")
	)
	(segment
		(start 295.52265 -186.509914)
		(end 295.40835 -186.395614)
		(width 0.1143)
		(layer "F.Cu")
		(net "MEMDQ_9")
	)
	(segment
		(start 297.5483 -186.37885)
		(end 297.5483 -187.653168)
		(width 0.1143)
		(layer "F.Cu")
		(net "MEMDQ_9")
	)
	(segment
		(start 295.8338 -186.852814)
		(end 295.8338 -186.624214)
		(width 0.1143)
		(layer "F.Cu")
		(net "MEMDQ_9")
	)
	(segment
		(start 295.40835 -187.081414)
		(end 295.52265 -186.967114)
		(width 0.1143)
		(layer "F.Cu")
		(net "MEMDQ_9")
	)
	(segment
		(start 297.319446 -187.882022)
		(end 297.319446 -187.890912)
		(width 0.1143)
		(layer "F.Cu")
		(net "MEMDQ_9")
	)
	(segment
		(start 296.09796 -196.93509)
		(end 296.48404 -197.32117)
		(width 0.1143)
		(layer "F.Cu")
		(net "MEMDQ_9")
	)
	(segment
		(start 295.7195 -187.424314)
		(end 295.52265 -187.424314)
		(width 0.1143)
		(layer "F.Cu")
		(net "MEMDQ_9")
	)
	(segment
		(start 296.48404 -197.32117)
		(end 296.48404 -197.32498)
		(width 0.1143)
		(layer "F.Cu")
		(net "MEMDQ_9")
	)
	(segment
		(start 295.40835 -186.100212)
		(end 295.234868 -185.92673)
		(width 0.1143)
		(layer "F.Cu")
		(net "MEMDQ_9")
	)
	(segment
		(start 295.40835 -186.395614)
		(end 295.40835 -186.100212)
		(width 0.1143)
		(layer "F.Cu")
		(net "MEMDQ_9")
	)
	(segment
		(start 295.40835 -188.42355)
		(end 295.40835 -187.995814)
		(width 0.1143)
		(layer "F.Cu")
		(net "MEMDQ_9")
	)
	(segment
		(start 295.234868 -185.92673)
		(end 295.234868 -184.24017)
		(width 0.1143)
		(layer "F.Cu")
		(net "MEMDQ_9")
	)
	(via
		(at 296.500804 -197.341744)
		(size 0.508)
		(drill 0.254)
		(layers "F.Cu" "B.Cu")
		(net "MEMDQ_9")
	)
	(via
		(at 297.561 -186.36615)
		(size 0.508)
		(drill 0.254)
		(layers "F.Cu" "B.Cu")
		(net "MEMDQ_9")
	)
	(via
		(at 296.291 -196.5706)
		(size 0.7112)
		(drill 0.3556)
		(layers "F.Cu" "B.Cu")
		(net "MEMDQ_9")
	)
	(segment
		(start 296.500804 -197.341744)
		(end 296.291 -197.13194)
		(width 0.1143)
		(layer "B.Cu")
		(net "MEMDQ_9")
	)
	(segment
		(start 296.291 -197.13194)
		(end 296.291 -196.5706)
		(width 0.1143)
		(layer "B.Cu")
		(net "MEMDQ_9")
	)
	(segment
		(start 297.5483 -186.736482)
		(end 297.7642 -186.952382)
		(width 0.127)
		(layer "In5.Cu")
		(net "MEMDQ_9")
	)
	(segment
		(start 297.5483 -186.37885)
		(end 297.5483 -186.736482)
		(width 0.127)
		(layer "In5.Cu")
		(net "MEMDQ_9")
	)
	(segment
		(start 297.7642 -196.078348)
		(end 296.500804 -197.341744)
		(width 0.127)
		(layer "In5.Cu")
		(net "MEMDQ_9")
	)
	(segment
		(start 297.561 -186.36615)
		(end 297.5483 -186.37885)
		(width 0.127)
		(layer "In5.Cu")
		(net "MEMDQ_9")
	)
	(segment
		(start 297.7642 -186.952382)
		(end 297.7642 -196.078348)
		(width 0.127)
		(layer "In5.Cu")
		(net "MEMDQ_9")
	)
	(segment
		(start 306.967636 -79.8195)
		(end 306.249578 -79.8195)
		(width 0.1397)
		(layer "F.Cu")
		(net "PCIE_10G_CPU_TX3_P")
	)
	(segment
		(start 305.19751 -80.25511)
		(end 304.74031 -80.71231)
		(width 0.1397)
		(layer "F.Cu")
		(net "PCIE_10G_CPU_TX3_P")
	)
	(segment
		(start 307.10759 -79.832708)
		(end 307.071014 -79.82712)
		(width 0.1397)
		(layer "F.Cu")
		(net "PCIE_10G_CPU_TX3_P")
	)
	(segment
		(start 308.675024 -79.600044)
		(end 307.716428 -79.600044)
		(width 0.1397)
		(layer "F.Cu")
		(net "PCIE_10G_CPU_TX3_P")
	)
	(segment
		(start 304.0761 -82.316574)
		(end 304.0761 -87.0204)
		(width 0.1397)
		(layer "F.Cu")
		(net "PCIE_10G_CPU_TX3_P")
	)
	(segment
		(start 303.912016 -87.416132)
		(end 303.80305 -87.525352)
		(width 0.1397)
		(layer "F.Cu")
		(net "PCIE_10G_CPU_TX3_P")
	)
	(via
		(at 303.80305 -87.525352)
		(size 0.5588)
		(drill 0.3048)
		(layers "F.Cu" "B.Cu")
		(net "PCIE_10G_CPU_TX3_P")
	)
	(arc
		(start 307.071014 -79.82712)
		(mid 307.019469 -79.821358)
		(end 306.967636 -79.8195)
		(width 0.1397)
		(layer "F.Cu")
		(net "PCIE_10G_CPU_TX3_P")
	)
	(arc
		(start 307.716428 -79.600044)
		(mid 307.512693 -79.640569)
		(end 307.34 -79.756)
		(width 0.1397)
		(layer "F.Cu")
		(net "PCIE_10G_CPU_TX3_P")
	)
	(arc
		(start 304.74031 -80.71231)
		(mid 304.248614 -81.448368)
		(end 304.0761 -82.316574)
		(width 0.1397)
		(layer "F.Cu")
		(net "PCIE_10G_CPU_TX3_P")
	)
	(arc
		(start 307.34 -79.756)
		(mid 307.232921 -79.822017)
		(end 307.10759 -79.832708)
		(width 0.1397)
		(layer "F.Cu")
		(net "PCIE_10G_CPU_TX3_P")
	)
	(arc
		(start 306.249578 -79.8195)
		(mid 305.680215 -79.93266)
		(end 305.19751 -80.25511)
		(width 0.1397)
		(layer "F.Cu")
		(net "PCIE_10G_CPU_TX3_P")
	)
	(arc
		(start 304.0761 -87.0204)
		(mid 304.033404 -87.234579)
		(end 303.912016 -87.416132)
		(width 0.1397)
		(layer "F.Cu")
		(net "PCIE_10G_CPU_TX3_P")
	)
	(segment
		(start 144.950942 -83.693)
		(end 145.415 -83.693)
		(width 0.127)
		(layer "In5.Cu")
		(net "PCIE_10G_CPU_TX3_P")
	)
	(segment
		(start 186.182 -87.1474)
		(end 301.502826 -87.1474)
		(width 0.127)
		(layer "In5.Cu")
		(net "PCIE_10G_CPU_TX3_P")
	)
	(segment
		(start 304.12182 -86.953344)
		(end 304.12182 -87.122)
		(width 0.127)
		(layer "In5.Cu")
		(net "PCIE_10G_CPU_TX3_P")
	)
	(segment
		(start 146.932904 -84.32165)
		(end 151.014938 -88.403684)
		(width 0.127)
		(layer "In5.Cu")
		(net "PCIE_10G_CPU_TX3_P")
	)
	(segment
		(start 141.449806 -78.24978)
		(end 141.449806 -78.336394)
		(width 0.127)
		(layer "In5.Cu")
		(net "PCIE_10G_CPU_TX3_P")
	)
	(segment
		(start 140.704824 -82.9564)
		(end 143.441928 -82.9564)
		(width 0.127)
		(layer "In5.Cu")
		(net "PCIE_10G_CPU_TX3_P")
	)
	(segment
		(start 151.661876 -88.6714)
		(end 183.414924 -88.6714)
		(width 0.127)
		(layer "In5.Cu")
		(net "PCIE_10G_CPU_TX3_P")
	)
	(segment
		(start 139.30757 -79.958946)
		(end 139.30757 -81.534)
		(width 0.127)
		(layer "In5.Cu")
		(net "PCIE_10G_CPU_TX3_P")
	)
	(segment
		(start 144.010888 -83.192112)
		(end 144.201388 -83.382612)
		(width 0.127)
		(layer "In5.Cu")
		(net "PCIE_10G_CPU_TX3_P")
	)
	(segment
		(start 304.06213 -87.266526)
		(end 303.80305 -87.525352)
		(width 0.127)
		(layer "In5.Cu")
		(net "PCIE_10G_CPU_TX3_P")
	)
	(segment
		(start 184.670954 -88.151208)
		(end 185.316114 -87.506048)
		(width 0.127)
		(layer "In5.Cu")
		(net "PCIE_10G_CPU_TX3_P")
	)
	(segment
		(start 139.902946 -79.0702)
		(end 139.515088 -79.458058)
		(width 0.127)
		(layer "In5.Cu")
		(net "PCIE_10G_CPU_TX3_P")
	)
	(segment
		(start 302.606964 -86.6902)
		(end 303.876456 -86.6902)
		(width 0.127)
		(layer "In5.Cu")
		(net "PCIE_10G_CPU_TX3_P")
	)
	(segment
		(start 140.9192 -78.867)
		(end 140.39342 -78.867)
		(width 0.127)
		(layer "In5.Cu")
		(net "PCIE_10G_CPU_TX3_P")
	)
	(segment
		(start 303.965864 -86.727284)
		(end 304.07229 -86.83371)
		(width 0.127)
		(layer "In5.Cu")
		(net "PCIE_10G_CPU_TX3_P")
	)
	(segment
		(start 139.578842 -82.189066)
		(end 140.09243 -82.702654)
		(width 0.127)
		(layer "In5.Cu")
		(net "PCIE_10G_CPU_TX3_P")
	)
	(arc
		(start 141.449806 -78.336394)
		(mid 141.294395 -78.711589)
		(end 140.9192 -78.867)
		(width 0.127)
		(layer "In5.Cu")
		(net "PCIE_10G_CPU_TX3_P")
	)
	(arc
		(start 144.201388 -83.382612)
		(mid 144.545286 -83.612397)
		(end 144.950942 -83.693)
		(width 0.127)
		(layer "In5.Cu")
		(net "PCIE_10G_CPU_TX3_P")
	)
	(arc
		(start 304.12182 -87.122)
		(mid 304.106358 -87.200204)
		(end 304.06213 -87.266526)
		(width 0.127)
		(layer "In5.Cu")
		(net "PCIE_10G_CPU_TX3_P")
	)
	(arc
		(start 183.414924 -88.6714)
		(mid 184.094655 -88.536193)
		(end 184.670954 -88.151208)
		(width 0.127)
		(layer "In5.Cu")
		(net "PCIE_10G_CPU_TX3_P")
	)
	(arc
		(start 139.515088 -79.458058)
		(mid 139.361505 -79.687867)
		(end 139.30757 -79.958946)
		(width 0.127)
		(layer "In5.Cu")
		(net "PCIE_10G_CPU_TX3_P")
	)
	(arc
		(start 143.441928 -82.9564)
		(mid 143.749863 -83.017652)
		(end 144.010888 -83.192112)
		(width 0.127)
		(layer "In5.Cu")
		(net "PCIE_10G_CPU_TX3_P")
	)
	(arc
		(start 140.09243 -82.702654)
		(mid 140.373398 -82.890421)
		(end 140.704824 -82.9564)
		(width 0.127)
		(layer "In5.Cu")
		(net "PCIE_10G_CPU_TX3_P")
	)
	(arc
		(start 145.415 -83.693)
		(mid 146.236465 -83.856382)
		(end 146.932904 -84.32165)
		(width 0.127)
		(layer "In5.Cu")
		(net "PCIE_10G_CPU_TX3_P")
	)
	(arc
		(start 151.014938 -88.403684)
		(mid 151.311772 -88.601899)
		(end 151.661876 -88.6714)
		(width 0.127)
		(layer "In5.Cu")
		(net "PCIE_10G_CPU_TX3_P")
	)
	(arc
		(start 301.502826 -87.1474)
		(mid 301.899559 -87.068578)
		(end 302.23587 -86.84387)
		(width 0.127)
		(layer "In5.Cu")
		(net "PCIE_10G_CPU_TX3_P")
	)
	(arc
		(start 302.23587 -86.84387)
		(mid 302.406129 -86.730106)
		(end 302.606964 -86.6902)
		(width 0.127)
		(layer "In5.Cu")
		(net "PCIE_10G_CPU_TX3_P")
	)
	(arc
		(start 139.30757 -81.534)
		(mid 139.378068 -81.888508)
		(end 139.578842 -82.189066)
		(width 0.127)
		(layer "In5.Cu")
		(net "PCIE_10G_CPU_TX3_P")
	)
	(arc
		(start 304.07229 -86.83371)
		(mid 304.108936 -86.888599)
		(end 304.12182 -86.953344)
		(width 0.127)
		(layer "In5.Cu")
		(net "PCIE_10G_CPU_TX3_P")
	)
	(arc
		(start 140.39342 -78.867)
		(mid 140.127962 -78.919803)
		(end 139.902946 -79.0702)
		(width 0.127)
		(layer "In5.Cu")
		(net "PCIE_10G_CPU_TX3_P")
	)
	(arc
		(start 185.316114 -87.506048)
		(mid 185.713386 -87.240599)
		(end 186.182 -87.1474)
		(width 0.127)
		(layer "In5.Cu")
		(net "PCIE_10G_CPU_TX3_P")
	)
	(arc
		(start 303.876456 -86.6902)
		(mid 303.924862 -86.699829)
		(end 303.965864 -86.727284)
		(width 0.127)
		(layer "In5.Cu")
		(net "PCIE_10G_CPU_TX3_P")
	)
	(segment
		(start 119.01424 -27.813)
		(end 136.45007 -27.813)
		(width 0.1397)
		(layer "F.Cu")
		(net "PCIE_SAS_CPU_TX_N7")
	)
	(segment
		(start 136.899142 -27.998928)
		(end 154.922474 -46.02226)
		(width 0.1397)
		(layer "F.Cu")
		(net "PCIE_SAS_CPU_TX_N7")
	)
	(segment
		(start 116.180108 -24.232108)
		(end 117.906546 -25.958546)
		(width 0.1397)
		(layer "F.Cu")
		(net "PCIE_SAS_CPU_TX_N7")
	)
	(segment
		(start 155.469082 -74.481182)
		(end 155.93695 -74.94905)
		(width 0.1397)
		(layer "F.Cu")
		(net "PCIE_SAS_CPU_TX_N7")
	)
	(segment
		(start 118.092474 -26.40711)
		(end 118.092474 -26.891234)
		(width 0.1397)
		(layer "F.Cu")
		(net "PCIE_SAS_CPU_TX_N7")
	)
	(segment
		(start 105.639616 -30.126686)
		(end 105.639616 -28.500578)
		(width 0.1397)
		(layer "F.Cu")
		(net "PCIE_SAS_CPU_TX_N7")
	)
	(segment
		(start 109.901228 -23.860252)
		(end 115.282218 -23.860252)
		(width 0.1397)
		(layer "F.Cu")
		(net "PCIE_SAS_CPU_TX_N7")
	)
	(segment
		(start 104.029002 -32.026606)
		(end 105.434892 -30.620716)
		(width 0.1397)
		(layer "F.Cu")
		(net "PCIE_SAS_CPU_TX_N7")
	)
	(segment
		(start 118.09222 -26.407364)
		(end 118.092474 -26.40711)
		(width 0.1397)
		(layer "F.Cu")
		(net "PCIE_SAS_CPU_TX_N7")
	)
	(segment
		(start 155.29433 -46.92015)
		(end 155.29433 -74.059288)
		(width 0.1397)
		(layer "F.Cu")
		(net "PCIE_SAS_CPU_TX_N7")
	)
	(segment
		(start 156.28874 -75.798426)
		(end 156.28874 -76.198984)
		(width 0.1397)
		(layer "F.Cu")
		(net "PCIE_SAS_CPU_TX_N7")
	)
	(segment
		(start 103.924608 -33.381696)
		(end 103.924608 -32.27832)
		(width 0.1397)
		(layer "F.Cu")
		(net "PCIE_SAS_CPU_TX_N7")
	)
	(segment
		(start 106.011472 -27.602688)
		(end 109.649514 -23.964646)
		(width 0.1397)
		(layer "F.Cu")
		(net "PCIE_SAS_CPU_TX_N7")
	)
	(segment
		(start 103.549958 -34.19983)
		(end 103.549958 -34.050986)
		(width 0.1397)
		(layer "F.Cu")
		(net "PCIE_SAS_CPU_TX_N7")
	)
	(segment
		(start 103.635556 -33.844484)
		(end 103.801672 -33.678368)
		(width 0.1397)
		(layer "F.Cu")
		(net "PCIE_SAS_CPU_TX_N7")
	)
	(via
		(at 155.946348 -77.0255)
		(size 0.5588)
		(drill 0.3048)
		(layers "F.Cu" "B.Cu")
		(net "PCIE_SAS_CPU_TX_N7")
	)
	(arc
		(start 103.549958 -34.050986)
		(mid 103.572208 -33.939218)
		(end 103.635556 -33.844484)
		(width 0.1397)
		(layer "F.Cu")
		(net "PCIE_SAS_CPU_TX_N7")
	)
	(arc
		(start 105.434892 -30.620716)
		(mid 105.586373 -30.394054)
		(end 105.639616 -30.126686)
		(width 0.1397)
		(layer "F.Cu")
		(net "PCIE_SAS_CPU_TX_N7")
	)
	(arc
		(start 136.45007 -27.813)
		(mid 136.693074 -27.861336)
		(end 136.899142 -27.998928)
		(width 0.1397)
		(layer "F.Cu")
		(net "PCIE_SAS_CPU_TX_N7")
	)
	(arc
		(start 103.924608 -32.27832)
		(mid 103.951798 -32.142097)
		(end 104.029002 -32.026606)
		(width 0.1397)
		(layer "F.Cu")
		(net "PCIE_SAS_CPU_TX_N7")
	)
	(arc
		(start 156.28874 -76.198984)
		(mid 156.199762 -76.646306)
		(end 155.946348 -77.0255)
		(width 0.1397)
		(layer "F.Cu")
		(net "PCIE_SAS_CPU_TX_N7")
	)
	(arc
		(start 155.29433 -74.059288)
		(mid 155.339732 -74.287629)
		(end 155.469082 -74.481182)
		(width 0.1397)
		(layer "F.Cu")
		(net "PCIE_SAS_CPU_TX_N7")
	)
	(arc
		(start 155.93695 -74.94905)
		(mid 156.197337 -75.338747)
		(end 156.28874 -75.798426)
		(width 0.1397)
		(layer "F.Cu")
		(net "PCIE_SAS_CPU_TX_N7")
	)
	(arc
		(start 115.282218 -23.860252)
		(mid 115.768143 -23.956891)
		(end 116.180108 -24.232108)
		(width 0.1397)
		(layer "F.Cu")
		(net "PCIE_SAS_CPU_TX_N7")
	)
	(arc
		(start 103.801672 -33.678368)
		(mid 103.892674 -33.542268)
		(end 103.924608 -33.381696)
		(width 0.1397)
		(layer "F.Cu")
		(net "PCIE_SAS_CPU_TX_N7")
	)
	(arc
		(start 105.639616 -28.500578)
		(mid 105.736255 -28.014653)
		(end 106.011472 -27.602688)
		(width 0.1397)
		(layer "F.Cu")
		(net "PCIE_SAS_CPU_TX_N7")
	)
	(arc
		(start 109.649514 -23.964646)
		(mid 109.764986 -23.887397)
		(end 109.901228 -23.860252)
		(width 0.1397)
		(layer "F.Cu")
		(net "PCIE_SAS_CPU_TX_N7")
	)
	(arc
		(start 154.922474 -46.02226)
		(mid 155.19768 -46.43423)
		(end 155.29433 -46.92015)
		(width 0.1397)
		(layer "F.Cu")
		(net "PCIE_SAS_CPU_TX_N7")
	)
	(arc
		(start 117.906546 -25.958546)
		(mid 118.044 -26.164495)
		(end 118.09222 -26.407364)
		(width 0.1397)
		(layer "F.Cu")
		(net "PCIE_SAS_CPU_TX_N7")
	)
	(arc
		(start 118.092474 -26.891234)
		(mid 118.362453 -27.543021)
		(end 119.01424 -27.813)
		(width 0.1397)
		(layer "F.Cu")
		(net "PCIE_SAS_CPU_TX_N7")
	)
	(segment
		(start 156.748226 -79.34071)
		(end 156.748226 -79.340964)
		(width 0.1397)
		(layer "B.Cu")
		(net "PCIE_SAS_CPU_TX_N7")
	)
	(segment
		(start 156.748734 -79.340964)
		(end 156.748226 -79.34071)
		(width 0.1397)
		(layer "B.Cu")
		(net "PCIE_SAS_CPU_TX_N7")
	)
	(segment
		(start 156.2608 -78.553564)
		(end 156.2608 -77.44206)
		(width 0.1397)
		(layer "B.Cu")
		(net "PCIE_SAS_CPU_TX_N7")
	)
	(segment
		(start 156.188664 -77.267562)
		(end 155.946348 -77.0255)
		(width 0.1397)
		(layer "B.Cu")
		(net "PCIE_SAS_CPU_TX_N7")
	)
	(segment
		(start 156.748988 -79.340964)
		(end 156.748734 -79.340964)
		(width 0.1397)
		(layer "B.Cu")
		(net "PCIE_SAS_CPU_TX_N7")
	)
	(segment
		(start 156.747718 -79.340202)
		(end 156.57957 -79.256128)
		(width 0.1397)
		(layer "B.Cu")
		(net "PCIE_SAS_CPU_TX_N7")
	)
	(segment
		(start 156.449776 -80.25003)
		(end 156.811218 -79.528416)
		(width 0.1397)
		(layer "B.Cu")
		(net "PCIE_SAS_CPU_TX_N7")
	)
	(arc
		(start 156.748226 -79.340964)
		(mid 156.747972 -79.340583)
		(end 156.747718 -79.340202)
		(width 0.1397)
		(layer "B.Cu")
		(net "PCIE_SAS_CPU_TX_N7")
	)
	(arc
		(start 156.811218 -79.528416)
		(mid 156.818834 -79.421857)
		(end 156.748988 -79.340964)
		(width 0.1397)
		(layer "B.Cu")
		(net "PCIE_SAS_CPU_TX_N7")
	)
	(arc
		(start 156.2608 -77.44206)
		(mid 156.242109 -77.347624)
		(end 156.188664 -77.267562)
		(width 0.1397)
		(layer "B.Cu")
		(net "PCIE_SAS_CPU_TX_N7")
	)
	(arc
		(start 156.57957 -79.256128)
		(mid 156.344281 -78.939287)
		(end 156.2608 -78.553564)
		(width 0.1397)
		(layer "B.Cu")
		(net "PCIE_SAS_CPU_TX_N7")
	)
	(segment
		(start 299.650912 -170.2562)
		(end 299.648626 -170.2562)
		(width 0.1143)
		(layer "F.Cu")
		(net "BMC0_SMB5_CLK")
	)
	(segment
		(start 300.03496 -170.640248)
		(end 299.650912 -170.2562)
		(width 0.1143)
		(layer "F.Cu")
		(net "BMC0_SMB5_CLK")
	)
	(segment
		(start 299.648626 -170.2562)
		(end 299.631862 -170.239436)
		(width 0.1143)
		(layer "F.Cu")
		(net "BMC0_SMB5_CLK")
	)
	(via
		(at 299.631862 -170.239436)
		(size 0.508)
		(drill 0.254)
		(layers "F.Cu" "B.Cu")
		(net "BMC0_SMB5_CLK")
	)
	(via
		(at 310.388 -169.291)
		(size 0.7112)
		(drill 0.3556)
		(layers "F.Cu" "B.Cu")
		(net "BMC0_SMB5_CLK")
	)
	(segment
		(start 317.5635 -167.894)
		(end 316.611 -167.894)
		(width 0.1143)
		(layer "B.Cu")
		(net "BMC0_SMB5_CLK")
	)
	(segment
		(start 316.611 -167.894)
		(end 315.341 -169.164)
		(width 0.1143)
		(layer "B.Cu")
		(net "BMC0_SMB5_CLK")
	)
	(segment
		(start 310.388 -169.291)
		(end 310.15305 -169.52595)
		(width 0.1143)
		(layer "B.Cu")
		(net "BMC0_SMB5_CLK")
	)
	(segment
		(start 303.614836 -169.52595)
		(end 303.284636 -169.85615)
		(width 0.1143)
		(layer "B.Cu")
		(net "BMC0_SMB5_CLK")
	)
	(segment
		(start 299.848016 -170.239436)
		(end 299.631862 -170.239436)
		(width 0.1143)
		(layer "B.Cu")
		(net "BMC0_SMB5_CLK")
	)
	(segment
		(start 300.260766 -169.826686)
		(end 299.848016 -170.239436)
		(width 0.1143)
		(layer "B.Cu")
		(net "BMC0_SMB5_CLK")
	)
	(segment
		(start 302.302926 -169.826686)
		(end 300.260766 -169.826686)
		(width 0.1143)
		(layer "B.Cu")
		(net "BMC0_SMB5_CLK")
	)
	(segment
		(start 315.341 -169.164)
		(end 310.515 -169.164)
		(width 0.1143)
		(layer "B.Cu")
		(net "BMC0_SMB5_CLK")
	)
	(segment
		(start 302.33239 -169.85615)
		(end 302.302926 -169.826686)
		(width 0.1143)
		(layer "B.Cu")
		(net "BMC0_SMB5_CLK")
	)
	(segment
		(start 303.284636 -169.85615)
		(end 302.33239 -169.85615)
		(width 0.1143)
		(layer "B.Cu")
		(net "BMC0_SMB5_CLK")
	)
	(segment
		(start 310.15305 -169.52595)
		(end 303.614836 -169.52595)
		(width 0.1143)
		(layer "B.Cu")
		(net "BMC0_SMB5_CLK")
	)
	(segment
		(start 310.515 -169.164)
		(end 310.388 -169.291)
		(width 0.1143)
		(layer "B.Cu")
		(net "BMC0_SMB5_CLK")
	)
	(segment
		(start 308.675024 -80.400144)
		(end 307.467 -80.400144)
		(width 0.1397)
		(layer "F.Cu")
		(net "PCIE_10G_CPU_TX3_N")
	)
	(segment
		(start 304.563272 -87.368634)
		(end 304.71999 -87.525352)
		(width 0.1397)
		(layer "F.Cu")
		(net "PCIE_10G_CPU_TX3_N")
	)
	(segment
		(start 307.265832 -80.316832)
		(end 307.213 -80.264)
		(width 0.1397)
		(layer "F.Cu")
		(net "PCIE_10G_CPU_TX3_N")
	)
	(segment
		(start 304.419 -82.31632)
		(end 304.419 -87.0204)
		(width 0.1397)
		(layer "F.Cu")
		(net "PCIE_10G_CPU_TX3_N")
	)
	(segment
		(start 306.967636 -80.1624)
		(end 306.249578 -80.1624)
		(width 0.1397)
		(layer "F.Cu")
		(net "PCIE_10G_CPU_TX3_N")
	)
	(segment
		(start 305.44008 -80.49768)
		(end 304.98288 -80.95488)
		(width 0.1397)
		(layer "F.Cu")
		(net "PCIE_10G_CPU_TX3_N")
	)
	(via
		(at 304.71999 -87.525352)
		(size 0.5588)
		(drill 0.3048)
		(layers "F.Cu" "B.Cu")
		(net "PCIE_10G_CPU_TX3_N")
	)
	(arc
		(start 304.98288 -80.95488)
		(mid 304.565513 -81.579514)
		(end 304.419 -82.31632)
		(width 0.1397)
		(layer "F.Cu")
		(net "PCIE_10G_CPU_TX3_N")
	)
	(arc
		(start 307.213 -80.264)
		(mid 307.100426 -80.18878)
		(end 306.967636 -80.1624)
		(width 0.1397)
		(layer "F.Cu")
		(net "PCIE_10G_CPU_TX3_N")
	)
	(arc
		(start 307.467 -80.400144)
		(mid 307.358134 -80.378489)
		(end 307.265832 -80.316832)
		(width 0.1397)
		(layer "F.Cu")
		(net "PCIE_10G_CPU_TX3_N")
	)
	(arc
		(start 304.419 -87.0204)
		(mid 304.45649 -87.208874)
		(end 304.563272 -87.368634)
		(width 0.1397)
		(layer "F.Cu")
		(net "PCIE_10G_CPU_TX3_N")
	)
	(arc
		(start 306.249578 -80.1624)
		(mid 305.81149 -80.249541)
		(end 305.44008 -80.49768)
		(width 0.1397)
		(layer "F.Cu")
		(net "PCIE_10G_CPU_TX3_N")
	)
	(segment
		(start 140.100558 -79.267812)
		(end 139.7127 -79.65567)
		(width 0.127)
		(layer "In5.Cu")
		(net "PCIE_10G_CPU_TX3_N")
	)
	(segment
		(start 139.58697 -79.9592)
		(end 139.58697 -81.534)
		(width 0.127)
		(layer "In5.Cu")
		(net "PCIE_10G_CPU_TX3_N")
	)
	(segment
		(start 161.090864 -88.24214)
		(end 161.471864 -88.24214)
		(width 0.127)
		(layer "In5.Cu")
		(net "PCIE_10G_CPU_TX3_N")
	)
	(segment
		(start 140.705078 -82.677)
		(end 143.442182 -82.677)
		(width 0.127)
		(layer "In5.Cu")
		(net "PCIE_10G_CPU_TX3_N")
	)
	(segment
		(start 159.729424 -88.24214)
		(end 160.110424 -88.24214)
		(width 0.127)
		(layer "In5.Cu")
		(net "PCIE_10G_CPU_TX3_N")
	)
	(segment
		(start 173.060614 -88.24214)
		(end 173.441614 -88.24214)
		(width 0.127)
		(layer "In5.Cu")
		(net "PCIE_10G_CPU_TX3_N")
	)
	(segment
		(start 167.91305 -88.392)
		(end 172.760894 -88.392)
		(width 0.127)
		(layer "In5.Cu")
		(net "PCIE_10G_CPU_TX3_N")
	)
	(segment
		(start 140.899896 -79.627984)
		(end 140.899896 -79.525622)
		(width 0.127)
		(layer "In5.Cu")
		(net "PCIE_10G_CPU_TX3_N")
	)
	(segment
		(start 161.771584 -88.392)
		(end 162.152584 -88.392)
		(width 0.127)
		(layer "In5.Cu")
		(net "PCIE_10G_CPU_TX3_N")
	)
	(segment
		(start 164.50945 -88.24214)
		(end 164.89045 -88.24214)
		(width 0.127)
		(layer "In5.Cu")
		(net "PCIE_10G_CPU_TX3_N")
	)
	(segment
		(start 162.452304 -88.24214)
		(end 162.833304 -88.24214)
		(width 0.127)
		(layer "In5.Cu")
		(net "PCIE_10G_CPU_TX3_N")
	)
	(segment
		(start 304.46091 -87.266526)
		(end 304.71999 -87.525352)
		(width 0.127)
		(layer "In5.Cu")
		(net "PCIE_10G_CPU_TX3_N")
	)
	(segment
		(start 176.464214 -88.392)
		(end 183.414924 -88.392)
		(width 0.127)
		(layer "In5.Cu")
		(net "PCIE_10G_CPU_TX3_N")
	)
	(segment
		(start 184.473342 -87.953596)
		(end 185.118502 -87.308436)
		(width 0.127)
		(layer "In5.Cu")
		(net "PCIE_10G_CPU_TX3_N")
	)
	(segment
		(start 302.606964 -86.4108)
		(end 303.87671 -86.4108)
		(width 0.127)
		(layer "In5.Cu")
		(net "PCIE_10G_CPU_TX3_N")
	)
	(segment
		(start 304.163476 -86.529672)
		(end 304.269902 -86.636098)
		(width 0.127)
		(layer "In5.Cu")
		(net "PCIE_10G_CPU_TX3_N")
	)
	(segment
		(start 186.182 -86.868)
		(end 301.502826 -86.868)
		(width 0.127)
		(layer "In5.Cu")
		(net "PCIE_10G_CPU_TX3_N")
	)
	(segment
		(start 144.950942 -83.4136)
		(end 145.414746 -83.4136)
		(width 0.127)
		(layer "In5.Cu")
		(net "PCIE_10G_CPU_TX3_N")
	)
	(segment
		(start 304.40122 -86.95309)
		(end 304.40122 -87.122)
		(width 0.127)
		(layer "In5.Cu")
		(net "PCIE_10G_CPU_TX3_N")
	)
	(segment
		(start 167.23233 -88.24214)
		(end 167.61333 -88.24214)
		(width 0.127)
		(layer "In5.Cu")
		(net "PCIE_10G_CPU_TX3_N")
	)
	(segment
		(start 139.776454 -81.991454)
		(end 140.290042 -82.505042)
		(width 0.127)
		(layer "In5.Cu")
		(net "PCIE_10G_CPU_TX3_N")
	)
	(segment
		(start 174.422054 -88.24214)
		(end 174.803054 -88.24214)
		(width 0.127)
		(layer "In5.Cu")
		(net "PCIE_10G_CPU_TX3_N")
	)
	(segment
		(start 163.133024 -88.392)
		(end 164.20973 -88.392)
		(width 0.127)
		(layer "In5.Cu")
		(net "PCIE_10G_CPU_TX3_N")
	)
	(segment
		(start 175.783494 -88.24214)
		(end 176.164494 -88.24214)
		(width 0.127)
		(layer "In5.Cu")
		(net "PCIE_10G_CPU_TX3_N")
	)
	(segment
		(start 151.661622 -88.392)
		(end 159.429704 -88.392)
		(width 0.127)
		(layer "In5.Cu")
		(net "PCIE_10G_CPU_TX3_N")
	)
	(segment
		(start 140.450316 -80.25003)
		(end 140.773912 -79.926434)
		(width 0.127)
		(layer "In5.Cu")
		(net "PCIE_10G_CPU_TX3_N")
	)
	(segment
		(start 160.410144 -88.392)
		(end 160.791144 -88.392)
		(width 0.127)
		(layer "In5.Cu")
		(net "PCIE_10G_CPU_TX3_N")
	)
	(segment
		(start 173.741334 -88.392)
		(end 174.122334 -88.392)
		(width 0.127)
		(layer "In5.Cu")
		(net "PCIE_10G_CPU_TX3_N")
	)
	(segment
		(start 147.130516 -84.124038)
		(end 151.21255 -88.206072)
		(width 0.127)
		(layer "In5.Cu")
		(net "PCIE_10G_CPU_TX3_N")
	)
	(segment
		(start 175.102774 -88.392)
		(end 175.483774 -88.392)
		(width 0.127)
		(layer "In5.Cu")
		(net "PCIE_10G_CPU_TX3_N")
	)
	(segment
		(start 144.2085 -82.9945)
		(end 144.399 -83.185)
		(width 0.127)
		(layer "In5.Cu")
		(net "PCIE_10G_CPU_TX3_N")
	)
	(segment
		(start 165.87089 -88.24214)
		(end 166.25189 -88.24214)
		(width 0.127)
		(layer "In5.Cu")
		(net "PCIE_10G_CPU_TX3_N")
	)
	(segment
		(start 165.19017 -88.392)
		(end 165.57117 -88.392)
		(width 0.127)
		(layer "In5.Cu")
		(net "PCIE_10G_CPU_TX3_N")
	)
	(segment
		(start 140.520674 -79.1464)
		(end 140.393674 -79.1464)
		(width 0.127)
		(layer "In5.Cu")
		(net "PCIE_10G_CPU_TX3_N")
	)
	(segment
		(start 166.55161 -88.392)
		(end 166.93261 -88.392)
		(width 0.127)
		(layer "In5.Cu")
		(net "PCIE_10G_CPU_TX3_N")
	)
	(arc
		(start 174.803054 -88.24214)
		(mid 174.886169 -88.263223)
		(end 174.952914 -88.31707)
		(width 0.127)
		(layer "In5.Cu")
		(net "PCIE_10G_CPU_TX3_N")
	)
	(arc
		(start 183.414924 -88.392)
		(mid 183.987733 -88.278061)
		(end 184.473342 -87.953596)
		(width 0.127)
		(layer "In5.Cu")
		(net "PCIE_10G_CPU_TX3_N")
	)
	(arc
		(start 303.87671 -86.4108)
		(mid 304.031901 -86.441745)
		(end 304.163476 -86.529672)
		(width 0.127)
		(layer "In5.Cu")
		(net "PCIE_10G_CPU_TX3_N")
	)
	(arc
		(start 161.621724 -88.31707)
		(mid 161.688448 -88.370959)
		(end 161.771584 -88.392)
		(width 0.127)
		(layer "In5.Cu")
		(net "PCIE_10G_CPU_TX3_N")
	)
	(arc
		(start 166.25189 -88.24214)
		(mid 166.335026 -88.263204)
		(end 166.40175 -88.31707)
		(width 0.127)
		(layer "In5.Cu")
		(net "PCIE_10G_CPU_TX3_N")
	)
	(arc
		(start 172.910754 -88.31707)
		(mid 172.977499 -88.263246)
		(end 173.060614 -88.24214)
		(width 0.127)
		(layer "In5.Cu")
		(net "PCIE_10G_CPU_TX3_N")
	)
	(arc
		(start 140.55979 -79.148178)
		(mid 140.540255 -79.14678)
		(end 140.520674 -79.1464)
		(width 0.127)
		(layer "In5.Cu")
		(net "PCIE_10G_CPU_TX3_N")
	)
	(arc
		(start 174.272194 -88.31707)
		(mid 174.338939 -88.263246)
		(end 174.422054 -88.24214)
		(width 0.127)
		(layer "In5.Cu")
		(net "PCIE_10G_CPU_TX3_N")
	)
	(arc
		(start 160.260284 -88.31707)
		(mid 160.327008 -88.370959)
		(end 160.410144 -88.392)
		(width 0.127)
		(layer "In5.Cu")
		(net "PCIE_10G_CPU_TX3_N")
	)
	(arc
		(start 304.40122 -87.122)
		(mid 304.416682 -87.200204)
		(end 304.46091 -87.266526)
		(width 0.127)
		(layer "In5.Cu")
		(net "PCIE_10G_CPU_TX3_N")
	)
	(arc
		(start 167.08247 -88.31707)
		(mid 167.149215 -88.263246)
		(end 167.23233 -88.24214)
		(width 0.127)
		(layer "In5.Cu")
		(net "PCIE_10G_CPU_TX3_N")
	)
	(arc
		(start 175.633634 -88.31707)
		(mid 175.700379 -88.263246)
		(end 175.783494 -88.24214)
		(width 0.127)
		(layer "In5.Cu")
		(net "PCIE_10G_CPU_TX3_N")
	)
	(arc
		(start 144.399 -83.185)
		(mid 144.652233 -83.354205)
		(end 144.950942 -83.4136)
		(width 0.127)
		(layer "In5.Cu")
		(net "PCIE_10G_CPU_TX3_N")
	)
	(arc
		(start 161.471864 -88.24214)
		(mid 161.555 -88.263204)
		(end 161.621724 -88.31707)
		(width 0.127)
		(layer "In5.Cu")
		(net "PCIE_10G_CPU_TX3_N")
	)
	(arc
		(start 162.833304 -88.24214)
		(mid 162.91644 -88.263204)
		(end 162.983164 -88.31707)
		(width 0.127)
		(layer "In5.Cu")
		(net "PCIE_10G_CPU_TX3_N")
	)
	(arc
		(start 162.983164 -88.31707)
		(mid 163.049888 -88.370959)
		(end 163.133024 -88.392)
		(width 0.127)
		(layer "In5.Cu")
		(net "PCIE_10G_CPU_TX3_N")
	)
	(arc
		(start 167.76319 -88.31707)
		(mid 167.829935 -88.370894)
		(end 167.91305 -88.392)
		(width 0.127)
		(layer "In5.Cu")
		(net "PCIE_10G_CPU_TX3_N")
	)
	(arc
		(start 159.429704 -88.392)
		(mid 159.51284 -88.370936)
		(end 159.579564 -88.31707)
		(width 0.127)
		(layer "In5.Cu")
		(net "PCIE_10G_CPU_TX3_N")
	)
	(arc
		(start 174.122334 -88.392)
		(mid 174.205449 -88.370917)
		(end 174.272194 -88.31707)
		(width 0.127)
		(layer "In5.Cu")
		(net "PCIE_10G_CPU_TX3_N")
	)
	(arc
		(start 140.773912 -79.926434)
		(mid 140.866123 -79.789533)
		(end 140.899896 -79.627984)
		(width 0.127)
		(layer "In5.Cu")
		(net "PCIE_10G_CPU_TX3_N")
	)
	(arc
		(start 139.7127 -79.65567)
		(mid 139.619649 -79.794931)
		(end 139.58697 -79.9592)
		(width 0.127)
		(layer "In5.Cu")
		(net "PCIE_10G_CPU_TX3_N")
	)
	(arc
		(start 164.20973 -88.392)
		(mid 164.292866 -88.370936)
		(end 164.35959 -88.31707)
		(width 0.127)
		(layer "In5.Cu")
		(net "PCIE_10G_CPU_TX3_N")
	)
	(arc
		(start 145.414746 -83.4136)
		(mid 146.343269 -83.598201)
		(end 147.130516 -84.124038)
		(width 0.127)
		(layer "In5.Cu")
		(net "PCIE_10G_CPU_TX3_N")
	)
	(arc
		(start 160.941004 -88.31707)
		(mid 161.007728 -88.263181)
		(end 161.090864 -88.24214)
		(width 0.127)
		(layer "In5.Cu")
		(net "PCIE_10G_CPU_TX3_N")
	)
	(arc
		(start 174.952914 -88.31707)
		(mid 175.019659 -88.370894)
		(end 175.102774 -88.392)
		(width 0.127)
		(layer "In5.Cu")
		(net "PCIE_10G_CPU_TX3_N")
	)
	(arc
		(start 162.152584 -88.392)
		(mid 162.23572 -88.370936)
		(end 162.302444 -88.31707)
		(width 0.127)
		(layer "In5.Cu")
		(net "PCIE_10G_CPU_TX3_N")
	)
	(arc
		(start 143.442182 -82.677)
		(mid 143.856902 -82.759569)
		(end 144.2085 -82.9945)
		(width 0.127)
		(layer "In5.Cu")
		(net "PCIE_10G_CPU_TX3_N")
	)
	(arc
		(start 140.290042 -82.505042)
		(mid 140.480462 -82.632277)
		(end 140.705078 -82.677)
		(width 0.127)
		(layer "In5.Cu")
		(net "PCIE_10G_CPU_TX3_N")
	)
	(arc
		(start 302.038258 -86.646258)
		(mid 302.299198 -86.471997)
		(end 302.606964 -86.4108)
		(width 0.127)
		(layer "In5.Cu")
		(net "PCIE_10G_CPU_TX3_N")
	)
	(arc
		(start 167.61333 -88.24214)
		(mid 167.696466 -88.263204)
		(end 167.76319 -88.31707)
		(width 0.127)
		(layer "In5.Cu")
		(net "PCIE_10G_CPU_TX3_N")
	)
	(arc
		(start 140.393674 -79.1464)
		(mid 140.235055 -79.177969)
		(end 140.100558 -79.267812)
		(width 0.127)
		(layer "In5.Cu")
		(net "PCIE_10G_CPU_TX3_N")
	)
	(arc
		(start 159.579564 -88.31707)
		(mid 159.646288 -88.263181)
		(end 159.729424 -88.24214)
		(width 0.127)
		(layer "In5.Cu")
		(net "PCIE_10G_CPU_TX3_N")
	)
	(arc
		(start 162.302444 -88.31707)
		(mid 162.369168 -88.263181)
		(end 162.452304 -88.24214)
		(width 0.127)
		(layer "In5.Cu")
		(net "PCIE_10G_CPU_TX3_N")
	)
	(arc
		(start 176.314354 -88.31707)
		(mid 176.381099 -88.370894)
		(end 176.464214 -88.392)
		(width 0.127)
		(layer "In5.Cu")
		(net "PCIE_10G_CPU_TX3_N")
	)
	(arc
		(start 166.93261 -88.392)
		(mid 167.015746 -88.370936)
		(end 167.08247 -88.31707)
		(width 0.127)
		(layer "In5.Cu")
		(net "PCIE_10G_CPU_TX3_N")
	)
	(arc
		(start 160.110424 -88.24214)
		(mid 160.19356 -88.263204)
		(end 160.260284 -88.31707)
		(width 0.127)
		(layer "In5.Cu")
		(net "PCIE_10G_CPU_TX3_N")
	)
	(arc
		(start 185.118502 -87.308436)
		(mid 185.606453 -86.982461)
		(end 186.182 -86.868)
		(width 0.127)
		(layer "In5.Cu")
		(net "PCIE_10G_CPU_TX3_N")
	)
	(arc
		(start 304.269902 -86.636098)
		(mid 304.36708 -86.781535)
		(end 304.40122 -86.95309)
		(width 0.127)
		(layer "In5.Cu")
		(net "PCIE_10G_CPU_TX3_N")
	)
	(arc
		(start 175.483774 -88.392)
		(mid 175.566889 -88.370917)
		(end 175.633634 -88.31707)
		(width 0.127)
		(layer "In5.Cu")
		(net "PCIE_10G_CPU_TX3_N")
	)
	(arc
		(start 151.21255 -88.206072)
		(mid 151.418586 -88.343741)
		(end 151.661622 -88.392)
		(width 0.127)
		(layer "In5.Cu")
		(net "PCIE_10G_CPU_TX3_N")
	)
	(arc
		(start 165.04031 -88.31707)
		(mid 165.107055 -88.370894)
		(end 165.19017 -88.392)
		(width 0.127)
		(layer "In5.Cu")
		(net "PCIE_10G_CPU_TX3_N")
	)
	(arc
		(start 173.441614 -88.24214)
		(mid 173.524729 -88.263223)
		(end 173.591474 -88.31707)
		(width 0.127)
		(layer "In5.Cu")
		(net "PCIE_10G_CPU_TX3_N")
	)
	(arc
		(start 164.35959 -88.31707)
		(mid 164.426335 -88.263246)
		(end 164.50945 -88.24214)
		(width 0.127)
		(layer "In5.Cu")
		(net "PCIE_10G_CPU_TX3_N")
	)
	(arc
		(start 140.899896 -79.525622)
		(mid 140.802325 -79.271592)
		(end 140.55979 -79.148178)
		(width 0.127)
		(layer "In5.Cu")
		(net "PCIE_10G_CPU_TX3_N")
	)
	(arc
		(start 173.591474 -88.31707)
		(mid 173.658219 -88.370894)
		(end 173.741334 -88.392)
		(width 0.127)
		(layer "In5.Cu")
		(net "PCIE_10G_CPU_TX3_N")
	)
	(arc
		(start 160.791144 -88.392)
		(mid 160.87428 -88.370936)
		(end 160.941004 -88.31707)
		(width 0.127)
		(layer "In5.Cu")
		(net "PCIE_10G_CPU_TX3_N")
	)
	(arc
		(start 165.72103 -88.31707)
		(mid 165.787775 -88.263246)
		(end 165.87089 -88.24214)
		(width 0.127)
		(layer "In5.Cu")
		(net "PCIE_10G_CPU_TX3_N")
	)
	(arc
		(start 301.502826 -86.868)
		(mid 301.792584 -86.810364)
		(end 302.038258 -86.646258)
		(width 0.127)
		(layer "In5.Cu")
		(net "PCIE_10G_CPU_TX3_N")
	)
	(arc
		(start 166.40175 -88.31707)
		(mid 166.468495 -88.370894)
		(end 166.55161 -88.392)
		(width 0.127)
		(layer "In5.Cu")
		(net "PCIE_10G_CPU_TX3_N")
	)
	(arc
		(start 165.57117 -88.392)
		(mid 165.654306 -88.370936)
		(end 165.72103 -88.31707)
		(width 0.127)
		(layer "In5.Cu")
		(net "PCIE_10G_CPU_TX3_N")
	)
	(arc
		(start 172.760894 -88.392)
		(mid 172.844009 -88.370917)
		(end 172.910754 -88.31707)
		(width 0.127)
		(layer "In5.Cu")
		(net "PCIE_10G_CPU_TX3_N")
	)
	(arc
		(start 139.58697 -81.534)
		(mid 139.636215 -81.781572)
		(end 139.776454 -81.991454)
		(width 0.127)
		(layer "In5.Cu")
		(net "PCIE_10G_CPU_TX3_N")
	)
	(arc
		(start 164.89045 -88.24214)
		(mid 164.973586 -88.263204)
		(end 165.04031 -88.31707)
		(width 0.127)
		(layer "In5.Cu")
		(net "PCIE_10G_CPU_TX3_N")
	)
	(arc
		(start 176.164494 -88.24214)
		(mid 176.247609 -88.263223)
		(end 176.314354 -88.31707)
		(width 0.127)
		(layer "In5.Cu")
		(net "PCIE_10G_CPU_TX3_N")
	)
	(segment
		(start 297.123358 -73.645014)
		(end 297.123358 -73.69175)
		(width 0.1397)
		(layer "F.Cu")
		(net "PCIE_10G_CPU_TX0_P")
	)
	(segment
		(start 299.669454 -72.136)
		(end 299.085 -72.136)
		(width 0.1397)
		(layer "F.Cu")
		(net "PCIE_10G_CPU_TX0_P")
	)
	(segment
		(start 297.784012 -72.674734)
		(end 297.7515 -72.7075)
		(width 0.1397)
		(layer "F.Cu")
		(net "PCIE_10G_CPU_TX0_P")
	)
	(segment
		(start 307.064156 -70.2183)
		(end 302.866806 -70.2183)
		(width 0.1397)
		(layer "F.Cu")
		(net "PCIE_10G_CPU_TX0_P")
	)
	(segment
		(start 301.885604 -70.6247)
		(end 300.872652 -71.637652)
		(width 0.1397)
		(layer "F.Cu")
		(net "PCIE_10G_CPU_TX0_P")
	)
	(segment
		(start 307.427376 -70.01637)
		(end 307.34 -70.104)
		(width 0.1397)
		(layer "F.Cu")
		(net "PCIE_10G_CPU_TX0_P")
	)
	(segment
		(start 297.7515 -72.7075)
		(end 297.342052 -73.116694)
		(width 0.1397)
		(layer "F.Cu")
		(net "PCIE_10G_CPU_TX0_P")
	)
	(segment
		(start 308.675024 -70.000114)
		(end 307.467 -70.000114)
		(width 0.1397)
		(layer "F.Cu")
		(net "PCIE_10G_CPU_TX0_P")
	)
	(via
		(at 297.123358 -73.69175)
		(size 0.5588)
		(drill 0.3048)
		(layers "F.Cu" "B.Cu")
		(net "PCIE_10G_CPU_TX0_P")
	)
	(arc
		(start 299.085 -72.136)
		(mid 298.380915 -72.275958)
		(end 297.784012 -72.674734)
		(width 0.1397)
		(layer "F.Cu")
		(net "PCIE_10G_CPU_TX0_P")
	)
	(arc
		(start 297.342052 -73.116694)
		(mid 297.180142 -73.359104)
		(end 297.123358 -73.645014)
		(width 0.1397)
		(layer "F.Cu")
		(net "PCIE_10G_CPU_TX0_P")
	)
	(arc
		(start 302.866806 -70.2183)
		(mid 302.335779 -70.32391)
		(end 301.885604 -70.6247)
		(width 0.1397)
		(layer "F.Cu")
		(net "PCIE_10G_CPU_TX0_P")
	)
	(arc
		(start 300.872652 -71.637652)
		(mid 300.32062 -72.006508)
		(end 299.669454 -72.136)
		(width 0.1397)
		(layer "F.Cu")
		(net "PCIE_10G_CPU_TX0_P")
	)
	(arc
		(start 307.467 -70.000114)
		(mid 307.445562 -70.004284)
		(end 307.427376 -70.01637)
		(width 0.1397)
		(layer "F.Cu")
		(net "PCIE_10G_CPU_TX0_P")
	)
	(arc
		(start 307.34 -70.104)
		(mid 307.213442 -70.188564)
		(end 307.064156 -70.2183)
		(width 0.1397)
		(layer "F.Cu")
		(net "PCIE_10G_CPU_TX0_P")
	)
	(segment
		(start 242.083336 -72.898)
		(end 247.201436 -72.898)
		(width 0.127)
		(layer "In5.Cu")
		(net "PCIE_10G_CPU_TX0_P")
	)
	(segment
		(start 240.041176 -73.04786)
		(end 240.422176 -73.04786)
		(width 0.127)
		(layer "In5.Cu")
		(net "PCIE_10G_CPU_TX0_P")
	)
	(segment
		(start 182.439056 -68.639944)
		(end 182.8673 -68.2117)
		(width 0.127)
		(layer "In5.Cu")
		(net "PCIE_10G_CPU_TX0_P")
	)
	(segment
		(start 152.899364 -79.068168)
		(end 152.89911 -79.068168)
		(width 0.127)
		(layer "In5.Cu")
		(net "PCIE_10G_CPU_TX0_P")
	)
	(segment
		(start 257.811778 -72.898)
		(end 258.192778 -72.898)
		(width 0.127)
		(layer "In5.Cu")
		(net "PCIE_10G_CPU_TX0_P")
	)
	(segment
		(start 249.543316 -72.898)
		(end 249.924316 -72.898)
		(width 0.127)
		(layer "In5.Cu")
		(net "PCIE_10G_CPU_TX0_P")
	)
	(segment
		(start 248.862596 -73.04786)
		(end 249.243596 -73.04786)
		(width 0.127)
		(layer "In5.Cu")
		(net "PCIE_10G_CPU_TX0_P")
	)
	(segment
		(start 182.430928 -68.64858)
		(end 182.439056 -68.639944)
		(width 0.127)
		(layer "In5.Cu")
		(net "PCIE_10G_CPU_TX0_P")
	)
	(segment
		(start 250.224036 -73.04786)
		(end 250.605036 -73.04786)
		(width 0.127)
		(layer "In5.Cu")
		(net "PCIE_10G_CPU_TX0_P")
	)
	(segment
		(start 250.904756 -72.898)
		(end 255.469898 -72.898)
		(width 0.127)
		(layer "In5.Cu")
		(net "PCIE_10G_CPU_TX0_P")
	)
	(segment
		(start 152.28697 -74.6506)
		(end 151.741632 -74.105516)
		(width 0.127)
		(layer "In5.Cu")
		(net "PCIE_10G_CPU_TX0_P")
	)
	(segment
		(start 258.492498 -73.04786)
		(end 258.873498 -73.04786)
		(width 0.127)
		(layer "In5.Cu")
		(net "PCIE_10G_CPU_TX0_P")
	)
	(segment
		(start 241.402616 -73.04786)
		(end 241.783616 -73.04786)
		(width 0.127)
		(layer "In5.Cu")
		(net "PCIE_10G_CPU_TX0_P")
	)
	(segment
		(start 235.84154 -72.898)
		(end 238.380016 -72.898)
		(width 0.127)
		(layer "In5.Cu")
		(net "PCIE_10G_CPU_TX0_P")
	)
	(segment
		(start 181.2798 -69.1261)
		(end 181.2798 -69.126354)
		(width 0.127)
		(layer "In5.Cu")
		(net "PCIE_10G_CPU_TX0_P")
	)
	(segment
		(start 259.173218 -72.898)
		(end 276.080982 -72.898)
		(width 0.127)
		(layer "In5.Cu")
		(net "PCIE_10G_CPU_TX0_P")
	)
	(segment
		(start 240.721896 -72.898)
		(end 241.102896 -72.898)
		(width 0.127)
		(layer "In5.Cu")
		(net "PCIE_10G_CPU_TX0_P")
	)
	(segment
		(start 255.769618 -73.04786)
		(end 256.150618 -73.04786)
		(width 0.127)
		(layer "In5.Cu")
		(net "PCIE_10G_CPU_TX0_P")
	)
	(segment
		(start 297.434 -73.0758)
		(end 297.434 -73.2536)
		(width 0.127)
		(layer "In5.Cu")
		(net "PCIE_10G_CPU_TX0_P")
	)
	(segment
		(start 248.181876 -72.898)
		(end 248.562876 -72.898)
		(width 0.127)
		(layer "In5.Cu")
		(net "PCIE_10G_CPU_TX0_P")
	)
	(segment
		(start 276.633432 -72.6694)
		(end 297.019472 -72.6694)
		(width 0.127)
		(layer "In5.Cu")
		(net "PCIE_10G_CPU_TX0_P")
	)
	(segment
		(start 184.124346 -67.691)
		(end 227.965 -67.691)
		(width 0.127)
		(layer "In5.Cu")
		(net "PCIE_10G_CPU_TX0_P")
	)
	(segment
		(start 153.450036 -78.24978)
		(end 153.069798 -79.011272)
		(width 0.127)
		(layer "In5.Cu")
		(net "PCIE_10G_CPU_TX0_P")
	)
	(segment
		(start 239.360456 -72.898)
		(end 239.741456 -72.898)
		(width 0.127)
		(layer "In5.Cu")
		(net "PCIE_10G_CPU_TX0_P")
	)
	(segment
		(start 297.312588 -72.790812)
		(end 297.31843 -72.7964)
		(width 0.127)
		(layer "In5.Cu")
		(net "PCIE_10G_CPU_TX0_P")
	)
	(segment
		(start 152.69337 -78.78953)
		(end 152.69337 -75.631802)
		(width 0.127)
		(layer "In5.Cu")
		(net "PCIE_10G_CPU_TX0_P")
	)
	(segment
		(start 152.89911 -79.068168)
		(end 152.898348 -79.067914)
		(width 0.127)
		(layer "In5.Cu")
		(net "PCIE_10G_CPU_TX0_P")
	)
	(segment
		(start 238.679736 -73.04786)
		(end 239.060736 -73.04786)
		(width 0.127)
		(layer "In5.Cu")
		(net "PCIE_10G_CPU_TX0_P")
	)
	(segment
		(start 256.450338 -72.898)
		(end 256.831338 -72.898)
		(width 0.127)
		(layer "In5.Cu")
		(net "PCIE_10G_CPU_TX0_P")
	)
	(segment
		(start 152.898348 -79.067914)
		(end 152.785318 -79.011526)
		(width 0.127)
		(layer "In5.Cu")
		(net "PCIE_10G_CPU_TX0_P")
	)
	(segment
		(start 152.101042 -72.804528)
		(end 155.115768 -69.789802)
		(width 0.127)
		(layer "In5.Cu")
		(net "PCIE_10G_CPU_TX0_P")
	)
	(segment
		(start 156.718 -69.1261)
		(end 181.2798 -69.1261)
		(width 0.127)
		(layer "In5.Cu")
		(net "PCIE_10G_CPU_TX0_P")
	)
	(segment
		(start 247.501156 -73.04786)
		(end 247.882156 -73.04786)
		(width 0.127)
		(layer "In5.Cu")
		(net "PCIE_10G_CPU_TX0_P")
	)
	(segment
		(start 229.916228 -68.499228)
		(end 233.2355 -71.8185)
		(width 0.127)
		(layer "In5.Cu")
		(net "PCIE_10G_CPU_TX0_P")
	)
	(segment
		(start 257.131058 -73.04786)
		(end 257.512058 -73.04786)
		(width 0.127)
		(layer "In5.Cu")
		(net "PCIE_10G_CPU_TX0_P")
	)
	(segment
		(start 297.34383 -73.471278)
		(end 297.123358 -73.69175)
		(width 0.127)
		(layer "In5.Cu")
		(net "PCIE_10G_CPU_TX0_P")
	)
	(arc
		(start 248.562876 -72.898)
		(mid 248.646012 -72.919064)
		(end 248.712736 -72.97293)
		(width 0.127)
		(layer "In5.Cu")
		(net "PCIE_10G_CPU_TX0_P")
	)
	(arc
		(start 239.060736 -73.04786)
		(mid 239.143872 -73.026796)
		(end 239.210596 -72.97293)
		(width 0.127)
		(layer "In5.Cu")
		(net "PCIE_10G_CPU_TX0_P")
	)
	(arc
		(start 276.524212 -72.714612)
		(mid 276.574323 -72.681159)
		(end 276.633432 -72.6694)
		(width 0.127)
		(layer "In5.Cu")
		(net "PCIE_10G_CPU_TX0_P")
	)
	(arc
		(start 255.619758 -72.97293)
		(mid 255.686482 -73.026819)
		(end 255.769618 -73.04786)
		(width 0.127)
		(layer "In5.Cu")
		(net "PCIE_10G_CPU_TX0_P")
	)
	(arc
		(start 249.924316 -72.898)
		(mid 250.007452 -72.919064)
		(end 250.074176 -72.97293)
		(width 0.127)
		(layer "In5.Cu")
		(net "PCIE_10G_CPU_TX0_P")
	)
	(arc
		(start 258.192778 -72.898)
		(mid 258.275914 -72.919064)
		(end 258.342638 -72.97293)
		(width 0.127)
		(layer "In5.Cu")
		(net "PCIE_10G_CPU_TX0_P")
	)
	(arc
		(start 258.873498 -73.04786)
		(mid 258.956634 -73.026796)
		(end 259.023358 -72.97293)
		(width 0.127)
		(layer "In5.Cu")
		(net "PCIE_10G_CPU_TX0_P")
	)
	(arc
		(start 255.469898 -72.898)
		(mid 255.553034 -72.919064)
		(end 255.619758 -72.97293)
		(width 0.127)
		(layer "In5.Cu")
		(net "PCIE_10G_CPU_TX0_P")
	)
	(arc
		(start 256.831338 -72.898)
		(mid 256.914474 -72.919064)
		(end 256.981198 -72.97293)
		(width 0.127)
		(layer "In5.Cu")
		(net "PCIE_10G_CPU_TX0_P")
	)
	(arc
		(start 241.783616 -73.04786)
		(mid 241.866752 -73.026796)
		(end 241.933476 -72.97293)
		(width 0.127)
		(layer "In5.Cu")
		(net "PCIE_10G_CPU_TX0_P")
	)
	(arc
		(start 276.080982 -72.898)
		(mid 276.320872 -72.850453)
		(end 276.524212 -72.714612)
		(width 0.127)
		(layer "In5.Cu")
		(net "PCIE_10G_CPU_TX0_P")
	)
	(arc
		(start 256.981198 -72.97293)
		(mid 257.047922 -73.026819)
		(end 257.131058 -73.04786)
		(width 0.127)
		(layer "In5.Cu")
		(net "PCIE_10G_CPU_TX0_P")
	)
	(arc
		(start 241.102896 -72.898)
		(mid 241.186032 -72.919064)
		(end 241.252756 -72.97293)
		(width 0.127)
		(layer "In5.Cu")
		(net "PCIE_10G_CPU_TX0_P")
	)
	(arc
		(start 241.933476 -72.97293)
		(mid 242.000221 -72.919106)
		(end 242.083336 -72.898)
		(width 0.127)
		(layer "In5.Cu")
		(net "PCIE_10G_CPU_TX0_P")
	)
	(arc
		(start 257.512058 -73.04786)
		(mid 257.595194 -73.026796)
		(end 257.661918 -72.97293)
		(width 0.127)
		(layer "In5.Cu")
		(net "PCIE_10G_CPU_TX0_P")
	)
	(arc
		(start 153.069798 -79.011272)
		(mid 152.996384 -79.075001)
		(end 152.899364 -79.068168)
		(width 0.127)
		(layer "In5.Cu")
		(net "PCIE_10G_CPU_TX0_P")
	)
	(arc
		(start 233.2355 -71.8185)
		(mid 234.431161 -72.617445)
		(end 235.84154 -72.898)
		(width 0.127)
		(layer "In5.Cu")
		(net "PCIE_10G_CPU_TX0_P")
	)
	(arc
		(start 238.529876 -72.97293)
		(mid 238.596621 -73.026754)
		(end 238.679736 -73.04786)
		(width 0.127)
		(layer "In5.Cu")
		(net "PCIE_10G_CPU_TX0_P")
	)
	(arc
		(start 239.891316 -72.97293)
		(mid 239.958061 -73.026754)
		(end 240.041176 -73.04786)
		(width 0.127)
		(layer "In5.Cu")
		(net "PCIE_10G_CPU_TX0_P")
	)
	(arc
		(start 249.393456 -72.97293)
		(mid 249.46018 -72.919041)
		(end 249.543316 -72.898)
		(width 0.127)
		(layer "In5.Cu")
		(net "PCIE_10G_CPU_TX0_P")
	)
	(arc
		(start 241.252756 -72.97293)
		(mid 241.319501 -73.026754)
		(end 241.402616 -73.04786)
		(width 0.127)
		(layer "In5.Cu")
		(net "PCIE_10G_CPU_TX0_P")
	)
	(arc
		(start 247.201436 -72.898)
		(mid 247.284572 -72.919064)
		(end 247.351296 -72.97293)
		(width 0.127)
		(layer "In5.Cu")
		(net "PCIE_10G_CPU_TX0_P")
	)
	(arc
		(start 239.741456 -72.898)
		(mid 239.824592 -72.919064)
		(end 239.891316 -72.97293)
		(width 0.127)
		(layer "In5.Cu")
		(net "PCIE_10G_CPU_TX0_P")
	)
	(arc
		(start 247.351296 -72.97293)
		(mid 247.41802 -73.026819)
		(end 247.501156 -73.04786)
		(width 0.127)
		(layer "In5.Cu")
		(net "PCIE_10G_CPU_TX0_P")
	)
	(arc
		(start 151.741632 -74.105516)
		(mid 151.675217 -74.005979)
		(end 151.65197 -73.8886)
		(width 0.127)
		(layer "In5.Cu")
		(net "PCIE_10G_CPU_TX0_P")
	)
	(arc
		(start 152.69337 -75.631802)
		(mid 152.587745 -75.10079)
		(end 152.28697 -74.6506)
		(width 0.127)
		(layer "In5.Cu")
		(net "PCIE_10G_CPU_TX0_P")
	)
	(arc
		(start 259.023358 -72.97293)
		(mid 259.090082 -72.919041)
		(end 259.173218 -72.898)
		(width 0.127)
		(layer "In5.Cu")
		(net "PCIE_10G_CPU_TX0_P")
	)
	(arc
		(start 181.2798 -69.126354)
		(mid 181.902994 -69.002218)
		(end 182.430928 -68.64858)
		(width 0.127)
		(layer "In5.Cu")
		(net "PCIE_10G_CPU_TX0_P")
	)
	(arc
		(start 155.115768 -69.789802)
		(mid 155.850878 -69.298617)
		(end 156.718 -69.1261)
		(width 0.127)
		(layer "In5.Cu")
		(net "PCIE_10G_CPU_TX0_P")
	)
	(arc
		(start 297.31843 -72.7964)
		(mid 297.404001 -72.924605)
		(end 297.434 -73.0758)
		(width 0.127)
		(layer "In5.Cu")
		(net "PCIE_10G_CPU_TX0_P")
	)
	(arc
		(start 249.243596 -73.04786)
		(mid 249.326732 -73.026796)
		(end 249.393456 -72.97293)
		(width 0.127)
		(layer "In5.Cu")
		(net "PCIE_10G_CPU_TX0_P")
	)
	(arc
		(start 248.032016 -72.97293)
		(mid 248.09874 -72.919041)
		(end 248.181876 -72.898)
		(width 0.127)
		(layer "In5.Cu")
		(net "PCIE_10G_CPU_TX0_P")
	)
	(arc
		(start 297.019472 -72.6694)
		(mid 297.178105 -72.700954)
		(end 297.312588 -72.790812)
		(width 0.127)
		(layer "In5.Cu")
		(net "PCIE_10G_CPU_TX0_P")
	)
	(arc
		(start 257.661918 -72.97293)
		(mid 257.728642 -72.919041)
		(end 257.811778 -72.898)
		(width 0.127)
		(layer "In5.Cu")
		(net "PCIE_10G_CPU_TX0_P")
	)
	(arc
		(start 239.210596 -72.97293)
		(mid 239.277341 -72.919106)
		(end 239.360456 -72.898)
		(width 0.127)
		(layer "In5.Cu")
		(net "PCIE_10G_CPU_TX0_P")
	)
	(arc
		(start 248.712736 -72.97293)
		(mid 248.77946 -73.026819)
		(end 248.862596 -73.04786)
		(width 0.127)
		(layer "In5.Cu")
		(net "PCIE_10G_CPU_TX0_P")
	)
	(arc
		(start 256.150618 -73.04786)
		(mid 256.233754 -73.026796)
		(end 256.300478 -72.97293)
		(width 0.127)
		(layer "In5.Cu")
		(net "PCIE_10G_CPU_TX0_P")
	)
	(arc
		(start 250.754896 -72.97293)
		(mid 250.82162 -72.919041)
		(end 250.904756 -72.898)
		(width 0.127)
		(layer "In5.Cu")
		(net "PCIE_10G_CPU_TX0_P")
	)
	(arc
		(start 250.605036 -73.04786)
		(mid 250.688172 -73.026796)
		(end 250.754896 -72.97293)
		(width 0.127)
		(layer "In5.Cu")
		(net "PCIE_10G_CPU_TX0_P")
	)
	(arc
		(start 240.572036 -72.97293)
		(mid 240.638781 -72.919106)
		(end 240.721896 -72.898)
		(width 0.127)
		(layer "In5.Cu")
		(net "PCIE_10G_CPU_TX0_P")
	)
	(arc
		(start 297.434 -73.2536)
		(mid 297.410566 -73.371408)
		(end 297.34383 -73.471278)
		(width 0.127)
		(layer "In5.Cu")
		(net "PCIE_10G_CPU_TX0_P")
	)
	(arc
		(start 238.380016 -72.898)
		(mid 238.463152 -72.919064)
		(end 238.529876 -72.97293)
		(width 0.127)
		(layer "In5.Cu")
		(net "PCIE_10G_CPU_TX0_P")
	)
	(arc
		(start 151.65197 -73.8886)
		(mid 151.768674 -73.301891)
		(end 152.101042 -72.804528)
		(width 0.127)
		(layer "In5.Cu")
		(net "PCIE_10G_CPU_TX0_P")
	)
	(arc
		(start 152.785318 -79.011526)
		(mid 152.717262 -78.909673)
		(end 152.69337 -78.78953)
		(width 0.127)
		(layer "In5.Cu")
		(net "PCIE_10G_CPU_TX0_P")
	)
	(arc
		(start 256.300478 -72.97293)
		(mid 256.367202 -72.919041)
		(end 256.450338 -72.898)
		(width 0.127)
		(layer "In5.Cu")
		(net "PCIE_10G_CPU_TX0_P")
	)
	(arc
		(start 182.8673 -68.2117)
		(mid 183.444052 -67.82639)
		(end 184.124346 -67.691)
		(width 0.127)
		(layer "In5.Cu")
		(net "PCIE_10G_CPU_TX0_P")
	)
	(arc
		(start 250.074176 -72.97293)
		(mid 250.1409 -73.026819)
		(end 250.224036 -73.04786)
		(width 0.127)
		(layer "In5.Cu")
		(net "PCIE_10G_CPU_TX0_P")
	)
	(arc
		(start 247.882156 -73.04786)
		(mid 247.965292 -73.026796)
		(end 248.032016 -72.97293)
		(width 0.127)
		(layer "In5.Cu")
		(net "PCIE_10G_CPU_TX0_P")
	)
	(arc
		(start 258.342638 -72.97293)
		(mid 258.409362 -73.026819)
		(end 258.492498 -73.04786)
		(width 0.127)
		(layer "In5.Cu")
		(net "PCIE_10G_CPU_TX0_P")
	)
	(arc
		(start 227.965 -67.691)
		(mid 229.020998 -67.901051)
		(end 229.916228 -68.499228)
		(width 0.127)
		(layer "In5.Cu")
		(net "PCIE_10G_CPU_TX0_P")
	)
	(arc
		(start 240.422176 -73.04786)
		(mid 240.505312 -73.026796)
		(end 240.572036 -72.97293)
		(width 0.127)
		(layer "In5.Cu")
		(net "PCIE_10G_CPU_TX0_P")
	)
	(segment
		(start 191.5541 -74.565764)
		(end 191.832484 -74.843894)
		(width 0.1397)
		(layer "F.Cu")
		(net "PCIE_SAS_CPU_TX_N3")
	)
	(segment
		(start 118.157244 -8.9789)
		(end 133.554216 -8.9789)
		(width 0.1397)
		(layer "F.Cu")
		(net "PCIE_SAS_CPU_TX_N3")
	)
	(segment
		(start 106.977688 -16.764)
		(end 109.70387 -16.764)
		(width 0.1397)
		(layer "F.Cu")
		(net "PCIE_SAS_CPU_TX_N3")
	)
	(segment
		(start 99.124516 -32.577278)
		(end 99.12477 -32.577024)
		(width 0.1397)
		(layer "F.Cu")
		(net "PCIE_SAS_CPU_TX_N3")
	)
	(segment
		(start 99.12477 -32.577024)
		(end 99.12477 -31.389066)
		(width 0.1397)
		(layer "F.Cu")
		(net "PCIE_SAS_CPU_TX_N3")
	)
	(segment
		(start 192.289176 -75.553824)
		(end 192.28943 -75.55357)
		(width 0.1397)
		(layer "F.Cu")
		(net "PCIE_SAS_CPU_TX_N3")
	)
	(segment
		(start 98.718878 -30.693868)
		(end 98.698558 -30.673294)
		(width 0.1397)
		(layer "F.Cu")
		(net "PCIE_SAS_CPU_TX_N3")
	)
	(segment
		(start 191.29502 -73.076054)
		(end 191.29502 -73.9394)
		(width 0.1397)
		(layer "F.Cu")
		(net "PCIE_SAS_CPU_TX_N3")
	)
	(segment
		(start 99.12477 -32.930084)
		(end 99.124516 -32.92983)
		(width 0.1397)
		(layer "F.Cu")
		(net "PCIE_SAS_CPU_TX_N3")
	)
	(segment
		(start 134.003288 -9.164828)
		(end 136.94283 -12.10437)
		(width 0.1397)
		(layer "F.Cu")
		(net "PCIE_SAS_CPU_TX_N3")
	)
	(segment
		(start 191.832484 -74.843894)
		(end 192.11036 -75.12177)
		(width 0.1397)
		(layer "F.Cu")
		(net "PCIE_SAS_CPU_TX_N3")
	)
	(segment
		(start 110.395512 -16.477488)
		(end 117.708172 -9.164828)
		(width 0.1397)
		(layer "F.Cu")
		(net "PCIE_SAS_CPU_TX_N3")
	)
	(segment
		(start 98.75012 -34.19983)
		(end 98.75012 -34.073592)
		(width 0.1397)
		(layer "F.Cu")
		(net "PCIE_SAS_CPU_TX_N3")
	)
	(segment
		(start 98.937572 -24.646128)
		(end 106.708448 -16.875506)
		(width 0.1397)
		(layer "F.Cu")
		(net "PCIE_SAS_CPU_TX_N3")
	)
	(segment
		(start 98.920046 -30.895036)
		(end 98.718878 -30.693868)
		(width 0.1397)
		(layer "F.Cu")
		(net "PCIE_SAS_CPU_TX_N3")
	)
	(segment
		(start 98.565716 -30.353)
		(end 98.565716 -25.544018)
		(width 0.1397)
		(layer "F.Cu")
		(net "PCIE_SAS_CPU_TX_N3")
	)
	(segment
		(start 137.414 -13.241528)
		(end 137.414 -17.808194)
		(width 0.1397)
		(layer "F.Cu")
		(net "PCIE_SAS_CPU_TX_N3")
	)
	(segment
		(start 192.28943 -75.55357)
		(end 192.28943 -76.198984)
		(width 0.1397)
		(layer "F.Cu")
		(net "PCIE_SAS_CPU_TX_N3")
	)
	(segment
		(start 137.886186 -18.9484)
		(end 190.786766 -71.84898)
		(width 0.1397)
		(layer "F.Cu")
		(net "PCIE_SAS_CPU_TX_N3")
	)
	(segment
		(start 99.124516 -32.92983)
		(end 99.124516 -32.577278)
		(width 0.1397)
		(layer "F.Cu")
		(net "PCIE_SAS_CPU_TX_N3")
	)
	(segment
		(start 98.81997 -33.90519)
		(end 98.969068 -33.756092)
		(width 0.1397)
		(layer "F.Cu")
		(net "PCIE_SAS_CPU_TX_N3")
	)
	(segment
		(start 99.12477 -33.380426)
		(end 99.12477 -32.930084)
		(width 0.1397)
		(layer "F.Cu")
		(net "PCIE_SAS_CPU_TX_N3")
	)
	(via
		(at 191.947038 -77.0255)
		(size 0.5588)
		(drill 0.3048)
		(layers "F.Cu" "B.Cu")
		(net "PCIE_SAS_CPU_TX_N3")
	)
	(arc
		(start 137.414 -17.808194)
		(mid 137.536706 -18.425258)
		(end 137.886186 -18.9484)
		(width 0.1397)
		(layer "F.Cu")
		(net "PCIE_SAS_CPU_TX_N3")
	)
	(arc
		(start 191.29502 -73.9394)
		(mid 191.362239 -74.278366)
		(end 191.5541 -74.565764)
		(width 0.1397)
		(layer "F.Cu")
		(net "PCIE_SAS_CPU_TX_N3")
	)
	(arc
		(start 190.786766 -71.84898)
		(mid 191.162941 -72.411966)
		(end 191.29502 -73.076054)
		(width 0.1397)
		(layer "F.Cu")
		(net "PCIE_SAS_CPU_TX_N3")
	)
	(arc
		(start 98.698558 -30.673294)
		(mid 98.600285 -30.526357)
		(end 98.565716 -30.353)
		(width 0.1397)
		(layer "F.Cu")
		(net "PCIE_SAS_CPU_TX_N3")
	)
	(arc
		(start 106.708448 -16.875506)
		(mid 106.831991 -16.793021)
		(end 106.977688 -16.764)
		(width 0.1397)
		(layer "F.Cu")
		(net "PCIE_SAS_CPU_TX_N3")
	)
	(arc
		(start 192.28943 -76.198984)
		(mid 192.200452 -76.646306)
		(end 191.947038 -77.0255)
		(width 0.1397)
		(layer "F.Cu")
		(net "PCIE_SAS_CPU_TX_N3")
	)
	(arc
		(start 136.94283 -12.10437)
		(mid 137.291523 -12.626087)
		(end 137.414 -13.241528)
		(width 0.1397)
		(layer "F.Cu")
		(net "PCIE_SAS_CPU_TX_N3")
	)
	(arc
		(start 109.70387 -16.764)
		(mid 110.078179 -16.689527)
		(end 110.395512 -16.477488)
		(width 0.1397)
		(layer "F.Cu")
		(net "PCIE_SAS_CPU_TX_N3")
	)
	(arc
		(start 99.12477 -31.389066)
		(mid 99.071513 -31.121704)
		(end 98.920046 -30.895036)
		(width 0.1397)
		(layer "F.Cu")
		(net "PCIE_SAS_CPU_TX_N3")
	)
	(arc
		(start 98.75012 -34.073592)
		(mid 98.768271 -33.982431)
		(end 98.81997 -33.90519)
		(width 0.1397)
		(layer "F.Cu")
		(net "PCIE_SAS_CPU_TX_N3")
	)
	(arc
		(start 192.11036 -75.12177)
		(mid 192.242729 -75.320013)
		(end 192.289176 -75.553824)
		(width 0.1397)
		(layer "F.Cu")
		(net "PCIE_SAS_CPU_TX_N3")
	)
	(arc
		(start 117.708172 -9.164828)
		(mid 117.914208 -9.027159)
		(end 118.157244 -8.9789)
		(width 0.1397)
		(layer "F.Cu")
		(net "PCIE_SAS_CPU_TX_N3")
	)
	(arc
		(start 98.969068 -33.756092)
		(mid 99.084287 -33.583749)
		(end 99.12477 -33.380426)
		(width 0.1397)
		(layer "F.Cu")
		(net "PCIE_SAS_CPU_TX_N3")
	)
	(arc
		(start 98.565716 -25.544018)
		(mid 98.662355 -25.058093)
		(end 98.937572 -24.646128)
		(width 0.1397)
		(layer "F.Cu")
		(net "PCIE_SAS_CPU_TX_N3")
	)
	(arc
		(start 133.554216 -8.9789)
		(mid 133.79722 -9.027236)
		(end 134.003288 -9.164828)
		(width 0.1397)
		(layer "F.Cu")
		(net "PCIE_SAS_CPU_TX_N3")
	)
	(segment
		(start 192.748408 -79.340202)
		(end 192.58026 -79.256128)
		(width 0.1397)
		(layer "B.Cu")
		(net "PCIE_SAS_CPU_TX_N3")
	)
	(segment
		(start 192.749678 -79.340964)
		(end 192.749424 -79.340964)
		(width 0.1397)
		(layer "B.Cu")
		(net "PCIE_SAS_CPU_TX_N3")
	)
	(segment
		(start 192.748916 -79.34071)
		(end 192.748916 -79.340964)
		(width 0.1397)
		(layer "B.Cu")
		(net "PCIE_SAS_CPU_TX_N3")
	)
	(segment
		(start 192.450466 -80.25003)
		(end 192.811908 -79.528416)
		(width 0.1397)
		(layer "B.Cu")
		(net "PCIE_SAS_CPU_TX_N3")
	)
	(segment
		(start 192.189354 -77.267562)
		(end 191.947038 -77.0255)
		(width 0.1397)
		(layer "B.Cu")
		(net "PCIE_SAS_CPU_TX_N3")
	)
	(segment
		(start 192.749424 -79.340964)
		(end 192.748916 -79.34071)
		(width 0.1397)
		(layer "B.Cu")
		(net "PCIE_SAS_CPU_TX_N3")
	)
	(segment
		(start 192.26149 -78.553564)
		(end 192.26149 -77.44206)
		(width 0.1397)
		(layer "B.Cu")
		(net "PCIE_SAS_CPU_TX_N3")
	)
	(arc
		(start 192.748916 -79.340964)
		(mid 192.748662 -79.340583)
		(end 192.748408 -79.340202)
		(width 0.1397)
		(layer "B.Cu")
		(net "PCIE_SAS_CPU_TX_N3")
	)
	(arc
		(start 192.58026 -79.256128)
		(mid 192.344971 -78.939287)
		(end 192.26149 -78.553564)
		(width 0.1397)
		(layer "B.Cu")
		(net "PCIE_SAS_CPU_TX_N3")
	)
	(arc
		(start 192.811908 -79.528416)
		(mid 192.819524 -79.421857)
		(end 192.749678 -79.340964)
		(width 0.1397)
		(layer "B.Cu")
		(net "PCIE_SAS_CPU_TX_N3")
	)
	(arc
		(start 192.26149 -77.44206)
		(mid 192.242799 -77.347624)
		(end 192.189354 -77.267562)
		(width 0.1397)
		(layer "B.Cu")
		(net "PCIE_SAS_CPU_TX_N3")
	)
	(segment
		(start 295.717214 -201.316082)
		(end 295.717214 -200.233788)
		(width 0.1143)
		(layer "F.Cu")
		(net "MEMDQ_12")
	)
	(segment
		(start 295.234868 -181.840124)
		(end 295.630092 -182.235348)
		(width 0.1143)
		(layer "F.Cu")
		(net "MEMDQ_12")
	)
	(segment
		(start 295.717214 -200.233788)
		(end 295.926002 -200.025)
		(width 0.1143)
		(layer "F.Cu")
		(net "MEMDQ_12")
	)
	(segment
		(start 295.298114 -201.735182)
		(end 295.717214 -201.316082)
		(width 0.1143)
		(layer "F.Cu")
		(net "MEMDQ_12")
	)
	(via
		(at 295.926002 -200.025)
		(size 0.508)
		(drill 0.254)
		(layers "F.Cu" "B.Cu")
		(net "MEMDQ_12")
	)
	(via
		(at 295.926002 -200.7616)
		(size 0.7112)
		(drill 0.3556)
		(layers "F.Cu" "B.Cu")
		(net "MEMDQ_12")
	)
	(via
		(at 295.630092 -182.235348)
		(size 0.508)
		(drill 0.254)
		(layers "F.Cu" "B.Cu")
		(net "MEMDQ_12")
	)
	(segment
		(start 295.926002 -200.025)
		(end 295.926002 -200.7616)
		(width 0.1143)
		(layer "B.Cu")
		(net "MEMDQ_12")
	)
	(segment
		(start 296.00017 -199.950832)
		(end 296.00017 -199.026526)
		(width 0.127)
		(layer "In5.Cu")
		(net "MEMDQ_12")
	)
	(segment
		(start 297.9801 -186.815476)
		(end 297.9801 -185.735468)
		(width 0.127)
		(layer "In5.Cu")
		(net "MEMDQ_12")
	)
	(segment
		(start 298.196 -196.088)
		(end 298.196 -187.031376)
		(width 0.127)
		(layer "In5.Cu")
		(net "MEMDQ_12")
	)
	(segment
		(start 296.945304 -198.081392)
		(end 296.945304 -197.338696)
		(width 0.127)
		(layer "In5.Cu")
		(net "MEMDQ_12")
	)
	(segment
		(start 295.210992 -183.209184)
		(end 295.210992 -182.654448)
		(width 0.127)
		(layer "In5.Cu")
		(net "MEMDQ_12")
	)
	(segment
		(start 298.196 -187.031376)
		(end 297.9801 -186.815476)
		(width 0.127)
		(layer "In5.Cu")
		(net "MEMDQ_12")
	)
	(segment
		(start 296.00017 -199.026526)
		(end 296.945304 -198.081392)
		(width 0.127)
		(layer "In5.Cu")
		(net "MEMDQ_12")
	)
	(segment
		(start 296.945304 -197.338696)
		(end 298.196 -196.088)
		(width 0.127)
		(layer "In5.Cu")
		(net "MEMDQ_12")
	)
	(segment
		(start 296.572432 -184.3278)
		(end 296.329608 -184.3278)
		(width 0.127)
		(layer "In5.Cu")
		(net "MEMDQ_12")
	)
	(segment
		(start 295.210992 -182.654448)
		(end 295.630092 -182.235348)
		(width 0.127)
		(layer "In5.Cu")
		(net "MEMDQ_12")
	)
	(segment
		(start 297.9801 -185.735468)
		(end 296.572432 -184.3278)
		(width 0.127)
		(layer "In5.Cu")
		(net "MEMDQ_12")
	)
	(segment
		(start 296.329608 -184.3278)
		(end 295.210992 -183.209184)
		(width 0.127)
		(layer "In5.Cu")
		(net "MEMDQ_12")
	)
	(segment
		(start 295.926002 -200.025)
		(end 296.00017 -199.950832)
		(width 0.127)
		(layer "In5.Cu")
		(net "MEMDQ_12")
	)
	(segment
		(start 297.80357 -73.355962)
		(end 298.139358 -73.69175)
		(width 0.1397)
		(layer "F.Cu")
		(net "PCIE_10G_CPU_TX0_N")
	)
	(segment
		(start 302.128174 -70.86727)
		(end 301.115222 -71.880222)
		(width 0.1397)
		(layer "F.Cu")
		(net "PCIE_10G_CPU_TX0_N")
	)
	(segment
		(start 308.675024 -70.800214)
		(end 307.594 -70.800214)
		(width 0.1397)
		(layer "F.Cu")
		(net "PCIE_10G_CPU_TX0_N")
	)
	(segment
		(start 307.26507 -70.66407)
		(end 307.213 -70.612)
		(width 0.1397)
		(layer "F.Cu")
		(net "PCIE_10G_CPU_TX0_N")
	)
	(segment
		(start 299.669454 -72.4789)
		(end 299.084746 -72.4789)
		(width 0.1397)
		(layer "F.Cu")
		(net "PCIE_10G_CPU_TX0_N")
	)
	(segment
		(start 298.02709 -72.91705)
		(end 297.80357 -73.14057)
		(width 0.1397)
		(layer "F.Cu")
		(net "PCIE_10G_CPU_TX0_N")
	)
	(segment
		(start 307.090318 -70.5612)
		(end 302.86706 -70.5612)
		(width 0.1397)
		(layer "F.Cu")
		(net "PCIE_10G_CPU_TX0_N")
	)
	(via
		(at 298.139358 -73.69175)
		(size 0.5588)
		(drill 0.3048)
		(layers "F.Cu" "B.Cu")
		(net "PCIE_10G_CPU_TX0_N")
	)
	(arc
		(start 307.594 -70.800214)
		(mid 307.41601 -70.764827)
		(end 307.26507 -70.66407)
		(width 0.1397)
		(layer "F.Cu")
		(net "PCIE_10G_CPU_TX0_N")
	)
	(arc
		(start 301.115222 -71.880222)
		(mid 300.451883 -72.323358)
		(end 299.669454 -72.4789)
		(width 0.1397)
		(layer "F.Cu")
		(net "PCIE_10G_CPU_TX0_N")
	)
	(arc
		(start 302.86706 -70.5612)
		(mid 302.467173 -70.640743)
		(end 302.128174 -70.86727)
		(width 0.1397)
		(layer "F.Cu")
		(net "PCIE_10G_CPU_TX0_N")
	)
	(arc
		(start 297.80357 -73.14057)
		(mid 297.758961 -73.248266)
		(end 297.80357 -73.355962)
		(width 0.1397)
		(layer "F.Cu")
		(net "PCIE_10G_CPU_TX0_N")
	)
	(arc
		(start 307.213 -70.612)
		(mid 307.156713 -70.57439)
		(end 307.090318 -70.5612)
		(width 0.1397)
		(layer "F.Cu")
		(net "PCIE_10G_CPU_TX0_N")
	)
	(arc
		(start 299.084746 -72.4789)
		(mid 298.512376 -72.592867)
		(end 298.02709 -72.91705)
		(width 0.1397)
		(layer "F.Cu")
		(net "PCIE_10G_CPU_TX0_N")
	)
	(segment
		(start 182.231284 -68.452746)
		(end 182.237888 -68.445888)
		(width 0.127)
		(layer "In5.Cu")
		(net "PCIE_10G_CPU_TX0_N")
	)
	(segment
		(start 152.773888 -79.318104)
		(end 152.715976 -79.289402)
		(width 0.127)
		(layer "In5.Cu")
		(net "PCIE_10G_CPU_TX0_N")
	)
	(segment
		(start 156.718 -68.8467)
		(end 181.2798 -68.8467)
		(width 0.127)
		(layer "In5.Cu")
		(net "PCIE_10G_CPU_TX0_N")
	)
	(segment
		(start 152.089358 -74.848212)
		(end 151.816562 -74.57567)
		(width 0.127)
		(layer "In5.Cu")
		(net "PCIE_10G_CPU_TX0_N")
	)
	(segment
		(start 182.237888 -68.445888)
		(end 182.669688 -68.014088)
		(width 0.127)
		(layer "In5.Cu")
		(net "PCIE_10G_CPU_TX0_N")
	)
	(segment
		(start 297.50639 -72.58939)
		(end 297.513756 -72.596248)
		(width 0.127)
		(layer "In5.Cu")
		(net "PCIE_10G_CPU_TX0_N")
	)
	(segment
		(start 297.713654 -73.0758)
		(end 297.7134 -73.0758)
		(width 0.127)
		(layer "In5.Cu")
		(net "PCIE_10G_CPU_TX0_N")
	)
	(segment
		(start 152.41397 -75.631548)
		(end 152.413716 -75.631802)
		(width 0.127)
		(layer "In5.Cu")
		(net "PCIE_10G_CPU_TX0_N")
	)
	(segment
		(start 152.41397 -78.789276)
		(end 152.41397 -75.631548)
		(width 0.127)
		(layer "In5.Cu")
		(net "PCIE_10G_CPU_TX0_N")
	)
	(segment
		(start 152.450546 -80.25003)
		(end 152.831038 -79.488538)
		(width 0.127)
		(layer "In5.Cu")
		(net "PCIE_10G_CPU_TX0_N")
	)
	(segment
		(start 184.124346 -67.4116)
		(end 227.965 -67.4116)
		(width 0.127)
		(layer "In5.Cu")
		(net "PCIE_10G_CPU_TX0_N")
	)
	(segment
		(start 151.816562 -74.57567)
		(end 151.54402 -74.303128)
		(width 0.127)
		(layer "In5.Cu")
		(net "PCIE_10G_CPU_TX0_N")
	)
	(segment
		(start 276.633178 -72.39)
		(end 297.019218 -72.39)
		(width 0.127)
		(layer "In5.Cu")
		(net "PCIE_10G_CPU_TX0_N")
	)
	(segment
		(start 151.90343 -72.606916)
		(end 154.918156 -69.59219)
		(width 0.127)
		(layer "In5.Cu")
		(net "PCIE_10G_CPU_TX0_N")
	)
	(segment
		(start 152.715976 -79.289402)
		(end 152.626568 -79.244698)
		(width 0.127)
		(layer "In5.Cu")
		(net "PCIE_10G_CPU_TX0_N")
	)
	(segment
		(start 152.774142 -79.318104)
		(end 152.773888 -79.318104)
		(width 0.127)
		(layer "In5.Cu")
		(net "PCIE_10G_CPU_TX0_N")
	)
	(segment
		(start 235.841794 -72.6186)
		(end 276.081236 -72.6186)
		(width 0.127)
		(layer "In5.Cu")
		(net "PCIE_10G_CPU_TX0_N")
	)
	(segment
		(start 297.7134 -73.0758)
		(end 297.7134 -73.265792)
		(width 0.127)
		(layer "In5.Cu")
		(net "PCIE_10G_CPU_TX0_N")
	)
	(segment
		(start 230.11384 -68.301616)
		(end 233.433112 -71.620888)
		(width 0.127)
		(layer "In5.Cu")
		(net "PCIE_10G_CPU_TX0_N")
	)
	(arc
		(start 227.965 -67.4116)
		(mid 229.127934 -67.642904)
		(end 230.11384 -68.301616)
		(width 0.127)
		(layer "In5.Cu")
		(net "PCIE_10G_CPU_TX0_N")
	)
	(arc
		(start 152.413716 -75.631802)
		(mid 152.329476 -75.207741)
		(end 152.089358 -74.848212)
		(width 0.127)
		(layer "In5.Cu")
		(net "PCIE_10G_CPU_TX0_N")
	)
	(arc
		(start 154.918156 -69.59219)
		(mid 155.743931 -69.040424)
		(end 156.718 -68.8467)
		(width 0.127)
		(layer "In5.Cu")
		(net "PCIE_10G_CPU_TX0_N")
	)
	(arc
		(start 181.2798 -68.8467)
		(mid 181.794731 -68.744368)
		(end 182.231284 -68.452746)
		(width 0.127)
		(layer "In5.Cu")
		(net "PCIE_10G_CPU_TX0_N")
	)
	(arc
		(start 276.081236 -72.6186)
		(mid 276.214013 -72.592189)
		(end 276.3266 -72.517)
		(width 0.127)
		(layer "In5.Cu")
		(net "PCIE_10G_CPU_TX0_N")
	)
	(arc
		(start 152.626568 -79.244698)
		(mid 152.469633 -79.040616)
		(end 152.41397 -78.789276)
		(width 0.127)
		(layer "In5.Cu")
		(net "PCIE_10G_CPU_TX0_N")
	)
	(arc
		(start 152.831038 -79.488538)
		(mid 152.837797 -79.391593)
		(end 152.774142 -79.318104)
		(width 0.127)
		(layer "In5.Cu")
		(net "PCIE_10G_CPU_TX0_N")
	)
	(arc
		(start 151.37257 -73.8886)
		(mid 151.510542 -73.194969)
		(end 151.90343 -72.606916)
		(width 0.127)
		(layer "In5.Cu")
		(net "PCIE_10G_CPU_TX0_N")
	)
	(arc
		(start 297.7134 -73.265792)
		(mid 297.83816 -73.56699)
		(end 298.139358 -73.69175)
		(width 0.127)
		(layer "In5.Cu")
		(net "PCIE_10G_CPU_TX0_N")
	)
	(arc
		(start 276.3266 -72.517)
		(mid 276.467259 -72.423015)
		(end 276.633178 -72.39)
		(width 0.127)
		(layer "In5.Cu")
		(net "PCIE_10G_CPU_TX0_N")
	)
	(arc
		(start 297.513756 -72.596248)
		(mid 297.661712 -72.816011)
		(end 297.713654 -73.0758)
		(width 0.127)
		(layer "In5.Cu")
		(net "PCIE_10G_CPU_TX0_N")
	)
	(arc
		(start 233.433112 -71.620888)
		(mid 234.538225 -72.359301)
		(end 235.841794 -72.6186)
		(width 0.127)
		(layer "In5.Cu")
		(net "PCIE_10G_CPU_TX0_N")
	)
	(arc
		(start 182.669688 -68.014088)
		(mid 183.337105 -67.568197)
		(end 184.124346 -67.4116)
		(width 0.127)
		(layer "In5.Cu")
		(net "PCIE_10G_CPU_TX0_N")
	)
	(arc
		(start 151.54402 -74.303128)
		(mid 151.417024 -74.112926)
		(end 151.37257 -73.8886)
		(width 0.127)
		(layer "In5.Cu")
		(net "PCIE_10G_CPU_TX0_N")
	)
	(arc
		(start 297.019218 -72.39)
		(mid 297.282419 -72.441748)
		(end 297.50639 -72.58939)
		(width 0.127)
		(layer "In5.Cu")
		(net "PCIE_10G_CPU_TX0_N")
	)
	(segment
		(start 274.80641 -188.341)
		(end 275.206714 -187.940696)
		(width 0.1143)
		(layer "F.Cu")
		(net "PECI0_R")
	)
	(segment
		(start 270.732504 -189.484)
		(end 270.859504 -189.611)
		(width 0.1143)
		(layer "F.Cu")
		(net "PECI0_R")
	)
	(segment
		(start 284.314392 -183.87822)
		(end 285.085028 -183.87822)
		(width 0.1143)
		(layer "F.Cu")
		(net "PECI0_R")
	)
	(segment
		(start 273.685 -188.341)
		(end 274.80641 -188.341)
		(width 0.1143)
		(layer "F.Cu")
		(net "PECI0_R")
	)
	(segment
		(start 270.684752 -190.462916)
		(end 270.684752 -189.484)
		(width 0.1143)
		(layer "F.Cu")
		(net "PECI0_R")
	)
	(segment
		(start 285.523178 -183.44007)
		(end 285.634938 -183.44007)
		(width 0.1143)
		(layer "F.Cu")
		(net "PECI0_R")
	)
	(segment
		(start 270.684752 -189.484)
		(end 270.732504 -189.484)
		(width 0.1143)
		(layer "F.Cu")
		(net "PECI0_R")
	)
	(segment
		(start 270.859504 -189.611)
		(end 272.415 -189.611)
		(width 0.1143)
		(layer "F.Cu")
		(net "PECI0_R")
	)
	(segment
		(start 277.26005 -186.28995)
		(end 282.154122 -186.28995)
		(width 0.1143)
		(layer "F.Cu")
		(net "PECI0_R")
	)
	(segment
		(start 272.415 -189.611)
		(end 273.685 -188.341)
		(width 0.1143)
		(layer "F.Cu")
		(net "PECI0_R")
	)
	(segment
		(start 283.621226 -184.822846)
		(end 283.621226 -184.571386)
		(width 0.1143)
		(layer "F.Cu")
		(net "PECI0_R")
	)
	(segment
		(start 275.609304 -187.940696)
		(end 277.26005 -186.28995)
		(width 0.1143)
		(layer "F.Cu")
		(net "PECI0_R")
	)
	(segment
		(start 285.085028 -183.87822)
		(end 285.523178 -183.44007)
		(width 0.1143)
		(layer "F.Cu")
		(net "PECI0_R")
	)
	(segment
		(start 283.621226 -184.571386)
		(end 284.314392 -183.87822)
		(width 0.1143)
		(layer "F.Cu")
		(net "PECI0_R")
	)
	(segment
		(start 275.206714 -187.940696)
		(end 275.609304 -187.940696)
		(width 0.1143)
		(layer "F.Cu")
		(net "PECI0_R")
	)
	(segment
		(start 282.154122 -186.28995)
		(end 283.621226 -184.822846)
		(width 0.1143)
		(layer "F.Cu")
		(net "PECI0_R")
	)
	(via
		(at 270.684752 -189.484)
		(size 0.7112)
		(drill 0.3556)
		(layers "F.Cu" "B.Cu")
		(net "PECI0_R")
	)
	(segment
		(start 285.698184 -201.72807)
		(end 285.306516 -201.336402)
		(width 0.1143)
		(layer "F.Cu")
		(net "MEMA_7")
	)
	(segment
		(start 287.812734 -184.46242)
		(end 287.812734 -184.601866)
		(width 0.1143)
		(layer "F.Cu")
		(net "MEMA_7")
	)
	(segment
		(start 286.842454 -185.904886)
		(end 286.24657 -185.904886)
		(width 0.1143)
		(layer "F.Cu")
		(net "MEMA_7")
	)
	(segment
		(start 287.812734 -184.601866)
		(end 287.168336 -185.246264)
		(width 0.1143)
		(layer "F.Cu")
		(net "MEMA_7")
	)
	(segment
		(start 287.168336 -185.246264)
		(end 287.168336 -185.579004)
		(width 0.1143)
		(layer "F.Cu")
		(net "MEMA_7")
	)
	(segment
		(start 288.034984 -184.24017)
		(end 287.812734 -184.46242)
		(width 0.1143)
		(layer "F.Cu")
		(net "MEMA_7")
	)
	(segment
		(start 287.168336 -185.579004)
		(end 286.842454 -185.904886)
		(width 0.1143)
		(layer "F.Cu")
		(net "MEMA_7")
	)
	(segment
		(start 285.698184 -201.735182)
		(end 285.698184 -201.72807)
		(width 0.1143)
		(layer "F.Cu")
		(net "MEMA_7")
	)
	(via
		(at 285.306516 -201.336402)
		(size 0.508)
		(drill 0.254)
		(layers "F.Cu" "B.Cu")
		(net "MEMA_7")
	)
	(via
		(at 285.369 -202.184)
		(size 0.7112)
		(drill 0.3556)
		(layers "F.Cu" "B.Cu")
		(net "MEMA_7")
	)
	(via
		(at 286.24657 -185.904886)
		(size 0.508)
		(drill 0.254)
		(layers "F.Cu" "B.Cu")
		(net "MEMA_7")
	)
	(segment
		(start 285.369 -201.398886)
		(end 285.306516 -201.336402)
		(width 0.1143)
		(layer "B.Cu")
		(net "MEMA_7")
	)
	(segment
		(start 282.4607 -194.08902)
		(end 282.448 -194.07632)
		(width 0.1143)
		(layer "B.Cu")
		(net "MEMA_7")
	)
	(segment
		(start 286.143446 -186.00801)
		(end 286.24657 -185.904886)
		(width 0.1143)
		(layer "B.Cu")
		(net "MEMA_7")
	)
	(segment
		(start 282.6004 -199.427338)
		(end 282.6004 -195.735448)
		(width 0.1143)
		(layer "B.Cu")
		(net "MEMA_7")
	)
	(segment
		(start 285.369 -202.184)
		(end 285.369 -201.398886)
		(width 0.1143)
		(layer "B.Cu")
		(net "MEMA_7")
	)
	(segment
		(start 283.655262 -200.4822)
		(end 282.6004 -199.427338)
		(width 0.1143)
		(layer "B.Cu")
		(net "MEMA_7")
	)
	(segment
		(start 284.452314 -200.4822)
		(end 283.655262 -200.4822)
		(width 0.1143)
		(layer "B.Cu")
		(net "MEMA_7")
	)
	(segment
		(start 285.213298 -186.00801)
		(end 286.143446 -186.00801)
		(width 0.1143)
		(layer "B.Cu")
		(net "MEMA_7")
	)
	(segment
		(start 282.60675 -195.126102)
		(end 282.4607 -194.980052)
		(width 0.1143)
		(layer "B.Cu")
		(net "MEMA_7")
	)
	(segment
		(start 282.4607 -194.980052)
		(end 282.4607 -194.08902)
		(width 0.1143)
		(layer "B.Cu")
		(net "MEMA_7")
	)
	(segment
		(start 285.306516 -201.336402)
		(end 284.452314 -200.4822)
		(width 0.1143)
		(layer "B.Cu")
		(net "MEMA_7")
	)
	(segment
		(start 282.6004 -195.735448)
		(end 282.60675 -195.729098)
		(width 0.1143)
		(layer "B.Cu")
		(net "MEMA_7")
	)
	(segment
		(start 282.60675 -195.729098)
		(end 282.60675 -195.126102)
		(width 0.1143)
		(layer "B.Cu")
		(net "MEMA_7")
	)
	(segment
		(start 282.448 -188.773308)
		(end 285.213298 -186.00801)
		(width 0.1143)
		(layer "B.Cu")
		(net "MEMA_7")
	)
	(segment
		(start 282.448 -194.07632)
		(end 282.448 -188.773308)
		(width 0.1143)
		(layer "B.Cu")
		(net "MEMA_7")
	)
	(segment
		(start 293.913306 -80.10271)
		(end 293.6494 -80.36687)
		(width 0.1397)
		(layer "F.Cu")
		(net "CLK_100M_CLKBUFF_ENET1_DN")
	)
	(segment
		(start 294.84574 -79.70774)
		(end 294.8305 -79.72298)
		(width 0.1397)
		(layer "F.Cu")
		(net "CLK_100M_CLKBUFF_ENET1_DN")
	)
	(segment
		(start 301.908464 -67.81419)
		(end 301.0154 -67.81419)
		(width 0.1397)
		(layer "F.Cu")
		(net "CLK_100M_CLKBUFF_ENET1_DN")
	)
	(segment
		(start 295.05402 -74.364342)
		(end 295.05402 -79.20482)
		(width 0.1397)
		(layer "F.Cu")
		(net "CLK_100M_CLKBUFF_ENET1_DN")
	)
	(segment
		(start 300.306486 -68.107814)
		(end 295.76395 -72.65035)
		(width 0.1397)
		(layer "F.Cu")
		(net "CLK_100M_CLKBUFF_ENET1_DN")
	)
	(via
		(at 293.6494 -80.36687)
		(size 0.5588)
		(drill 0.3048)
		(layers "F.Cu" "B.Cu")
		(net "CLK_100M_CLKBUFF_ENET1_DN")
	)
	(arc
		(start 294.8305 -79.72298)
		(mid 294.498474 -79.944769)
		(end 294.106854 -80.0227)
		(width 0.1397)
		(layer "F.Cu")
		(net "CLK_100M_CLKBUFF_ENET1_DN")
	)
	(arc
		(start 294.106854 -80.0227)
		(mid 294.002114 -80.04344)
		(end 293.913306 -80.10271)
		(width 0.1397)
		(layer "F.Cu")
		(net "CLK_100M_CLKBUFF_ENET1_DN")
	)
	(arc
		(start 302.874172 -68.21424)
		(mid 302.431101 -67.91819)
		(end 301.908464 -67.81419)
		(width 0.1397)
		(layer "F.Cu")
		(net "CLK_100M_CLKBUFF_ENET1_DN")
	)
	(arc
		(start 295.05402 -79.20482)
		(mid 294.999898 -79.476999)
		(end 294.84574 -79.70774)
		(width 0.1397)
		(layer "F.Cu")
		(net "CLK_100M_CLKBUFF_ENET1_DN")
	)
	(arc
		(start 295.76395 -72.65035)
		(mid 295.238504 -73.436736)
		(end 295.05402 -74.364342)
		(width 0.1397)
		(layer "F.Cu")
		(net "CLK_100M_CLKBUFF_ENET1_DN")
	)
	(arc
		(start 301.0154 -67.81419)
		(mid 300.631745 -67.890504)
		(end 300.306486 -68.107814)
		(width 0.1397)
		(layer "F.Cu")
		(net "CLK_100M_CLKBUFF_ENET1_DN")
	)
	(segment
		(start 185.31078 -79.518256)
		(end 185.5978 -79.518256)
		(width 0.127)
		(layer "In5.Cu")
		(net "CLK_100M_CLKBUFF_ENET1_DN")
	)
	(segment
		(start 185.923682 -79.383128)
		(end 185.942732 -79.364332)
		(width 0.127)
		(layer "In5.Cu")
		(net "CLK_100M_CLKBUFF_ENET1_DN")
	)
	(segment
		(start 185.942732 -79.364332)
		(end 186.374532 -78.932532)
		(width 0.127)
		(layer "In5.Cu")
		(net "CLK_100M_CLKBUFF_ENET1_DN")
	)
	(segment
		(start 293.417498 -80.134714)
		(end 293.6494 -80.36687)
		(width 0.127)
		(layer "In5.Cu")
		(net "CLK_100M_CLKBUFF_ENET1_DN")
	)
	(segment
		(start 226.00539 -73.15581)
		(end 232.16489 -79.31531)
		(width 0.127)
		(layer "In5.Cu")
		(net "CLK_100M_CLKBUFF_ENET1_DN")
	)
	(segment
		(start 187.660026 -73.316338)
		(end 187.942982 -73.033382)
		(width 0.127)
		(layer "In5.Cu")
		(net "CLK_100M_CLKBUFF_ENET1_DN")
	)
	(segment
		(start 184.976516 -79.72298)
		(end 185.0898 -79.60995)
		(width 0.127)
		(layer "In5.Cu")
		(net "CLK_100M_CLKBUFF_ENET1_DN")
	)
	(segment
		(start 186.60872 -78.366874)
		(end 186.60872 -75.548744)
		(width 0.127)
		(layer "In5.Cu")
		(net "CLK_100M_CLKBUFF_ENET1_DN")
	)
	(segment
		(start 187.5282 -74.137266)
		(end 187.5282 -73.6346)
		(width 0.127)
		(layer "In5.Cu")
		(net "CLK_100M_CLKBUFF_ENET1_DN")
	)
	(segment
		(start 186.754262 -75.197462)
		(end 187.325762 -74.625962)
		(width 0.127)
		(layer "In5.Cu")
		(net "CLK_100M_CLKBUFF_ENET1_DN")
	)
	(segment
		(start 188.453776 -72.8218)
		(end 225.19894 -72.8218)
		(width 0.127)
		(layer "In5.Cu")
		(net "CLK_100M_CLKBUFF_ENET1_DN")
	)
	(segment
		(start 184.449466 -80.25003)
		(end 184.976516 -79.72298)
		(width 0.127)
		(layer "In5.Cu")
		(net "CLK_100M_CLKBUFF_ENET1_DN")
	)
	(segment
		(start 233.841798 -80.01)
		(end 293.116 -80.01)
		(width 0.127)
		(layer "In5.Cu")
		(net "CLK_100M_CLKBUFF_ENET1_DN")
	)
	(arc
		(start 186.374532 -78.932532)
		(mid 186.547859 -78.672991)
		(end 186.60872 -78.366874)
		(width 0.127)
		(layer "In5.Cu")
		(net "CLK_100M_CLKBUFF_ENET1_DN")
	)
	(arc
		(start 232.16489 -79.31531)
		(mid 232.934261 -79.829417)
		(end 233.841798 -80.01)
		(width 0.127)
		(layer "In5.Cu")
		(net "CLK_100M_CLKBUFF_ENET1_DN")
	)
	(arc
		(start 187.5282 -73.6346)
		(mid 187.562461 -73.462359)
		(end 187.660026 -73.316338)
		(width 0.127)
		(layer "In5.Cu")
		(net "CLK_100M_CLKBUFF_ENET1_DN")
	)
	(arc
		(start 187.942982 -73.033382)
		(mid 188.177336 -72.876791)
		(end 188.453776 -72.8218)
		(width 0.127)
		(layer "In5.Cu")
		(net "CLK_100M_CLKBUFF_ENET1_DN")
	)
	(arc
		(start 225.19894 -72.8218)
		(mid 225.635375 -72.908612)
		(end 226.00539 -73.15581)
		(width 0.127)
		(layer "In5.Cu")
		(net "CLK_100M_CLKBUFF_ENET1_DN")
	)
	(arc
		(start 185.5978 -79.518256)
		(mid 185.774167 -79.483081)
		(end 185.923682 -79.383128)
		(width 0.127)
		(layer "In5.Cu")
		(net "CLK_100M_CLKBUFF_ENET1_DN")
	)
	(arc
		(start 185.0898 -79.60995)
		(mid 185.191171 -79.542123)
		(end 185.31078 -79.518256)
		(width 0.127)
		(layer "In5.Cu")
		(net "CLK_100M_CLKBUFF_ENET1_DN")
	)
	(arc
		(start 293.116 -80.01)
		(mid 293.279158 -80.04236)
		(end 293.417498 -80.134714)
		(width 0.127)
		(layer "In5.Cu")
		(net "CLK_100M_CLKBUFF_ENET1_DN")
	)
	(arc
		(start 187.325762 -74.625962)
		(mid 187.475578 -74.401746)
		(end 187.5282 -74.137266)
		(width 0.127)
		(layer "In5.Cu")
		(net "CLK_100M_CLKBUFF_ENET1_DN")
	)
	(arc
		(start 186.60872 -75.548744)
		(mid 186.646538 -75.358618)
		(end 186.754262 -75.197462)
		(width 0.127)
		(layer "In5.Cu")
		(net "CLK_100M_CLKBUFF_ENET1_DN")
	)
	(segment
		(start 89.925652 -137.209276)
		(end 89.925652 -135.640318)
		(width 0.1143)
		(layer "F.Cu")
		(net "DPB_HW_REVISION")
	)
	(segment
		(start 286.030162 -171.835572)
		(end 286.029908 -171.835572)
		(width 0.1143)
		(layer "F.Cu")
		(net "DPB_HW_REVISION")
	)
	(segment
		(start 286.434784 -172.240194)
		(end 286.030162 -171.835572)
		(width 0.1143)
		(layer "F.Cu")
		(net "DPB_HW_REVISION")
	)
	(segment
		(start 140.999972 -232.42524)
		(end 142.748 -230.677212)
		(width 0.1143)
		(layer "F.Cu")
		(net "DPB_HW_REVISION")
	)
	(segment
		(start 89.925652 -135.640318)
		(end 89.92997 -135.636)
		(width 0.1143)
		(layer "F.Cu")
		(net "DPB_HW_REVISION")
	)
	(segment
		(start 142.748 -230.677212)
		(end 142.748 -169.164)
		(width 0.1143)
		(layer "F.Cu")
		(net "DPB_HW_REVISION")
	)
	(segment
		(start 142.748 -169.164)
		(end 128.524 -154.94)
		(width 0.1143)
		(layer "F.Cu")
		(net "DPB_HW_REVISION")
	)
	(segment
		(start 140.999972 -256.25044)
		(end 140.999972 -232.42524)
		(width 0.1143)
		(layer "F.Cu")
		(net "DPB_HW_REVISION")
	)
	(via
		(at 286.029908 -171.835572)
		(size 0.508)
		(drill 0.254)
		(layers "F.Cu" "B.Cu")
		(net "DPB_HW_REVISION")
	)
	(via
		(at 128.524 -154.94)
		(size 0.5588)
		(drill 0.3048)
		(layers "F.Cu" "B.Cu")
		(net "DPB_HW_REVISION")
	)
	(via
		(at 263.652 -153.416)
		(size 0.5588)
		(drill 0.3048)
		(layers "F.Cu" "B.Cu")
		(net "DPB_HW_REVISION")
	)
	(via
		(at 281.311096 -171.735496)
		(size 0.7112)
		(drill 0.3556)
		(layers "F.Cu" "B.Cu")
		(net "DPB_HW_REVISION")
	)
	(via
		(at 264.7823 -164.719)
		(size 0.5588)
		(drill 0.3048)
		(layers "F.Cu" "B.Cu")
		(net "DPB_HW_REVISION")
	)
	(via
		(at 89.92997 -135.636)
		(size 0.5588)
		(drill 0.3048)
		(layers "F.Cu" "B.Cu")
		(net "DPB_HW_REVISION")
	)
	(segment
		(start 285.397448 -172.25391)
		(end 283.985208 -172.25391)
		(width 0.1143)
		(layer "B.Cu")
		(net "DPB_HW_REVISION")
	)
	(segment
		(start 264.795 -164.719)
		(end 265.8491 -165.7731)
		(width 0.1143)
		(layer "B.Cu")
		(net "DPB_HW_REVISION")
	)
	(segment
		(start 274.883372 -165.7731)
		(end 280.845768 -171.735496)
		(width 0.1143)
		(layer "B.Cu")
		(net "DPB_HW_REVISION")
	)
	(segment
		(start 280.845768 -171.735496)
		(end 281.311096 -171.735496)
		(width 0.1143)
		(layer "B.Cu")
		(net "DPB_HW_REVISION")
	)
	(segment
		(start 286.029908 -171.835572)
		(end 285.815786 -171.835572)
		(width 0.1143)
		(layer "B.Cu")
		(net "DPB_HW_REVISION")
	)
	(segment
		(start 264.7823 -164.719)
		(end 264.795 -164.719)
		(width 0.1143)
		(layer "B.Cu")
		(net "DPB_HW_REVISION")
	)
	(segment
		(start 285.815786 -171.835572)
		(end 285.397448 -172.25391)
		(width 0.1143)
		(layer "B.Cu")
		(net "DPB_HW_REVISION")
	)
	(segment
		(start 283.466794 -171.735496)
		(end 281.311096 -171.735496)
		(width 0.1143)
		(layer "B.Cu")
		(net "DPB_HW_REVISION")
	)
	(segment
		(start 283.985208 -172.25391)
		(end 283.466794 -171.735496)
		(width 0.1143)
		(layer "B.Cu")
		(net "DPB_HW_REVISION")
	)
	(segment
		(start 265.8491 -165.7731)
		(end 274.883372 -165.7731)
		(width 0.1143)
		(layer "B.Cu")
		(net "DPB_HW_REVISION")
	)
	(segment
		(start 262.899144 -152.663144)
		(end 211.669376 -152.663144)
		(width 0.127)
		(layer "In2.Cu")
		(net "DPB_HW_REVISION")
	)
	(segment
		(start 211.669376 -152.663144)
		(end 211.43722 -152.8953)
		(width 0.127)
		(layer "In2.Cu")
		(net "DPB_HW_REVISION")
	)
	(segment
		(start 92.837 -139.446)
		(end 92.456 -139.065)
		(width 0.127)
		(layer "In2.Cu")
		(net "DPB_HW_REVISION")
	)
	(segment
		(start 145.796 -153.67)
		(end 144.526 -154.94)
		(width 0.127)
		(layer "In2.Cu")
		(net "DPB_HW_REVISION")
	)
	(segment
		(start 144.526 -154.94)
		(end 128.524 -154.94)
		(width 0.127)
		(layer "In2.Cu")
		(net "DPB_HW_REVISION")
	)
	(segment
		(start 171.577 -153.67)
		(end 145.796 -153.67)
		(width 0.127)
		(layer "In2.Cu")
		(net "DPB_HW_REVISION")
	)
	(segment
		(start 172.3517 -152.8953)
		(end 171.577 -153.67)
		(width 0.127)
		(layer "In2.Cu")
		(net "DPB_HW_REVISION")
	)
	(segment
		(start 263.652 -153.416)
		(end 262.899144 -152.663144)
		(width 0.127)
		(layer "In2.Cu")
		(net "DPB_HW_REVISION")
	)
	(segment
		(start 94.869 -139.446)
		(end 92.837 -139.446)
		(width 0.127)
		(layer "In2.Cu")
		(net "DPB_HW_REVISION")
	)
	(segment
		(start 110.363 -154.94)
		(end 94.869 -139.446)
		(width 0.127)
		(layer "In2.Cu")
		(net "DPB_HW_REVISION")
	)
	(segment
		(start 92.456 -138.16203)
		(end 89.92997 -135.636)
		(width 0.127)
		(layer "In2.Cu")
		(net "DPB_HW_REVISION")
	)
	(segment
		(start 211.43722 -152.8953)
		(end 172.3517 -152.8953)
		(width 0.127)
		(layer "In2.Cu")
		(net "DPB_HW_REVISION")
	)
	(segment
		(start 92.456 -139.065)
		(end 92.456 -138.16203)
		(width 0.127)
		(layer "In2.Cu")
		(net "DPB_HW_REVISION")
	)
	(segment
		(start 128.524 -154.94)
		(end 110.363 -154.94)
		(width 0.127)
		(layer "In2.Cu")
		(net "DPB_HW_REVISION")
	)
	(segment
		(start 263.652 -153.416)
		(end 264.7823 -154.5463)
		(width 0.127)
		(layer "In5.Cu")
		(net "DPB_HW_REVISION")
	)
	(segment
		(start 264.7823 -154.5463)
		(end 264.7823 -164.719)
		(width 0.127)
		(layer "In5.Cu")
		(net "DPB_HW_REVISION")
	)
	(segment
		(start 294.6146 -199.281034)
		(end 294.899588 -199.566022)
		(width 0.1143)
		(layer "F.Cu")
		(net "MEMDQ_8")
	)
	(segment
		(start 294.039544 -180.6448)
		(end 294.434768 -181.040024)
		(width 0.1143)
		(layer "F.Cu")
		(net "MEMDQ_8")
	)
	(segment
		(start 294.498014 -197.73519)
		(end 294.6146 -197.851776)
		(width 0.1143)
		(layer "F.Cu")
		(net "MEMDQ_8")
	)
	(segment
		(start 294.6146 -197.851776)
		(end 294.6146 -199.281034)
		(width 0.1143)
		(layer "F.Cu")
		(net "MEMDQ_8")
	)
	(via
		(at 294.899588 -199.566022)
		(size 0.508)
		(drill 0.254)
		(layers "F.Cu" "B.Cu")
		(net "MEMDQ_8")
	)
	(via
		(at 294.335454 -197.621652)
		(size 0.7112)
		(drill 0.3556)
		(layers "F.Cu" "B.Cu")
		(net "MEMDQ_8")
	)
	(via
		(at 294.039544 -180.6448)
		(size 0.508)
		(drill 0.254)
		(layers "F.Cu" "B.Cu")
		(net "MEMDQ_8")
	)
	(segment
		(start 294.335454 -197.621652)
		(end 294.455596 -197.741794)
		(width 0.1143)
		(layer "B.Cu")
		(net "MEMDQ_8")
	)
	(segment
		(start 294.899588 -199.065388)
		(end 294.899588 -199.566022)
		(width 0.1143)
		(layer "B.Cu")
		(net "MEMDQ_8")
	)
	(segment
		(start 294.455596 -197.741794)
		(end 294.455596 -198.621396)
		(width 0.1143)
		(layer "B.Cu")
		(net "MEMDQ_8")
	)
	(segment
		(start 294.455596 -198.621396)
		(end 294.899588 -199.065388)
		(width 0.1143)
		(layer "B.Cu")
		(net "MEMDQ_8")
	)
	(segment
		(start 295.6941 -188.448442)
		(end 295.6941 -186.91733)
		(width 0.127)
		(layer "In5.Cu")
		(net "MEMDQ_8")
	)
	(segment
		(start 295.5163 -186.73953)
		(end 295.5163 -184.233312)
		(width 0.127)
		(layer "In5.Cu")
		(net "MEMDQ_8")
	)
	(segment
		(start 295.5163 -184.233312)
		(end 294.702992 -183.420004)
		(width 0.127)
		(layer "In5.Cu")
		(net "MEMDQ_8")
	)
	(segment
		(start 294.5638 -193.021204)
		(end 294.5638 -192.8368)
		(width 0.127)
		(layer "In5.Cu")
		(net "MEMDQ_8")
	)
	(segment
		(start 294.702992 -183.420004)
		(end 294.702992 -181.524656)
		(width 0.127)
		(layer "In5.Cu")
		(net "MEMDQ_8")
	)
	(segment
		(start 294.56888 -193.026284)
		(end 294.5638 -193.021204)
		(width 0.127)
		(layer "In5.Cu")
		(net "MEMDQ_8")
	)
	(segment
		(start 294.56888 -194.7926)
		(end 294.56888 -193.026284)
		(width 0.127)
		(layer "In5.Cu")
		(net "MEMDQ_8")
	)
	(segment
		(start 295.16578 -196.400674)
		(end 295.7068 -195.8594)
		(width 0.127)
		(layer "In5.Cu")
		(net "MEMDQ_8")
	)
	(segment
		(start 294.702992 -181.524656)
		(end 294.039544 -180.861208)
		(width 0.127)
		(layer "In5.Cu")
		(net "MEMDQ_8")
	)
	(segment
		(start 294.899588 -199.566022)
		(end 294.879522 -199.545956)
		(width 0.127)
		(layer "In5.Cu")
		(net "MEMDQ_8")
	)
	(segment
		(start 295.7068 -195.8594)
		(end 295.7068 -195.19011)
		(width 0.127)
		(layer "In5.Cu")
		(net "MEMDQ_8")
	)
	(segment
		(start 294.70604 -194.92976)
		(end 294.56888 -194.7926)
		(width 0.127)
		(layer "In5.Cu")
		(net "MEMDQ_8")
	)
	(segment
		(start 295.6941 -186.91733)
		(end 295.5163 -186.73953)
		(width 0.127)
		(layer "In5.Cu")
		(net "MEMDQ_8")
	)
	(segment
		(start 294.229282 -189.91326)
		(end 295.6941 -188.448442)
		(width 0.127)
		(layer "In5.Cu")
		(net "MEMDQ_8")
	)
	(segment
		(start 295.44645 -194.92976)
		(end 294.70604 -194.92976)
		(width 0.127)
		(layer "In5.Cu")
		(net "MEMDQ_8")
	)
	(segment
		(start 294.879522 -197.344538)
		(end 295.16578 -197.05828)
		(width 0.127)
		(layer "In5.Cu")
		(net "MEMDQ_8")
	)
	(segment
		(start 294.5638 -192.8368)
		(end 294.229282 -192.502282)
		(width 0.127)
		(layer "In5.Cu")
		(net "MEMDQ_8")
	)
	(segment
		(start 294.879522 -199.545956)
		(end 294.879522 -197.344538)
		(width 0.127)
		(layer "In5.Cu")
		(net "MEMDQ_8")
	)
	(segment
		(start 294.229282 -192.502282)
		(end 294.229282 -189.91326)
		(width 0.127)
		(layer "In5.Cu")
		(net "MEMDQ_8")
	)
	(segment
		(start 295.16578 -197.05828)
		(end 295.16578 -196.400674)
		(width 0.127)
		(layer "In5.Cu")
		(net "MEMDQ_8")
	)
	(segment
		(start 295.7068 -195.19011)
		(end 295.44645 -194.92976)
		(width 0.127)
		(layer "In5.Cu")
		(net "MEMDQ_8")
	)
	(segment
		(start 294.039544 -180.861208)
		(end 294.039544 -180.6448)
		(width 0.127)
		(layer "In5.Cu")
		(net "MEMDQ_8")
	)
	(segment
		(start 254.869188 -124.606812)
		(end 256.436876 -126.1745)
		(width 0.1143)
		(layer "F.Cu")
		(net "CPU_TXD")
	)
	(segment
		(start 247.104916 -91.2495)
		(end 251.3457 -95.490284)
		(width 0.1143)
		(layer "F.Cu")
		(net "CPU_TXD")
	)
	(segment
		(start 216.915746 -77.216)
		(end 228.981 -77.216)
		(width 0.1143)
		(layer "F.Cu")
		(net "CPU_TXD")
	)
	(segment
		(start 252.2474 -109.2454)
		(end 252.2474 -112.8776)
		(width 0.1143)
		(layer "F.Cu")
		(net "CPU_TXD")
	)
	(segment
		(start 252.2474 -112.8776)
		(end 250.317 -114.808)
		(width 0.1143)
		(layer "F.Cu")
		(net "CPU_TXD")
	)
	(segment
		(start 215.450166 -75.75042)
		(end 216.915746 -77.216)
		(width 0.1143)
		(layer "F.Cu")
		(net "CPU_TXD")
	)
	(segment
		(start 252.5395 -124.7775)
		(end 252.603 -124.714)
		(width 0.1143)
		(layer "F.Cu")
		(net "CPU_TXD")
	)
	(segment
		(start 243.0145 -91.2495)
		(end 247.104916 -91.2495)
		(width 0.1143)
		(layer "F.Cu")
		(net "CPU_TXD")
	)
	(segment
		(start 251.3457 -95.490284)
		(end 251.3457 -108.3437)
		(width 0.1143)
		(layer "F.Cu")
		(net "CPU_TXD")
	)
	(segment
		(start 252.5395 -126.111)
		(end 252.5395 -124.7775)
		(width 0.1143)
		(layer "F.Cu")
		(net "CPU_TXD")
	)
	(segment
		(start 250.317 -114.808)
		(end 250.317 -122.428)
		(width 0.1143)
		(layer "F.Cu")
		(net "CPU_TXD")
	)
	(segment
		(start 256.436876 -126.1745)
		(end 256.794 -126.1745)
		(width 0.1143)
		(layer "F.Cu")
		(net "CPU_TXD")
	)
	(segment
		(start 228.981 -77.216)
		(end 243.0145 -91.2495)
		(width 0.1143)
		(layer "F.Cu")
		(net "CPU_TXD")
	)
	(segment
		(start 251.3457 -108.3437)
		(end 252.2474 -109.2454)
		(width 0.1143)
		(layer "F.Cu")
		(net "CPU_TXD")
	)
	(segment
		(start 250.317 -122.428)
		(end 252.603 -124.714)
		(width 0.1143)
		(layer "F.Cu")
		(net "CPU_TXD")
	)
	(via
		(at 254.869188 -124.606812)
		(size 0.5588)
		(drill 0.3048)
		(layers "F.Cu" "B.Cu")
		(net "CPU_TXD")
	)
	(via
		(at 252.603 -124.714)
		(size 0.5588)
		(drill 0.3048)
		(layers "F.Cu" "B.Cu")
		(net "CPU_TXD")
	)
	(segment
		(start 254.849376 -124.587)
		(end 252.73 -124.587)
		(width 0.1143)
		(layer "B.Cu")
		(net "CPU_TXD")
	)
	(segment
		(start 252.73 -124.587)
		(end 252.603 -124.714)
		(width 0.1143)
		(layer "B.Cu")
		(net "CPU_TXD")
	)
	(segment
		(start 254.869188 -124.606812)
		(end 254.849376 -124.587)
		(width 0.1143)
		(layer "B.Cu")
		(net "CPU_TXD")
	)
	(segment
		(start 299.23486 -170.640248)
		(end 298.839636 -171.035472)
		(width 0.1143)
		(layer "F.Cu")
		(net "BMC0_ENTEST1")
	)
	(via
		(at 298.839636 -171.035472)
		(size 0.508)
		(drill 0.254)
		(layers "F.Cu" "B.Cu")
		(net "BMC0_ENTEST1")
	)
	(via
		(at 314.833 -170.434)
		(size 0.7112)
		(drill 0.3048)
		(layers "F.Cu" "B.Cu")
		(net "BMC0_ENTEST1")
	)
	(segment
		(start 299.265848 -171.461684)
		(end 298.839636 -171.035472)
		(width 0.1143)
		(layer "B.Cu")
		(net "BMC0_ENTEST1")
	)
	(segment
		(start 312.3438 -170.434)
		(end 312.18505 -170.59275)
		(width 0.1143)
		(layer "B.Cu")
		(net "BMC0_ENTEST1")
	)
	(segment
		(start 300.674278 -170.59275)
		(end 299.805344 -171.461684)
		(width 0.1143)
		(layer "B.Cu")
		(net "BMC0_ENTEST1")
	)
	(segment
		(start 314.833 -170.434)
		(end 312.3438 -170.434)
		(width 0.1143)
		(layer "B.Cu")
		(net "BMC0_ENTEST1")
	)
	(segment
		(start 299.805344 -171.461684)
		(end 299.265848 -171.461684)
		(width 0.1143)
		(layer "B.Cu")
		(net "BMC0_ENTEST1")
	)
	(segment
		(start 317.5635 -170.434)
		(end 314.833 -170.434)
		(width 0.1143)
		(layer "B.Cu")
		(net "BMC0_ENTEST1")
	)
	(segment
		(start 312.18505 -170.59275)
		(end 300.674278 -170.59275)
		(width 0.1143)
		(layer "B.Cu")
		(net "BMC0_ENTEST1")
	)
	(segment
		(start 295.660064 -196.57314)
		(end 295.660064 -195.705476)
		(width 0.1143)
		(layer "F.Cu")
		(net "MEMDQ_13")
	)
	(segment
		(start 295.660064 -195.705476)
		(end 296.418508 -194.947032)
		(width 0.1143)
		(layer "F.Cu")
		(net "MEMDQ_13")
	)
	(segment
		(start 295.298114 -196.93509)
		(end 295.660064 -196.57314)
		(width 0.1143)
		(layer "F.Cu")
		(net "MEMDQ_13")
	)
	(segment
		(start 295.628568 -180.646324)
		(end 295.63187 -180.646324)
		(width 0.1143)
		(layer "F.Cu")
		(net "MEMDQ_13")
	)
	(segment
		(start 295.234868 -181.040024)
		(end 295.628568 -180.646324)
		(width 0.1143)
		(layer "F.Cu")
		(net "MEMDQ_13")
	)
	(via
		(at 297.307 -195.072)
		(size 0.7112)
		(drill 0.3556)
		(layers "F.Cu" "B.Cu")
		(net "MEMDQ_13")
	)
	(via
		(at 296.418508 -194.947032)
		(size 0.508)
		(drill 0.254)
		(layers "F.Cu" "B.Cu")
		(net "MEMDQ_13")
	)
	(via
		(at 295.63187 -180.646324)
		(size 0.508)
		(drill 0.254)
		(layers "F.Cu" "B.Cu")
		(net "MEMDQ_13")
	)
	(segment
		(start 296.418508 -194.947032)
		(end 296.557192 -194.947032)
		(width 0.1143)
		(layer "B.Cu")
		(net "MEMDQ_13")
	)
	(segment
		(start 296.557192 -194.947032)
		(end 297.307 -195.072)
		(width 0.1143)
		(layer "B.Cu")
		(net "MEMDQ_13")
	)
	(segment
		(start 295.823132 -194.947032)
		(end 296.418508 -194.947032)
		(width 0.127)
		(layer "In5.Cu")
		(net "MEMDQ_13")
	)
	(segment
		(start 295.313354 -190.436246)
		(end 295.219882 -190.529718)
		(width 0.127)
		(layer "In5.Cu")
		(net "MEMDQ_13")
	)
	(segment
		(start 295.63187 -180.646324)
		(end 295.184068 -180.646324)
		(width 0.127)
		(layer "In5.Cu")
		(net "MEMDQ_13")
	)
	(segment
		(start 295.219882 -190.529718)
		(end 295.219882 -191.619632)
		(width 0.127)
		(layer "In5.Cu")
		(net "MEMDQ_13")
	)
	(segment
		(start 295.7703 -185.9915)
		(end 296.1767 -186.3979)
		(width 0.127)
		(layer "In5.Cu")
		(net "MEMDQ_13")
	)
	(segment
		(start 294.9956 -191.843914)
		(end 294.9956 -192.842134)
		(width 0.127)
		(layer "In5.Cu")
		(net "MEMDQ_13")
	)
	(segment
		(start 294.956992 -180.8734)
		(end 294.956992 -181.139592)
		(width 0.127)
		(layer "In5.Cu")
		(net "MEMDQ_13")
	)
	(segment
		(start 294.956992 -181.139592)
		(end 295.083992 -181.266592)
		(width 0.127)
		(layer "In5.Cu")
		(net "MEMDQ_13")
	)
	(segment
		(start 296.1767 -190.067184)
		(end 295.807638 -190.436246)
		(width 0.127)
		(layer "In5.Cu")
		(net "MEMDQ_13")
	)
	(segment
		(start 294.9956 -192.842134)
		(end 295.00068 -192.847214)
		(width 0.127)
		(layer "In5.Cu")
		(net "MEMDQ_13")
	)
	(segment
		(start 295.083992 -181.774592)
		(end 294.956992 -181.901592)
		(width 0.127)
		(layer "In5.Cu")
		(net "MEMDQ_13")
	)
	(segment
		(start 295.00068 -194.44208)
		(end 295.23436 -194.67576)
		(width 0.127)
		(layer "In5.Cu")
		(net "MEMDQ_13")
	)
	(segment
		(start 295.7703 -184.127902)
		(end 295.7703 -185.9915)
		(width 0.127)
		(layer "In5.Cu")
		(net "MEMDQ_13")
	)
	(segment
		(start 295.083992 -181.266592)
		(end 295.2496 -181.266592)
		(width 0.127)
		(layer "In5.Cu")
		(net "MEMDQ_13")
	)
	(segment
		(start 295.807638 -190.436246)
		(end 295.313354 -190.436246)
		(width 0.127)
		(layer "In5.Cu")
		(net "MEMDQ_13")
	)
	(segment
		(start 295.00068 -192.847214)
		(end 295.00068 -194.44208)
		(width 0.127)
		(layer "In5.Cu")
		(net "MEMDQ_13")
	)
	(segment
		(start 296.1767 -186.3979)
		(end 296.1767 -190.067184)
		(width 0.127)
		(layer "In5.Cu")
		(net "MEMDQ_13")
	)
	(segment
		(start 295.55186 -194.67576)
		(end 295.823132 -194.947032)
		(width 0.127)
		(layer "In5.Cu")
		(net "MEMDQ_13")
	)
	(segment
		(start 295.23436 -194.67576)
		(end 295.55186 -194.67576)
		(width 0.127)
		(layer "In5.Cu")
		(net "MEMDQ_13")
	)
	(segment
		(start 295.3766 -181.393592)
		(end 295.3766 -181.647592)
		(width 0.127)
		(layer "In5.Cu")
		(net "MEMDQ_13")
	)
	(segment
		(start 295.184068 -180.646324)
		(end 294.956992 -180.8734)
		(width 0.127)
		(layer "In5.Cu")
		(net "MEMDQ_13")
	)
	(segment
		(start 294.956992 -183.314594)
		(end 295.7703 -184.127902)
		(width 0.127)
		(layer "In5.Cu")
		(net "MEMDQ_13")
	)
	(segment
		(start 295.2496 -181.774592)
		(end 295.083992 -181.774592)
		(width 0.127)
		(layer "In5.Cu")
		(net "MEMDQ_13")
	)
	(segment
		(start 295.2496 -181.266592)
		(end 295.3766 -181.393592)
		(width 0.127)
		(layer "In5.Cu")
		(net "MEMDQ_13")
	)
	(segment
		(start 295.3766 -181.647592)
		(end 295.2496 -181.774592)
		(width 0.127)
		(layer "In5.Cu")
		(net "MEMDQ_13")
	)
	(segment
		(start 295.219882 -191.619632)
		(end 294.9956 -191.843914)
		(width 0.127)
		(layer "In5.Cu")
		(net "MEMDQ_13")
	)
	(segment
		(start 294.956992 -181.901592)
		(end 294.956992 -183.314594)
		(width 0.127)
		(layer "In5.Cu")
		(net "MEMDQ_13")
	)
	(segment
		(start 216.662 -75.994768)
		(end 216.662 -75.92949)
		(width 0.1143)
		(layer "F.Cu")
		(net "CPU_RXD")
	)
	(segment
		(start 251.9172 -106.89336)
		(end 251.9172 -95.253556)
		(width 0.1143)
		(layer "F.Cu")
		(net "CPU_RXD")
	)
	(segment
		(start 256.667 -111.64316)
		(end 251.9172 -106.89336)
		(width 0.1143)
		(layer "F.Cu")
		(net "CPU_RXD")
	)
	(segment
		(start 217.147902 -76.48067)
		(end 216.662 -75.994768)
		(width 0.1143)
		(layer "F.Cu")
		(net "CPU_RXD")
	)
	(segment
		(start 229.13467 -76.48067)
		(end 217.147902 -76.48067)
		(width 0.1143)
		(layer "F.Cu")
		(net "CPU_RXD")
	)
	(segment
		(start 243.2685 -90.6145)
		(end 229.13467 -76.48067)
		(width 0.1143)
		(layer "F.Cu")
		(net "CPU_RXD")
	)
	(segment
		(start 216.662 -75.92949)
		(end 214.48268 -73.75017)
		(width 0.1143)
		(layer "F.Cu")
		(net "CPU_RXD")
	)
	(segment
		(start 214.48268 -73.75017)
		(end 214.449406 -73.75017)
		(width 0.1143)
		(layer "F.Cu")
		(net "CPU_RXD")
	)
	(segment
		(start 251.9172 -95.253556)
		(end 247.278144 -90.6145)
		(width 0.1143)
		(layer "F.Cu")
		(net "CPU_RXD")
	)
	(segment
		(start 256.667 -114.7445)
		(end 256.667 -111.64316)
		(width 0.1143)
		(layer "F.Cu")
		(net "CPU_RXD")
	)
	(segment
		(start 247.278144 -90.6145)
		(end 243.2685 -90.6145)
		(width 0.1143)
		(layer "F.Cu")
		(net "CPU_RXD")
	)
	(segment
		(start 287.234884 -170.640248)
		(end 286.844486 -170.24985)
		(width 0.1143)
		(layer "F.Cu")
		(net "LPCRST0_N")
	)
	(segment
		(start 286.844486 -170.24985)
		(end 286.834834 -170.24985)
		(width 0.1143)
		(layer "F.Cu")
		(net "LPCRST0_N")
	)
	(via
		(at 286.834834 -170.24985)
		(size 0.508)
		(drill 0.254)
		(layers "F.Cu" "B.Cu")
		(net "LPCRST0_N")
	)
	(via
		(at 282.067 -167.659304)
		(size 0.7112)
		(drill 0.3556)
		(layers "F.Cu" "B.Cu")
		(net "LPCRST0_N")
	)
	(segment
		(start 276.098 -163.322)
		(end 277.729696 -163.322)
		(width 0.1143)
		(layer "B.Cu")
		(net "LPCRST0_N")
	)
	(segment
		(start 277.729696 -163.322)
		(end 282.067 -167.659304)
		(width 0.1143)
		(layer "B.Cu")
		(net "LPCRST0_N")
	)
	(segment
		(start 285.409386 -170.659298)
		(end 285.818834 -170.24985)
		(width 0.1143)
		(layer "B.Cu")
		(net "LPCRST0_N")
	)
	(segment
		(start 285.066994 -170.659298)
		(end 285.409386 -170.659298)
		(width 0.1143)
		(layer "B.Cu")
		(net "LPCRST0_N")
	)
	(segment
		(start 274.6375 -162.56)
		(end 275.6535 -162.56)
		(width 0.1143)
		(layer "B.Cu")
		(net "LPCRST0_N")
	)
	(segment
		(start 285.818834 -170.24985)
		(end 286.834834 -170.24985)
		(width 0.1143)
		(layer "B.Cu")
		(net "LPCRST0_N")
	)
	(segment
		(start 275.6535 -162.8775)
		(end 276.098 -163.322)
		(width 0.1143)
		(layer "B.Cu")
		(net "LPCRST0_N")
	)
	(segment
		(start 282.067 -167.659304)
		(end 285.066994 -170.659298)
		(width 0.1143)
		(layer "B.Cu")
		(net "LPCRST0_N")
	)
	(segment
		(start 275.6535 -162.56)
		(end 275.6535 -162.8775)
		(width 0.1143)
		(layer "B.Cu")
		(net "LPCRST0_N")
	)
	(segment
		(start 300.83125 -169.840148)
		(end 300.431962 -170.239436)
		(width 0.1143)
		(layer "F.Cu")
		(net "BMC0_SMB5_DAT")
	)
	(segment
		(start 300.834806 -169.840148)
		(end 300.83125 -169.840148)
		(width 0.1143)
		(layer "F.Cu")
		(net "BMC0_SMB5_DAT")
	)
	(via
		(at 311.531 -169.799)
		(size 0.7112)
		(drill 0.3556)
		(layers "F.Cu" "B.Cu")
		(net "BMC0_SMB5_DAT")
	)
	(via
		(at 300.431962 -170.239436)
		(size 0.508)
		(drill 0.254)
		(layers "F.Cu" "B.Cu")
		(net "BMC0_SMB5_DAT")
	)
	(segment
		(start 311.531 -169.799)
		(end 311.23255 -170.09745)
		(width 0.1143)
		(layer "B.Cu")
		(net "BMC0_SMB5_DAT")
	)
	(segment
		(start 311.23255 -170.09745)
		(end 300.573948 -170.09745)
		(width 0.1143)
		(layer "B.Cu")
		(net "BMC0_SMB5_DAT")
	)
	(segment
		(start 311.658 -169.672)
		(end 311.531 -169.799)
		(width 0.1143)
		(layer "B.Cu")
		(net "BMC0_SMB5_DAT")
	)
	(segment
		(start 300.573948 -170.09745)
		(end 300.431962 -170.239436)
		(width 0.1143)
		(layer "B.Cu")
		(net "BMC0_SMB5_DAT")
	)
	(segment
		(start 317.5635 -169.418)
		(end 317.3095 -169.672)
		(width 0.1143)
		(layer "B.Cu")
		(net "BMC0_SMB5_DAT")
	)
	(segment
		(start 317.3095 -169.672)
		(end 311.658 -169.672)
		(width 0.1143)
		(layer "B.Cu")
		(net "BMC0_SMB5_DAT")
	)
	(segment
		(start 298.069 -139.8016)
		(end 298.069 -140.716)
		(width 0.1143)
		(layer "F.Cu")
		(net "EXP_ID")
	)
	(segment
		(start 91.446096 -248.705116)
		(end 91.446096 -248.6914)
		(width 0.1143)
		(layer "F.Cu")
		(net "EXP_ID")
	)
	(segment
		(start 91.739212 -248.998232)
		(end 91.446096 -248.705116)
		(width 0.1143)
		(layer "F.Cu")
		(net "EXP_ID")
	)
	(segment
		(start 91.739212 -249.4915)
		(end 91.739212 -248.998232)
		(width 0.1143)
		(layer "F.Cu")
		(net "EXP_ID")
	)
	(via
		(at 169.3545 -244.2337)
		(size 0.5588)
		(drill 0.3048)
		(layers "F.Cu" "B.Cu")
		(net "EXP_ID")
	)
	(via
		(at 298.069 -140.716)
		(size 0.5588)
		(drill 0.3048)
		(layers "F.Cu" "B.Cu")
		(net "EXP_ID")
	)
	(via
		(at 172.72 -162.56)
		(size 0.5588)
		(drill 0.3048)
		(layers "F.Cu" "B.Cu")
		(net "EXP_ID")
	)
	(via
		(at 91.446096 -248.6914)
		(size 0.5588)
		(drill 0.3048)
		(layers "F.Cu" "B.Cu")
		(net "EXP_ID")
	)
	(via
		(at 298.069 -139.8016)
		(size 0.7112)
		(drill 0.3556)
		(layers "F.Cu" "B.Cu")
		(net "EXP_ID")
	)
	(segment
		(start 169.3545 -165.9255)
		(end 172.72 -162.56)
		(width 0.1143)
		(layer "B.Cu")
		(net "EXP_ID")
	)
	(segment
		(start 313.501278 -140.354558)
		(end 298.430442 -140.354558)
		(width 0.1143)
		(layer "B.Cu")
		(net "EXP_ID")
	)
	(segment
		(start 298.430442 -140.354558)
		(end 298.069 -140.716)
		(width 0.1143)
		(layer "B.Cu")
		(net "EXP_ID")
	)
	(segment
		(start 313.8805 -140.73378)
		(end 313.501278 -140.354558)
		(width 0.1143)
		(layer "B.Cu")
		(net "EXP_ID")
	)
	(segment
		(start 299.339 -163.6395)
		(end 299.339 -162.306)
		(width 0.1143)
		(layer "B.Cu")
		(net "EXP_ID")
	)
	(segment
		(start 169.3545 -244.2337)
		(end 169.3545 -165.9255)
		(width 0.1143)
		(layer "B.Cu")
		(net "EXP_ID")
	)
	(segment
		(start 303.89195 -157.75305)
		(end 308.163722 -157.75305)
		(width 0.1143)
		(layer "B.Cu")
		(net "EXP_ID")
	)
	(segment
		(start 308.163722 -157.75305)
		(end 313.8805 -152.036272)
		(width 0.1143)
		(layer "B.Cu")
		(net "EXP_ID")
	)
	(segment
		(start 313.8805 -152.036272)
		(end 313.8805 -140.73378)
		(width 0.1143)
		(layer "B.Cu")
		(net "EXP_ID")
	)
	(segment
		(start 299.339 -162.306)
		(end 303.89195 -157.75305)
		(width 0.1143)
		(layer "B.Cu")
		(net "EXP_ID")
	)
	(segment
		(start 91.446096 -248.481088)
		(end 94.177358 -245.749826)
		(width 0.127)
		(layer "In2.Cu")
		(net "EXP_ID")
	)
	(segment
		(start 191.426846 -162.6362)
		(end 193.319146 -160.7439)
		(width 0.127)
		(layer "In2.Cu")
		(net "EXP_ID")
	)
	(segment
		(start 91.446096 -248.6914)
		(end 91.446096 -248.481088)
		(width 0.127)
		(layer "In2.Cu")
		(net "EXP_ID")
	)
	(segment
		(start 203.65593 -160.9471)
		(end 227.748338 -160.9471)
		(width 0.127)
		(layer "In2.Cu")
		(net "EXP_ID")
	)
	(segment
		(start 268.968728 -158.9151)
		(end 286.786828 -141.097)
		(width 0.127)
		(layer "In2.Cu")
		(net "EXP_ID")
	)
	(segment
		(start 172.7962 -162.6362)
		(end 191.426846 -162.6362)
		(width 0.127)
		(layer "In2.Cu")
		(net "EXP_ID")
	)
	(segment
		(start 169.2656 -244.1448)
		(end 169.3545 -244.2337)
		(width 0.127)
		(layer "In2.Cu")
		(net "EXP_ID")
	)
	(segment
		(start 193.319146 -160.7439)
		(end 203.45273 -160.7439)
		(width 0.127)
		(layer "In2.Cu")
		(net "EXP_ID")
	)
	(segment
		(start 229.780338 -158.9151)
		(end 268.968728 -158.9151)
		(width 0.127)
		(layer "In2.Cu")
		(net "EXP_ID")
	)
	(segment
		(start 203.45273 -160.7439)
		(end 203.65593 -160.9471)
		(width 0.127)
		(layer "In2.Cu")
		(net "EXP_ID")
	)
	(segment
		(start 122.185938 -244.1448)
		(end 169.2656 -244.1448)
		(width 0.127)
		(layer "In2.Cu")
		(net "EXP_ID")
	)
	(segment
		(start 94.177358 -245.749826)
		(end 120.580912 -245.749826)
		(width 0.127)
		(layer "In2.Cu")
		(net "EXP_ID")
	)
	(segment
		(start 172.72 -162.56)
		(end 172.7962 -162.6362)
		(width 0.127)
		(layer "In2.Cu")
		(net "EXP_ID")
	)
	(segment
		(start 120.580912 -245.749826)
		(end 122.185938 -244.1448)
		(width 0.127)
		(layer "In2.Cu")
		(net "EXP_ID")
	)
	(segment
		(start 297.688 -141.097)
		(end 298.069 -140.716)
		(width 0.127)
		(layer "In2.Cu")
		(net "EXP_ID")
	)
	(segment
		(start 286.786828 -141.097)
		(end 297.688 -141.097)
		(width 0.127)
		(layer "In2.Cu")
		(net "EXP_ID")
	)
	(segment
		(start 227.748338 -160.9471)
		(end 229.780338 -158.9151)
		(width 0.127)
		(layer "In2.Cu")
		(net "EXP_ID")
	)
	(segment
		(start 188.976 -40.005)
		(end 189.040008 -40.069008)
		(width 0.127)
		(layer "F.Cu")
		(net "FM_BMC_RESET_N")
	)
	(segment
		(start 187.3504 -40.005)
		(end 188.976 -40.005)
		(width 0.127)
		(layer "F.Cu")
		(net "FM_BMC_RESET_N")
	)
	(segment
		(start 271.901412 -191.382396)
		(end 271.804892 -191.478916)
		(width 0.127)
		(layer "F.Cu")
		(net "FM_BMC_RESET_N")
	)
	(segment
		(start 280.55316 -211.7725)
		(end 279.2857 -213.03996)
		(width 0.127)
		(layer "F.Cu")
		(net "FM_BMC_RESET_N")
	)
	(segment
		(start 264.96645 -121.745502)
		(end 264.96645 -136.82345)
		(width 0.127)
		(layer "F.Cu")
		(net "FM_BMC_RESET_N")
	)
	(segment
		(start 278.51989 -212.27415)
		(end 279.2857 -213.03996)
		(width 0.127)
		(layer "F.Cu")
		(net "FM_BMC_RESET_N")
	)
	(segment
		(start 280.543 -211.2645)
		(end 280.543 -210.269836)
		(width 0.127)
		(layer "F.Cu")
		(net "FM_BMC_RESET_N")
	)
	(segment
		(start 257.84175 -93.564202)
		(end 257.84175 -95.042736)
		(width 0.127)
		(layer "F.Cu")
		(net "FM_BMC_RESET_N")
	)
	(segment
		(start 270.722852 -192.479676)
		(end 269.314676 -192.479676)
		(width 0.127)
		(layer "F.Cu")
		(net "FM_BMC_RESET_N")
	)
	(segment
		(start 187.006992 -38.6715)
		(end 186.817 -38.861492)
		(width 0.127)
		(layer "F.Cu")
		(net "FM_BMC_RESET_N")
	)
	(segment
		(start 281.051 -211.7725)
		(end 280.55316 -211.7725)
		(width 0.127)
		(layer "F.Cu")
		(net "FM_BMC_RESET_N")
	)
	(segment
		(start 257.84175 -95.042736)
		(end 263.84885 -101.049836)
		(width 0.127)
		(layer "F.Cu")
		(net "FM_BMC_RESET_N")
	)
	(segment
		(start 186.817 -39.4716)
		(end 187.3504 -40.005)
		(width 0.127)
		(layer "F.Cu")
		(net "FM_BMC_RESET_N")
	)
	(segment
		(start 271.804892 -191.478916)
		(end 271.804892 -192.489836)
		(width 0.127)
		(layer "F.Cu")
		(net "FM_BMC_RESET_N")
	)
	(segment
		(start 271.804892 -192.489836)
		(end 271.794732 -192.479676)
		(width 0.127)
		(layer "F.Cu")
		(net "FM_BMC_RESET_N")
	)
	(segment
		(start 263.84885 -101.06025)
		(end 263.9695 -101.1809)
		(width 0.127)
		(layer "F.Cu")
		(net "FM_BMC_RESET_N")
	)
	(segment
		(start 263.9695 -101.1809)
		(end 263.9695 -120.748552)
		(width 0.127)
		(layer "F.Cu")
		(net "FM_BMC_RESET_N")
	)
	(segment
		(start 264.96645 -136.82345)
		(end 272.161 -144.018)
		(width 0.127)
		(layer "F.Cu")
		(net "FM_BMC_RESET_N")
	)
	(segment
		(start 271.794732 -192.479676)
		(end 270.722852 -192.479676)
		(width 0.127)
		(layer "F.Cu")
		(net "FM_BMC_RESET_N")
	)
	(segment
		(start 281.051 -211.7725)
		(end 280.543 -211.2645)
		(width 0.127)
		(layer "F.Cu")
		(net "FM_BMC_RESET_N")
	)
	(segment
		(start 263.9695 -120.748552)
		(end 264.96645 -121.745502)
		(width 0.127)
		(layer "F.Cu")
		(net "FM_BMC_RESET_N")
	)
	(segment
		(start 269.314676 -192.479676)
		(end 268.3129 -191.4779)
		(width 0.127)
		(layer "F.Cu")
		(net "FM_BMC_RESET_N")
	)
	(segment
		(start 204.346556 -40.069008)
		(end 257.84175 -93.564202)
		(width 0.127)
		(layer "F.Cu")
		(net "FM_BMC_RESET_N")
	)
	(segment
		(start 263.84885 -101.049836)
		(end 263.84885 -101.06025)
		(width 0.127)
		(layer "F.Cu")
		(net "FM_BMC_RESET_N")
	)
	(segment
		(start 280.543 -210.269836)
		(end 280.554684 -210.258152)
		(width 0.127)
		(layer "F.Cu")
		(net "FM_BMC_RESET_N")
	)
	(segment
		(start 275.2598 -212.27415)
		(end 278.51989 -212.27415)
		(width 0.127)
		(layer "F.Cu")
		(net "FM_BMC_RESET_N")
	)
	(segment
		(start 268.3129 -191.4779)
		(end 268.3129 -189.992)
		(width 0.127)
		(layer "F.Cu")
		(net "FM_BMC_RESET_N")
	)
	(segment
		(start 280.554684 -210.258152)
		(end 280.554684 -209.129376)
		(width 0.127)
		(layer "F.Cu")
		(net "FM_BMC_RESET_N")
	)
	(segment
		(start 189.040008 -40.069008)
		(end 204.346556 -40.069008)
		(width 0.127)
		(layer "F.Cu")
		(net "FM_BMC_RESET_N")
	)
	(segment
		(start 272.161 -144.018)
		(end 272.161 -149.606)
		(width 0.127)
		(layer "F.Cu")
		(net "FM_BMC_RESET_N")
	)
	(segment
		(start 186.817 -38.861492)
		(end 186.817 -39.4716)
		(width 0.127)
		(layer "F.Cu")
		(net "FM_BMC_RESET_N")
	)
	(via
		(at 188.976 -40.005)
		(size 0.7112)
		(drill 0.3556)
		(layers "F.Cu" "B.Cu")
		(net "FM_BMC_RESET_N")
	)
	(via
		(at 275.2598 -212.27415)
		(size 0.5588)
		(drill 0.3048)
		(layers "F.Cu" "B.Cu")
		(net "FM_BMC_RESET_N")
	)
	(via
		(at 272.161 -149.606)
		(size 0.5588)
		(drill 0.3048)
		(layers "F.Cu" "B.Cu")
		(net "FM_BMC_RESET_N")
	)
	(via
		(at 268.3129 -189.992)
		(size 0.5588)
		(drill 0.3048)
		(layers "F.Cu" "B.Cu")
		(net "FM_BMC_RESET_N")
	)
	(segment
		(start 273.2913 -172.163232)
		(end 272.353532 -173.101)
		(width 0.127)
		(layer "In5.Cu")
		(net "FM_BMC_RESET_N")
	)
	(segment
		(start 273.86915 -212.27415)
		(end 268.3129 -206.7179)
		(width 0.127)
		(layer "In5.Cu")
		(net "FM_BMC_RESET_N")
	)
	(segment
		(start 273.60372 -171.311824)
		(end 273.2913 -171.624244)
		(width 0.127)
		(layer "In5.Cu")
		(net "FM_BMC_RESET_N")
	)
	(segment
		(start 270.08836 -174.83582)
		(end 270.08836 -188.21654)
		(width 0.127)
		(layer "In5.Cu")
		(net "FM_BMC_RESET_N")
	)
	(segment
		(start 274.701 -152.146)
		(end 274.701 -164.268658)
		(width 0.127)
		(layer "In5.Cu")
		(net "FM_BMC_RESET_N")
	)
	(segment
		(start 270.08836 -188.21654)
		(end 268.3129 -189.992)
		(width 0.127)
		(layer "In5.Cu")
		(net "FM_BMC_RESET_N")
	)
	(segment
		(start 272.353532 -173.101)
		(end 271.82318 -173.101)
		(width 0.127)
		(layer "In5.Cu")
		(net "FM_BMC_RESET_N")
	)
	(segment
		(start 273.60372 -166.3827)
		(end 273.60372 -171.311824)
		(width 0.127)
		(layer "In5.Cu")
		(net "FM_BMC_RESET_N")
	)
	(segment
		(start 275.2598 -212.27415)
		(end 273.86915 -212.27415)
		(width 0.127)
		(layer "In5.Cu")
		(net "FM_BMC_RESET_N")
	)
	(segment
		(start 273.2913 -171.624244)
		(end 273.2913 -172.163232)
		(width 0.127)
		(layer "In5.Cu")
		(net "FM_BMC_RESET_N")
	)
	(segment
		(start 268.3129 -206.7179)
		(end 268.3129 -189.992)
		(width 0.127)
		(layer "In5.Cu")
		(net "FM_BMC_RESET_N")
	)
	(segment
		(start 274.701 -164.268658)
		(end 274.193 -164.776658)
		(width 0.127)
		(layer "In5.Cu")
		(net "FM_BMC_RESET_N")
	)
	(segment
		(start 272.161 -149.606)
		(end 274.701 -152.146)
		(width 0.127)
		(layer "In5.Cu")
		(net "FM_BMC_RESET_N")
	)
	(segment
		(start 274.193 -164.776658)
		(end 274.193 -165.79342)
		(width 0.127)
		(layer "In5.Cu")
		(net "FM_BMC_RESET_N")
	)
	(segment
		(start 274.193 -165.79342)
		(end 273.60372 -166.3827)
		(width 0.127)
		(layer "In5.Cu")
		(net "FM_BMC_RESET_N")
	)
	(segment
		(start 271.82318 -173.101)
		(end 270.08836 -174.83582)
		(width 0.127)
		(layer "In5.Cu")
		(net "FM_BMC_RESET_N")
	)
	(segment
		(start 211.709 -74.168)
		(end 212.09 -74.549)
		(width 0.1143)
		(layer "F.Cu")
		(net "SVR_ID2")
	)
	(segment
		(start 213.449916 -75.654916)
		(end 213.449916 -75.75042)
		(width 0.1143)
		(layer "F.Cu")
		(net "SVR_ID2")
	)
	(segment
		(start 212.344 -74.549)
		(end 213.449916 -75.654916)
		(width 0.1143)
		(layer "F.Cu")
		(net "SVR_ID2")
	)
	(segment
		(start 211.709 -69.54647)
		(end 211.709 -74.168)
		(width 0.1143)
		(layer "F.Cu")
		(net "SVR_ID2")
	)
	(segment
		(start 212.86597 -69.5325)
		(end 211.72297 -69.5325)
		(width 0.1143)
		(layer "F.Cu")
		(net "SVR_ID2")
	)
	(segment
		(start 211.72297 -69.5325)
		(end 211.709 -69.54647)
		(width 0.1143)
		(layer "F.Cu")
		(net "SVR_ID2")
	)
	(segment
		(start 212.09 -74.549)
		(end 212.344 -74.549)
		(width 0.1143)
		(layer "F.Cu")
		(net "SVR_ID2")
	)
	(segment
		(start 194.563492 -179.782216)
		(end 193.204084 -179.782216)
		(width 0.127)
		(layer "F.Cu")
		(net "HB_OUT")
	)
	(segment
		(start 316.865 -88.138)
		(end 316.865 -93.98)
		(width 0.127)
		(layer "F.Cu")
		(net "HB_OUT")
	)
	(segment
		(start 194.6275 -177.419)
		(end 194.6275 -179.718208)
		(width 0.127)
		(layer "F.Cu")
		(net "HB_OUT")
	)
	(segment
		(start 264.9474 -91.579446)
		(end 264.9474 -86.786212)
		(width 0.127)
		(layer "F.Cu")
		(net "HB_OUT")
	)
	(segment
		(start 316.865 -93.98)
		(end 308.102 -102.743)
		(width 0.127)
		(layer "F.Cu")
		(net "HB_OUT")
	)
	(segment
		(start 271.3101 -97.942146)
		(end 264.9474 -91.579446)
		(width 0.127)
		(layer "F.Cu")
		(net "HB_OUT")
	)
	(segment
		(start 276.606 -126.238)
		(end 271.3101 -120.9421)
		(width 0.127)
		(layer "F.Cu")
		(net "HB_OUT")
	)
	(segment
		(start 195.261484 -175.959516)
		(end 196.834252 -175.959516)
		(width 0.127)
		(layer "F.Cu")
		(net "HB_OUT")
	)
	(segment
		(start 194.6275 -179.718208)
		(end 194.563492 -179.782216)
		(width 0.127)
		(layer "F.Cu")
		(net "HB_OUT")
	)
	(segment
		(start 196.834252 -175.959516)
		(end 196.834252 -175.402748)
		(width 0.127)
		(layer "F.Cu")
		(net "HB_OUT")
	)
	(segment
		(start 197.104 -175.133)
		(end 199.309228 -175.133)
		(width 0.127)
		(layer "F.Cu")
		(net "HB_OUT")
	)
	(segment
		(start 322.326 -82.677)
		(end 316.865 -88.138)
		(width 0.127)
		(layer "F.Cu")
		(net "HB_OUT")
	)
	(segment
		(start 96.546162 -254.01905)
		(end 96.546162 -251.493528)
		(width 0.127)
		(layer "F.Cu")
		(net "HB_OUT")
	)
	(segment
		(start 322.326 -67.564)
		(end 322.326 -82.677)
		(width 0.127)
		(layer "F.Cu")
		(net "HB_OUT")
	)
	(segment
		(start 276.606 -129.159)
		(end 276.606 -126.238)
		(width 0.127)
		(layer "F.Cu")
		(net "HB_OUT")
	)
	(segment
		(start 271.3101 -120.9421)
		(end 271.3101 -97.942146)
		(width 0.127)
		(layer "F.Cu")
		(net "HB_OUT")
	)
	(segment
		(start 331.40904 -14.887448)
		(end 325.628 -14.887448)
		(width 0.127)
		(layer "F.Cu")
		(net "HB_OUT")
	)
	(segment
		(start 194.6275 -176.5935)
		(end 195.261484 -175.959516)
		(width 0.127)
		(layer "F.Cu")
		(net "HB_OUT")
	)
	(segment
		(start 199.309228 -175.133)
		(end 210.439 -164.003228)
		(width 0.127)
		(layer "F.Cu")
		(net "HB_OUT")
	)
	(segment
		(start 325.12 -64.77)
		(end 322.326 -67.564)
		(width 0.127)
		(layer "F.Cu")
		(net "HB_OUT")
	)
	(segment
		(start 96.000062 -256.25044)
		(end 96.000062 -254.56515)
		(width 0.127)
		(layer "F.Cu")
		(net "HB_OUT")
	)
	(segment
		(start 196.834252 -175.402748)
		(end 197.104 -175.133)
		(width 0.127)
		(layer "F.Cu")
		(net "HB_OUT")
	)
	(segment
		(start 323.342 -57.15)
		(end 325.12 -58.928)
		(width 0.127)
		(layer "F.Cu")
		(net "HB_OUT")
	)
	(segment
		(start 96.000062 -254.56515)
		(end 96.546162 -254.01905)
		(width 0.127)
		(layer "F.Cu")
		(net "HB_OUT")
	)
	(segment
		(start 217.805 -147.701)
		(end 217.805 -123.317)
		(width 0.127)
		(layer "F.Cu")
		(net "HB_OUT")
	)
	(segment
		(start 264.9474 -86.786212)
		(end 241.95405 -63.792862)
		(width 0.127)
		(layer "F.Cu")
		(net "HB_OUT")
	)
	(segment
		(start 210.439 -155.067)
		(end 217.805 -147.701)
		(width 0.127)
		(layer "F.Cu")
		(net "HB_OUT")
	)
	(segment
		(start 323.342 -17.173448)
		(end 323.342 -57.15)
		(width 0.127)
		(layer "F.Cu")
		(net "HB_OUT")
	)
	(segment
		(start 325.12 -58.928)
		(end 325.12 -64.77)
		(width 0.127)
		(layer "F.Cu")
		(net "HB_OUT")
	)
	(segment
		(start 241.95405 -63.792862)
		(end 241.95405 -14.612112)
		(width 0.127)
		(layer "F.Cu")
		(net "HB_OUT")
	)
	(segment
		(start 308.102 -102.743)
		(end 307.213 -102.743)
		(width 0.127)
		(layer "F.Cu")
		(net "HB_OUT")
	)
	(segment
		(start 193.204084 -179.782216)
		(end 193.167 -179.8193)
		(width 0.127)
		(layer "F.Cu")
		(net "HB_OUT")
	)
	(segment
		(start 96.546162 -251.493528)
		(end 95.875856 -250.823222)
		(width 0.127)
		(layer "F.Cu")
		(net "HB_OUT")
	)
	(segment
		(start 241.95405 -14.612112)
		(end 240.498376 -13.156438)
		(width 0.127)
		(layer "F.Cu")
		(net "HB_OUT")
	)
	(segment
		(start 194.6275 -177.419)
		(end 194.6275 -176.5935)
		(width 0.127)
		(layer "F.Cu")
		(net "HB_OUT")
	)
	(segment
		(start 210.439 -164.003228)
		(end 210.439 -155.067)
		(width 0.127)
		(layer "F.Cu")
		(net "HB_OUT")
	)
	(segment
		(start 325.628 -14.887448)
		(end 323.342 -17.173448)
		(width 0.127)
		(layer "F.Cu")
		(net "HB_OUT")
	)
	(via
		(at 95.875856 -250.823222)
		(size 0.5588)
		(drill 0.3048)
		(layers "F.Cu" "B.Cu")
		(net "HB_OUT")
	)
	(via
		(at 190.373 -247.4722)
		(size 0.5588)
		(drill 0.3048)
		(layers "F.Cu" "B.Cu")
		(net "HB_OUT")
	)
	(via
		(at 276.606 -129.159)
		(size 0.5588)
		(drill 0.3048)
		(layers "F.Cu" "B.Cu")
		(net "HB_OUT")
	)
	(via
		(at 307.213 -102.743)
		(size 0.5588)
		(drill 0.3048)
		(layers "F.Cu" "B.Cu")
		(net "HB_OUT")
	)
	(via
		(at 193.167 -179.8193)
		(size 0.5588)
		(drill 0.3048)
		(layers "F.Cu" "B.Cu")
		(net "HB_OUT")
	)
	(via
		(at 217.805 -123.317)
		(size 0.5588)
		(drill 0.3048)
		(layers "F.Cu" "B.Cu")
		(net "HB_OUT")
	)
	(via
		(at 307.34 -128.905)
		(size 0.5588)
		(drill 0.3048)
		(layers "F.Cu" "B.Cu")
		(net "HB_OUT")
	)
	(via
		(at 237.998 -124.206)
		(size 0.5588)
		(drill 0.3048)
		(layers "F.Cu" "B.Cu")
		(net "HB_OUT")
	)
	(via
		(at 193.167 -220.035882)
		(size 0.7112)
		(drill 0.3556)
		(layers "F.Cu" "B.Cu")
		(net "HB_OUT")
	)
	(segment
		(start 190.373 -244.983)
		(end 193.167 -242.189)
		(width 0.127)
		(layer "B.Cu")
		(net "HB_OUT")
	)
	(segment
		(start 190.373 -247.4722)
		(end 190.373 -244.983)
		(width 0.127)
		(layer "B.Cu")
		(net "HB_OUT")
	)
	(segment
		(start 193.167 -242.189)
		(end 193.167 -220.035882)
		(width 0.127)
		(layer "B.Cu")
		(net "HB_OUT")
	)
	(segment
		(start 193.167 -179.8193)
		(end 193.167 -220.035882)
		(width 0.127)
		(layer "B.Cu")
		(net "HB_OUT")
	)
	(segment
		(start 276.9235 -129.4765)
		(end 306.7685 -129.4765)
		(width 0.127)
		(layer "B.Cu")
		(net "HB_OUT")
	)
	(segment
		(start 306.7685 -129.4765)
		(end 307.34 -128.905)
		(width 0.127)
		(layer "B.Cu")
		(net "HB_OUT")
	)
	(segment
		(start 272.923 -129.159)
		(end 276.606 -129.159)
		(width 0.127)
		(layer "B.Cu")
		(net "HB_OUT")
	)
	(segment
		(start 237.998 -124.206)
		(end 239.2045 -122.9995)
		(width 0.127)
		(layer "B.Cu")
		(net "HB_OUT")
	)
	(segment
		(start 240.7412 -122.9995)
		(end 240.87455 -123.13285)
		(width 0.127)
		(layer "B.Cu")
		(net "HB_OUT")
	)
	(segment
		(start 266.89685 -123.13285)
		(end 272.923 -129.159)
		(width 0.127)
		(layer "B.Cu")
		(net "HB_OUT")
	)
	(segment
		(start 239.2045 -122.9995)
		(end 240.7412 -122.9995)
		(width 0.127)
		(layer "B.Cu")
		(net "HB_OUT")
	)
	(segment
		(start 240.87455 -123.13285)
		(end 266.89685 -123.13285)
		(width 0.127)
		(layer "B.Cu")
		(net "HB_OUT")
	)
	(segment
		(start 276.606 -129.159)
		(end 276.9235 -129.4765)
		(width 0.127)
		(layer "B.Cu")
		(net "HB_OUT")
	)
	(segment
		(start 172.593 -247.65)
		(end 123.571 -247.65)
		(width 0.127)
		(layer "In2.Cu")
		(net "HB_OUT")
	)
	(segment
		(start 220.345 -123.317)
		(end 217.805 -123.317)
		(width 0.127)
		(layer "In2.Cu")
		(net "HB_OUT")
	)
	(segment
		(start 97.4471 -249.251978)
		(end 95.875856 -250.823222)
		(width 0.127)
		(layer "In2.Cu")
		(net "HB_OUT")
	)
	(segment
		(start 190.373 -247.4722)
		(end 172.7708 -247.4722)
		(width 0.127)
		(layer "In2.Cu")
		(net "HB_OUT")
	)
	(segment
		(start 237.998 -124.206)
		(end 221.234 -124.206)
		(width 0.127)
		(layer "In2.Cu")
		(net "HB_OUT")
	)
	(segment
		(start 221.234 -124.206)
		(end 220.345 -123.317)
		(width 0.127)
		(layer "In2.Cu")
		(net "HB_OUT")
	)
	(segment
		(start 121.969022 -249.251978)
		(end 97.4471 -249.251978)
		(width 0.127)
		(layer "In2.Cu")
		(net "HB_OUT")
	)
	(segment
		(start 123.571 -247.65)
		(end 121.969022 -249.251978)
		(width 0.127)
		(layer "In2.Cu")
		(net "HB_OUT")
	)
	(segment
		(start 172.7708 -247.4722)
		(end 172.593 -247.65)
		(width 0.127)
		(layer "In2.Cu")
		(net "HB_OUT")
	)
	(segment
		(start 308.2925 -111.21644)
		(end 308.483 -111.02594)
		(width 0.127)
		(layer "In5.Cu")
		(net "HB_OUT")
	)
	(segment
		(start 308.2925 -111.6965)
		(end 308.2925 -111.21644)
		(width 0.127)
		(layer "In5.Cu")
		(net "HB_OUT")
	)
	(segment
		(start 307.213 -128.778)
		(end 307.213 -112.776)
		(width 0.127)
		(layer "In5.Cu")
		(net "HB_OUT")
	)
	(segment
		(start 307.213 -109.22)
		(end 307.213 -102.743)
		(width 0.127)
		(layer "In5.Cu")
		(net "HB_OUT")
	)
	(segment
		(start 307.34 -128.905)
		(end 307.213 -128.778)
		(width 0.127)
		(layer "In5.Cu")
		(net "HB_OUT")
	)
	(segment
		(start 307.213 -112.776)
		(end 308.2925 -111.6965)
		(width 0.127)
		(layer "In5.Cu")
		(net "HB_OUT")
	)
	(segment
		(start 308.483 -110.49)
		(end 307.213 -109.22)
		(width 0.127)
		(layer "In5.Cu")
		(net "HB_OUT")
	)
	(segment
		(start 308.483 -111.02594)
		(end 308.483 -110.49)
		(width 0.127)
		(layer "In5.Cu")
		(net "HB_OUT")
	)
	(segment
		(start 318.516 -175.8315)
		(end 317.627 -175.8315)
		(width 0.1778)
		(layer "F.Cu")
		(net "ADCVREFFP")
	)
	(segment
		(start 311.0865 -175.8315)
		(end 309.85968 -175.8315)
		(width 0.1778)
		(layer "F.Cu")
		(net "ADCVREFFP")
	)
	(segment
		(start 303.017428 -174.63135)
		(end 303.008284 -174.64024)
		(width 0.1778)
		(layer "F.Cu")
		(net "ADCVREFFP")
	)
	(segment
		(start 309.85968 -175.8315)
		(end 308.65953 -174.63135)
		(width 0.1778)
		(layer "F.Cu")
		(net "ADCVREFFP")
	)
	(segment
		(start 303.008284 -174.64024)
		(end 301.634906 -174.64024)
		(width 0.1778)
		(layer "F.Cu")
		(net "ADCVREFFP")
	)
	(segment
		(start 317.627 -175.8315)
		(end 311.0865 -175.8315)
		(width 0.1778)
		(layer "F.Cu")
		(net "ADCVREFFP")
	)
	(segment
		(start 308.65953 -174.63135)
		(end 303.017428 -174.63135)
		(width 0.1778)
		(layer "F.Cu")
		(net "ADCVREFFP")
	)
	(via
		(at 311.0865 -175.8315)
		(size 0.7112)
		(drill 0.3556)
		(layers "F.Cu" "B.Cu")
		(net "ADCVREFFP")
	)
	(segment
		(start 296.96918 -199.051164)
		(end 297.362372 -198.657972)
		(width 0.1143)
		(layer "F.Cu")
		(net "MEMDQ_14")
	)
	(segment
		(start 296.96918 -200.863962)
		(end 296.96918 -199.051164)
		(width 0.1143)
		(layer "F.Cu")
		(net "MEMDQ_14")
	)
	(segment
		(start 296.034968 -182.640224)
		(end 296.430192 -183.035448)
		(width 0.1143)
		(layer "F.Cu")
		(net "MEMDQ_14")
	)
	(segment
		(start 296.89806 -200.935082)
		(end 296.96918 -200.863962)
		(width 0.1143)
		(layer "F.Cu")
		(net "MEMDQ_14")
	)
	(via
		(at 297.362372 -198.657972)
		(size 0.508)
		(drill 0.254)
		(layers "F.Cu" "B.Cu")
		(net "MEMDQ_14")
	)
	(via
		(at 296.430192 -183.035448)
		(size 0.508)
		(drill 0.254)
		(layers "F.Cu" "B.Cu")
		(net "MEMDQ_14")
	)
	(via
		(at 298.008802 -198.032624)
		(size 0.7112)
		(drill 0.3556)
		(layers "F.Cu" "B.Cu")
		(net "MEMDQ_14")
	)
	(segment
		(start 297.362372 -198.657972)
		(end 297.901614 -198.11873)
		(width 0.1143)
		(layer "B.Cu")
		(net "MEMDQ_14")
	)
	(segment
		(start 297.901614 -198.11873)
		(end 297.922696 -198.11873)
		(width 0.1143)
		(layer "B.Cu")
		(net "MEMDQ_14")
	)
	(segment
		(start 297.922696 -198.11873)
		(end 298.008802 -198.032624)
		(width 0.1143)
		(layer "B.Cu")
		(net "MEMDQ_14")
	)
	(segment
		(start 296.430192 -183.21528)
		(end 299.4914 -186.276488)
		(width 0.127)
		(layer "In5.Cu")
		(net "MEMDQ_14")
	)
	(segment
		(start 297.570144 -198.5645)
		(end 297.455844 -198.5645)
		(width 0.127)
		(layer "In5.Cu")
		(net "MEMDQ_14")
	)
	(segment
		(start 297.455844 -198.5645)
		(end 297.362372 -198.657972)
		(width 0.127)
		(layer "In5.Cu")
		(net "MEMDQ_14")
	)
	(segment
		(start 299.4914 -186.276488)
		(end 299.4914 -196.643244)
		(width 0.127)
		(layer "In5.Cu")
		(net "MEMDQ_14")
	)
	(segment
		(start 296.430192 -183.035448)
		(end 296.430192 -183.21528)
		(width 0.127)
		(layer "In5.Cu")
		(net "MEMDQ_14")
	)
	(segment
		(start 299.4914 -196.643244)
		(end 297.570144 -198.5645)
		(width 0.127)
		(layer "In5.Cu")
		(net "MEMDQ_14")
	)
	(segment
		(start 314.350654 -71.640954)
		(end 314.497466 -71.787766)
		(width 0.1397)
		(layer "F.Cu")
		(net "PCIE_10G_CPU_RX0_P")
	)
	(segment
		(start 315.924438 -72.3392)
		(end 317.1444 -72.3392)
		(width 0.1397)
		(layer "F.Cu")
		(net "PCIE_10G_CPU_RX0_P")
	)
	(segment
		(start 314.596272 -71.82866)
		(end 314.772802 -71.82866)
		(width 0.1397)
		(layer "F.Cu")
		(net "PCIE_10G_CPU_RX0_P")
	)
	(segment
		(start 317.481458 -72.199754)
		(end 317.671958 -72.009)
		(width 0.1397)
		(layer "F.Cu")
		(net "PCIE_10G_CPU_RX0_P")
	)
	(segment
		(start 313.125104 -71.60006)
		(end 314.251848 -71.60006)
		(width 0.1397)
		(layer "F.Cu")
		(net "PCIE_10G_CPU_RX0_P")
	)
	(segment
		(start 315.13145 -71.97725)
		(end 315.1886 -72.0344)
		(width 0.1397)
		(layer "F.Cu")
		(net "PCIE_10G_CPU_RX0_P")
	)
	(via
		(at 317.671958 -72.009)
		(size 0.5588)
		(drill 0.3048)
		(layers "F.Cu" "B.Cu")
		(net "PCIE_10G_CPU_RX0_P")
	)
	(arc
		(start 315.1886 -72.0344)
		(mid 315.526205 -72.259981)
		(end 315.924438 -72.3392)
		(width 0.1397)
		(layer "F.Cu")
		(net "PCIE_10G_CPU_RX0_P")
	)
	(arc
		(start 317.1444 -72.3392)
		(mid 317.326804 -72.303011)
		(end 317.481458 -72.199754)
		(width 0.1397)
		(layer "F.Cu")
		(net "PCIE_10G_CPU_RX0_P")
	)
	(arc
		(start 314.772802 -71.82866)
		(mid 314.966914 -71.867271)
		(end 315.13145 -71.97725)
		(width 0.1397)
		(layer "F.Cu")
		(net "PCIE_10G_CPU_RX0_P")
	)
	(arc
		(start 314.251848 -71.60006)
		(mid 314.305309 -71.610694)
		(end 314.350654 -71.640954)
		(width 0.1397)
		(layer "F.Cu")
		(net "PCIE_10G_CPU_RX0_P")
	)
	(arc
		(start 314.497466 -71.787766)
		(mid 314.542799 -71.818056)
		(end 314.596272 -71.82866)
		(width 0.1397)
		(layer "F.Cu")
		(net "PCIE_10G_CPU_RX0_P")
	)
	(segment
		(start 155.450286 -75.75042)
		(end 155.029916 -75.329796)
		(width 0.127)
		(layer "In5.Cu")
		(net "PCIE_10G_CPU_RX0_P")
	)
	(segment
		(start 309.047388 -77.018388)
		(end 312.920888 -73.144888)
		(width 0.127)
		(layer "In5.Cu")
		(net "PCIE_10G_CPU_RX0_P")
	)
	(segment
		(start 229.178612 -70.033388)
		(end 234.106212 -74.960988)
		(width 0.127)
		(layer "In5.Cu")
		(net "PCIE_10G_CPU_RX0_P")
	)
	(segment
		(start 153.435304 -72.991726)
		(end 153.599388 -72.827388)
		(width 0.127)
		(layer "In5.Cu")
		(net "PCIE_10G_CPU_RX0_P")
	)
	(segment
		(start 157.885384 -70.866)
		(end 182.061612 -70.866)
		(width 0.127)
		(layer "In5.Cu")
		(net "PCIE_10G_CPU_RX0_P")
	)
	(segment
		(start 317.348108 -72.333104)
		(end 317.671958 -72.009)
		(width 0.127)
		(layer "In5.Cu")
		(net "PCIE_10G_CPU_RX0_P")
	)
	(segment
		(start 300.608746 -77.1398)
		(end 308.754272 -77.1398)
		(width 0.127)
		(layer "In5.Cu")
		(net "PCIE_10G_CPU_RX0_P")
	)
	(segment
		(start 153.599388 -72.827388)
		(end 153.916888 -72.509888)
		(width 0.127)
		(layer "In5.Cu")
		(net "PCIE_10G_CPU_RX0_P")
	)
	(segment
		(start 153.2636 -73.988676)
		(end 153.2636 -73.405746)
		(width 0.127)
		(layer "In5.Cu")
		(net "PCIE_10G_CPU_RX0_P")
	)
	(segment
		(start 314.62091 -72.4408)
		(end 317.087758 -72.4408)
		(width 0.127)
		(layer "In5.Cu")
		(net "PCIE_10G_CPU_RX0_P")
	)
	(segment
		(start 185.300874 -69.1896)
		(end 227.141278 -69.1896)
		(width 0.127)
		(layer "In5.Cu")
		(net "PCIE_10G_CPU_RX0_P")
	)
	(segment
		(start 236.116368 -75.7936)
		(end 297.536616 -75.7936)
		(width 0.127)
		(layer "In5.Cu")
		(net "PCIE_10G_CPU_RX0_P")
	)
	(segment
		(start 153.80081 -74.821034)
		(end 153.472388 -74.492612)
		(width 0.127)
		(layer "In5.Cu")
		(net "PCIE_10G_CPU_RX0_P")
	)
	(segment
		(start 298.469812 -76.180188)
		(end 298.595288 -76.305664)
		(width 0.127)
		(layer "In5.Cu")
		(net "PCIE_10G_CPU_RX0_P")
	)
	(segment
		(start 182.783988 -70.566788)
		(end 183.355488 -69.995288)
		(width 0.127)
		(layer "In5.Cu")
		(net "PCIE_10G_CPU_RX0_P")
	)
	(arc
		(start 155.029916 -75.329796)
		(mid 154.755691 -75.146658)
		(end 154.432254 -75.0824)
		(width 0.127)
		(layer "In5.Cu")
		(net "PCIE_10G_CPU_RX0_P")
	)
	(arc
		(start 234.106212 -74.960988)
		(mid 235.028479 -75.577227)
		(end 236.116368 -75.7936)
		(width 0.127)
		(layer "In5.Cu")
		(net "PCIE_10G_CPU_RX0_P")
	)
	(arc
		(start 153.472388 -74.492612)
		(mid 153.317871 -74.261405)
		(end 153.2636 -73.988676)
		(width 0.127)
		(layer "In5.Cu")
		(net "PCIE_10G_CPU_RX0_P")
	)
	(arc
		(start 183.355488 -69.995288)
		(mid 184.248054 -69.398988)
		(end 185.300874 -69.1896)
		(width 0.127)
		(layer "In5.Cu")
		(net "PCIE_10G_CPU_RX0_P")
	)
	(arc
		(start 153.2636 -73.405746)
		(mid 153.308253 -73.181639)
		(end 153.435304 -72.991726)
		(width 0.127)
		(layer "In5.Cu")
		(net "PCIE_10G_CPU_RX0_P")
	)
	(arc
		(start 308.754272 -77.1398)
		(mid 308.912891 -77.108231)
		(end 309.047388 -77.018388)
		(width 0.127)
		(layer "In5.Cu")
		(net "PCIE_10G_CPU_RX0_P")
	)
	(arc
		(start 182.061612 -70.866)
		(mid 182.452557 -70.788236)
		(end 182.783988 -70.566788)
		(width 0.127)
		(layer "In5.Cu")
		(net "PCIE_10G_CPU_RX0_P")
	)
	(arc
		(start 153.916888 -72.509888)
		(mid 155.737649 -71.293265)
		(end 157.885384 -70.866)
		(width 0.127)
		(layer "In5.Cu")
		(net "PCIE_10G_CPU_RX0_P")
	)
	(arc
		(start 297.536616 -75.7936)
		(mid 298.041636 -75.89413)
		(end 298.469812 -76.180188)
		(width 0.127)
		(layer "In5.Cu")
		(net "PCIE_10G_CPU_RX0_P")
	)
	(arc
		(start 312.920888 -73.144888)
		(mid 313.700865 -72.623724)
		(end 314.62091 -72.4408)
		(width 0.127)
		(layer "In5.Cu")
		(net "PCIE_10G_CPU_RX0_P")
	)
	(arc
		(start 227.141278 -69.1896)
		(mid 228.243889 -69.408829)
		(end 229.178612 -70.033388)
		(width 0.127)
		(layer "In5.Cu")
		(net "PCIE_10G_CPU_RX0_P")
	)
	(arc
		(start 298.595288 -76.305664)
		(mid 299.51907 -76.922945)
		(end 300.608746 -77.1398)
		(width 0.127)
		(layer "In5.Cu")
		(net "PCIE_10G_CPU_RX0_P")
	)
	(arc
		(start 154.432254 -75.0824)
		(mid 154.090551 -75.014507)
		(end 153.80081 -74.821034)
		(width 0.127)
		(layer "In5.Cu")
		(net "PCIE_10G_CPU_RX0_P")
	)
	(arc
		(start 317.087758 -72.4408)
		(mid 317.228657 -72.412867)
		(end 317.348108 -72.333104)
		(width 0.127)
		(layer "In5.Cu")
		(net "PCIE_10G_CPU_RX0_P")
	)
	(segment
		(start 160.288986 -75.553824)
		(end 160.28924 -75.55357)
		(width 0.1397)
		(layer "F.Cu")
		(net "PCIE_SAS_CPU_TX_N6")
	)
	(segment
		(start 103.124762 -33.55721)
		(end 103.124762 -33.191704)
		(width 0.1397)
		(layer "F.Cu")
		(net "PCIE_SAS_CPU_TX_N6")
	)
	(segment
		(start 104.258872 -26.876502)
		(end 108.841794 -22.29358)
		(width 0.1397)
		(layer "F.Cu")
		(net "PCIE_SAS_CPU_TX_N6")
	)
	(segment
		(start 102.750112 -34.19983)
		(end 102.750112 -34.166048)
		(width 0.1397)
		(layer "F.Cu")
		(net "PCIE_SAS_CPU_TX_N6")
	)
	(segment
		(start 102.750112 -34.166048)
		(end 102.959154 -33.957006)
		(width 0.1397)
		(layer "F.Cu")
		(net "PCIE_SAS_CPU_TX_N6")
	)
	(segment
		(start 103.223822 -32.952436)
		(end 103.223822 -31.255208)
		(width 0.1397)
		(layer "F.Cu")
		(net "PCIE_SAS_CPU_TX_N6")
	)
	(segment
		(start 109.290866 -22.107652)
		(end 110.693454 -22.107652)
		(width 0.1397)
		(layer "F.Cu")
		(net "PCIE_SAS_CPU_TX_N6")
	)
	(segment
		(start 159.29483 -48.441864)
		(end 159.29483 -73.9394)
		(width 0.1397)
		(layer "F.Cu")
		(net "PCIE_SAS_CPU_TX_N6")
	)
	(segment
		(start 103.328216 -31.003494)
		(end 103.682292 -30.649418)
		(width 0.1397)
		(layer "F.Cu")
		(net "PCIE_SAS_CPU_TX_N6")
	)
	(segment
		(start 159.554164 -74.565764)
		(end 160.11017 -75.12177)
		(width 0.1397)
		(layer "F.Cu")
		(net "PCIE_SAS_CPU_TX_N6")
	)
	(segment
		(start 118.896384 -14.5669)
		(end 130.32613 -14.5669)
		(width 0.1397)
		(layer "F.Cu")
		(net "PCIE_SAS_CPU_TX_N6")
	)
	(segment
		(start 111.374428 -21.825458)
		(end 118.447312 -14.752828)
		(width 0.1397)
		(layer "F.Cu")
		(net "PCIE_SAS_CPU_TX_N6")
	)
	(segment
		(start 160.28924 -75.55357)
		(end 160.28924 -76.198984)
		(width 0.1397)
		(layer "F.Cu")
		(net "PCIE_SAS_CPU_TX_N6")
	)
	(segment
		(start 131.826 -16.587216)
		(end 131.826 -19.77898)
		(width 0.1397)
		(layer "F.Cu")
		(net "PCIE_SAS_CPU_TX_N6")
	)
	(segment
		(start 132.29844 -20.91944)
		(end 158.922974 -47.543974)
		(width 0.1397)
		(layer "F.Cu")
		(net "PCIE_SAS_CPU_TX_N6")
	)
	(segment
		(start 103.887016 -30.155388)
		(end 103.887016 -27.774392)
		(width 0.1397)
		(layer "F.Cu")
		(net "PCIE_SAS_CPU_TX_N6")
	)
	(via
		(at 159.946848 -77.0255)
		(size 0.5588)
		(drill 0.3048)
		(layers "F.Cu" "B.Cu")
		(net "PCIE_SAS_CPU_TX_N6")
	)
	(arc
		(start 103.682292 -30.649418)
		(mid 103.833773 -30.422756)
		(end 103.887016 -30.155388)
		(width 0.1397)
		(layer "F.Cu")
		(net "PCIE_SAS_CPU_TX_N6")
	)
	(arc
		(start 160.11017 -75.12177)
		(mid 160.242539 -75.320013)
		(end 160.288986 -75.553824)
		(width 0.1397)
		(layer "F.Cu")
		(net "PCIE_SAS_CPU_TX_N6")
	)
	(arc
		(start 160.28924 -76.198984)
		(mid 160.200262 -76.646306)
		(end 159.946848 -77.0255)
		(width 0.1397)
		(layer "F.Cu")
		(net "PCIE_SAS_CPU_TX_N6")
	)
	(arc
		(start 158.922974 -47.543974)
		(mid 159.19818 -47.955944)
		(end 159.29483 -48.441864)
		(width 0.1397)
		(layer "F.Cu")
		(net "PCIE_SAS_CPU_TX_N6")
	)
	(arc
		(start 103.124762 -33.191704)
		(mid 103.137639 -33.126968)
		(end 103.174292 -33.07207)
		(width 0.1397)
		(layer "F.Cu")
		(net "PCIE_SAS_CPU_TX_N6")
	)
	(arc
		(start 118.447312 -14.752828)
		(mid 118.653348 -14.615159)
		(end 118.896384 -14.5669)
		(width 0.1397)
		(layer "F.Cu")
		(net "PCIE_SAS_CPU_TX_N6")
	)
	(arc
		(start 131.826 -19.77898)
		(mid 131.948775 -20.39621)
		(end 132.29844 -20.91944)
		(width 0.1397)
		(layer "F.Cu")
		(net "PCIE_SAS_CPU_TX_N6")
	)
	(arc
		(start 103.887016 -27.774392)
		(mid 103.983655 -27.288467)
		(end 104.258872 -26.876502)
		(width 0.1397)
		(layer "F.Cu")
		(net "PCIE_SAS_CPU_TX_N6")
	)
	(arc
		(start 102.959154 -33.957006)
		(mid 103.081717 -33.773578)
		(end 103.124762 -33.55721)
		(width 0.1397)
		(layer "F.Cu")
		(net "PCIE_SAS_CPU_TX_N6")
	)
	(arc
		(start 130.32613 -14.5669)
		(mid 130.759149 -14.653051)
		(end 131.12623 -14.89837)
		(width 0.1397)
		(layer "F.Cu")
		(net "PCIE_SAS_CPU_TX_N6")
	)
	(arc
		(start 159.29483 -73.9394)
		(mid 159.362167 -74.278396)
		(end 159.554164 -74.565764)
		(width 0.1397)
		(layer "F.Cu")
		(net "PCIE_SAS_CPU_TX_N6")
	)
	(arc
		(start 103.174292 -33.07207)
		(mid 103.210967 -33.017181)
		(end 103.223822 -32.952436)
		(width 0.1397)
		(layer "F.Cu")
		(net "PCIE_SAS_CPU_TX_N6")
	)
	(arc
		(start 103.223822 -31.255208)
		(mid 103.251012 -31.118985)
		(end 103.328216 -31.003494)
		(width 0.1397)
		(layer "F.Cu")
		(net "PCIE_SAS_CPU_TX_N6")
	)
	(arc
		(start 108.841794 -22.29358)
		(mid 109.04783 -22.155911)
		(end 109.290866 -22.107652)
		(width 0.1397)
		(layer "F.Cu")
		(net "PCIE_SAS_CPU_TX_N6")
	)
	(arc
		(start 110.693454 -22.107652)
		(mid 111.062003 -22.034267)
		(end 111.374428 -21.825458)
		(width 0.1397)
		(layer "F.Cu")
		(net "PCIE_SAS_CPU_TX_N6")
	)
	(arc
		(start 131.12623 -14.89837)
		(mid 131.64408 -15.673203)
		(end 131.826 -16.587216)
		(width 0.1397)
		(layer "F.Cu")
		(net "PCIE_SAS_CPU_TX_N6")
	)
	(segment
		(start 160.115504 -77.194156)
		(end 159.946848 -77.0255)
		(width 0.1397)
		(layer "B.Cu")
		(net "PCIE_SAS_CPU_TX_N6")
	)
	(segment
		(start 160.748472 -79.341218)
		(end 160.74771 -79.34071)
		(width 0.1397)
		(layer "B.Cu")
		(net "PCIE_SAS_CPU_TX_N6")
	)
	(segment
		(start 160.26765 -78.570328)
		(end 160.26765 -77.56144)
		(width 0.1397)
		(layer "B.Cu")
		(net "PCIE_SAS_CPU_TX_N6")
	)
	(segment
		(start 160.450276 -80.25003)
		(end 160.810956 -79.52867)
		(width 0.1397)
		(layer "B.Cu")
		(net "PCIE_SAS_CPU_TX_N6")
	)
	(segment
		(start 160.62325 -79.27848)
		(end 160.579308 -79.256382)
		(width 0.1397)
		(layer "B.Cu")
		(net "PCIE_SAS_CPU_TX_N6")
	)
	(segment
		(start 160.74771 -79.34071)
		(end 160.62325 -79.27848)
		(width 0.1397)
		(layer "B.Cu")
		(net "PCIE_SAS_CPU_TX_N6")
	)
	(arc
		(start 160.579308 -79.256382)
		(mid 160.556342 -79.235686)
		(end 160.534096 -79.214218)
		(width 0.1397)
		(layer "B.Cu")
		(net "PCIE_SAS_CPU_TX_N6")
	)
	(arc
		(start 160.810956 -79.52867)
		(mid 160.818537 -79.422003)
		(end 160.748472 -79.341218)
		(width 0.1397)
		(layer "B.Cu")
		(net "PCIE_SAS_CPU_TX_N6")
	)
	(arc
		(start 160.534096 -79.214218)
		(mid 160.336815 -78.918783)
		(end 160.26765 -78.570328)
		(width 0.1397)
		(layer "B.Cu")
		(net "PCIE_SAS_CPU_TX_N6")
	)
	(arc
		(start 160.26765 -77.56144)
		(mid 160.228111 -77.362663)
		(end 160.115504 -77.194156)
		(width 0.1397)
		(layer "B.Cu")
		(net "PCIE_SAS_CPU_TX_N6")
	)
	(segment
		(start 310.45785 -179.77485)
		(end 310.769 -180.086)
		(width 0.1778)
		(layer "F.Cu")
		(net "DACRSET")
	)
	(segment
		(start 317.246 -181.864)
		(end 316.611 -181.864)
		(width 0.1778)
		(layer "F.Cu")
		(net "DACRSET")
	)
	(segment
		(start 301.747174 -178.7525)
		(end 306.7685 -178.7525)
		(width 0.1778)
		(layer "F.Cu")
		(net "DACRSET")
	)
	(segment
		(start 306.7685 -178.7525)
		(end 307.79085 -179.77485)
		(width 0.1778)
		(layer "F.Cu")
		(net "DACRSET")
	)
	(segment
		(start 314.833 -180.086)
		(end 310.769 -180.086)
		(width 0.1778)
		(layer "F.Cu")
		(net "DACRSET")
	)
	(segment
		(start 307.79085 -179.77485)
		(end 310.45785 -179.77485)
		(width 0.1778)
		(layer "F.Cu")
		(net "DACRSET")
	)
	(segment
		(start 316.611 -181.864)
		(end 314.833 -180.086)
		(width 0.1778)
		(layer "F.Cu")
		(net "DACRSET")
	)
	(segment
		(start 301.634906 -178.640232)
		(end 301.747174 -178.7525)
		(width 0.1778)
		(layer "F.Cu")
		(net "DACRSET")
	)
	(via
		(at 310.769 -180.086)
		(size 0.7112)
		(drill 0.3556)
		(layers "F.Cu" "B.Cu")
		(net "DACRSET")
	)
	(segment
		(start 297.4086 -201.224642)
		(end 297.4086 -199.370442)
		(width 0.1143)
		(layer "F.Cu")
		(net "MEMDQ_15")
	)
	(segment
		(start 296.3545 -182.169308)
		(end 296.430446 -182.245254)
		(width 0.1143)
		(layer "F.Cu")
		(net "MEMDQ_15")
	)
	(segment
		(start 296.034968 -181.840124)
		(end 296.3545 -182.159656)
		(width 0.1143)
		(layer "F.Cu")
		(net "MEMDQ_15")
	)
	(segment
		(start 296.89806 -201.735182)
		(end 297.4086 -201.224642)
		(width 0.1143)
		(layer "F.Cu")
		(net "MEMDQ_15")
	)
	(segment
		(start 296.3545 -182.159656)
		(end 296.3545 -182.169308)
		(width 0.1143)
		(layer "F.Cu")
		(net "MEMDQ_15")
	)
	(segment
		(start 297.4086 -199.370442)
		(end 297.411394 -199.367648)
		(width 0.1143)
		(layer "F.Cu")
		(net "MEMDQ_15")
	)
	(via
		(at 298.171108 -199.241156)
		(size 0.7112)
		(drill 0.3556)
		(layers "F.Cu" "B.Cu")
		(net "MEMDQ_15")
	)
	(via
		(at 297.411394 -199.367648)
		(size 0.508)
		(drill 0.254)
		(layers "F.Cu" "B.Cu")
		(net "MEMDQ_15")
	)
	(via
		(at 296.430446 -182.245254)
		(size 0.508)
		(drill 0.254)
		(layers "F.Cu" "B.Cu")
		(net "MEMDQ_15")
	)
	(segment
		(start 298.171108 -199.241156)
		(end 298.137834 -199.27443)
		(width 0.1143)
		(layer "B.Cu")
		(net "MEMDQ_15")
	)
	(segment
		(start 298.137834 -199.276208)
		(end 298.04614 -199.367648)
		(width 0.1143)
		(layer "B.Cu")
		(net "MEMDQ_15")
	)
	(segment
		(start 298.04614 -199.367648)
		(end 297.411394 -199.367648)
		(width 0.1143)
		(layer "B.Cu")
		(net "MEMDQ_15")
	)
	(segment
		(start 298.137834 -199.27443)
		(end 298.137834 -199.276208)
		(width 0.1143)
		(layer "B.Cu")
		(net "MEMDQ_15")
	)
	(segment
		(start 296.849292 -183.27497)
		(end 296.849292 -182.861712)
		(width 0.127)
		(layer "In5.Cu")
		(net "MEMDQ_15")
	)
	(segment
		(start 299.9232 -196.855842)
		(end 299.9232 -186.5122)
		(width 0.127)
		(layer "In5.Cu")
		(net "MEMDQ_15")
	)
	(segment
		(start 299.7454 -186.3344)
		(end 299.7454 -186.171078)
		(width 0.127)
		(layer "In5.Cu")
		(net "MEMDQ_15")
	)
	(segment
		(start 299.9232 -186.5122)
		(end 299.7454 -186.3344)
		(width 0.127)
		(layer "In5.Cu")
		(net "MEMDQ_15")
	)
	(segment
		(start 296.556938 -182.616348)
		(end 296.430446 -182.489856)
		(width 0.127)
		(layer "In5.Cu")
		(net "MEMDQ_15")
	)
	(segment
		(start 296.849292 -182.861712)
		(end 296.603928 -182.616348)
		(width 0.127)
		(layer "In5.Cu")
		(net "MEMDQ_15")
	)
	(segment
		(start 299.7454 -186.171078)
		(end 296.849292 -183.27497)
		(width 0.127)
		(layer "In5.Cu")
		(net "MEMDQ_15")
	)
	(segment
		(start 296.430446 -182.489856)
		(end 296.430446 -182.245254)
		(width 0.127)
		(layer "In5.Cu")
		(net "MEMDQ_15")
	)
	(segment
		(start 297.411394 -199.367648)
		(end 299.9232 -196.855842)
		(width 0.127)
		(layer "In5.Cu")
		(net "MEMDQ_15")
	)
	(segment
		(start 296.603928 -182.616348)
		(end 296.556938 -182.616348)
		(width 0.127)
		(layer "In5.Cu")
		(net "MEMDQ_15")
	)
	(segment
		(start 317.459614 -72.812656)
		(end 317.671958 -73.025)
		(width 0.1397)
		(layer "F.Cu")
		(net "PCIE_10G_CPU_RX0_N")
	)
	(segment
		(start 313.125104 -72.40016)
		(end 314.251848 -72.40016)
		(width 0.1397)
		(layer "F.Cu")
		(net "PCIE_10G_CPU_RX0_N")
	)
	(segment
		(start 314.596272 -72.17156)
		(end 314.772802 -72.17156)
		(width 0.1397)
		(layer "F.Cu")
		(net "PCIE_10G_CPU_RX0_N")
	)
	(segment
		(start 315.924184 -72.6821)
		(end 317.1444 -72.6821)
		(width 0.1397)
		(layer "F.Cu")
		(net "PCIE_10G_CPU_RX0_N")
	)
	(segment
		(start 314.350654 -72.359266)
		(end 314.497466 -72.212454)
		(width 0.1397)
		(layer "F.Cu")
		(net "PCIE_10G_CPU_RX0_N")
	)
	(segment
		(start 314.88888 -72.21982)
		(end 314.94603 -72.27697)
		(width 0.1397)
		(layer "F.Cu")
		(net "PCIE_10G_CPU_RX0_N")
	)
	(via
		(at 317.671958 -73.025)
		(size 0.5588)
		(drill 0.3048)
		(layers "F.Cu" "B.Cu")
		(net "PCIE_10G_CPU_RX0_N")
	)
	(arc
		(start 314.251848 -72.40016)
		(mid 314.305309 -72.389526)
		(end 314.350654 -72.359266)
		(width 0.1397)
		(layer "F.Cu")
		(net "PCIE_10G_CPU_RX0_N")
	)
	(arc
		(start 314.772802 -72.17156)
		(mid 314.835623 -72.184168)
		(end 314.88888 -72.21982)
		(width 0.1397)
		(layer "F.Cu")
		(net "PCIE_10G_CPU_RX0_N")
	)
	(arc
		(start 314.497466 -72.212454)
		(mid 314.542799 -72.182164)
		(end 314.596272 -72.17156)
		(width 0.1397)
		(layer "F.Cu")
		(net "PCIE_10G_CPU_RX0_N")
	)
	(arc
		(start 314.94603 -72.27697)
		(mid 315.394825 -72.576782)
		(end 315.924184 -72.6821)
		(width 0.1397)
		(layer "F.Cu")
		(net "PCIE_10G_CPU_RX0_N")
	)
	(arc
		(start 317.1444 -72.6821)
		(mid 317.314989 -72.716032)
		(end 317.459614 -72.812656)
		(width 0.1397)
		(layer "F.Cu")
		(net "PCIE_10G_CPU_RX0_N")
	)
	(segment
		(start 165.715442 -71.29526)
		(end 166.096442 -71.29526)
		(width 0.127)
		(layer "In5.Cu")
		(net "PCIE_10G_CPU_RX0_N")
	)
	(segment
		(start 314.62091 -72.7202)
		(end 316.986158 -72.7202)
		(width 0.127)
		(layer "In5.Cu")
		(net "PCIE_10G_CPU_RX0_N")
	)
	(segment
		(start 162.390582 -71.1454)
		(end 164.054282 -71.1454)
		(width 0.127)
		(layer "In5.Cu")
		(net "PCIE_10G_CPU_RX0_N")
	)
	(segment
		(start 154.940254 -74.548746)
		(end 154.850338 -74.638916)
		(width 0.127)
		(layer "In5.Cu")
		(net "PCIE_10G_CPU_RX0_N")
	)
	(segment
		(start 300.609 -77.4192)
		(end 308.754526 -77.4192)
		(width 0.127)
		(layer "In5.Cu")
		(net "PCIE_10G_CPU_RX0_N")
	)
	(segment
		(start 298.2722 -76.3778)
		(end 298.397676 -76.503276)
		(width 0.127)
		(layer "In5.Cu")
		(net "PCIE_10G_CPU_RX0_N")
	)
	(segment
		(start 159.667702 -71.1454)
		(end 160.048702 -71.1454)
		(width 0.127)
		(layer "In5.Cu")
		(net "PCIE_10G_CPU_RX0_N")
	)
	(segment
		(start 161.709862 -71.29526)
		(end 162.090862 -71.29526)
		(width 0.127)
		(layer "In5.Cu")
		(net "PCIE_10G_CPU_RX0_N")
	)
	(segment
		(start 167.076882 -71.29526)
		(end 167.457882 -71.29526)
		(width 0.127)
		(layer "In5.Cu")
		(net "PCIE_10G_CPU_RX0_N")
	)
	(segment
		(start 153.998422 -74.623422)
		(end 153.67 -74.295)
		(width 0.127)
		(layer "In5.Cu")
		(net "PCIE_10G_CPU_RX0_N")
	)
	(segment
		(start 165.034722 -71.1454)
		(end 165.415722 -71.1454)
		(width 0.127)
		(layer "In5.Cu")
		(net "PCIE_10G_CPU_RX0_N")
	)
	(segment
		(start 160.348422 -71.29526)
		(end 160.729422 -71.29526)
		(width 0.127)
		(layer "In5.Cu")
		(net "PCIE_10G_CPU_RX0_N")
	)
	(segment
		(start 157.885638 -71.1454)
		(end 158.687262 -71.1454)
		(width 0.127)
		(layer "In5.Cu")
		(net "PCIE_10G_CPU_RX0_N")
	)
	(segment
		(start 236.116368 -76.073)
		(end 297.536362 -76.073)
		(width 0.127)
		(layer "In5.Cu")
		(net "PCIE_10G_CPU_RX0_N")
	)
	(segment
		(start 185.300874 -69.469)
		(end 227.141278 -69.469)
		(width 0.127)
		(layer "In5.Cu")
		(net "PCIE_10G_CPU_RX0_N")
	)
	(segment
		(start 317.636398 -72.989694)
		(end 317.671958 -73.025)
		(width 0.127)
		(layer "In5.Cu")
		(net "PCIE_10G_CPU_RX0_N")
	)
	(segment
		(start 153.543 -73.988422)
		(end 153.543 -73.406)
		(width 0.127)
		(layer "In5.Cu")
		(net "PCIE_10G_CPU_RX0_N")
	)
	(segment
		(start 166.396162 -71.1454)
		(end 166.777162 -71.1454)
		(width 0.127)
		(layer "In5.Cu")
		(net "PCIE_10G_CPU_RX0_N")
	)
	(segment
		(start 158.986982 -71.29526)
		(end 159.367982 -71.29526)
		(width 0.127)
		(layer "In5.Cu")
		(net "PCIE_10G_CPU_RX0_N")
	)
	(segment
		(start 164.354002 -71.29526)
		(end 164.735002 -71.29526)
		(width 0.127)
		(layer "In5.Cu")
		(net "PCIE_10G_CPU_RX0_N")
	)
	(segment
		(start 228.981 -70.231)
		(end 233.9086 -75.1586)
		(width 0.127)
		(layer "In5.Cu")
		(net "PCIE_10G_CPU_RX0_N")
	)
	(segment
		(start 182.9816 -70.7644)
		(end 183.5531 -70.1929)
		(width 0.127)
		(layer "In5.Cu")
		(net "PCIE_10G_CPU_RX0_N")
	)
	(segment
		(start 154.449526 -73.75017)
		(end 154.940254 -74.240898)
		(width 0.127)
		(layer "In5.Cu")
		(net "PCIE_10G_CPU_RX0_N")
	)
	(segment
		(start 154.453844 -74.803)
		(end 154.432 -74.803)
		(width 0.127)
		(layer "In5.Cu")
		(net "PCIE_10G_CPU_RX0_N")
	)
	(segment
		(start 309.245 -77.216)
		(end 313.1185 -73.3425)
		(width 0.127)
		(layer "In5.Cu")
		(net "PCIE_10G_CPU_RX0_N")
	)
	(segment
		(start 153.632916 -73.189338)
		(end 153.797 -73.025)
		(width 0.127)
		(layer "In5.Cu")
		(net "PCIE_10G_CPU_RX0_N")
	)
	(segment
		(start 167.757602 -71.1454)
		(end 182.061612 -71.1454)
		(width 0.127)
		(layer "In5.Cu")
		(net "PCIE_10G_CPU_RX0_N")
	)
	(segment
		(start 153.797 -73.025)
		(end 154.1145 -72.7075)
		(width 0.127)
		(layer "In5.Cu")
		(net "PCIE_10G_CPU_RX0_N")
	)
	(segment
		(start 161.029142 -71.1454)
		(end 161.410142 -71.1454)
		(width 0.127)
		(layer "In5.Cu")
		(net "PCIE_10G_CPU_RX0_N")
	)
	(arc
		(start 166.246302 -71.22033)
		(mid 166.313047 -71.166506)
		(end 166.396162 -71.1454)
		(width 0.127)
		(layer "In5.Cu")
		(net "PCIE_10G_CPU_RX0_N")
	)
	(arc
		(start 154.850338 -74.638916)
		(mid 154.66841 -74.760383)
		(end 154.453844 -74.803)
		(width 0.127)
		(layer "In5.Cu")
		(net "PCIE_10G_CPU_RX0_N")
	)
	(arc
		(start 158.687262 -71.1454)
		(mid 158.770398 -71.166464)
		(end 158.837122 -71.22033)
		(width 0.127)
		(layer "In5.Cu")
		(net "PCIE_10G_CPU_RX0_N")
	)
	(arc
		(start 298.397676 -76.503276)
		(mid 299.41224 -77.181186)
		(end 300.609 -77.4192)
		(width 0.127)
		(layer "In5.Cu")
		(net "PCIE_10G_CPU_RX0_N")
	)
	(arc
		(start 154.1145 -72.7075)
		(mid 155.844713 -71.551409)
		(end 157.885638 -71.1454)
		(width 0.127)
		(layer "In5.Cu")
		(net "PCIE_10G_CPU_RX0_N")
	)
	(arc
		(start 317.194692 -72.744076)
		(mid 317.432762 -72.835928)
		(end 317.636398 -72.989694)
		(width 0.127)
		(layer "In5.Cu")
		(net "PCIE_10G_CPU_RX0_N")
	)
	(arc
		(start 316.986158 -72.7202)
		(mid 317.025052 -72.720905)
		(end 317.063882 -72.723248)
		(width 0.127)
		(layer "In5.Cu")
		(net "PCIE_10G_CPU_RX0_N")
	)
	(arc
		(start 165.565582 -71.22033)
		(mid 165.632327 -71.274154)
		(end 165.715442 -71.29526)
		(width 0.127)
		(layer "In5.Cu")
		(net "PCIE_10G_CPU_RX0_N")
	)
	(arc
		(start 166.096442 -71.29526)
		(mid 166.179578 -71.274196)
		(end 166.246302 -71.22033)
		(width 0.127)
		(layer "In5.Cu")
		(net "PCIE_10G_CPU_RX0_N")
	)
	(arc
		(start 227.141278 -69.469)
		(mid 228.136914 -69.667044)
		(end 228.981 -70.231)
		(width 0.127)
		(layer "In5.Cu")
		(net "PCIE_10G_CPU_RX0_N")
	)
	(arc
		(start 297.536362 -76.073)
		(mid 297.934597 -76.152214)
		(end 298.2722 -76.3778)
		(width 0.127)
		(layer "In5.Cu")
		(net "PCIE_10G_CPU_RX0_N")
	)
	(arc
		(start 161.560002 -71.22033)
		(mid 161.626726 -71.274219)
		(end 161.709862 -71.29526)
		(width 0.127)
		(layer "In5.Cu")
		(net "PCIE_10G_CPU_RX0_N")
	)
	(arc
		(start 167.607742 -71.22033)
		(mid 167.674487 -71.166506)
		(end 167.757602 -71.1454)
		(width 0.127)
		(layer "In5.Cu")
		(net "PCIE_10G_CPU_RX0_N")
	)
	(arc
		(start 159.517842 -71.22033)
		(mid 159.584566 -71.166441)
		(end 159.667702 -71.1454)
		(width 0.127)
		(layer "In5.Cu")
		(net "PCIE_10G_CPU_RX0_N")
	)
	(arc
		(start 167.457882 -71.29526)
		(mid 167.541018 -71.274196)
		(end 167.607742 -71.22033)
		(width 0.127)
		(layer "In5.Cu")
		(net "PCIE_10G_CPU_RX0_N")
	)
	(arc
		(start 160.729422 -71.29526)
		(mid 160.812558 -71.274196)
		(end 160.879282 -71.22033)
		(width 0.127)
		(layer "In5.Cu")
		(net "PCIE_10G_CPU_RX0_N")
	)
	(arc
		(start 162.090862 -71.29526)
		(mid 162.173998 -71.274196)
		(end 162.240722 -71.22033)
		(width 0.127)
		(layer "In5.Cu")
		(net "PCIE_10G_CPU_RX0_N")
	)
	(arc
		(start 164.735002 -71.29526)
		(mid 164.818138 -71.274196)
		(end 164.884862 -71.22033)
		(width 0.127)
		(layer "In5.Cu")
		(net "PCIE_10G_CPU_RX0_N")
	)
	(arc
		(start 317.063882 -72.723248)
		(mid 317.129664 -72.731296)
		(end 317.194692 -72.744076)
		(width 0.127)
		(layer "In5.Cu")
		(net "PCIE_10G_CPU_RX0_N")
	)
	(arc
		(start 164.204142 -71.22033)
		(mid 164.270887 -71.274154)
		(end 164.354002 -71.29526)
		(width 0.127)
		(layer "In5.Cu")
		(net "PCIE_10G_CPU_RX0_N")
	)
	(arc
		(start 160.879282 -71.22033)
		(mid 160.946006 -71.166441)
		(end 161.029142 -71.1454)
		(width 0.127)
		(layer "In5.Cu")
		(net "PCIE_10G_CPU_RX0_N")
	)
	(arc
		(start 154.432 -74.803)
		(mid 154.197355 -74.756326)
		(end 153.998422 -74.623422)
		(width 0.127)
		(layer "In5.Cu")
		(net "PCIE_10G_CPU_RX0_N")
	)
	(arc
		(start 164.884862 -71.22033)
		(mid 164.951607 -71.166506)
		(end 165.034722 -71.1454)
		(width 0.127)
		(layer "In5.Cu")
		(net "PCIE_10G_CPU_RX0_N")
	)
	(arc
		(start 162.240722 -71.22033)
		(mid 162.307446 -71.166441)
		(end 162.390582 -71.1454)
		(width 0.127)
		(layer "In5.Cu")
		(net "PCIE_10G_CPU_RX0_N")
	)
	(arc
		(start 153.67 -74.295)
		(mid 153.576015 -74.154341)
		(end 153.543 -73.988422)
		(width 0.127)
		(layer "In5.Cu")
		(net "PCIE_10G_CPU_RX0_N")
	)
	(arc
		(start 182.061612 -71.1454)
		(mid 182.559479 -71.046368)
		(end 182.9816 -70.7644)
		(width 0.127)
		(layer "In5.Cu")
		(net "PCIE_10G_CPU_RX0_N")
	)
	(arc
		(start 165.415722 -71.1454)
		(mid 165.498858 -71.166464)
		(end 165.565582 -71.22033)
		(width 0.127)
		(layer "In5.Cu")
		(net "PCIE_10G_CPU_RX0_N")
	)
	(arc
		(start 153.543 -73.406)
		(mid 153.56642 -73.288731)
		(end 153.632916 -73.189338)
		(width 0.127)
		(layer "In5.Cu")
		(net "PCIE_10G_CPU_RX0_N")
	)
	(arc
		(start 160.048702 -71.1454)
		(mid 160.131838 -71.166464)
		(end 160.198562 -71.22033)
		(width 0.127)
		(layer "In5.Cu")
		(net "PCIE_10G_CPU_RX0_N")
	)
	(arc
		(start 164.054282 -71.1454)
		(mid 164.137418 -71.166464)
		(end 164.204142 -71.22033)
		(width 0.127)
		(layer "In5.Cu")
		(net "PCIE_10G_CPU_RX0_N")
	)
	(arc
		(start 154.940254 -74.240898)
		(mid 155.004011 -74.394822)
		(end 154.940254 -74.548746)
		(width 0.127)
		(layer "In5.Cu")
		(net "PCIE_10G_CPU_RX0_N")
	)
	(arc
		(start 160.198562 -71.22033)
		(mid 160.265286 -71.274219)
		(end 160.348422 -71.29526)
		(width 0.127)
		(layer "In5.Cu")
		(net "PCIE_10G_CPU_RX0_N")
	)
	(arc
		(start 308.754526 -77.4192)
		(mid 309.019984 -77.366397)
		(end 309.245 -77.216)
		(width 0.127)
		(layer "In5.Cu")
		(net "PCIE_10G_CPU_RX0_N")
	)
	(arc
		(start 166.927022 -71.22033)
		(mid 166.993767 -71.274154)
		(end 167.076882 -71.29526)
		(width 0.127)
		(layer "In5.Cu")
		(net "PCIE_10G_CPU_RX0_N")
	)
	(arc
		(start 183.5531 -70.1929)
		(mid 184.354986 -69.657097)
		(end 185.300874 -69.469)
		(width 0.127)
		(layer "In5.Cu")
		(net "PCIE_10G_CPU_RX0_N")
	)
	(arc
		(start 161.410142 -71.1454)
		(mid 161.493278 -71.166464)
		(end 161.560002 -71.22033)
		(width 0.127)
		(layer "In5.Cu")
		(net "PCIE_10G_CPU_RX0_N")
	)
	(arc
		(start 158.837122 -71.22033)
		(mid 158.903846 -71.274219)
		(end 158.986982 -71.29526)
		(width 0.127)
		(layer "In5.Cu")
		(net "PCIE_10G_CPU_RX0_N")
	)
	(arc
		(start 313.1185 -73.3425)
		(mid 313.807812 -72.881917)
		(end 314.62091 -72.7202)
		(width 0.127)
		(layer "In5.Cu")
		(net "PCIE_10G_CPU_RX0_N")
	)
	(arc
		(start 159.367982 -71.29526)
		(mid 159.451118 -71.274196)
		(end 159.517842 -71.22033)
		(width 0.127)
		(layer "In5.Cu")
		(net "PCIE_10G_CPU_RX0_N")
	)
	(arc
		(start 166.777162 -71.1454)
		(mid 166.860298 -71.166464)
		(end 166.927022 -71.22033)
		(width 0.127)
		(layer "In5.Cu")
		(net "PCIE_10G_CPU_RX0_N")
	)
	(arc
		(start 233.9086 -75.1586)
		(mid 234.921533 -75.83542)
		(end 236.116368 -76.073)
		(width 0.127)
		(layer "In5.Cu")
		(net "PCIE_10G_CPU_RX0_N")
	)
	(segment
		(start 320.1035 -176.7205)
		(end 320.675 -177.292)
		(width 0.508)
		(layer "F.Cu")
		(net "ADCAV33")
	)
	(segment
		(start 300.043596 -177.840132)
		(end 300.434502 -177.449226)
		(width 0.3556)
		(layer "F.Cu")
		(net "ADCAV33")
	)
	(segment
		(start 318.516 -176.7205)
		(end 320.1035 -176.7205)
		(width 0.508)
		(layer "F.Cu")
		(net "ADCAV33")
	)
	(segment
		(start 300.03496 -177.840132)
		(end 300.043596 -177.840132)
		(width 0.3556)
		(layer "F.Cu")
		(net "ADCAV33")
	)
	(segment
		(start 320.675 -177.292)
		(end 320.675 -177.75555)
		(width 0.508)
		(layer "F.Cu")
		(net "ADCAV33")
	)
	(via
		(at 320.675 -177.75555)
		(size 0.5588)
		(drill 0.3048)
		(layers "F.Cu" "B.Cu")
		(net "ADCAV33")
	)
	(via
		(at 309.245 -179.1208)
		(size 0.7112)
		(drill 0.3556)
		(layers "F.Cu" "B.Cu")
		(net "ADCAV33")
	)
	(via
		(at 308.864 -178.435)
		(size 0.5588)
		(drill 0.3048)
		(layers "F.Cu" "B.Cu")
		(net "ADCAV33")
	)
	(via
		(at 300.434502 -177.449226)
		(size 0.508)
		(drill 0.254)
		(layers "F.Cu" "B.Cu")
		(net "ADCAV33")
	)
	(segment
		(start 308.864 -178.435)
		(end 309.245 -178.816)
		(width 0.508)
		(layer "B.Cu")
		(net "ADCAV33")
	)
	(segment
		(start 309.245 -179.1208)
		(end 307.594 -179.1208)
		(width 0.508)
		(layer "B.Cu")
		(net "ADCAV33")
	)
	(segment
		(start 304.89398 -178.943)
		(end 305.22418 -178.6128)
		(width 0.508)
		(layer "B.Cu")
		(net "ADCAV33")
	)
	(segment
		(start 307.086 -178.6128)
		(end 305.91506 -178.6128)
		(width 0.508)
		(layer "B.Cu")
		(net "ADCAV33")
	)
	(segment
		(start 305.22418 -178.6128)
		(end 305.91506 -178.6128)
		(width 0.508)
		(layer "B.Cu")
		(net "ADCAV33")
	)
	(segment
		(start 307.594 -179.1208)
		(end 307.086 -178.6128)
		(width 0.508)
		(layer "B.Cu")
		(net "ADCAV33")
	)
	(segment
		(start 309.245 -178.816)
		(end 309.245 -179.1208)
		(width 0.508)
		(layer "B.Cu")
		(net "ADCAV33")
	)
	(segment
		(start 308.864 -178.435254)
		(end 310.641746 -180.213)
		(width 0.508)
		(layer "In5.Cu")
		(net "ADCAV33")
	)
	(segment
		(start 302.006 -178.562)
		(end 300.893226 -177.449226)
		(width 0.508)
		(layer "In5.Cu")
		(net "ADCAV33")
	)
	(segment
		(start 318.21755 -180.213)
		(end 320.675 -177.75555)
		(width 0.508)
		(layer "In5.Cu")
		(net "ADCAV33")
	)
	(segment
		(start 307.34 -178.435)
		(end 307.213 -178.562)
		(width 0.508)
		(layer "In5.Cu")
		(net "ADCAV33")
	)
	(segment
		(start 308.864 -178.435)
		(end 307.34 -178.435)
		(width 0.508)
		(layer "In5.Cu")
		(net "ADCAV33")
	)
	(segment
		(start 300.893226 -177.449226)
		(end 300.434502 -177.449226)
		(width 0.508)
		(layer "In5.Cu")
		(net "ADCAV33")
	)
	(segment
		(start 308.864 -178.435)
		(end 308.864 -178.435254)
		(width 0.508)
		(layer "In5.Cu")
		(net "ADCAV33")
	)
	(segment
		(start 307.213 -178.562)
		(end 302.006 -178.562)
		(width 0.508)
		(layer "In5.Cu")
		(net "ADCAV33")
	)
	(segment
		(start 310.641746 -180.213)
		(end 318.21755 -180.213)
		(width 0.508)
		(layer "In5.Cu")
		(net "ADCAV33")
	)
	(segment
		(start 66.675 -106.426)
		(end 66.797174 -106.426)
		(width 0.635)
		(layer "F.Cu")
		(net "P12V")
	)
	(segment
		(start 54.052724 -117.348)
		(end 55.753 -117.348)
		(width 0.635)
		(layer "F.Cu")
		(net "P12V")
	)
	(segment
		(start 280.2382 -118.755668)
		(end 280.2382 -124.968)
		(width 0.508)
		(layer "F.Cu")
		(net "P12V")
	)
	(segment
		(start 275.027136 -50.999136)
		(end 275.463 -51.435)
		(width 0.508)
		(layer "F.Cu")
		(net "P12V")
	)
	(segment
		(start 162.139122 -112.20958)
		(end 161.671 -112.622584)
		(width 0.508)
		(layer "F.Cu")
		(net "P12V")
	)
	(segment
		(start 280.238708 -118.737634)
		(end 280.238454 -118.744746)
		(width 0.508)
		(layer "F.Cu")
		(net "P12V")
	)
	(segment
		(start 55.753 -117.348)
		(end 66.675 -106.426)
		(width 0.635)
		(layer "F.Cu")
		(net "P12V")
	)
	(segment
		(start 274.3962 -48.4378)
		(end 274.3962 -48.514)
		(width 0.508)
		(layer "F.Cu")
		(net "P12V")
	)
	(segment
		(start 37.176456 -73.70826)
		(end 37.176456 -75.184)
		(width 1.016)
		(layer "F.Cu")
		(net "P12V")
	)
	(segment
		(start 274.438872 -52.713636)
		(end 274.438872 -52.459128)
		(width 0.508)
		(layer "F.Cu")
		(net "P12V")
	)
	(segment
		(start 63.591948 -219.71)
		(end 63.1825 -219.71)
		(width 0.508)
		(layer "F.Cu")
		(net "P12V")
	)
	(segment
		(start 163.7665 -111.76)
		(end 162.588702 -111.76)
		(width 0.508)
		(layer "F.Cu")
		(net "P12V")
	)
	(segment
		(start 280.67 -109.2835)
		(end 280.67 -118.306342)
		(width 0.508)
		(layer "F.Cu")
		(net "P12V")
	)
	(segment
		(start 51.943 -119.457724)
		(end 46.953424 -124.4473)
		(width 0.635)
		(layer "F.Cu")
		(net "P12V")
	)
	(segment
		(start 63.1825 -219.71)
		(end 62.8015 -219.329)
		(width 0.508)
		(layer "F.Cu")
		(net "P12V")
	)
	(segment
		(start 62.8015 -217.297)
		(end 63.881 -217.297)
		(width 0.508)
		(layer "F.Cu")
		(net "P12V")
	)
	(segment
		(start 280.67 -118.306342)
		(end 280.238708 -118.737634)
		(width 0.508)
		(layer "F.Cu")
		(net "P12V")
	)
	(segment
		(start 267.2334 -46.3804)
		(end 267.335 -46.482)
		(width 0.508)
		(layer "F.Cu")
		(net "P12V")
	)
	(segment
		(start 273.994372 -50.999136)
		(end 275.027136 -50.999136)
		(width 0.508)
		(layer "F.Cu")
		(net "P12V")
	)
	(segment
		(start 51.943 -119.38)
		(end 52.020724 -119.38)
		(width 0.635)
		(layer "F.Cu")
		(net "P12V")
	)
	(segment
		(start 66.840862 -106.382312)
		(end 73.801986 -106.382312)
		(width 0.635)
		(layer "F.Cu")
		(net "P12V")
	)
	(segment
		(start 280.0985 -108.712)
		(end 280.67 -109.2835)
		(width 0.508)
		(layer "F.Cu")
		(net "P12V")
	)
	(segment
		(start 62.6745 -212.217)
		(end 63.754 -212.217)
		(width 0.508)
		(layer "F.Cu")
		(net "P12V")
	)
	(segment
		(start 41.13784 -124.4473)
		(end 30.734 -134.85114)
		(width 0.635)
		(layer "F.Cu")
		(net "P12V")
	)
	(segment
		(start 46.953424 -124.4473)
		(end 41.13784 -124.4473)
		(width 0.635)
		(layer "F.Cu")
		(net "P12V")
	)
	(segment
		(start 51.943 -119.38)
		(end 51.943 -119.457724)
		(width 0.635)
		(layer "F.Cu")
		(net "P12V")
	)
	(segment
		(start 336.169 -113.9825)
		(end 336.169 -114.935)
		(width 0.508)
		(layer "F.Cu")
		(net "P12V")
	)
	(segment
		(start 280.238454 -118.744746)
		(end 280.2382 -118.755668)
		(width 0.508)
		(layer "F.Cu")
		(net "P12V")
	)
	(segment
		(start 275.082 -47.752)
		(end 274.3962 -48.4378)
		(width 0.508)
		(layer "F.Cu")
		(net "P12V")
	)
	(segment
		(start 30.734 -134.85114)
		(end 30.734 -138.557)
		(width 0.635)
		(layer "F.Cu")
		(net "P12V")
	)
	(segment
		(start 162.588702 -111.76)
		(end 162.139122 -112.20958)
		(width 0.508)
		(layer "F.Cu")
		(net "P12V")
	)
	(segment
		(start 66.797174 -106.426)
		(end 66.840862 -106.382312)
		(width 0.635)
		(layer "F.Cu")
		(net "P12V")
	)
	(segment
		(start 52.020724 -119.38)
		(end 54.052724 -117.348)
		(width 0.635)
		(layer "F.Cu")
		(net "P12V")
	)
	(segment
		(start 267.335 -46.482)
		(end 267.335 -47.625)
		(width 0.508)
		(layer "F.Cu")
		(net "P12V")
	)
	(segment
		(start 349.123 -114.173)
		(end 349.123 -117.5512)
		(width 0.508)
		(layer "F.Cu")
		(net "P12V")
	)
	(segment
		(start 73.801986 -106.382312)
		(end 74.017886 -106.598212)
		(width 0.635)
		(layer "F.Cu")
		(net "P12V")
	)
	(segment
		(start 275.082 -45.9232)
		(end 275.082 -47.752)
		(width 0.508)
		(layer "F.Cu")
		(net "P12V")
	)
	(segment
		(start 161.671 -112.622584)
		(end 161.671 -112.9792)
		(width 0.508)
		(layer "F.Cu")
		(net "P12V")
	)
	(segment
		(start 274.438872 -52.459128)
		(end 275.463 -51.435)
		(width 0.508)
		(layer "F.Cu")
		(net "P12V")
	)
	(via
		(at 325.0184 -176.4792)
		(size 0.508)
		(drill 0.254)
		(layers "F.Cu" "B.Cu")
		(net "P12V")
	)
	(via
		(at 317.627 -144.018)
		(size 0.5588)
		(drill 0.3048)
		(layers "F.Cu" "B.Cu")
		(net "P12V")
	)
	(via
		(at 81.407 -2.794)
		(size 0.7112)
		(drill 0.4064)
		(layers "F.Cu" "B.Cu")
		(net "P12V")
	)
	(via
		(at 82.296 -4.953)
		(size 0.7112)
		(drill 0.4064)
		(layers "F.Cu" "B.Cu")
		(net "P12V")
	)
	(via
		(at 93.853 -155.956)
		(size 0.7112)
		(drill 0.4064)
		(layers "F.Cu" "B.Cu")
		(net "P12V")
	)
	(via
		(at 66.802 -223.266)
		(size 0.7112)
		(drill 0.3556)
		(layers "F.Cu" "B.Cu")
		(net "P12V")
	)
	(via
		(at 152.273 -167.513)
		(size 0.7112)
		(drill 0.4064)
		(layers "F.Cu" "B.Cu")
		(net "P12V")
	)
	(via
		(at 349.123 -117.5512)
		(size 0.5588)
		(drill 0.3048)
		(layers "F.Cu" "B.Cu")
		(net "P12V")
	)
	(via
		(at 215.011 -118.872)
		(size 0.7112)
		(drill 0.3556)
		(layers "F.Cu" "B.Cu")
		(net "P12V")
	)
	(via
		(at 150.749 -166.116)
		(size 0.7112)
		(drill 0.4064)
		(layers "F.Cu" "B.Cu")
		(net "P12V")
	)
	(via
		(at 302.133 -122.936)
		(size 0.7112)
		(drill 0.4064)
		(layers "F.Cu" "B.Cu")
		(net "P12V")
	)
	(via
		(at 280.2382 -124.968)
		(size 0.508)
		(drill 0.254)
		(layers "F.Cu" "B.Cu")
		(net "P12V")
	)
	(via
		(at 150.749 -167.513)
		(size 0.7112)
		(drill 0.4064)
		(layers "F.Cu" "B.Cu")
		(net "P12V")
	)
	(via
		(at 348.361 -64.516)
		(size 0.7112)
		(drill 0.4064)
		(layers "F.Cu" "B.Cu")
		(net "P12V")
	)
	(via
		(at 305.689 -49.2252)
		(size 0.7112)
		(drill 0.4064)
		(layers "F.Cu" "B.Cu")
		(net "P12V")
	)
	(via
		(at 344.043 -123.571)
		(size 0.7112)
		(drill 0.4064)
		(layers "F.Cu" "B.Cu")
		(net "P12V")
	)
	(via
		(at 65.151 -224.282)
		(size 0.7112)
		(drill 0.4064)
		(layers "F.Cu" "B.Cu")
		(net "P12V")
	)
	(via
		(at 306.832 -49.2252)
		(size 0.7112)
		(drill 0.4064)
		(layers "F.Cu" "B.Cu")
		(net "P12V")
	)
	(via
		(at 346.964 -65.913)
		(size 0.7112)
		(drill 0.4064)
		(layers "F.Cu" "B.Cu")
		(net "P12V")
	)
	(via
		(at 214.1982 -129.0066)
		(size 0.7112)
		(drill 0.4064)
		(layers "F.Cu" "B.Cu")
		(net "P12V")
	)
	(via
		(at 345.567 -120.65)
		(size 0.7112)
		(drill 0.4064)
		(layers "F.Cu" "B.Cu")
		(net "P12V")
	)
	(via
		(at 95.631 -154.559)
		(size 0.7112)
		(drill 0.4064)
		(layers "F.Cu" "B.Cu")
		(net "P12V")
	)
	(via
		(at 308.273958 -48.514)
		(size 0.7112)
		(drill 0.3556)
		(layers "F.Cu" "B.Cu")
		(net "P12V")
	)
	(via
		(at 93.853 -154.559)
		(size 0.7112)
		(drill 0.4064)
		(layers "F.Cu" "B.Cu")
		(net "P12V")
	)
	(via
		(at 275.844 -47.625)
		(size 0.7112)
		(drill 0.4064)
		(layers "F.Cu" "B.Cu")
		(net "P12V")
	)
	(via
		(at 344.043 -120.65)
		(size 0.7112)
		(drill 0.4064)
		(layers "F.Cu" "B.Cu")
		(net "P12V")
	)
	(via
		(at 63.881 -217.297)
		(size 0.5588)
		(drill 0.3048)
		(layers "F.Cu" "B.Cu")
		(net "P12V")
	)
	(via
		(at 63.754 -212.217)
		(size 0.5588)
		(drill 0.3048)
		(layers "F.Cu" "B.Cu")
		(net "P12V")
	)
	(via
		(at 306.832 -50.292)
		(size 0.7112)
		(drill 0.4064)
		(layers "F.Cu" "B.Cu")
		(net "P12V")
	)
	(via
		(at 90.297 -154.559)
		(size 0.7112)
		(drill 0.4064)
		(layers "F.Cu" "B.Cu")
		(net "P12V")
	)
	(via
		(at 215.5444 -131.3434)
		(size 0.7112)
		(drill 0.4064)
		(layers "F.Cu" "B.Cu")
		(net "P12V")
	)
	(via
		(at 62.865 -224.282)
		(size 0.7112)
		(drill 0.4064)
		(layers "F.Cu" "B.Cu")
		(net "P12V")
	)
	(via
		(at 342.8492 -65.5066)
		(size 0.7112)
		(drill 0.3556)
		(layers "F.Cu" "B.Cu")
		(net "P12V")
	)
	(via
		(at 215.5952 -129.032)
		(size 0.7112)
		(drill 0.4064)
		(layers "F.Cu" "B.Cu")
		(net "P12V")
	)
	(via
		(at 92.075 -155.956)
		(size 0.7112)
		(drill 0.4064)
		(layers "F.Cu" "B.Cu")
		(net "P12V")
	)
	(via
		(at 214.1474 -131.318)
		(size 0.7112)
		(drill 0.4064)
		(layers "F.Cu" "B.Cu")
		(net "P12V")
	)
	(via
		(at 82.296 -6.096)
		(size 0.7112)
		(drill 0.4064)
		(layers "F.Cu" "B.Cu")
		(net "P12V")
	)
	(via
		(at 302.133 -124.079)
		(size 0.7112)
		(drill 0.4064)
		(layers "F.Cu" "B.Cu")
		(net "P12V")
	)
	(via
		(at 63.591948 -219.71)
		(size 0.5588)
		(drill 0.3048)
		(layers "F.Cu" "B.Cu")
		(net "P12V")
	)
	(via
		(at 317.246 -129.413)
		(size 0.5588)
		(drill 0.3048)
		(layers "F.Cu" "B.Cu")
		(net "P12V")
	)
	(via
		(at 344.043 -122.047)
		(size 0.7112)
		(drill 0.4064)
		(layers "F.Cu" "B.Cu")
		(net "P12V")
	)
	(via
		(at 275.844 -48.895)
		(size 0.7112)
		(drill 0.4064)
		(layers "F.Cu" "B.Cu")
		(net "P12V")
	)
	(via
		(at 214.1728 -130.2512)
		(size 0.7112)
		(drill 0.4064)
		(layers "F.Cu" "B.Cu")
		(net "P12V")
	)
	(via
		(at 346.964 -64.516)
		(size 0.7112)
		(drill 0.4064)
		(layers "F.Cu" "B.Cu")
		(net "P12V")
	)
	(via
		(at 152.273 -166.116)
		(size 0.7112)
		(drill 0.4064)
		(layers "F.Cu" "B.Cu")
		(net "P12V")
	)
	(via
		(at 348.361 -67.056)
		(size 0.7112)
		(drill 0.4064)
		(layers "F.Cu" "B.Cu")
		(net "P12V")
	)
	(via
		(at 80.264 -2.794)
		(size 0.7112)
		(drill 0.4064)
		(layers "F.Cu" "B.Cu")
		(net "P12V")
	)
	(via
		(at 345.567 -122.047)
		(size 0.7112)
		(drill 0.4064)
		(layers "F.Cu" "B.Cu")
		(net "P12V")
	)
	(via
		(at 67.437 -224.282)
		(size 0.7112)
		(drill 0.4064)
		(layers "F.Cu" "B.Cu")
		(net "P12V")
	)
	(via
		(at 267.335 -47.625)
		(size 0.5588)
		(drill 0.3048)
		(layers "F.Cu" "B.Cu")
		(net "P12V")
	)
	(via
		(at 82.296 -3.81)
		(size 0.7112)
		(drill 0.4064)
		(layers "F.Cu" "B.Cu")
		(net "P12V")
	)
	(via
		(at 303.276 -122.936)
		(size 0.7112)
		(drill 0.4064)
		(layers "F.Cu" "B.Cu")
		(net "P12V")
	)
	(via
		(at 161.671 -112.9792)
		(size 0.5588)
		(drill 0.3048)
		(layers "F.Cu" "B.Cu")
		(net "P12V")
	)
	(via
		(at 303.276 -124.079)
		(size 0.7112)
		(drill 0.4064)
		(layers "F.Cu" "B.Cu")
		(net "P12V")
	)
	(via
		(at 160.655 -134.62)
		(size 0.508)
		(drill 0.254)
		(layers "F.Cu" "B.Cu")
		(net "P12V")
	)
	(via
		(at 346.964 -67.056)
		(size 0.7112)
		(drill 0.4064)
		(layers "F.Cu" "B.Cu")
		(net "P12V")
	)
	(via
		(at 95.631 -155.956)
		(size 0.7112)
		(drill 0.4064)
		(layers "F.Cu" "B.Cu")
		(net "P12V")
	)
	(via
		(at 152.273 -164.719)
		(size 0.7112)
		(drill 0.4064)
		(layers "F.Cu" "B.Cu")
		(net "P12V")
	)
	(via
		(at 30.734 -138.557)
		(size 0.7112)
		(drill 0.4064)
		(layers "F.Cu" "B.Cu")
		(net "P12V")
	)
	(via
		(at 348.361 -65.913)
		(size 0.7112)
		(drill 0.4064)
		(layers "F.Cu" "B.Cu")
		(net "P12V")
	)
	(via
		(at 61.722 -224.282)
		(size 0.7112)
		(drill 0.4064)
		(layers "F.Cu" "B.Cu")
		(net "P12V")
	)
	(via
		(at 303.276 -125.222)
		(size 0.7112)
		(drill 0.4064)
		(layers "F.Cu" "B.Cu")
		(net "P12V")
	)
	(via
		(at 305.689 -50.292)
		(size 0.7112)
		(drill 0.4064)
		(layers "F.Cu" "B.Cu")
		(net "P12V")
	)
	(via
		(at 336.169 -114.935)
		(size 0.5588)
		(drill 0.3048)
		(layers "F.Cu" "B.Cu")
		(net "P12V")
	)
	(via
		(at 66.294 -224.282)
		(size 0.7112)
		(drill 0.4064)
		(layers "F.Cu" "B.Cu")
		(net "P12V")
	)
	(via
		(at 209.042 -131.826)
		(size 0.7112)
		(drill 0.3556)
		(layers "F.Cu" "B.Cu")
		(net "P12V")
	)
	(via
		(at 275.463 -51.435)
		(size 0.5588)
		(drill 0.3048)
		(layers "F.Cu" "B.Cu")
		(net "P12V")
	)
	(via
		(at 90.551 -158.115)
		(size 0.7112)
		(drill 0.3556)
		(layers "F.Cu" "B.Cu")
		(net "P12V")
	)
	(via
		(at 51.943 -119.38)
		(size 0.5588)
		(drill 0.3048)
		(layers "F.Cu" "B.Cu")
		(net "P12V")
	)
	(via
		(at 90.297 -155.956)
		(size 0.7112)
		(drill 0.4064)
		(layers "F.Cu" "B.Cu")
		(net "P12V")
	)
	(via
		(at 215.5698 -130.2766)
		(size 0.7112)
		(drill 0.4064)
		(layers "F.Cu" "B.Cu")
		(net "P12V")
	)
	(via
		(at 150.749 -164.719)
		(size 0.7112)
		(drill 0.4064)
		(layers "F.Cu" "B.Cu")
		(net "P12V")
	)
	(via
		(at 302.133 -125.1966)
		(size 0.7112)
		(drill 0.4064)
		(layers "F.Cu" "B.Cu")
		(net "P12V")
	)
	(via
		(at 92.075 -154.559)
		(size 0.7112)
		(drill 0.4064)
		(layers "F.Cu" "B.Cu")
		(net "P12V")
	)
	(via
		(at 64.008 -224.282)
		(size 0.7112)
		(drill 0.4064)
		(layers "F.Cu" "B.Cu")
		(net "P12V")
	)
	(via
		(at 274.3962 -48.514)
		(size 0.5588)
		(drill 0.3048)
		(layers "F.Cu" "B.Cu")
		(net "P12V")
	)
	(via
		(at 37.176456 -75.184)
		(size 0.7112)
		(drill 0.4064)
		(layers "F.Cu" "B.Cu")
		(net "P12V")
	)
	(via
		(at 345.567 -123.571)
		(size 0.7112)
		(drill 0.4064)
		(layers "F.Cu" "B.Cu")
		(net "P12V")
	)
	(segment
		(start 275.082 -49.276)
		(end 274.3962 -48.5902)
		(width 0.508)
		(layer "B.Cu")
		(net "P12V")
	)
	(segment
		(start 274.32 -48.514)
		(end 273.685 -47.879)
		(width 0.508)
		(layer "B.Cu")
		(net "P12V")
	)
	(segment
		(start 161.671 -114.808)
		(end 161.671 -112.9792)
		(width 0.508)
		(layer "B.Cu")
		(net "P12V")
	)
	(segment
		(start 336.169 -114.935)
		(end 336.169 -115.568222)
		(width 0.508)
		(layer "B.Cu")
		(net "P12V")
	)
	(segment
		(start 274.3962 -48.514)
		(end 274.32 -48.514)
		(width 0.508)
		(layer "B.Cu")
		(net "P12V")
	)
	(segment
		(start 275.082 -51.054)
		(end 275.082 -49.276)
		(width 0.508)
		(layer "B.Cu")
		(net "P12V")
	)
	(segment
		(start 160.655 -115.824)
		(end 161.671 -114.808)
		(width 0.508)
		(layer "B.Cu")
		(net "P12V")
	)
	(segment
		(start 267.589 -47.879)
		(end 267.335 -47.625)
		(width 0.508)
		(layer "B.Cu")
		(net "P12V")
	)
	(segment
		(start 325.374 -176.1236)
		(end 325.0184 -176.4792)
		(width 0.508)
		(layer "B.Cu")
		(net "P12V")
	)
	(segment
		(start 337.948778 -117.348)
		(end 348.9198 -117.348)
		(width 0.508)
		(layer "B.Cu")
		(net "P12V")
	)
	(segment
		(start 325.374 -175.4505)
		(end 325.374 -176.1236)
		(width 0.508)
		(layer "B.Cu")
		(net "P12V")
	)
	(segment
		(start 274.3962 -48.5902)
		(end 274.3962 -48.514)
		(width 0.508)
		(layer "B.Cu")
		(net "P12V")
	)
	(segment
		(start 275.463 -51.435)
		(end 275.082 -51.054)
		(width 0.508)
		(layer "B.Cu")
		(net "P12V")
	)
	(segment
		(start 348.9198 -117.348)
		(end 349.123 -117.5512)
		(width 0.508)
		(layer "B.Cu")
		(net "P12V")
	)
	(segment
		(start 336.169 -115.568222)
		(end 337.948778 -117.348)
		(width 0.508)
		(layer "B.Cu")
		(net "P12V")
	)
	(segment
		(start 273.685 -47.879)
		(end 267.589 -47.879)
		(width 0.508)
		(layer "B.Cu")
		(net "P12V")
	)
	(segment
		(start 160.655 -134.62)
		(end 160.655 -115.824)
		(width 0.508)
		(layer "B.Cu")
		(net "P12V")
	)
	(segment
		(start 323.252592 -155.575)
		(end 324.231 -156.553408)
		(width 0.508)
		(layer "In2.Cu")
		(net "P12V")
	)
	(segment
		(start 324.231 -161.6075)
		(end 324.63867 -162.01517)
		(width 0.508)
		(layer "In2.Cu")
		(net "P12V")
	)
	(segment
		(start 41.905936 -87.757)
		(end 37.87394 -87.757)
		(width 0.508)
		(layer "In2.Cu")
		(net "P12V")
	)
	(segment
		(start 324.231 -156.553408)
		(end 324.231 -161.6075)
		(width 0.508)
		(layer "In2.Cu")
		(net "P12V")
	)
	(segment
		(start 325.0184 -170.2689)
		(end 325.0184 -176.4792)
		(width 0.508)
		(layer "In2.Cu")
		(net "P12V")
	)
	(segment
		(start 37.87394 -87.757)
		(end 32.7152 -82.59826)
		(width 0.508)
		(layer "In2.Cu")
		(net "P12V")
	)
	(segment
		(start 34.255456 -78.105)
		(end 37.176456 -75.184)
		(width 0.508)
		(layer "In2.Cu")
		(net "P12V")
	)
	(segment
		(start 318.643 -145.034)
		(end 318.643 -151.071326)
		(width 0.508)
		(layer "In2.Cu")
		(net "P12V")
	)
	(segment
		(start 32.7152 -82.59826)
		(end 32.7152 -79.344774)
		(width 0.508)
		(layer "In2.Cu")
		(net "P12V")
	)
	(segment
		(start 324.63867 -169.88917)
		(end 325.0184 -170.2689)
		(width 0.508)
		(layer "In2.Cu")
		(net "P12V")
	)
	(segment
		(start 33.954974 -78.105)
		(end 34.255456 -78.105)
		(width 0.508)
		(layer "In2.Cu")
		(net "P12V")
	)
	(segment
		(start 32.7152 -79.344774)
		(end 33.954974 -78.105)
		(width 0.508)
		(layer "In2.Cu")
		(net "P12V")
	)
	(segment
		(start 51.943 -119.38)
		(end 51.943 -114.427)
		(width 0.508)
		(layer "In2.Cu")
		(net "P12V")
	)
	(segment
		(start 317.627 -144.018)
		(end 318.643 -145.034)
		(width 0.508)
		(layer "In2.Cu")
		(net "P12V")
	)
	(segment
		(start 318.643 -151.071326)
		(end 323.146674 -155.575)
		(width 0.508)
		(layer "In2.Cu")
		(net "P12V")
	)
	(segment
		(start 324.63867 -162.01517)
		(end 324.63867 -169.88917)
		(width 0.508)
		(layer "In2.Cu")
		(net "P12V")
	)
	(segment
		(start 51.943 -114.427)
		(end 45.085 -107.569)
		(width 0.508)
		(layer "In2.Cu")
		(net "P12V")
	)
	(segment
		(start 323.146674 -155.575)
		(end 323.252592 -155.575)
		(width 0.508)
		(layer "In2.Cu")
		(net "P12V")
	)
	(segment
		(start 45.085 -107.569)
		(end 45.085 -90.936064)
		(width 0.508)
		(layer "In2.Cu")
		(net "P12V")
	)
	(segment
		(start 45.085 -90.936064)
		(end 41.905936 -87.757)
		(width 0.508)
		(layer "In2.Cu")
		(net "P12V")
	)
	(segment
		(start 30.734 -147.5232)
		(end 30.734 -138.557)
		(width 0.508)
		(layer "In5.Cu")
		(net "P12V")
	)
	(segment
		(start 316.623954 -130.035046)
		(end 316.623954 -143.014954)
		(width 0.508)
		(layer "In5.Cu")
		(net "P12V")
	)
	(segment
		(start 317.246 -129.413)
		(end 316.623954 -130.035046)
		(width 0.508)
		(layer "In5.Cu")
		(net "P12V")
	)
	(segment
		(start 87.503 -151.765)
		(end 32.353504 -151.765)
		(width 0.508)
		(layer "In5.Cu")
		(net "P12V")
	)
	(segment
		(start 30.1244 -149.535896)
		(end 30.1244 -148.1328)
		(width 0.508)
		(layer "In5.Cu")
		(net "P12V")
	)
	(segment
		(start 30.1244 -148.1328)
		(end 30.734 -147.5232)
		(width 0.508)
		(layer "In5.Cu")
		(net "P12V")
	)
	(segment
		(start 32.353504 -151.765)
		(end 30.1244 -149.535896)
		(width 0.508)
		(layer "In5.Cu")
		(net "P12V")
	)
	(segment
		(start 316.623954 -143.014954)
		(end 317.627 -144.018)
		(width 0.508)
		(layer "In5.Cu")
		(net "P12V")
	)
	(segment
		(start 90.297 -154.559)
		(end 87.503 -151.765)
		(width 0.508)
		(layer "In5.Cu")
		(net "P12V")
	)
	(segment
		(start 189.976252 -59.05754)
		(end 203.332588 -72.413876)
		(width 0.1397)
		(layer "F.Cu")
		(net "PCIE_SAS_CPU_TX_P0")
	)
	(segment
		(start 104.365044 -11.0871)
		(end 108.941616 -11.0871)
		(width 0.1397)
		(layer "F.Cu")
		(net "PCIE_SAS_CPU_TX_P0")
	)
	(segment
		(start 137.6172 -3.7846)
		(end 142.621 -8.7884)
		(width 0.1397)
		(layer "F.Cu")
		(net "PCIE_SAS_CPU_TX_P0")
	)
	(segment
		(start 95.284798 -32.759396)
		(end 95.220282 -32.695134)
		(width 0.1397)
		(layer "F.Cu")
		(net "PCIE_SAS_CPU_TX_P0")
	)
	(segment
		(start 203.63815 -73.152254)
		(end 203.63815 -73.787)
		(width 0.1397)
		(layer "F.Cu")
		(net "PCIE_SAS_CPU_TX_P0")
	)
	(segment
		(start 143.3449 -10.536174)
		(end 143.3449 -15.587726)
		(width 0.1397)
		(layer "F.Cu")
		(net "PCIE_SAS_CPU_TX_P0")
	)
	(segment
		(start 109.390688 -10.901172)
		(end 116.703348 -3.588512)
		(width 0.1397)
		(layer "F.Cu")
		(net "PCIE_SAS_CPU_TX_P0")
	)
	(segment
		(start 204.63256 -75.553824)
		(end 204.63256 -76.30922)
		(width 0.1397)
		(layer "F.Cu")
		(net "PCIE_SAS_CPU_TX_P0")
	)
	(segment
		(start 95.220282 -32.69488)
		(end 93.437456 -30.912054)
		(width 0.1397)
		(layer "F.Cu")
		(net "PCIE_SAS_CPU_TX_P0")
	)
	(segment
		(start 117.39499 -3.302)
		(end 136.451594 -3.302)
		(width 0.1397)
		(layer "F.Cu")
		(net "PCIE_SAS_CPU_TX_P0")
	)
	(segment
		(start 143.716756 -16.485616)
		(end 185.444384 -58.213244)
		(width 0.1397)
		(layer "F.Cu")
		(net "PCIE_SAS_CPU_TX_P0")
	)
	(segment
		(start 93.437456 -21.609304)
		(end 103.673402 -11.373358)
		(width 0.1397)
		(layer "F.Cu")
		(net "PCIE_SAS_CPU_TX_P0")
	)
	(segment
		(start 186.342274 -58.5851)
		(end 188.835792 -58.5851)
		(width 0.1397)
		(layer "F.Cu")
		(net "PCIE_SAS_CPU_TX_P0")
	)
	(segment
		(start 203.905104 -74.431144)
		(end 204.35316 -74.8792)
		(width 0.1397)
		(layer "F.Cu")
		(net "PCIE_SAS_CPU_TX_P0")
	)
	(segment
		(start 92.965016 -29.771594)
		(end 92.965016 -22.749764)
		(width 0.1397)
		(layer "F.Cu")
		(net "PCIE_SAS_CPU_TX_P0")
	)
	(segment
		(start 95.220282 -32.695134)
		(end 95.220282 -32.69488)
		(width 0.1397)
		(layer "F.Cu")
		(net "PCIE_SAS_CPU_TX_P0")
	)
	(via
		(at 204.929232 -77.0255)
		(size 0.5588)
		(drill 0.3048)
		(layers "F.Cu" "B.Cu")
		(net "PCIE_SAS_CPU_TX_P0")
	)
	(arc
		(start 93.437456 -30.912054)
		(mid 93.087833 -30.388807)
		(end 92.965016 -29.771594)
		(width 0.1397)
		(layer "F.Cu")
		(net "PCIE_SAS_CPU_TX_P0")
	)
	(arc
		(start 204.35316 -74.8792)
		(mid 204.559975 -75.18872)
		(end 204.63256 -75.553824)
		(width 0.1397)
		(layer "F.Cu")
		(net "PCIE_SAS_CPU_TX_P0")
	)
	(arc
		(start 142.621 -8.7884)
		(mid 143.156803 -9.590286)
		(end 143.3449 -10.536174)
		(width 0.1397)
		(layer "F.Cu")
		(net "PCIE_SAS_CPU_TX_P0")
	)
	(arc
		(start 108.941616 -11.0871)
		(mid 109.18462 -11.038764)
		(end 109.390688 -10.901172)
		(width 0.1397)
		(layer "F.Cu")
		(net "PCIE_SAS_CPU_TX_P0")
	)
	(arc
		(start 203.63815 -73.787)
		(mid 203.707586 -74.135608)
		(end 203.905104 -74.431144)
		(width 0.1397)
		(layer "F.Cu")
		(net "PCIE_SAS_CPU_TX_P0")
	)
	(arc
		(start 185.444384 -58.213244)
		(mid 185.856354 -58.48845)
		(end 186.342274 -58.5851)
		(width 0.1397)
		(layer "F.Cu")
		(net "PCIE_SAS_CPU_TX_P0")
	)
	(arc
		(start 136.451594 -3.302)
		(mid 137.082414 -3.427326)
		(end 137.6172 -3.7846)
		(width 0.1397)
		(layer "F.Cu")
		(net "PCIE_SAS_CPU_TX_P0")
	)
	(arc
		(start 143.3449 -15.587726)
		(mid 143.441539 -16.073651)
		(end 143.716756 -16.485616)
		(width 0.1397)
		(layer "F.Cu")
		(net "PCIE_SAS_CPU_TX_P0")
	)
	(arc
		(start 103.673402 -11.373358)
		(mid 103.990745 -11.161409)
		(end 104.365044 -11.0871)
		(width 0.1397)
		(layer "F.Cu")
		(net "PCIE_SAS_CPU_TX_P0")
	)
	(arc
		(start 203.332588 -72.413876)
		(mid 203.558835 -72.752663)
		(end 203.63815 -73.152254)
		(width 0.1397)
		(layer "F.Cu")
		(net "PCIE_SAS_CPU_TX_P0")
	)
	(arc
		(start 92.965016 -22.749764)
		(mid 93.087791 -22.132534)
		(end 93.437456 -21.609304)
		(width 0.1397)
		(layer "F.Cu")
		(net "PCIE_SAS_CPU_TX_P0")
	)
	(arc
		(start 95.549974 -33.399984)
		(mid 95.48111 -33.053309)
		(end 95.284798 -32.759396)
		(width 0.1397)
		(layer "F.Cu")
		(net "PCIE_SAS_CPU_TX_P0")
	)
	(arc
		(start 116.703348 -3.588512)
		(mid 117.020662 -3.376426)
		(end 117.39499 -3.302)
		(width 0.1397)
		(layer "F.Cu")
		(net "PCIE_SAS_CPU_TX_P0")
	)
	(arc
		(start 188.835792 -58.5851)
		(mid 189.453022 -58.707875)
		(end 189.976252 -59.05754)
		(width 0.1397)
		(layer "F.Cu")
		(net "PCIE_SAS_CPU_TX_P0")
	)
	(arc
		(start 204.63256 -76.30922)
		(mid 204.709666 -76.69686)
		(end 204.929232 -77.0255)
		(width 0.1397)
		(layer "F.Cu")
		(net "PCIE_SAS_CPU_TX_P0")
	)
	(segment
		(start 204.60462 -78.55331)
		(end 204.60462 -77.44206)
		(width 0.1397)
		(layer "B.Cu")
		(net "PCIE_SAS_CPU_TX_P0")
	)
	(segment
		(start 205.450186 -78.24978)
		(end 205.49997 -78.299564)
		(width 0.1397)
		(layer "B.Cu")
		(net "PCIE_SAS_CPU_TX_P0")
	)
	(segment
		(start 204.669644 -77.285088)
		(end 204.929232 -77.0255)
		(width 0.1397)
		(layer "B.Cu")
		(net "PCIE_SAS_CPU_TX_P0")
	)
	(segment
		(start 205.097634 -79.033624)
		(end 204.927962 -79.033624)
		(width 0.1397)
		(layer "B.Cu")
		(net "PCIE_SAS_CPU_TX_P0")
	)
	(arc
		(start 204.927962 -79.033624)
		(mid 204.846701 -79.01746)
		(end 204.777848 -78.971394)
		(width 0.1397)
		(layer "B.Cu")
		(net "PCIE_SAS_CPU_TX_P0")
	)
	(arc
		(start 205.49997 -78.299564)
		(mid 205.61749 -78.583282)
		(end 205.49997 -78.867)
		(width 0.1397)
		(layer "B.Cu")
		(net "PCIE_SAS_CPU_TX_P0")
	)
	(arc
		(start 205.49997 -78.867)
		(mid 205.315377 -78.990341)
		(end 205.097634 -79.033624)
		(width 0.1397)
		(layer "B.Cu")
		(net "PCIE_SAS_CPU_TX_P0")
	)
	(arc
		(start 204.777848 -78.971394)
		(mid 204.649679 -78.779575)
		(end 204.60462 -78.55331)
		(width 0.1397)
		(layer "B.Cu")
		(net "PCIE_SAS_CPU_TX_P0")
	)
	(arc
		(start 204.60462 -77.44206)
		(mid 204.621518 -77.357106)
		(end 204.669644 -77.285088)
		(width 0.1397)
		(layer "B.Cu")
		(net "PCIE_SAS_CPU_TX_P0")
	)
	(segment
		(start 302.64862 -175.00854)
		(end 302.98263 -175.34255)
		(width 0.1778)
		(layer "F.Cu")
		(net "ADCVREFFN")
	)
	(segment
		(start 302.98263 -175.34255)
		(end 308.36489 -175.34255)
		(width 0.1778)
		(layer "F.Cu")
		(net "ADCVREFFN")
	)
	(segment
		(start 317.627 -176.7205)
		(end 317.627 -177.6095)
		(width 0.1778)
		(layer "F.Cu")
		(net "ADCVREFFN")
	)
	(segment
		(start 309.93334 -176.911)
		(end 314.7314 -176.911)
		(width 0.1778)
		(layer "F.Cu")
		(net "ADCVREFFN")
	)
	(segment
		(start 316.992 -177.673)
		(end 317.5635 -177.673)
		(width 0.1778)
		(layer "F.Cu")
		(net "ADCVREFFN")
	)
	(segment
		(start 300.834806 -174.64024)
		(end 301.203106 -175.00854)
		(width 0.1778)
		(layer "F.Cu")
		(net "ADCVREFFN")
	)
	(segment
		(start 301.203106 -175.00854)
		(end 302.64862 -175.00854)
		(width 0.1778)
		(layer "F.Cu")
		(net "ADCVREFFN")
	)
	(segment
		(start 317.627 -177.6095)
		(end 317.5635 -177.673)
		(width 0.1778)
		(layer "F.Cu")
		(net "ADCVREFFN")
	)
	(segment
		(start 314.7314 -176.911)
		(end 316.23 -176.911)
		(width 0.1778)
		(layer "F.Cu")
		(net "ADCVREFFN")
	)
	(segment
		(start 308.36489 -175.34255)
		(end 309.93334 -176.911)
		(width 0.1778)
		(layer "F.Cu")
		(net "ADCVREFFN")
	)
	(segment
		(start 316.23 -176.911)
		(end 316.992 -177.673)
		(width 0.1778)
		(layer "F.Cu")
		(net "ADCVREFFN")
	)
	(via
		(at 314.7314 -176.911)
		(size 0.7112)
		(drill 0.3556)
		(layers "F.Cu" "B.Cu")
		(net "ADCVREFFN")
	)
	(segment
		(start 281.296872 -204.808836)
		(end 281.305 -204.800708)
		(width 0.1143)
		(layer "F.Cu")
		(net "BMC_DDR3_RST_N")
	)
	(segment
		(start 279.899872 -204.859636)
		(end 281.246072 -204.859636)
		(width 0.1143)
		(layer "F.Cu")
		(net "BMC_DDR3_RST_N")
	)
	(segment
		(start 281.305 -204.800708)
		(end 281.305 -203.581)
		(width 0.1143)
		(layer "F.Cu")
		(net "BMC_DDR3_RST_N")
	)
	(segment
		(start 284.898084 -201.735182)
		(end 283.052266 -203.581)
		(width 0.1143)
		(layer "F.Cu")
		(net "BMC_DDR3_RST_N")
	)
	(segment
		(start 281.246072 -204.859636)
		(end 281.296872 -204.808836)
		(width 0.1143)
		(layer "F.Cu")
		(net "BMC_DDR3_RST_N")
	)
	(segment
		(start 283.052266 -203.581)
		(end 281.305 -203.581)
		(width 0.1143)
		(layer "F.Cu")
		(net "BMC_DDR3_RST_N")
	)
	(via
		(at 281.305 -203.581)
		(size 0.7112)
		(drill 0.3556)
		(layers "F.Cu" "B.Cu")
		(net "BMC_DDR3_RST_N")
	)
	(segment
		(start 316.738 -180.721)
		(end 315.08065 -179.06365)
		(width 0.1778)
		(layer "F.Cu")
		(net "ADCVREXT")
	)
	(segment
		(start 307.45938 -178.181)
		(end 307.213 -178.181)
		(width 0.1778)
		(layer "F.Cu")
		(net "ADCVREXT")
	)
	(segment
		(start 300.834806 -177.840132)
		(end 301.228506 -178.233832)
		(width 0.1778)
		(layer "F.Cu")
		(net "ADCVREXT")
	)
	(segment
		(start 315.08065 -179.06365)
		(end 308.34203 -179.06365)
		(width 0.1778)
		(layer "F.Cu")
		(net "ADCVREXT")
	)
	(segment
		(start 302.480218 -178.284632)
		(end 302.848518 -178.284632)
		(width 0.1778)
		(layer "F.Cu")
		(net "ADCVREXT")
	)
	(segment
		(start 308.34203 -179.06365)
		(end 307.45938 -178.181)
		(width 0.1778)
		(layer "F.Cu")
		(net "ADCVREXT")
	)
	(segment
		(start 317.5635 -180.721)
		(end 316.738 -180.721)
		(width 0.1778)
		(layer "F.Cu")
		(net "ADCVREXT")
	)
	(segment
		(start 303.09185 -178.0413)
		(end 307.0733 -178.0413)
		(width 0.1778)
		(layer "F.Cu")
		(net "ADCVREXT")
	)
	(segment
		(start 302.429418 -178.233832)
		(end 302.480218 -178.284632)
		(width 0.1778)
		(layer "F.Cu")
		(net "ADCVREXT")
	)
	(segment
		(start 302.848518 -178.284632)
		(end 303.09185 -178.0413)
		(width 0.1778)
		(layer "F.Cu")
		(net "ADCVREXT")
	)
	(segment
		(start 301.228506 -178.233832)
		(end 302.429418 -178.233832)
		(width 0.1778)
		(layer "F.Cu")
		(net "ADCVREXT")
	)
	(segment
		(start 307.0733 -178.0413)
		(end 307.213 -178.181)
		(width 0.1778)
		(layer "F.Cu")
		(net "ADCVREXT")
	)
	(via
		(at 307.213 -178.181)
		(size 0.7112)
		(drill 0.3556)
		(layers "F.Cu" "B.Cu")
		(net "ADCVREXT")
	)
	(segment
		(start 218.58097 -69.5325)
		(end 219.72397 -69.5325)
		(width 0.1143)
		(layer "F.Cu")
		(net "SVR_ID0")
	)
	(segment
		(start 259.8674 -122.322336)
		(end 261.0612 -123.516136)
		(width 0.1143)
		(layer "F.Cu")
		(net "SVR_ID0")
	)
	(segment
		(start 261.0612 -123.516136)
		(end 261.0612 -146.3548)
		(width 0.1143)
		(layer "F.Cu")
		(net "SVR_ID0")
	)
	(segment
		(start 254.5715 -94.998032)
		(end 254.5715 -96.397826)
		(width 0.1143)
		(layer "F.Cu")
		(net "SVR_ID0")
	)
	(segment
		(start 219.72397 -69.5325)
		(end 219.72397 -70.612)
		(width 0.1143)
		(layer "F.Cu")
		(net "SVR_ID0")
	)
	(segment
		(start 254.5715 -96.397826)
		(end 259.8674 -101.693726)
		(width 0.1143)
		(layer "F.Cu")
		(net "SVR_ID0")
	)
	(segment
		(start 301.625 -196.342)
		(end 301.879 -196.342)
		(width 0.1143)
		(layer "F.Cu")
		(net "SVR_ID0")
	)
	(segment
		(start 259.8674 -101.693726)
		(end 259.8674 -122.322336)
		(width 0.1143)
		(layer "F.Cu")
		(net "SVR_ID0")
	)
	(segment
		(start 235.323888 -75.75042)
		(end 254.5715 -94.998032)
		(width 0.1143)
		(layer "F.Cu")
		(net "SVR_ID0")
	)
	(segment
		(start 218.60383 -75.02017)
		(end 222.377 -75.02017)
		(width 0.1143)
		(layer "F.Cu")
		(net "SVR_ID0")
	)
	(segment
		(start 217.450416 -75.75042)
		(end 217.87358 -75.75042)
		(width 0.1143)
		(layer "F.Cu")
		(net "SVR_ID0")
	)
	(segment
		(start 298.704 -193.421)
		(end 301.625 -196.342)
		(width 0.1143)
		(layer "F.Cu")
		(net "SVR_ID0")
	)
	(segment
		(start 262.3312 -159.9692)
		(end 263.652 -161.29)
		(width 0.1143)
		(layer "F.Cu")
		(net "SVR_ID0")
	)
	(segment
		(start 298.704 -192.3415)
		(end 298.704 -193.421)
		(width 0.1143)
		(layer "F.Cu")
		(net "SVR_ID0")
	)
	(segment
		(start 261.0612 -146.3548)
		(end 262.3312 -147.6248)
		(width 0.1143)
		(layer "F.Cu")
		(net "SVR_ID0")
	)
	(segment
		(start 222.377 -75.02017)
		(end 223.10725 -75.75042)
		(width 0.1143)
		(layer "F.Cu")
		(net "SVR_ID0")
	)
	(segment
		(start 219.72397 -70.612)
		(end 217.43797 -72.898)
		(width 0.1143)
		(layer "F.Cu")
		(net "SVR_ID0")
	)
	(segment
		(start 262.3312 -147.6248)
		(end 262.3312 -159.9692)
		(width 0.1143)
		(layer "F.Cu")
		(net "SVR_ID0")
	)
	(segment
		(start 223.10725 -75.75042)
		(end 235.323888 -75.75042)
		(width 0.1143)
		(layer "F.Cu")
		(net "SVR_ID0")
	)
	(segment
		(start 217.43797 -75.737974)
		(end 217.450416 -75.75042)
		(width 0.1143)
		(layer "F.Cu")
		(net "SVR_ID0")
	)
	(segment
		(start 217.43797 -72.898)
		(end 217.43797 -75.737974)
		(width 0.1143)
		(layer "F.Cu")
		(net "SVR_ID0")
	)
	(segment
		(start 217.87358 -75.75042)
		(end 218.60383 -75.02017)
		(width 0.1143)
		(layer "F.Cu")
		(net "SVR_ID0")
	)
	(via
		(at 301.879 -196.342)
		(size 0.5588)
		(drill 0.3048)
		(layers "F.Cu" "B.Cu")
		(net "SVR_ID0")
	)
	(via
		(at 265.176 -194.04076)
		(size 0.5588)
		(drill 0.3048)
		(layers "F.Cu" "B.Cu")
		(net "SVR_ID0")
	)
	(via
		(at 263.652 -161.29)
		(size 0.5588)
		(drill 0.3048)
		(layers "F.Cu" "B.Cu")
		(net "SVR_ID0")
	)
	(segment
		(start 282.611068 -206.091536)
		(end 279.113996 -206.091536)
		(width 0.127)
		(layer "In2.Cu")
		(net "SVR_ID0")
	)
	(segment
		(start 279.113996 -206.091536)
		(end 278.462232 -206.7433)
		(width 0.127)
		(layer "In2.Cu")
		(net "SVR_ID0")
	)
	(segment
		(start 278.462232 -206.7433)
		(end 274.775168 -206.7433)
		(width 0.127)
		(layer "In2.Cu")
		(net "SVR_ID0")
	)
	(segment
		(start 282.729432 -206.2099)
		(end 282.611068 -206.091536)
		(width 0.127)
		(layer "In2.Cu")
		(net "SVR_ID0")
	)
	(segment
		(start 301.879 -196.342)
		(end 301.752 -196.342)
		(width 0.127)
		(layer "In2.Cu")
		(net "SVR_ID0")
	)
	(segment
		(start 301.4218 -202.140058)
		(end 297.351958 -206.2099)
		(width 0.127)
		(layer "In2.Cu")
		(net "SVR_ID0")
	)
	(segment
		(start 301.752 -196.342)
		(end 301.4218 -196.6722)
		(width 0.127)
		(layer "In2.Cu")
		(net "SVR_ID0")
	)
	(segment
		(start 297.351958 -206.2099)
		(end 282.729432 -206.2099)
		(width 0.127)
		(layer "In2.Cu")
		(net "SVR_ID0")
	)
	(segment
		(start 265.176 -197.144132)
		(end 265.176 -194.04076)
		(width 0.127)
		(layer "In2.Cu")
		(net "SVR_ID0")
	)
	(segment
		(start 301.4218 -196.6722)
		(end 301.4218 -202.140058)
		(width 0.127)
		(layer "In2.Cu")
		(net "SVR_ID0")
	)
	(segment
		(start 274.775168 -206.7433)
		(end 265.176 -197.144132)
		(width 0.127)
		(layer "In2.Cu")
		(net "SVR_ID0")
	)
	(segment
		(start 264.2743 -164.929566)
		(end 265.2649 -165.920166)
		(width 0.127)
		(layer "In5.Cu")
		(net "SVR_ID0")
	)
	(segment
		(start 264.2743 -161.9123)
		(end 264.2743 -164.929566)
		(width 0.127)
		(layer "In5.Cu")
		(net "SVR_ID0")
	)
	(segment
		(start 265.2649 -174.068232)
		(end 265.176 -174.157132)
		(width 0.127)
		(layer "In5.Cu")
		(net "SVR_ID0")
	)
	(segment
		(start 265.176 -174.157132)
		(end 265.176 -194.04076)
		(width 0.127)
		(layer "In5.Cu")
		(net "SVR_ID0")
	)
	(segment
		(start 263.652 -161.29)
		(end 264.2743 -161.9123)
		(width 0.127)
		(layer "In5.Cu")
		(net "SVR_ID0")
	)
	(segment
		(start 265.2649 -165.920166)
		(end 265.2649 -174.068232)
		(width 0.127)
		(layer "In5.Cu")
		(net "SVR_ID0")
	)
	(segment
		(start 280.162 -191.3255)
		(end 279.273 -191.3255)
		(width 0.508)
		(layer "F.Cu")
		(net "V1PLLAV12")
	)
	(segment
		(start 281.0764 -191.262)
		(end 281.0129 -191.3255)
		(width 0.508)
		(layer "F.Cu")
		(net "V1PLLAV12")
	)
	(segment
		(start 278.4475 -191.3255)
		(end 278.13 -191.008)
		(width 0.508)
		(layer "F.Cu")
		(net "V1PLLAV12")
	)
	(segment
		(start 287.234884 -181.840124)
		(end 286.83966 -181.4449)
		(width 0.3556)
		(layer "F.Cu")
		(net "V1PLLAV12")
	)
	(segment
		(start 286.83966 -181.4449)
		(end 286.83204 -181.4449)
		(width 0.3556)
		(layer "F.Cu")
		(net "V1PLLAV12")
	)
	(segment
		(start 281.0129 -191.3255)
		(end 280.162 -191.3255)
		(width 0.508)
		(layer "F.Cu")
		(net "V1PLLAV12")
	)
	(segment
		(start 277.6982 -191.4398)
		(end 278.13 -191.008)
		(width 0.508)
		(layer "F.Cu")
		(net "V1PLLAV12")
	)
	(segment
		(start 279.273 -191.3255)
		(end 278.4475 -191.3255)
		(width 0.508)
		(layer "F.Cu")
		(net "V1PLLAV12")
	)
	(segment
		(start 286.434784 -182.640224)
		(end 287.234884 -181.840124)
		(width 0.3556)
		(layer "F.Cu")
		(net "V1PLLAV12")
	)
	(segment
		(start 276.479 -191.4398)
		(end 277.6982 -191.4398)
		(width 0.508)
		(layer "F.Cu")
		(net "V1PLLAV12")
	)
	(via
		(at 286.512 -182.372)
		(size 0.7112)
		(drill 0.3556)
		(layers "F.Cu" "B.Cu")
		(net "V1PLLAV12")
	)
	(via
		(at 286.83204 -181.4449)
		(size 0.508)
		(drill 0.254)
		(layers "F.Cu" "B.Cu")
		(net "V1PLLAV12")
	)
	(via
		(at 281.0764 -191.262)
		(size 0.7112)
		(drill 0.4064)
		(layers "F.Cu" "B.Cu")
		(net "V1PLLAV12")
	)
	(segment
		(start 286.83204 -181.4449)
		(end 286.83204 -182.05196)
		(width 0.254)
		(layer "B.Cu")
		(net "V1PLLAV12")
	)
	(segment
		(start 286.83204 -182.05196)
		(end 286.512 -182.372)
		(width 0.254)
		(layer "B.Cu")
		(net "V1PLLAV12")
	)
	(segment
		(start 286.287464 -182.059072)
		(end 285.427928 -182.059072)
		(width 0.508)
		(layer "In2.Cu")
		(net "V1PLLAV12")
	)
	(segment
		(start 282.956 -184.531)
		(end 282.956 -187.959492)
		(width 0.508)
		(layer "In2.Cu")
		(net "V1PLLAV12")
	)
	(segment
		(start 286.644334 -181.702202)
		(end 286.287464 -182.059072)
		(width 0.508)
		(layer "In2.Cu")
		(net "V1PLLAV12")
	)
	(segment
		(start 285.427928 -182.059072)
		(end 282.956 -184.531)
		(width 0.508)
		(layer "In2.Cu")
		(net "V1PLLAV12")
	)
	(segment
		(start 286.83204 -181.4449)
		(end 286.644334 -181.632606)
		(width 0.508)
		(layer "In2.Cu")
		(net "V1PLLAV12")
	)
	(segment
		(start 282.956 -187.959492)
		(end 281.0764 -189.839092)
		(width 0.508)
		(layer "In2.Cu")
		(net "V1PLLAV12")
	)
	(segment
		(start 286.644334 -181.632606)
		(end 286.644334 -181.702202)
		(width 0.508)
		(layer "In2.Cu")
		(net "V1PLLAV12")
	)
	(segment
		(start 281.0764 -189.839092)
		(end 281.0764 -191.262)
		(width 0.508)
		(layer "In2.Cu")
		(net "V1PLLAV12")
	)
	(segment
		(start 290.581842 -198.00443)
		(end 290.581842 -198.36257)
		(width 0.1016)
		(layer "F.Cu")
		(net "MEMCK_P")
	)
	(segment
		(start 292.8493 -184.6199)
		(end 292.7096 -184.7596)
		(width 0.1016)
		(layer "F.Cu")
		(net "MEMCK_P")
	)
	(segment
		(start 292.8493 -184.254648)
		(end 292.8493 -184.6199)
		(width 0.1016)
		(layer "F.Cu")
		(net "MEMCK_P")
	)
	(segment
		(start 290.44138 -198.503032)
		(end 290.44138 -198.83247)
		(width 0.1016)
		(layer "F.Cu")
		(net "MEMCK_P")
	)
	(segment
		(start 290.498022 -197.92061)
		(end 290.581842 -198.00443)
		(width 0.1016)
		(layer "F.Cu")
		(net "MEMCK_P")
	)
	(segment
		(start 290.581842 -198.36257)
		(end 290.44138 -198.503032)
		(width 0.1016)
		(layer "F.Cu")
		(net "MEMCK_P")
	)
	(segment
		(start 290.498022 -197.73519)
		(end 290.498022 -197.92061)
		(width 0.1016)
		(layer "F.Cu")
		(net "MEMCK_P")
	)
	(segment
		(start 292.834822 -184.24017)
		(end 292.8493 -184.254648)
		(width 0.1016)
		(layer "F.Cu")
		(net "MEMCK_P")
	)
	(segment
		(start 292.7096 -184.7596)
		(end 292.7096 -184.8104)
		(width 0.1016)
		(layer "F.Cu")
		(net "MEMCK_P")
	)
	(via
		(at 290.44138 -198.83247)
		(size 0.508)
		(drill 0.254)
		(layers "F.Cu" "B.Cu")
		(net "MEMCK_P")
	)
	(via
		(at 293.8018 -189.0014)
		(size 0.7112)
		(drill 0.3556)
		(layers "F.Cu" "B.Cu")
		(net "MEMCK_P")
	)
	(via
		(at 292.7096 -184.8104)
		(size 0.508)
		(drill 0.254)
		(layers "F.Cu" "B.Cu")
		(net "MEMCK_P")
	)
	(segment
		(start 291.21862 -198.11873)
		(end 290.931346 -198.11873)
		(width 0.1016)
		(layer "B.Cu")
		(net "MEMCK_P")
	)
	(segment
		(start 293.039038 -185.15457)
		(end 293.4462 -185.561732)
		(width 0.1016)
		(layer "B.Cu")
		(net "MEMCK_P")
	)
	(segment
		(start 293.6748 -191.87541)
		(end 293.6748 -192.5574)
		(width 0.1016)
		(layer "B.Cu")
		(net "MEMCK_P")
	)
	(segment
		(start 292.2905 -194.85864)
		(end 292.2905 -195.793106)
		(width 0.1016)
		(layer "B.Cu")
		(net "MEMCK_P")
	)
	(segment
		(start 292.95725 -190.73495)
		(end 292.95725 -191.34455)
		(width 0.1016)
		(layer "B.Cu")
		(net "MEMCK_P")
	)
	(segment
		(start 293.05885 -189.33795)
		(end 293.8018 -189.33795)
		(width 0.1016)
		(layer "B.Cu")
		(net "MEMCK_P")
	)
	(segment
		(start 290.931346 -198.11873)
		(end 290.44138 -198.608696)
		(width 0.1016)
		(layer "B.Cu")
		(net "MEMCK_P")
	)
	(segment
		(start 293.8018 -189.33795)
		(end 293.8018 -189.0014)
		(width 0.1016)
		(layer "B.Cu")
		(net "MEMCK_P")
	)
	(segment
		(start 292.95725 -188.62675)
		(end 292.95725 -189.23635)
		(width 0.1016)
		(layer "B.Cu")
		(net "MEMCK_P")
	)
	(segment
		(start 292.95725 -191.34455)
		(end 293.05885 -191.44615)
		(width 0.1016)
		(layer "B.Cu")
		(net "MEMCK_P")
	)
	(segment
		(start 291.824156 -197.513194)
		(end 291.21862 -198.11873)
		(width 0.1016)
		(layer "B.Cu")
		(net "MEMCK_P")
	)
	(segment
		(start 293.98595 -189.33795)
		(end 294.3606 -189.7126)
		(width 0.1016)
		(layer "B.Cu")
		(net "MEMCK_P")
	)
	(segment
		(start 293.05885 -190.63335)
		(end 292.95725 -190.73495)
		(width 0.1016)
		(layer "B.Cu")
		(net "MEMCK_P")
	)
	(segment
		(start 293.05885 -191.44615)
		(end 293.24554 -191.44615)
		(width 0.1016)
		(layer "B.Cu")
		(net "MEMCK_P")
	)
	(segment
		(start 292.7096 -184.8104)
		(end 292.7096 -184.863232)
		(width 0.1016)
		(layer "B.Cu")
		(net "MEMCK_P")
	)
	(segment
		(start 293.92245 -190.63335)
		(end 293.05885 -190.63335)
		(width 0.1016)
		(layer "B.Cu")
		(net "MEMCK_P")
	)
	(segment
		(start 293.4462 -185.561732)
		(end 293.4462 -187.85332)
		(width 0.1016)
		(layer "B.Cu")
		(net "MEMCK_P")
	)
	(segment
		(start 293.4462 -187.85332)
		(end 293.446454 -187.853574)
		(width 0.1016)
		(layer "B.Cu")
		(net "MEMCK_P")
	)
	(segment
		(start 293.6748 -192.5574)
		(end 293.3192 -192.913)
		(width 0.1016)
		(layer "B.Cu")
		(net "MEMCK_P")
	)
	(segment
		(start 293.8018 -189.33795)
		(end 293.98595 -189.33795)
		(width 0.1016)
		(layer "B.Cu")
		(net "MEMCK_P")
	)
	(segment
		(start 292.2905 -195.793106)
		(end 291.824156 -196.25945)
		(width 0.1016)
		(layer "B.Cu")
		(net "MEMCK_P")
	)
	(segment
		(start 293.24554 -191.44615)
		(end 293.6748 -191.87541)
		(width 0.1016)
		(layer "B.Cu")
		(net "MEMCK_P")
	)
	(segment
		(start 292.95725 -193.09715)
		(end 292.95725 -194.19189)
		(width 0.1016)
		(layer "B.Cu")
		(net "MEMCK_P")
	)
	(segment
		(start 294.3606 -190.1952)
		(end 293.92245 -190.63335)
		(width 0.1016)
		(layer "B.Cu")
		(net "MEMCK_P")
	)
	(segment
		(start 294.3606 -189.7126)
		(end 294.3606 -190.1952)
		(width 0.1016)
		(layer "B.Cu")
		(net "MEMCK_P")
	)
	(segment
		(start 290.44138 -198.608696)
		(end 290.44138 -198.83247)
		(width 0.1016)
		(layer "B.Cu")
		(net "MEMCK_P")
	)
	(segment
		(start 293.1414 -192.913)
		(end 292.95725 -193.09715)
		(width 0.1016)
		(layer "B.Cu")
		(net "MEMCK_P")
	)
	(segment
		(start 292.95725 -189.23635)
		(end 293.05885 -189.33795)
		(width 0.1016)
		(layer "B.Cu")
		(net "MEMCK_P")
	)
	(segment
		(start 292.95725 -194.19189)
		(end 292.2905 -194.85864)
		(width 0.1016)
		(layer "B.Cu")
		(net "MEMCK_P")
	)
	(segment
		(start 293.446454 -188.137546)
		(end 292.95725 -188.62675)
		(width 0.1016)
		(layer "B.Cu")
		(net "MEMCK_P")
	)
	(segment
		(start 293.446454 -187.853574)
		(end 293.446454 -188.137546)
		(width 0.1016)
		(layer "B.Cu")
		(net "MEMCK_P")
	)
	(segment
		(start 292.7096 -184.863232)
		(end 293.000938 -185.15457)
		(width 0.1016)
		(layer "B.Cu")
		(net "MEMCK_P")
	)
	(segment
		(start 293.3192 -192.913)
		(end 293.1414 -192.913)
		(width 0.1016)
		(layer "B.Cu")
		(net "MEMCK_P")
	)
	(segment
		(start 291.824156 -196.25945)
		(end 291.824156 -197.513194)
		(width 0.1016)
		(layer "B.Cu")
		(net "MEMCK_P")
	)
	(segment
		(start 293.000938 -185.15457)
		(end 293.039038 -185.15457)
		(width 0.1016)
		(layer "B.Cu")
		(net "MEMCK_P")
	)
	(segment
		(start 91.924632 -137.209276)
		(end 91.924632 -135.927338)
		(width 0.1143)
		(layer "F.Cu")
		(net "EXP_TRAY_ID")
	)
	(segment
		(start 258.572 -175.160432)
		(end 258.572 -155.194)
		(width 0.1143)
		(layer "F.Cu")
		(net "EXP_TRAY_ID")
	)
	(segment
		(start 258.572 -155.194)
		(end 253.619 -150.241)
		(width 0.1143)
		(layer "F.Cu")
		(net "EXP_TRAY_ID")
	)
	(segment
		(start 264.527284 -181.115716)
		(end 258.572 -175.160432)
		(width 0.1143)
		(layer "F.Cu")
		(net "EXP_TRAY_ID")
	)
	(segment
		(start 91.924632 -135.927338)
		(end 92.08897 -135.763)
		(width 0.1143)
		(layer "F.Cu")
		(net "EXP_TRAY_ID")
	)
	(segment
		(start 265.6205 -181.102)
		(end 264.527284 -181.115716)
		(width 0.1143)
		(layer "F.Cu")
		(net "EXP_TRAY_ID")
	)
	(via
		(at 129.0574 -153.797)
		(size 0.5588)
		(drill 0.3048)
		(layers "F.Cu" "B.Cu")
		(net "EXP_TRAY_ID")
	)
	(via
		(at 253.619 -150.241)
		(size 0.5588)
		(drill 0.3048)
		(layers "F.Cu" "B.Cu")
		(net "EXP_TRAY_ID")
	)
	(via
		(at 92.08897 -135.763)
		(size 0.5588)
		(drill 0.3048)
		(layers "F.Cu" "B.Cu")
		(net "EXP_TRAY_ID")
	)
	(via
		(at 138.221212 -242.824)
		(size 0.7112)
		(drill 0.3556)
		(layers "F.Cu" "B.Cu")
		(net "EXP_TRAY_ID")
	)
	(segment
		(start 138.221212 -242.57)
		(end 138.221212 -242.824)
		(width 0.1143)
		(layer "B.Cu")
		(net "EXP_TRAY_ID")
	)
	(segment
		(start 129.0574 -153.797)
		(end 139.337034 -164.076634)
		(width 0.1143)
		(layer "B.Cu")
		(net "EXP_TRAY_ID")
	)
	(segment
		(start 139.337034 -241.454178)
		(end 138.221212 -242.57)
		(width 0.1143)
		(layer "B.Cu")
		(net "EXP_TRAY_ID")
	)
	(segment
		(start 138.221212 -245.0465)
		(end 138.221212 -242.824)
		(width 0.1143)
		(layer "B.Cu")
		(net "EXP_TRAY_ID")
	)
	(segment
		(start 139.337034 -164.076634)
		(end 139.337034 -241.454178)
		(width 0.1143)
		(layer "B.Cu")
		(net "EXP_TRAY_ID")
	)
	(segment
		(start 210.1469 -151.9301)
		(end 211.7852 -150.2918)
		(width 0.127)
		(layer "In2.Cu")
		(net "EXP_TRAY_ID")
	)
	(segment
		(start 129.0574 -153.797)
		(end 140.843 -153.797)
		(width 0.127)
		(layer "In2.Cu")
		(net "EXP_TRAY_ID")
	)
	(segment
		(start 93.806264 -137.4775)
		(end 93.67774 -137.4775)
		(width 0.127)
		(layer "In2.Cu")
		(net "EXP_TRAY_ID")
	)
	(segment
		(start 94.504764 -138.176)
		(end 93.806264 -137.4775)
		(width 0.127)
		(layer "In2.Cu")
		(net "EXP_TRAY_ID")
	)
	(segment
		(start 140.843 -153.797)
		(end 141.9606 -152.6794)
		(width 0.127)
		(layer "In2.Cu")
		(net "EXP_TRAY_ID")
	)
	(segment
		(start 93.67774 -137.4775)
		(end 92.08897 -135.88873)
		(width 0.127)
		(layer "In2.Cu")
		(net "EXP_TRAY_ID")
	)
	(segment
		(start 169.442638 -152.6794)
		(end 170.191938 -151.9301)
		(width 0.127)
		(layer "In2.Cu")
		(net "EXP_TRAY_ID")
	)
	(segment
		(start 211.7852 -150.2918)
		(end 253.5682 -150.2918)
		(width 0.127)
		(layer "In2.Cu")
		(net "EXP_TRAY_ID")
	)
	(segment
		(start 95.123 -138.176)
		(end 94.504764 -138.176)
		(width 0.127)
		(layer "In2.Cu")
		(net "EXP_TRAY_ID")
	)
	(segment
		(start 129.0574 -153.797)
		(end 127.9144 -152.654)
		(width 0.127)
		(layer "In2.Cu")
		(net "EXP_TRAY_ID")
	)
	(segment
		(start 253.5682 -150.2918)
		(end 253.619 -150.241)
		(width 0.127)
		(layer "In2.Cu")
		(net "EXP_TRAY_ID")
	)
	(segment
		(start 141.9606 -152.6794)
		(end 169.442638 -152.6794)
		(width 0.127)
		(layer "In2.Cu")
		(net "EXP_TRAY_ID")
	)
	(segment
		(start 170.191938 -151.9301)
		(end 210.1469 -151.9301)
		(width 0.127)
		(layer "In2.Cu")
		(net "EXP_TRAY_ID")
	)
	(segment
		(start 127.9144 -152.654)
		(end 109.601 -152.654)
		(width 0.127)
		(layer "In2.Cu")
		(net "EXP_TRAY_ID")
	)
	(segment
		(start 109.601 -152.654)
		(end 95.123 -138.176)
		(width 0.127)
		(layer "In2.Cu")
		(net "EXP_TRAY_ID")
	)
	(segment
		(start 92.08897 -135.88873)
		(end 92.08897 -135.763)
		(width 0.127)
		(layer "In2.Cu")
		(net "EXP_TRAY_ID")
	)
	(segment
		(start 280.7335 -197.231)
		(end 281.051 -197.5485)
		(width 0.508)
		(layer "F.Cu")
		(net "MPLLAV33")
	)
	(segment
		(start 280.797 -195.235322)
		(end 280.7335 -195.298822)
		(width 0.508)
		(layer "F.Cu")
		(net "MPLLAV33")
	)
	(segment
		(start 286.55518 -184.60212)
		(end 286.250126 -184.907174)
		(width 0.1143)
		(layer "F.Cu")
		(net "MPLLAV33")
	)
	(segment
		(start 289.13328 -180.356764)
		(end 289.13328 -180.741574)
		(width 0.2032)
		(layer "F.Cu")
		(net "MPLLAV33")
	)
	(segment
		(start 280.7335 -195.298822)
		(end 280.7335 -196.215)
		(width 0.508)
		(layer "F.Cu")
		(net "MPLLAV33")
	)
	(segment
		(start 281.051 -199.1868)
		(end 280.289 -199.9488)
		(width 0.508)
		(layer "F.Cu")
		(net "MPLLAV33")
	)
	(segment
		(start 281.051 -197.5485)
		(end 281.051 -198.247)
		(width 0.508)
		(layer "F.Cu")
		(net "MPLLAV33")
	)
	(segment
		(start 286.946848 -184.24017)
		(end 286.584898 -184.60212)
		(width 0.1143)
		(layer "F.Cu")
		(net "MPLLAV33")
	)
	(segment
		(start 286.584898 -184.60212)
		(end 286.55518 -184.60212)
		(width 0.1143)
		(layer "F.Cu")
		(net "MPLLAV33")
	)
	(segment
		(start 287.234884 -184.24017)
		(end 286.946848 -184.24017)
		(width 0.1143)
		(layer "F.Cu")
		(net "MPLLAV33")
	)
	(segment
		(start 281.051 -198.247)
		(end 281.051 -199.1868)
		(width 0.508)
		(layer "F.Cu")
		(net "MPLLAV33")
	)
	(segment
		(start 280.7335 -196.215)
		(end 280.7335 -197.231)
		(width 0.508)
		(layer "F.Cu")
		(net "MPLLAV33")
	)
	(segment
		(start 289.13328 -180.741574)
		(end 288.83483 -181.040024)
		(width 0.2032)
		(layer "F.Cu")
		(net "MPLLAV33")
	)
	(segment
		(start 281.178 -193.802)
		(end 280.797 -194.183)
		(width 0.508)
		(layer "F.Cu")
		(net "MPLLAV33")
	)
	(segment
		(start 280.797 -194.183)
		(end 280.797 -195.235322)
		(width 0.508)
		(layer "F.Cu")
		(net "MPLLAV33")
	)
	(via
		(at 281.178 -193.802)
		(size 0.5588)
		(drill 0.3048)
		(layers "F.Cu" "B.Cu")
		(net "MPLLAV33")
	)
	(via
		(at 286.250126 -184.907174)
		(size 0.508)
		(drill 0.254)
		(layers "F.Cu" "B.Cu")
		(net "MPLLAV33")
	)
	(via
		(at 286.398716 -184.018428)
		(size 0.7112)
		(drill 0.3556)
		(layers "F.Cu" "B.Cu")
		(net "MPLLAV33")
	)
	(via
		(at 289.13328 -180.356764)
		(size 0.508)
		(drill 0.254)
		(layers "F.Cu" "B.Cu")
		(net "MPLLAV33")
	)
	(segment
		(start 286.398716 -184.018428)
		(end 286.389572 -184.027572)
		(width 0.1143)
		(layer "B.Cu")
		(net "MPLLAV33")
	)
	(segment
		(start 286.389572 -184.027572)
		(end 286.389572 -184.767728)
		(width 0.1143)
		(layer "B.Cu")
		(net "MPLLAV33")
	)
	(segment
		(start 286.389572 -184.767728)
		(end 286.250126 -184.907174)
		(width 0.1143)
		(layer "B.Cu")
		(net "MPLLAV33")
	)
	(segment
		(start 287.418018 -184.040018)
		(end 287.117282 -184.040018)
		(width 0.3048)
		(layer "In2.Cu")
		(net "MPLLAV33")
	)
	(segment
		(start 282.067 -192.913)
		(end 281.178 -193.802)
		(width 0.508)
		(layer "In2.Cu")
		(net "MPLLAV33")
	)
	(segment
		(start 282.067 -192.532)
		(end 282.067 -192.913)
		(width 0.508)
		(layer "In2.Cu")
		(net "MPLLAV33")
	)
	(segment
		(start 283.845 -188.595)
		(end 283.337 -189.103)
		(width 0.508)
		(layer "In2.Cu")
		(net "MPLLAV33")
	)
	(segment
		(start 283.845 -184.658)
		(end 283.845 -188.595)
		(width 0.508)
		(layer "In2.Cu")
		(net "MPLLAV33")
	)
	(segment
		(start 285.683706 -184.340754)
		(end 284.162246 -184.340754)
		(width 0.508)
		(layer "In2.Cu")
		(net "MPLLAV33")
	)
	(segment
		(start 289.13328 -180.356764)
		(end 289.13328 -180.732176)
		(width 0.3048)
		(layer "In2.Cu")
		(net "MPLLAV33")
	)
	(segment
		(start 287.117282 -184.040018)
		(end 286.250126 -184.907174)
		(width 0.3048)
		(layer "In2.Cu")
		(net "MPLLAV33")
	)
	(segment
		(start 289.13328 -180.732176)
		(end 288.544 -181.321456)
		(width 0.3048)
		(layer "In2.Cu")
		(net "MPLLAV33")
	)
	(segment
		(start 284.162246 -184.340754)
		(end 283.845 -184.658)
		(width 0.508)
		(layer "In2.Cu")
		(net "MPLLAV33")
	)
	(segment
		(start 288.544 -181.321456)
		(end 288.544 -182.914036)
		(width 0.3048)
		(layer "In2.Cu")
		(net "MPLLAV33")
	)
	(segment
		(start 286.250126 -184.907174)
		(end 285.683706 -184.340754)
		(width 0.508)
		(layer "In2.Cu")
		(net "MPLLAV33")
	)
	(segment
		(start 288.544 -182.914036)
		(end 287.418018 -184.040018)
		(width 0.3048)
		(layer "In2.Cu")
		(net "MPLLAV33")
	)
	(segment
		(start 283.337 -189.103)
		(end 283.337 -191.262)
		(width 0.508)
		(layer "In2.Cu")
		(net "MPLLAV33")
	)
	(segment
		(start 283.337 -191.262)
		(end 282.067 -192.532)
		(width 0.508)
		(layer "In2.Cu")
		(net "MPLLAV33")
	)
	(segment
		(start 293.634922 -182.640224)
		(end 293.62527 -182.640224)
		(width 0.1143)
		(layer "F.Cu")
		(net "MEMDQ_4")
	)
	(segment
		(start 293.62527 -182.640224)
		(end 293.22522 -182.240174)
		(width 0.1143)
		(layer "F.Cu")
		(net "MEMDQ_4")
	)
	(segment
		(start 292.898068 -201.729848)
		(end 292.50386 -201.33564)
		(width 0.1143)
		(layer "F.Cu")
		(net "MEMDQ_4")
	)
	(segment
		(start 292.898068 -201.735182)
		(end 292.898068 -201.729848)
		(width 0.1143)
		(layer "F.Cu")
		(net "MEMDQ_4")
	)
	(via
		(at 293.22522 -182.240174)
		(size 0.508)
		(drill 0.254)
		(layers "F.Cu" "B.Cu")
		(net "MEMDQ_4")
	)
	(via
		(at 292.50386 -201.33564)
		(size 0.508)
		(drill 0.254)
		(layers "F.Cu" "B.Cu")
		(net "MEMDQ_4")
	)
	(via
		(at 291.78504 -200.410064)
		(size 0.7112)
		(drill 0.3556)
		(layers "F.Cu" "B.Cu")
		(net "MEMDQ_4")
	)
	(segment
		(start 292.50386 -201.128884)
		(end 292.50386 -201.33564)
		(width 0.1143)
		(layer "B.Cu")
		(net "MEMDQ_4")
	)
	(segment
		(start 291.78504 -200.410064)
		(end 292.50386 -201.128884)
		(width 0.1143)
		(layer "B.Cu")
		(net "MEMDQ_4")
	)
	(segment
		(start 289.40633 -189.981078)
		(end 289.70732 -189.680088)
		(width 0.127)
		(layer "In5.Cu")
		(net "MEMDQ_4")
	)
	(segment
		(start 289.40633 -196.64553)
		(end 289.40633 -189.981078)
		(width 0.127)
		(layer "In5.Cu")
		(net "MEMDQ_4")
	)
	(segment
		(start 292.92296 -182.81904)
		(end 292.92296 -182.77586)
		(width 0.127)
		(layer "In5.Cu")
		(net "MEMDQ_4")
	)
	(segment
		(start 289.52952 -186.21248)
		(end 292.92296 -182.81904)
		(width 0.127)
		(layer "In5.Cu")
		(net "MEMDQ_4")
	)
	(segment
		(start 291.46246 -200.269094)
		(end 291.46246 -198.70166)
		(width 0.127)
		(layer "In5.Cu")
		(net "MEMDQ_4")
	)
	(segment
		(start 289.70732 -189.680088)
		(end 289.70732 -187.01893)
		(width 0.127)
		(layer "In5.Cu")
		(net "MEMDQ_4")
	)
	(segment
		(start 289.52952 -186.84113)
		(end 289.52952 -186.21248)
		(width 0.127)
		(layer "In5.Cu")
		(net "MEMDQ_4")
	)
	(segment
		(start 292.92296 -182.77586)
		(end 293.22522 -182.473346)
		(width 0.127)
		(layer "In5.Cu")
		(net "MEMDQ_4")
	)
	(segment
		(start 293.22522 -182.473346)
		(end 293.22522 -182.240174)
		(width 0.127)
		(layer "In5.Cu")
		(net "MEMDQ_4")
	)
	(segment
		(start 292.50386 -201.33564)
		(end 292.50386 -201.310494)
		(width 0.127)
		(layer "In5.Cu")
		(net "MEMDQ_4")
	)
	(segment
		(start 289.70732 -187.01893)
		(end 289.52952 -186.84113)
		(width 0.127)
		(layer "In5.Cu")
		(net "MEMDQ_4")
	)
	(segment
		(start 291.46246 -198.70166)
		(end 289.40633 -196.64553)
		(width 0.127)
		(layer "In5.Cu")
		(net "MEMDQ_4")
	)
	(segment
		(start 292.50386 -201.310494)
		(end 291.46246 -200.269094)
		(width 0.127)
		(layer "In5.Cu")
		(net "MEMDQ_4")
	)
	(segment
		(start 169.309542 -186.163458)
		(end 175.514 -179.959)
		(width 0.1143)
		(layer "F.Cu")
		(net "PMU_PWRBTN_N")
	)
	(segment
		(start 260.35 -166.751)
		(end 260.35 -151.638)
		(width 0.1143)
		(layer "F.Cu")
		(net "PMU_PWRBTN_N")
	)
	(segment
		(start 260.477 -166.878)
		(end 260.35 -166.751)
		(width 0.1143)
		(layer "F.Cu")
		(net "PMU_PWRBTN_N")
	)
	(segment
		(start 242.697 -91.821)
		(end 229.76205 -78.88605)
		(width 0.1143)
		(layer "F.Cu")
		(net "PMU_PWRBTN_N")
	)
	(segment
		(start 250.95835 -137.287)
		(end 248.158 -134.48665)
		(width 0.1143)
		(layer "F.Cu")
		(net "PMU_PWRBTN_N")
	)
	(segment
		(start 248.1453 -118.9863)
		(end 248.1453 -117.491256)
		(width 0.1143)
		(layer "F.Cu")
		(net "PMU_PWRBTN_N")
	)
	(segment
		(start 251.6759 -112.244632)
		(end 251.6759 -109.482128)
		(width 0.1143)
		(layer "F.Cu")
		(net "PMU_PWRBTN_N")
	)
	(segment
		(start 225.552 -79.121)
		(end 215.578436 -79.121)
		(width 0.1143)
		(layer "F.Cu")
		(net "PMU_PWRBTN_N")
	)
	(segment
		(start 171.991782 -219.23375)
		(end 171.280582 -219.94495)
		(width 0.1143)
		(layer "F.Cu")
		(net "PMU_PWRBTN_N")
	)
	(segment
		(start 246.868188 -91.821)
		(end 242.697 -91.821)
		(width 0.1143)
		(layer "F.Cu")
		(net "PMU_PWRBTN_N")
	)
	(segment
		(start 178.16576 -220.32976)
		(end 177.4825 -219.6465)
		(width 0.1143)
		(layer "F.Cu")
		(net "PMU_PWRBTN_N")
	)
	(segment
		(start 225.78695 -78.88605)
		(end 225.552 -79.121)
		(width 0.1143)
		(layer "F.Cu")
		(net "PMU_PWRBTN_N")
	)
	(segment
		(start 169.309542 -218.388184)
		(end 169.309542 -186.163458)
		(width 0.1143)
		(layer "F.Cu")
		(net "PMU_PWRBTN_N")
	)
	(segment
		(start 177.4825 -219.6465)
		(end 177.4825 -219.329)
		(width 0.1143)
		(layer "F.Cu")
		(net "PMU_PWRBTN_N")
	)
	(segment
		(start 176.403 -219.329)
		(end 176.30775 -219.23375)
		(width 0.1143)
		(layer "F.Cu")
		(net "PMU_PWRBTN_N")
	)
	(segment
		(start 248.1453 -117.491256)
		(end 249.495564 -116.140992)
		(width 0.1143)
		(layer "F.Cu")
		(net "PMU_PWRBTN_N")
	)
	(segment
		(start 175.514 -179.959)
		(end 175.514 -178.943)
		(width 0.1143)
		(layer "F.Cu")
		(net "PMU_PWRBTN_N")
	)
	(segment
		(start 176.30775 -219.23375)
		(end 171.991782 -219.23375)
		(width 0.1143)
		(layer "F.Cu")
		(net "PMU_PWRBTN_N")
	)
	(segment
		(start 250.7742 -95.727012)
		(end 246.868188 -91.821)
		(width 0.1143)
		(layer "F.Cu")
		(net "PMU_PWRBTN_N")
	)
	(segment
		(start 250.7742 -108.580428)
		(end 250.7742 -95.727012)
		(width 0.1143)
		(layer "F.Cu")
		(net "PMU_PWRBTN_N")
	)
	(segment
		(start 171.280582 -219.94495)
		(end 170.866308 -219.94495)
		(width 0.1143)
		(layer "F.Cu")
		(net "PMU_PWRBTN_N")
	)
	(segment
		(start 249.495564 -116.140992)
		(end 249.495564 -114.424968)
		(width 0.1143)
		(layer "F.Cu")
		(net "PMU_PWRBTN_N")
	)
	(segment
		(start 215.578436 -79.121)
		(end 214.449406 -80.25003)
		(width 0.1143)
		(layer "F.Cu")
		(net "PMU_PWRBTN_N")
	)
	(segment
		(start 248.158 -118.999)
		(end 248.1453 -118.9863)
		(width 0.1143)
		(layer "F.Cu")
		(net "PMU_PWRBTN_N")
	)
	(segment
		(start 249.495564 -114.424968)
		(end 251.6759 -112.244632)
		(width 0.1143)
		(layer "F.Cu")
		(net "PMU_PWRBTN_N")
	)
	(segment
		(start 250.95835 -142.24635)
		(end 250.95835 -137.287)
		(width 0.1143)
		(layer "F.Cu")
		(net "PMU_PWRBTN_N")
	)
	(segment
		(start 178.16576 -221.0435)
		(end 178.16576 -220.32976)
		(width 0.1143)
		(layer "F.Cu")
		(net "PMU_PWRBTN_N")
	)
	(segment
		(start 229.76205 -78.88605)
		(end 225.78695 -78.88605)
		(width 0.1143)
		(layer "F.Cu")
		(net "PMU_PWRBTN_N")
	)
	(segment
		(start 170.866308 -219.94495)
		(end 169.309542 -218.388184)
		(width 0.1143)
		(layer "F.Cu")
		(net "PMU_PWRBTN_N")
	)
	(segment
		(start 248.158 -134.48665)
		(end 248.158 -118.999)
		(width 0.1143)
		(layer "F.Cu")
		(net "PMU_PWRBTN_N")
	)
	(segment
		(start 251.6759 -109.482128)
		(end 250.7742 -108.580428)
		(width 0.1143)
		(layer "F.Cu")
		(net "PMU_PWRBTN_N")
	)
	(segment
		(start 177.4825 -219.329)
		(end 176.403 -219.329)
		(width 0.1143)
		(layer "F.Cu")
		(net "PMU_PWRBTN_N")
	)
	(segment
		(start 260.35 -151.638)
		(end 250.95835 -142.24635)
		(width 0.1143)
		(layer "F.Cu")
		(net "PMU_PWRBTN_N")
	)
	(via
		(at 260.477 -166.878)
		(size 0.5588)
		(drill 0.3048)
		(layers "F.Cu" "B.Cu")
		(net "PMU_PWRBTN_N")
	)
	(via
		(at 263.398 -186.436)
		(size 0.5588)
		(drill 0.3048)
		(layers "F.Cu" "B.Cu")
		(net "PMU_PWRBTN_N")
	)
	(via
		(at 175.514 -178.943)
		(size 0.5588)
		(drill 0.3048)
		(layers "F.Cu" "B.Cu")
		(net "PMU_PWRBTN_N")
	)
	(segment
		(start 207.842866 -174.8917)
		(end 202.915266 -179.8193)
		(width 0.127)
		(layer "In2.Cu")
		(net "PMU_PWRBTN_N")
	)
	(segment
		(start 263.398 -186.436)
		(end 263.271 -186.436)
		(width 0.127)
		(layer "In2.Cu")
		(net "PMU_PWRBTN_N")
	)
	(segment
		(start 263.271 -186.436)
		(end 252.3998 -175.5648)
		(width 0.127)
		(layer "In2.Cu")
		(net "PMU_PWRBTN_N")
	)
	(segment
		(start 202.915266 -179.8193)
		(end 200.1393 -179.8193)
		(width 0.127)
		(layer "In2.Cu")
		(net "PMU_PWRBTN_N")
	)
	(segment
		(start 229.517702 -175.5648)
		(end 228.844602 -174.8917)
		(width 0.127)
		(layer "In2.Cu")
		(net "PMU_PWRBTN_N")
	)
	(segment
		(start 198.882 -178.562)
		(end 175.895 -178.562)
		(width 0.127)
		(layer "In2.Cu")
		(net "PMU_PWRBTN_N")
	)
	(segment
		(start 175.895 -178.562)
		(end 175.514 -178.943)
		(width 0.127)
		(layer "In2.Cu")
		(net "PMU_PWRBTN_N")
	)
	(segment
		(start 228.844602 -174.8917)
		(end 207.842866 -174.8917)
		(width 0.127)
		(layer "In2.Cu")
		(net "PMU_PWRBTN_N")
	)
	(segment
		(start 200.1393 -179.8193)
		(end 198.882 -178.562)
		(width 0.127)
		(layer "In2.Cu")
		(net "PMU_PWRBTN_N")
	)
	(segment
		(start 252.3998 -175.5648)
		(end 229.517702 -175.5648)
		(width 0.127)
		(layer "In2.Cu")
		(net "PMU_PWRBTN_N")
	)
	(segment
		(start 262.3693 -168.7703)
		(end 260.477 -166.878)
		(width 0.127)
		(layer "In5.Cu")
		(net "PMU_PWRBTN_N")
	)
	(segment
		(start 263.398 -186.436)
		(end 262.3693 -185.4073)
		(width 0.127)
		(layer "In5.Cu")
		(net "PMU_PWRBTN_N")
	)
	(segment
		(start 262.3693 -185.4073)
		(end 262.3693 -168.7703)
		(width 0.127)
		(layer "In5.Cu")
		(net "PMU_PWRBTN_N")
	)
	(segment
		(start 331.5335 -80.391)
		(end 329.946 -80.391)
		(width 0.1143)
		(layer "F.Cu")
		(net "AS_ROMA0_R")
	)
	(segment
		(start 329.946 -80.391)
		(end 329.184 -81.153)
		(width 0.1143)
		(layer "F.Cu")
		(net "AS_ROMA0_R")
	)
	(segment
		(start 277.882096 -170.186096)
		(end 281.683206 -173.987206)
		(width 0.1143)
		(layer "F.Cu")
		(net "BMC0_SMB1_DAT")
	)
	(segment
		(start 277.7744 -170.186096)
		(end 277.882096 -170.186096)
		(width 0.1143)
		(layer "F.Cu")
		(net "BMC0_SMB1_DAT")
	)
	(segment
		(start 275.012404 -170.186096)
		(end 277.7744 -170.186096)
		(width 0.1143)
		(layer "F.Cu")
		(net "BMC0_SMB1_DAT")
	)
	(segment
		(start 274.6375 -170.561)
		(end 275.012404 -170.186096)
		(width 0.1143)
		(layer "F.Cu")
		(net "BMC0_SMB1_DAT")
	)
	(segment
		(start 284.43174 -174.64024)
		(end 284.834838 -174.64024)
		(width 0.1143)
		(layer "F.Cu")
		(net "BMC0_SMB1_DAT")
	)
	(segment
		(start 283.775658 -174.355506)
		(end 284.147006 -174.355506)
		(width 0.1143)
		(layer "F.Cu")
		(net "BMC0_SMB1_DAT")
	)
	(segment
		(start 283.407358 -173.987206)
		(end 283.775658 -174.355506)
		(width 0.1143)
		(layer "F.Cu")
		(net "BMC0_SMB1_DAT")
	)
	(segment
		(start 284.147006 -174.355506)
		(end 284.43174 -174.64024)
		(width 0.1143)
		(layer "F.Cu")
		(net "BMC0_SMB1_DAT")
	)
	(segment
		(start 281.683206 -173.987206)
		(end 283.407358 -173.987206)
		(width 0.1143)
		(layer "F.Cu")
		(net "BMC0_SMB1_DAT")
	)
	(via
		(at 277.7744 -170.186096)
		(size 0.7112)
		(drill 0.3556)
		(layers "F.Cu" "B.Cu")
		(net "BMC0_SMB1_DAT")
	)
	(segment
		(start 216.29497 -69.5325)
		(end 216.29497 -73.595484)
		(width 0.1143)
		(layer "F.Cu")
		(net "SVR_ID1")
	)
	(segment
		(start 217.43797 -69.5325)
		(end 216.29497 -69.5325)
		(width 0.1143)
		(layer "F.Cu")
		(net "SVR_ID1")
	)
	(segment
		(start 216.29497 -73.595484)
		(end 216.449656 -73.75017)
		(width 0.1143)
		(layer "F.Cu")
		(net "SVR_ID1")
	)
	(segment
		(start 289.698176 -195.362576)
		(end 289.48253 -195.14693)
		(width 0.1143)
		(layer "F.Cu")
		(net "MEMCKE")
	)
	(segment
		(start 289.051238 -195.14693)
		(end 288.8996 -195.298568)
		(width 0.1143)
		(layer "F.Cu")
		(net "MEMCKE")
	)
	(segment
		(start 292.481 -183.007)
		(end 292.481 -184.3532)
		(width 0.1143)
		(layer "F.Cu")
		(net "MEMCKE")
	)
	(segment
		(start 288.8996 -195.298568)
		(end 288.8996 -195.624704)
		(width 0.1143)
		(layer "F.Cu")
		(net "MEMCKE")
	)
	(segment
		(start 289.2552 -197.09003)
		(end 289.2552 -197.301866)
		(width 0.1143)
		(layer "F.Cu")
		(net "MEMCKE")
	)
	(segment
		(start 289.260026 -197.085204)
		(end 289.2552 -197.09003)
		(width 0.1143)
		(layer "F.Cu")
		(net "MEMCKE")
	)
	(segment
		(start 289.48253 -195.14693)
		(end 289.051238 -195.14693)
		(width 0.1143)
		(layer "F.Cu")
		(net "MEMCKE")
	)
	(segment
		(start 289.260026 -195.98513)
		(end 289.260026 -197.085204)
		(width 0.1143)
		(layer "F.Cu")
		(net "MEMCKE")
	)
	(segment
		(start 292.834822 -182.653178)
		(end 292.481 -183.007)
		(width 0.1143)
		(layer "F.Cu")
		(net "MEMCKE")
	)
	(segment
		(start 292.481 -184.3532)
		(end 291.4396 -185.3946)
		(width 0.1143)
		(layer "F.Cu")
		(net "MEMCKE")
	)
	(segment
		(start 289.698176 -196.135244)
		(end 289.698176 -195.362576)
		(width 0.1143)
		(layer "F.Cu")
		(net "MEMCKE")
	)
	(segment
		(start 289.2552 -197.301866)
		(end 289.296094 -197.34276)
		(width 0.1143)
		(layer "F.Cu")
		(net "MEMCKE")
	)
	(segment
		(start 288.8996 -195.624704)
		(end 289.260026 -195.98513)
		(width 0.1143)
		(layer "F.Cu")
		(net "MEMCKE")
	)
	(segment
		(start 292.834822 -182.640224)
		(end 292.834822 -182.653178)
		(width 0.1143)
		(layer "F.Cu")
		(net "MEMCKE")
	)
	(via
		(at 290.59505 -187.80125)
		(size 0.7112)
		(drill 0.3556)
		(layers "F.Cu" "B.Cu")
		(net "MEMCKE")
	)
	(via
		(at 291.4396 -185.3946)
		(size 0.5588)
		(drill 0.3048)
		(layers "F.Cu" "B.Cu")
		(net "MEMCKE")
	)
	(via
		(at 289.296094 -197.34276)
		(size 0.508)
		(drill 0.254)
		(layers "F.Cu" "B.Cu")
		(net "MEMCKE")
	)
	(segment
		(start 289.9664 -195.8848)
		(end 289.0012 -196.85)
		(width 0.1143)
		(layer "B.Cu")
		(net "MEMCKE")
	)
	(segment
		(start 290.957 -190.585598)
		(end 290.957 -190.839598)
		(width 0.1143)
		(layer "B.Cu")
		(net "MEMCKE")
	)
	(segment
		(start 290.957 -189.925198)
		(end 291.1602 -190.128398)
		(width 0.1143)
		(layer "B.Cu")
		(net "MEMCKE")
	)
	(segment
		(start 291.1602 -192.871598)
		(end 291.1602 -193.125598)
		(width 0.1143)
		(layer "B.Cu")
		(net "MEMCKE")
	)
	(segment
		(start 291.1602 -190.382398)
		(end 290.957 -190.585598)
		(width 0.1143)
		(layer "B.Cu")
		(net "MEMCKE")
	)
	(segment
		(start 291.1602 -191.042798)
		(end 291.1602 -191.296798)
		(width 0.1143)
		(layer "B.Cu")
		(net "MEMCKE")
	)
	(segment
		(start 291.1602 -191.296798)
		(end 290.957 -191.499998)
		(width 0.1143)
		(layer "B.Cu")
		(net "MEMCKE")
	)
	(segment
		(start 290.80206 -193.902838)
		(end 290.80206 -193.90614)
		(width 0.1143)
		(layer "B.Cu")
		(net "MEMCKE")
	)
	(segment
		(start 290.957 -192.414398)
		(end 290.957 -192.668398)
		(width 0.1143)
		(layer "B.Cu")
		(net "MEMCKE")
	)
	(segment
		(start 290.957 -189.671198)
		(end 290.957 -189.925198)
		(width 0.1143)
		(layer "B.Cu")
		(net "MEMCKE")
	)
	(segment
		(start 291.1602 -191.957198)
		(end 291.1602 -192.211198)
		(width 0.1143)
		(layer "B.Cu")
		(net "MEMCKE")
	)
	(segment
		(start 290.59505 -188.068458)
		(end 290.957 -188.430408)
		(width 0.1143)
		(layer "B.Cu")
		(net "MEMCKE")
	)
	(segment
		(start 291.4396 -185.3946)
		(end 290.59505 -186.23915)
		(width 0.1143)
		(layer "B.Cu")
		(net "MEMCKE")
	)
	(segment
		(start 291.1602 -192.211198)
		(end 290.957 -192.414398)
		(width 0.1143)
		(layer "B.Cu")
		(net "MEMCKE")
	)
	(segment
		(start 290.957 -188.430408)
		(end 290.957 -189.010798)
		(width 0.1143)
		(layer "B.Cu")
		(net "MEMCKE")
	)
	(segment
		(start 290.54425 -186.557412)
		(end 290.54425 -187.025788)
		(width 0.1143)
		(layer "B.Cu")
		(net "MEMCKE")
	)
	(segment
		(start 290.957 -192.668398)
		(end 291.1602 -192.871598)
		(width 0.1143)
		(layer "B.Cu")
		(net "MEMCKE")
	)
	(segment
		(start 291.1602 -189.213998)
		(end 291.1602 -189.467998)
		(width 0.1143)
		(layer "B.Cu")
		(net "MEMCKE")
	)
	(segment
		(start 289.9664 -194.7418)
		(end 289.9664 -195.8848)
		(width 0.1143)
		(layer "B.Cu")
		(net "MEMCKE")
	)
	(segment
		(start 291.1602 -193.125598)
		(end 290.957 -193.328798)
		(width 0.1143)
		(layer "B.Cu")
		(net "MEMCKE")
	)
	(segment
		(start 289.2044 -197.34276)
		(end 289.296094 -197.34276)
		(width 0.1143)
		(layer "B.Cu")
		(net "MEMCKE")
	)
	(segment
		(start 290.80206 -193.90614)
		(end 289.9664 -194.7418)
		(width 0.1143)
		(layer "B.Cu")
		(net "MEMCKE")
	)
	(segment
		(start 290.59505 -186.506612)
		(end 290.54425 -186.557412)
		(width 0.1143)
		(layer "B.Cu")
		(net "MEMCKE")
	)
	(segment
		(start 290.957 -190.839598)
		(end 291.1602 -191.042798)
		(width 0.1143)
		(layer "B.Cu")
		(net "MEMCKE")
	)
	(segment
		(start 289.0012 -196.85)
		(end 289.0012 -197.13956)
		(width 0.1143)
		(layer "B.Cu")
		(net "MEMCKE")
	)
	(segment
		(start 290.957 -189.010798)
		(end 291.1602 -189.213998)
		(width 0.1143)
		(layer "B.Cu")
		(net "MEMCKE")
	)
	(segment
		(start 290.54425 -187.025788)
		(end 290.59505 -187.076588)
		(width 0.1143)
		(layer "B.Cu")
		(net "MEMCKE")
	)
	(segment
		(start 290.957 -193.747898)
		(end 290.80206 -193.902838)
		(width 0.1143)
		(layer "B.Cu")
		(net "MEMCKE")
	)
	(segment
		(start 289.0012 -197.13956)
		(end 289.2044 -197.34276)
		(width 0.1143)
		(layer "B.Cu")
		(net "MEMCKE")
	)
	(segment
		(start 290.59505 -187.076588)
		(end 290.59505 -187.80125)
		(width 0.1143)
		(layer "B.Cu")
		(net "MEMCKE")
	)
	(segment
		(start 290.59505 -186.23915)
		(end 290.59505 -186.506612)
		(width 0.1143)
		(layer "B.Cu")
		(net "MEMCKE")
	)
	(segment
		(start 290.59505 -187.80125)
		(end 290.59505 -188.068458)
		(width 0.1143)
		(layer "B.Cu")
		(net "MEMCKE")
	)
	(segment
		(start 290.957 -191.753998)
		(end 291.1602 -191.957198)
		(width 0.1143)
		(layer "B.Cu")
		(net "MEMCKE")
	)
	(segment
		(start 291.1602 -190.128398)
		(end 291.1602 -190.382398)
		(width 0.1143)
		(layer "B.Cu")
		(net "MEMCKE")
	)
	(segment
		(start 291.1602 -189.467998)
		(end 290.957 -189.671198)
		(width 0.1143)
		(layer "B.Cu")
		(net "MEMCKE")
	)
	(segment
		(start 290.957 -191.499998)
		(end 290.957 -191.753998)
		(width 0.1143)
		(layer "B.Cu")
		(net "MEMCKE")
	)
	(segment
		(start 290.957 -193.328798)
		(end 290.957 -193.747898)
		(width 0.1143)
		(layer "B.Cu")
		(net "MEMCKE")
	)
	(segment
		(start 215.15197 -69.5325)
		(end 214.00897 -69.5325)
		(width 0.1143)
		(layer "F.Cu")
		(net "SVR_ID3")
	)
	(segment
		(start 212.86597 -70.6755)
		(end 212.86597 -73.334626)
		(width 0.1143)
		(layer "F.Cu")
		(net "SVR_ID3")
	)
	(segment
		(start 214.00897 -69.5325)
		(end 212.86597 -70.6755)
		(width 0.1143)
		(layer "F.Cu")
		(net "SVR_ID3")
	)
	(segment
		(start 212.86597 -73.334626)
		(end 212.450426 -73.75017)
		(width 0.1143)
		(layer "F.Cu")
		(net "SVR_ID3")
	)
	(segment
		(start 181.565804 -26.543)
		(end 181.114192 -26.091388)
		(width 0.1778)
		(layer "F.Cu")
		(net "PHY_F100")
	)
	(segment
		(start 179.505864 -22.995636)
		(end 179.505864 -23.105872)
		(width 0.1778)
		(layer "F.Cu")
		(net "PHY_F100")
	)
	(segment
		(start 181.114192 -26.091388)
		(end 181.114192 -24.7142)
		(width 0.1778)
		(layer "F.Cu")
		(net "PHY_F100")
	)
	(segment
		(start 181.565804 -27.377136)
		(end 181.565804 -26.543)
		(width 0.1778)
		(layer "F.Cu")
		(net "PHY_F100")
	)
	(segment
		(start 181.114192 -24.7142)
		(end 180.301392 -23.9014)
		(width 0.1778)
		(layer "F.Cu")
		(net "PHY_F100")
	)
	(segment
		(start 179.505864 -23.105872)
		(end 180.301392 -23.9014)
		(width 0.1778)
		(layer "F.Cu")
		(net "PHY_F100")
	)
	(via
		(at 180.301392 -23.9014)
		(size 0.7112)
		(drill 0.3556)
		(layers "F.Cu" "B.Cu")
		(net "PHY_F100")
	)
	(segment
		(start 288.8234 -197.809866)
		(end 288.8234 -198.444612)
		(width 0.1143)
		(layer "F.Cu")
		(net "MEMA_10")
	)
	(segment
		(start 290.04768 -183.02732)
		(end 290.04768 -183.036718)
		(width 0.1143)
		(layer "F.Cu")
		(net "MEMA_10")
	)
	(segment
		(start 288.8234 -198.444612)
		(end 288.603944 -198.664068)
		(width 0.1143)
		(layer "F.Cu")
		(net "MEMA_10")
	)
	(segment
		(start 290.434776 -182.640224)
		(end 290.04768 -183.02732)
		(width 0.1143)
		(layer "F.Cu")
		(net "MEMA_10")
	)
	(segment
		(start 288.898076 -197.73519)
		(end 288.8234 -197.809866)
		(width 0.1143)
		(layer "F.Cu")
		(net "MEMA_10")
	)
	(segment
		(start 290.04768 -183.036718)
		(end 290.043616 -183.040782)
		(width 0.1143)
		(layer "F.Cu")
		(net "MEMA_10")
	)
	(via
		(at 288.603944 -198.664068)
		(size 0.508)
		(drill 0.254)
		(layers "F.Cu" "B.Cu")
		(net "MEMA_10")
	)
	(via
		(at 290.273994 -185.6994)
		(size 0.7112)
		(drill 0.3556)
		(layers "F.Cu" "B.Cu")
		(net "MEMA_10")
	)
	(via
		(at 290.043616 -183.040782)
		(size 0.508)
		(drill 0.254)
		(layers "F.Cu" "B.Cu")
		(net "MEMA_10")
	)
	(segment
		(start 290.17595 -186.944762)
		(end 290.0299 -187.090812)
		(width 0.1143)
		(layer "B.Cu")
		(net "MEMA_10")
	)
	(segment
		(start 290.388294 -184.741058)
		(end 290.88715 -184.741058)
		(width 0.1143)
		(layer "B.Cu")
		(net "MEMA_10")
	)
	(segment
		(start 290.0299 -187.090812)
		(end 290.0299 -188.096144)
		(width 0.1143)
		(layer "B.Cu")
		(net "MEMA_10")
	)
	(segment
		(start 290.212526 -193.902838)
		(end 290.212526 -193.99631)
		(width 0.1143)
		(layer "B.Cu")
		(net "MEMA_10")
	)
	(segment
		(start 290.273994 -186.103006)
		(end 290.17595 -186.20105)
		(width 0.1143)
		(layer "B.Cu")
		(net "MEMA_10")
	)
	(segment
		(start 290.88715 -184.283858)
		(end 290.388294 -184.283858)
		(width 0.1143)
		(layer "B.Cu")
		(net "MEMA_10")
	)
	(segment
		(start 290.88715 -183.826658)
		(end 291.00145 -183.940958)
		(width 0.1143)
		(layer "B.Cu")
		(net "MEMA_10")
	)
	(segment
		(start 290.388294 -183.826658)
		(end 290.88715 -183.826658)
		(width 0.1143)
		(layer "B.Cu")
		(net "MEMA_10")
	)
	(segment
		(start 290.88715 -184.741058)
		(end 291.00145 -184.855358)
		(width 0.1143)
		(layer "B.Cu")
		(net "MEMA_10")
	)
	(segment
		(start 291.00145 -185.083958)
		(end 290.88715 -185.198258)
		(width 0.1143)
		(layer "B.Cu")
		(net "MEMA_10")
	)
	(segment
		(start 290.212526 -193.99631)
		(end 289.687 -194.521836)
		(width 0.1143)
		(layer "B.Cu")
		(net "MEMA_10")
	)
	(segment
		(start 290.526724 -193.585338)
		(end 290.38296 -193.729102)
		(width 0.1143)
		(layer "B.Cu")
		(net "MEMA_10")
	)
	(segment
		(start 290.273994 -185.312558)
		(end 290.273994 -185.6994)
		(width 0.1143)
		(layer "B.Cu")
		(net "MEMA_10")
	)
	(segment
		(start 290.388294 -184.283858)
		(end 290.273994 -184.398158)
		(width 0.1143)
		(layer "B.Cu")
		(net "MEMA_10")
	)
	(segment
		(start 291.00145 -183.940958)
		(end 291.00145 -184.169558)
		(width 0.1143)
		(layer "B.Cu")
		(net "MEMA_10")
	)
	(segment
		(start 290.38296 -193.732404)
		(end 290.212526 -193.902838)
		(width 0.1143)
		(layer "B.Cu")
		(net "MEMA_10")
	)
	(segment
		(start 288.6964 -196.807328)
		(end 288.6964 -198.571612)
		(width 0.1143)
		(layer "B.Cu")
		(net "MEMA_10")
	)
	(segment
		(start 288.6964 -198.571612)
		(end 288.603944 -198.664068)
		(width 0.1143)
		(layer "B.Cu")
		(net "MEMA_10")
	)
	(segment
		(start 290.273994 -184.398158)
		(end 290.273994 -184.626758)
		(width 0.1143)
		(layer "B.Cu")
		(net "MEMA_10")
	)
	(segment
		(start 290.388294 -185.198258)
		(end 290.273994 -185.312558)
		(width 0.1143)
		(layer "B.Cu")
		(net "MEMA_10")
	)
	(segment
		(start 290.17595 -186.20105)
		(end 290.17595 -186.944762)
		(width 0.1143)
		(layer "B.Cu")
		(net "MEMA_10")
	)
	(segment
		(start 290.526724 -188.592968)
		(end 290.526724 -193.585338)
		(width 0.1143)
		(layer "B.Cu")
		(net "MEMA_10")
	)
	(segment
		(start 290.273994 -185.6994)
		(end 290.273994 -186.103006)
		(width 0.1143)
		(layer "B.Cu")
		(net "MEMA_10")
	)
	(segment
		(start 290.273994 -183.27116)
		(end 290.273994 -183.712358)
		(width 0.1143)
		(layer "B.Cu")
		(net "MEMA_10")
	)
	(segment
		(start 291.00145 -184.855358)
		(end 291.00145 -185.083958)
		(width 0.1143)
		(layer "B.Cu")
		(net "MEMA_10")
	)
	(segment
		(start 290.273994 -184.626758)
		(end 290.388294 -184.741058)
		(width 0.1143)
		(layer "B.Cu")
		(net "MEMA_10")
	)
	(segment
		(start 290.273994 -183.712358)
		(end 290.388294 -183.826658)
		(width 0.1143)
		(layer "B.Cu")
		(net "MEMA_10")
	)
	(segment
		(start 290.043616 -183.040782)
		(end 290.273994 -183.27116)
		(width 0.1143)
		(layer "B.Cu")
		(net "MEMA_10")
	)
	(segment
		(start 290.38296 -193.729102)
		(end 290.38296 -193.732404)
		(width 0.1143)
		(layer "B.Cu")
		(net "MEMA_10")
	)
	(segment
		(start 291.00145 -184.169558)
		(end 290.88715 -184.283858)
		(width 0.1143)
		(layer "B.Cu")
		(net "MEMA_10")
	)
	(segment
		(start 290.0299 -188.096144)
		(end 290.526724 -188.592968)
		(width 0.1143)
		(layer "B.Cu")
		(net "MEMA_10")
	)
	(segment
		(start 289.687 -195.816728)
		(end 288.6964 -196.807328)
		(width 0.1143)
		(layer "B.Cu")
		(net "MEMA_10")
	)
	(segment
		(start 290.88715 -185.198258)
		(end 290.388294 -185.198258)
		(width 0.1143)
		(layer "B.Cu")
		(net "MEMA_10")
	)
	(segment
		(start 289.687 -194.521836)
		(end 289.687 -195.816728)
		(width 0.1143)
		(layer "B.Cu")
		(net "MEMA_10")
	)
	(segment
		(start 188.105796 -28.556204)
		(end 186.744864 -28.556204)
		(width 0.127)
		(layer "F.Cu")
		(net "NC_PHY_RXC")
	)
	(segment
		(start 189.611 -26.67)
		(end 189.611 -27.051)
		(width 0.127)
		(layer "F.Cu")
		(net "NC_PHY_RXC")
	)
	(segment
		(start 189.611 -27.051)
		(end 188.105796 -28.556204)
		(width 0.127)
		(layer "F.Cu")
		(net "NC_PHY_RXC")
	)
	(segment
		(start 289.983164 -171.09186)
		(end 289.9664 -171.09186)
		(width 0.1143)
		(layer "F.Cu")
		(net "BMC0_TP15")
	)
	(segment
		(start 290.434776 -170.640248)
		(end 289.983164 -171.09186)
		(width 0.1143)
		(layer "F.Cu")
		(net "BMC0_TP15")
	)
	(via
		(at 289.9664 -171.09186)
		(size 0.508)
		(drill 0.254)
		(layers "F.Cu" "B.Cu")
		(net "BMC0_TP15")
	)
	(segment
		(start 290.9316 -170.9674)
		(end 290.09086 -170.9674)
		(width 0.1143)
		(layer "B.Cu")
		(net "BMC0_TP15")
	)
	(segment
		(start 290.09086 -170.9674)
		(end 289.9664 -171.09186)
		(width 0.1143)
		(layer "B.Cu")
		(net "BMC0_TP15")
	)
	(segment
		(start 19.19986 -99.980242)
		(end 19.19986 -98.848164)
		(width 0.1016)
		(layer "F.Cu")
		(net "SAS_EXT_CONN_RX19_N")
	)
	(via
		(at 19.325082 -98.545904)
		(size 0.5588)
		(drill 0.3048)
		(layers "F.Cu" "B.Cu")
		(net "SAS_EXT_CONN_RX19_N")
	)
	(arc
		(start 19.19986 -98.848164)
		(mid 19.2324 -98.684574)
		(end 19.325082 -98.545904)
		(width 0.1016)
		(layer "F.Cu")
		(net "SAS_EXT_CONN_RX19_N")
	)
	(segment
		(start 19.170904 -99.956366)
		(end 19.170904 -98.918014)
		(width 0.1016)
		(layer "B.Cu")
		(net "SAS_EXT_CONN_RX19_N")
	)
	(arc
		(start 19.170904 -98.918014)
		(mid 19.210965 -98.716612)
		(end 19.325082 -98.545904)
		(width 0.1016)
		(layer "B.Cu")
		(net "SAS_EXT_CONN_RX19_N")
	)
	(segment
		(start 188.971428 -30.5562)
		(end 186.744864 -30.5562)
		(width 0.3048)
		(layer "F.Cu")
		(net "PHY_DVDD")
	)
	(segment
		(start 190.673228 -31.369)
		(end 191.832992 -31.369)
		(width 0.508)
		(layer "F.Cu")
		(net "PHY_DVDD")
	)
	(segment
		(start 190.554864 -31.250636)
		(end 190.673228 -31.369)
		(width 0.508)
		(layer "F.Cu")
		(net "PHY_DVDD")
	)
	(segment
		(start 189.665864 -31.250636)
		(end 190.554864 -31.250636)
		(width 0.508)
		(layer "F.Cu")
		(net "PHY_DVDD")
	)
	(segment
		(start 192.975992 -31.369)
		(end 191.832992 -31.369)
		(width 0.508)
		(layer "F.Cu")
		(net "PHY_DVDD")
	)
	(segment
		(start 189.665864 -31.250636)
		(end 188.971428 -30.5562)
		(width 0.3048)
		(layer "F.Cu")
		(net "PHY_DVDD")
	)
	(via
		(at 191.832992 -31.369)
		(size 0.7112)
		(drill 0.3556)
		(layers "F.Cu" "B.Cu")
		(net "PHY_DVDD")
	)
	(segment
		(start 13.60043 -99.980242)
		(end 13.60043 -98.6917)
		(width 0.1016)
		(layer "F.Cu")
		(net "SAS_EXT_CONN_RX17_P")
	)
	(via
		(at 13.508482 -98.469704)
		(size 0.5588)
		(drill 0.3048)
		(layers "F.Cu" "B.Cu")
		(net "SAS_EXT_CONN_RX17_P")
	)
	(arc
		(start 13.60043 -98.6917)
		(mid 13.576532 -98.571559)
		(end 13.508482 -98.469704)
		(width 0.1016)
		(layer "F.Cu")
		(net "SAS_EXT_CONN_RX17_P")
	)
	(segment
		(start 13.582904 -99.956366)
		(end 13.582904 -98.649282)
		(width 0.1016)
		(layer "B.Cu")
		(net "SAS_EXT_CONN_RX17_P")
	)
	(arc
		(start 13.582904 -98.649282)
		(mid 13.563569 -98.55208)
		(end 13.508482 -98.469704)
		(width 0.1016)
		(layer "B.Cu")
		(net "SAS_EXT_CONN_RX17_P")
	)
	(segment
		(start 150.982934 -232.664)
		(end 150.982934 -169.743628)
		(width 0.1143)
		(layer "F.Cu")
		(net "FCB_HW_REVISION")
	)
	(segment
		(start 89.525602 -136.398)
		(end 89.42197 -136.294368)
		(width 0.1143)
		(layer "F.Cu")
		(net "FCB_HW_REVISION")
	)
	(segment
		(start 150.000462 -233.646472)
		(end 150.982934 -232.664)
		(width 0.1143)
		(layer "F.Cu")
		(net "FCB_HW_REVISION")
	)
	(segment
		(start 89.54897 -135.128)
		(end 91.068906 -135.128)
		(width 0.1143)
		(layer "F.Cu")
		(net "FCB_HW_REVISION")
	)
	(segment
		(start 91.068906 -135.128)
		(end 91.134438 -135.193532)
		(width 0.1143)
		(layer "F.Cu")
		(net "FCB_HW_REVISION")
	)
	(segment
		(start 286.835088 -171.03979)
		(end 286.835088 -171.0309)
		(width 0.1143)
		(layer "F.Cu")
		(net "FCB_HW_REVISION")
	)
	(segment
		(start 150.982934 -169.743628)
		(end 142.113 -160.873694)
		(width 0.1143)
		(layer "F.Cu")
		(net "FCB_HW_REVISION")
	)
	(segment
		(start 142.113 -160.873694)
		(end 142.113 -153.543)
		(width 0.1143)
		(layer "F.Cu")
		(net "FCB_HW_REVISION")
	)
	(segment
		(start 150.000462 -256.25044)
		(end 150.000462 -233.646472)
		(width 0.1143)
		(layer "F.Cu")
		(net "FCB_HW_REVISION")
	)
	(segment
		(start 264.14095 -161.078418)
		(end 264.14095 -162.03295)
		(width 0.1143)
		(layer "F.Cu")
		(net "FCB_HW_REVISION")
	)
	(segment
		(start 89.525602 -137.209276)
		(end 89.525602 -136.398)
		(width 0.1143)
		(layer "F.Cu")
		(net "FCB_HW_REVISION")
	)
	(segment
		(start 89.42197 -135.255)
		(end 89.54897 -135.128)
		(width 0.1143)
		(layer "F.Cu")
		(net "FCB_HW_REVISION")
	)
	(segment
		(start 286.434784 -171.440094)
		(end 286.835088 -171.03979)
		(width 0.1143)
		(layer "F.Cu")
		(net "FCB_HW_REVISION")
	)
	(segment
		(start 264.14095 -162.03295)
		(end 265.684 -163.576)
		(width 0.1143)
		(layer "F.Cu")
		(net "FCB_HW_REVISION")
	)
	(segment
		(start 262.89 -151.003)
		(end 262.89 -159.827468)
		(width 0.1143)
		(layer "F.Cu")
		(net "FCB_HW_REVISION")
	)
	(segment
		(start 89.42197 -136.294368)
		(end 89.42197 -135.255)
		(width 0.1143)
		(layer "F.Cu")
		(net "FCB_HW_REVISION")
	)
	(segment
		(start 262.89 -159.827468)
		(end 264.14095 -161.078418)
		(width 0.1143)
		(layer "F.Cu")
		(net "FCB_HW_REVISION")
	)
	(via
		(at 286.835088 -171.0309)
		(size 0.508)
		(drill 0.254)
		(layers "F.Cu" "B.Cu")
		(net "FCB_HW_REVISION")
	)
	(via
		(at 265.684 -163.576)
		(size 0.5588)
		(drill 0.3048)
		(layers "F.Cu" "B.Cu")
		(net "FCB_HW_REVISION")
	)
	(via
		(at 91.134438 -135.193532)
		(size 0.5588)
		(drill 0.3048)
		(layers "F.Cu" "B.Cu")
		(net "FCB_HW_REVISION")
	)
	(via
		(at 142.113 -153.543)
		(size 0.5588)
		(drill 0.3048)
		(layers "F.Cu" "B.Cu")
		(net "FCB_HW_REVISION")
	)
	(via
		(at 262.89 -151.003)
		(size 0.5588)
		(drill 0.3048)
		(layers "F.Cu" "B.Cu")
		(net "FCB_HW_REVISION")
	)
	(via
		(at 271.272 -163.913566)
		(size 0.7112)
		(drill 0.3556)
		(layers "F.Cu" "B.Cu")
		(net "FCB_HW_REVISION")
	)
	(segment
		(start 271.272 -163.913566)
		(end 266.021566 -163.913566)
		(width 0.1143)
		(layer "B.Cu")
		(net "FCB_HW_REVISION")
	)
	(segment
		(start 277.16861 -163.89985)
		(end 276.035516 -163.89985)
		(width 0.1143)
		(layer "B.Cu")
		(net "FCB_HW_REVISION")
	)
	(segment
		(start 286.835088 -171.0309)
		(end 286.660336 -171.0309)
		(width 0.1143)
		(layer "B.Cu")
		(net "FCB_HW_REVISION")
	)
	(segment
		(start 286.660336 -171.0309)
		(end 286.559752 -170.930316)
		(width 0.1143)
		(layer "B.Cu")
		(net "FCB_HW_REVISION")
	)
	(segment
		(start 266.021566 -163.913566)
		(end 265.684 -163.576)
		(width 0.1143)
		(layer "B.Cu")
		(net "FCB_HW_REVISION")
	)
	(segment
		(start 286.559752 -170.930316)
		(end 284.199076 -170.930316)
		(width 0.1143)
		(layer "B.Cu")
		(net "FCB_HW_REVISION")
	)
	(segment
		(start 284.199076 -170.930316)
		(end 277.16861 -163.89985)
		(width 0.1143)
		(layer "B.Cu")
		(net "FCB_HW_REVISION")
	)
	(segment
		(start 276.035516 -163.89985)
		(end 276.0218 -163.913566)
		(width 0.1143)
		(layer "B.Cu")
		(net "FCB_HW_REVISION")
	)
	(segment
		(start 276.0218 -163.913566)
		(end 271.272 -163.913566)
		(width 0.1143)
		(layer "B.Cu")
		(net "FCB_HW_REVISION")
	)
	(segment
		(start 170.434 -152.5143)
		(end 211.279232 -152.5143)
		(width 0.127)
		(layer "In2.Cu")
		(net "FCB_HW_REVISION")
	)
	(segment
		(start 91.50477 -135.563864)
		(end 91.134438 -135.193532)
		(width 0.127)
		(layer "In2.Cu")
		(net "FCB_HW_REVISION")
	)
	(segment
		(start 92.837 -137.859262)
		(end 91.50477 -136.527032)
		(width 0.127)
		(layer "In2.Cu")
		(net "FCB_HW_REVISION")
	)
	(segment
		(start 127.386588 -153.2636)
		(end 109.3216 -153.2636)
		(width 0.127)
		(layer "In2.Cu")
		(net "FCB_HW_REVISION")
	)
	(segment
		(start 109.3216 -153.2636)
		(end 95.123 -139.065)
		(width 0.127)
		(layer "In2.Cu")
		(net "FCB_HW_REVISION")
	)
	(segment
		(start 92.837 -138.811)
		(end 92.837 -137.859262)
		(width 0.127)
		(layer "In2.Cu")
		(net "FCB_HW_REVISION")
	)
	(segment
		(start 128.504188 -154.3812)
		(end 127.386588 -153.2636)
		(width 0.127)
		(layer "In2.Cu")
		(net "FCB_HW_REVISION")
	)
	(segment
		(start 212.790532 -151.003)
		(end 262.89 -151.003)
		(width 0.127)
		(layer "In2.Cu")
		(net "FCB_HW_REVISION")
	)
	(segment
		(start 95.123 -139.065)
		(end 93.091 -139.065)
		(width 0.127)
		(layer "In2.Cu")
		(net "FCB_HW_REVISION")
	)
	(segment
		(start 169.6847 -153.2636)
		(end 170.434 -152.5143)
		(width 0.127)
		(layer "In2.Cu")
		(net "FCB_HW_REVISION")
	)
	(segment
		(start 93.091 -139.065)
		(end 92.837 -138.811)
		(width 0.127)
		(layer "In2.Cu")
		(net "FCB_HW_REVISION")
	)
	(segment
		(start 211.279232 -152.5143)
		(end 212.790532 -151.003)
		(width 0.127)
		(layer "In2.Cu")
		(net "FCB_HW_REVISION")
	)
	(segment
		(start 91.50477 -136.527032)
		(end 91.50477 -135.563864)
		(width 0.127)
		(layer "In2.Cu")
		(net "FCB_HW_REVISION")
	)
	(segment
		(start 141.2748 -154.3812)
		(end 128.504188 -154.3812)
		(width 0.127)
		(layer "In2.Cu")
		(net "FCB_HW_REVISION")
	)
	(segment
		(start 142.113 -153.543)
		(end 142.3924 -153.2636)
		(width 0.127)
		(layer "In2.Cu")
		(net "FCB_HW_REVISION")
	)
	(segment
		(start 142.113 -153.543)
		(end 141.2748 -154.3812)
		(width 0.127)
		(layer "In2.Cu")
		(net "FCB_HW_REVISION")
	)
	(segment
		(start 142.3924 -153.2636)
		(end 169.6847 -153.2636)
		(width 0.127)
		(layer "In2.Cu")
		(net "FCB_HW_REVISION")
	)
	(segment
		(start 180.526182 -26.13279)
		(end 181.065932 -26.67254)
		(width 0.127)
		(layer "F.Cu")
		(net "NC_PHYSPLOED_N")
	)
	(segment
		(start 181.065932 -26.67254)
		(end 181.065932 -27.377136)
		(width 0.127)
		(layer "F.Cu")
		(net "NC_PHYSPLOED_N")
	)
	(segment
		(start 180.529992 -25.4)
		(end 180.526182 -26.13279)
		(width 0.127)
		(layer "F.Cu")
		(net "NC_PHYSPLOED_N")
	)
	(segment
		(start 285.68396 -187.590684)
		(end 285.578804 -187.69584)
		(width 0.1143)
		(layer "F.Cu")
		(net "MEMA_11")
	)
	(segment
		(start 288.385758 -185.554112)
		(end 286.349186 -187.590684)
		(width 0.1143)
		(layer "F.Cu")
		(net "MEMA_11")
	)
	(segment
		(start 289.17138 -183.904128)
		(end 289.17138 -184.379616)
		(width 0.1143)
		(layer "F.Cu")
		(net "MEMA_11")
	)
	(segment
		(start 285.326328 -199.7329)
		(end 284.614366 -199.7329)
		(width 0.1143)
		(layer "F.Cu")
		(net "MEMA_11")
	)
	(segment
		(start 289.63493 -183.44007)
		(end 289.63493 -183.440578)
		(width 0.1143)
		(layer "F.Cu")
		(net "MEMA_11")
	)
	(segment
		(start 285.75635 -198.918322)
		(end 285.75635 -199.302878)
		(width 0.1143)
		(layer "F.Cu")
		(net "MEMA_11")
	)
	(segment
		(start 285.698184 -197.73519)
		(end 285.698184 -198.860156)
		(width 0.1143)
		(layer "F.Cu")
		(net "MEMA_11")
	)
	(segment
		(start 289.63493 -183.440578)
		(end 289.17138 -183.904128)
		(width 0.1143)
		(layer "F.Cu")
		(net "MEMA_11")
	)
	(segment
		(start 288.385758 -185.165238)
		(end 288.385758 -185.554112)
		(width 0.1143)
		(layer "F.Cu")
		(net "MEMA_11")
	)
	(segment
		(start 285.75635 -199.302878)
		(end 285.326328 -199.7329)
		(width 0.1143)
		(layer "F.Cu")
		(net "MEMA_11")
	)
	(segment
		(start 285.698184 -198.860156)
		(end 285.75635 -198.918322)
		(width 0.1143)
		(layer "F.Cu")
		(net "MEMA_11")
	)
	(segment
		(start 289.17138 -184.379616)
		(end 288.385758 -185.165238)
		(width 0.1143)
		(layer "F.Cu")
		(net "MEMA_11")
	)
	(segment
		(start 286.349186 -187.590684)
		(end 285.68396 -187.590684)
		(width 0.1143)
		(layer "F.Cu")
		(net "MEMA_11")
	)
	(via
		(at 283.87802 -198.00951)
		(size 0.7112)
		(drill 0.3556)
		(layers "F.Cu" "B.Cu")
		(net "MEMA_11")
	)
	(via
		(at 285.578804 -187.69584)
		(size 0.508)
		(drill 0.254)
		(layers "F.Cu" "B.Cu")
		(net "MEMA_11")
	)
	(via
		(at 284.614366 -199.7329)
		(size 0.508)
		(drill 0.254)
		(layers "F.Cu" "B.Cu")
		(net "MEMA_11")
	)
	(segment
		(start 284.614366 -199.7329)
		(end 284.614366 -199.425306)
		(width 0.1143)
		(layer "B.Cu")
		(net "MEMA_11")
	)
	(segment
		(start 283.87802 -198.00951)
		(end 283.6926 -197.82409)
		(width 0.1143)
		(layer "B.Cu")
		(net "MEMA_11")
	)
	(segment
		(start 283.718 -189.281816)
		(end 285.163006 -187.83681)
		(width 0.1143)
		(layer "B.Cu")
		(net "MEMA_11")
	)
	(segment
		(start 283.6926 -195.185538)
		(end 283.97835 -194.899788)
		(width 0.1143)
		(layer "B.Cu")
		(net "MEMA_11")
	)
	(segment
		(start 283.91231 -198.0438)
		(end 283.87802 -198.00951)
		(width 0.1143)
		(layer "B.Cu")
		(net "MEMA_11")
	)
	(segment
		(start 285.163006 -187.83681)
		(end 285.437834 -187.83681)
		(width 0.1143)
		(layer "B.Cu")
		(net "MEMA_11")
	)
	(segment
		(start 283.97835 -194.431412)
		(end 283.718 -194.171062)
		(width 0.1143)
		(layer "B.Cu")
		(net "MEMA_11")
	)
	(segment
		(start 285.437834 -187.83681)
		(end 285.578804 -187.69584)
		(width 0.1143)
		(layer "B.Cu")
		(net "MEMA_11")
	)
	(segment
		(start 283.91231 -198.72325)
		(end 283.91231 -198.0438)
		(width 0.1143)
		(layer "B.Cu")
		(net "MEMA_11")
	)
	(segment
		(start 284.614366 -199.425306)
		(end 283.91231 -198.72325)
		(width 0.1143)
		(layer "B.Cu")
		(net "MEMA_11")
	)
	(segment
		(start 283.6926 -197.82409)
		(end 283.6926 -195.185538)
		(width 0.1143)
		(layer "B.Cu")
		(net "MEMA_11")
	)
	(segment
		(start 283.718 -194.171062)
		(end 283.718 -189.281816)
		(width 0.1143)
		(layer "B.Cu")
		(net "MEMA_11")
	)
	(segment
		(start 283.97835 -194.899788)
		(end 283.97835 -194.431412)
		(width 0.1143)
		(layer "B.Cu")
		(net "MEMA_11")
	)
	(segment
		(start 306.5399 -165.0111)
		(end 303.633378 -165.0111)
		(width 0.1143)
		(layer "F.Cu")
		(net "PU_BMC0_SCL11")
	)
	(segment
		(start 309.118 -161.0995)
		(end 309.118 -162.433)
		(width 0.1143)
		(layer "F.Cu")
		(net "PU_BMC0_SCL11")
	)
	(segment
		(start 309.118 -162.433)
		(end 308.356 -163.195)
		(width 0.1143)
		(layer "F.Cu")
		(net "PU_BMC0_SCL11")
	)
	(segment
		(start 303.633378 -165.0111)
		(end 302.769778 -165.8747)
		(width 0.1143)
		(layer "F.Cu")
		(net "PU_BMC0_SCL11")
	)
	(segment
		(start 301.0027 -167.272208)
		(end 300.834806 -167.440102)
		(width 0.1143)
		(layer "F.Cu")
		(net "PU_BMC0_SCL11")
	)
	(segment
		(start 308.356 -163.195)
		(end 306.5399 -165.0111)
		(width 0.1143)
		(layer "F.Cu")
		(net "PU_BMC0_SCL11")
	)
	(segment
		(start 302.286924 -165.8747)
		(end 301.0027 -167.158924)
		(width 0.1143)
		(layer "F.Cu")
		(net "PU_BMC0_SCL11")
	)
	(segment
		(start 301.0027 -167.158924)
		(end 301.0027 -167.272208)
		(width 0.1143)
		(layer "F.Cu")
		(net "PU_BMC0_SCL11")
	)
	(segment
		(start 302.769778 -165.8747)
		(end 302.286924 -165.8747)
		(width 0.1143)
		(layer "F.Cu")
		(net "PU_BMC0_SCL11")
	)
	(via
		(at 308.356 -163.195)
		(size 0.7112)
		(drill 0.3556)
		(layers "F.Cu" "B.Cu")
		(net "PU_BMC0_SCL11")
	)
	(segment
		(start 14.40053 -99.980242)
		(end 14.40053 -98.63582)
		(width 0.1016)
		(layer "F.Cu")
		(net "SAS_EXT_CONN_RX17_N")
	)
	(via
		(at 14.448282 -98.520504)
		(size 0.5588)
		(drill 0.3048)
		(layers "F.Cu" "B.Cu")
		(net "SAS_EXT_CONN_RX17_N")
	)
	(arc
		(start 14.40053 -98.63582)
		(mid 14.412943 -98.573417)
		(end 14.448282 -98.520504)
		(width 0.1016)
		(layer "F.Cu")
		(net "SAS_EXT_CONN_RX17_N")
	)
	(segment
		(start 14.471904 -99.956366)
		(end 14.471904 -98.544126)
		(width 0.1016)
		(layer "B.Cu")
		(net "SAS_EXT_CONN_RX17_N")
	)
	(segment
		(start 14.471904 -98.544126)
		(end 14.448282 -98.520504)
		(width 0.1016)
		(layer "B.Cu")
		(net "SAS_EXT_CONN_RX17_N")
	)
	(segment
		(start 190.012066 -30.056074)
		(end 186.744864 -30.056074)
		(width 0.127)
		(layer "F.Cu")
		(net "NC_PHY_TXC")
	)
	(segment
		(start 190.054992 -30.099)
		(end 190.012066 -30.056074)
		(width 0.127)
		(layer "F.Cu")
		(net "NC_PHY_TXC")
	)
	(segment
		(start 293.1922 -184.112408)
		(end 293.1922 -185.001408)
		(width 0.1016)
		(layer "F.Cu")
		(net "MEMCK_N")
	)
	(segment
		(start 292.834822 -183.44007)
		(end 292.834822 -183.75503)
		(width 0.1016)
		(layer "F.Cu")
		(net "MEMCK_N")
	)
	(segment
		(start 289.701732 -197.73519)
		(end 290.150042 -198.1835)
		(width 0.1016)
		(layer "F.Cu")
		(net "MEMCK_N")
	)
	(segment
		(start 292.834822 -183.75503)
		(end 293.1922 -184.112408)
		(width 0.1016)
		(layer "F.Cu")
		(net "MEMCK_N")
	)
	(segment
		(start 289.698176 -197.73519)
		(end 289.701732 -197.73519)
		(width 0.1016)
		(layer "F.Cu")
		(net "MEMCK_N")
	)
	(segment
		(start 293.1922 -185.001408)
		(end 292.670992 -185.522616)
		(width 0.1016)
		(layer "F.Cu")
		(net "MEMCK_N")
	)
	(via
		(at 292.670992 -185.522616)
		(size 0.508)
		(drill 0.254)
		(layers "F.Cu" "B.Cu")
		(net "MEMCK_N")
	)
	(via
		(at 290.150042 -198.1835)
		(size 0.508)
		(drill 0.254)
		(layers "F.Cu" "B.Cu")
		(net "MEMCK_N")
	)
	(via
		(at 292.5826 -188.087)
		(size 0.7112)
		(drill 0.3556)
		(layers "F.Cu" "B.Cu")
		(net "MEMCK_N")
	)
	(segment
		(start 293.17696 -192.5701)
		(end 292.99916 -192.5701)
		(width 0.1016)
		(layer "B.Cu")
		(net "MEMCK_N")
	)
	(segment
		(start 291.9476 -194.7164)
		(end 291.9476 -195.650866)
		(width 0.1016)
		(layer "B.Cu")
		(net "MEMCK_N")
	)
	(segment
		(start 292.79723 -188.30163)
		(end 292.61435 -188.48451)
		(width 0.1016)
		(layer "B.Cu")
		(net "MEMCK_N")
	)
	(segment
		(start 290.381436 -198.1835)
		(end 290.150042 -198.1835)
		(width 0.1016)
		(layer "B.Cu")
		(net "MEMCK_N")
	)
	(segment
		(start 293.1033 -185.703972)
		(end 293.1033 -187.99556)
		(width 0.1016)
		(layer "B.Cu")
		(net "MEMCK_N")
	)
	(segment
		(start 292.61435 -194.04965)
		(end 291.9476 -194.7164)
		(width 0.1016)
		(layer "B.Cu")
		(net "MEMCK_N")
	)
	(segment
		(start 292.91661 -189.68085)
		(end 293.84371 -189.68085)
		(width 0.1016)
		(layer "B.Cu")
		(net "MEMCK_N")
	)
	(segment
		(start 292.91661 -191.78905)
		(end 293.1033 -191.78905)
		(width 0.1016)
		(layer "B.Cu")
		(net "MEMCK_N")
	)
	(segment
		(start 292.61435 -189.37859)
		(end 292.91661 -189.68085)
		(width 0.1016)
		(layer "B.Cu")
		(net "MEMCK_N")
	)
	(segment
		(start 291.481256 -196.11721)
		(end 291.481256 -197.370954)
		(width 0.1016)
		(layer "B.Cu")
		(net "MEMCK_N")
	)
	(segment
		(start 291.9476 -195.650866)
		(end 291.481256 -196.11721)
		(width 0.1016)
		(layer "B.Cu")
		(net "MEMCK_N")
	)
	(segment
		(start 292.61435 -188.48451)
		(end 292.61435 -189.37859)
		(width 0.1016)
		(layer "B.Cu")
		(net "MEMCK_N")
	)
	(segment
		(start 290.789106 -197.77583)
		(end 290.381436 -198.1835)
		(width 0.1016)
		(layer "B.Cu")
		(net "MEMCK_N")
	)
	(segment
		(start 294.0177 -190.05296)
		(end 293.78021 -190.29045)
		(width 0.1016)
		(layer "B.Cu")
		(net "MEMCK_N")
	)
	(segment
		(start 291.481256 -197.370954)
		(end 291.07638 -197.77583)
		(width 0.1016)
		(layer "B.Cu")
		(net "MEMCK_N")
	)
	(segment
		(start 293.1033 -191.78905)
		(end 293.3319 -192.01765)
		(width 0.1016)
		(layer "B.Cu")
		(net "MEMCK_N")
	)
	(segment
		(start 293.1033 -187.99556)
		(end 292.79723 -188.30163)
		(width 0.1016)
		(layer "B.Cu")
		(net "MEMCK_N")
	)
	(segment
		(start 291.07638 -197.77583)
		(end 290.789106 -197.77583)
		(width 0.1016)
		(layer "B.Cu")
		(net "MEMCK_N")
	)
	(segment
		(start 293.78021 -190.29045)
		(end 292.91661 -190.29045)
		(width 0.1016)
		(layer "B.Cu")
		(net "MEMCK_N")
	)
	(segment
		(start 292.61435 -191.48679)
		(end 292.91661 -191.78905)
		(width 0.1016)
		(layer "B.Cu")
		(net "MEMCK_N")
	)
	(segment
		(start 292.921944 -185.522616)
		(end 293.1033 -185.703972)
		(width 0.1016)
		(layer "B.Cu")
		(net "MEMCK_N")
	)
	(segment
		(start 294.0177 -189.85484)
		(end 294.0177 -190.05296)
		(width 0.1016)
		(layer "B.Cu")
		(net "MEMCK_N")
	)
	(segment
		(start 292.61435 -192.95491)
		(end 292.61435 -194.04965)
		(width 0.1016)
		(layer "B.Cu")
		(net "MEMCK_N")
	)
	(segment
		(start 292.79723 -188.30163)
		(end 292.5826 -188.087)
		(width 0.1016)
		(layer "B.Cu")
		(net "MEMCK_N")
	)
	(segment
		(start 292.670992 -185.522616)
		(end 292.921944 -185.522616)
		(width 0.1016)
		(layer "B.Cu")
		(net "MEMCK_N")
	)
	(segment
		(start 292.61435 -190.59271)
		(end 292.61435 -191.48679)
		(width 0.1016)
		(layer "B.Cu")
		(net "MEMCK_N")
	)
	(segment
		(start 292.99916 -192.5701)
		(end 292.61435 -192.95491)
		(width 0.1016)
		(layer "B.Cu")
		(net "MEMCK_N")
	)
	(segment
		(start 293.3319 -192.01765)
		(end 293.3319 -192.41516)
		(width 0.1016)
		(layer "B.Cu")
		(net "MEMCK_N")
	)
	(segment
		(start 293.3319 -192.41516)
		(end 293.17696 -192.5701)
		(width 0.1016)
		(layer "B.Cu")
		(net "MEMCK_N")
	)
	(segment
		(start 293.84371 -189.68085)
		(end 294.0177 -189.85484)
		(width 0.1016)
		(layer "B.Cu")
		(net "MEMCK_N")
	)
	(segment
		(start 292.91661 -190.29045)
		(end 292.61435 -190.59271)
		(width 0.1016)
		(layer "B.Cu")
		(net "MEMCK_N")
	)
	(segment
		(start 16.79956 -99.980242)
		(end 16.79956 -98.730816)
		(width 0.1016)
		(layer "F.Cu")
		(net "SAS_EXT_CONN_RX18_N")
	)
	(via
		(at 16.886682 -98.520504)
		(size 0.5588)
		(drill 0.3048)
		(layers "F.Cu" "B.Cu")
		(net "SAS_EXT_CONN_RX18_N")
	)
	(arc
		(start 16.79956 -98.730816)
		(mid 16.822201 -98.616993)
		(end 16.886682 -98.520504)
		(width 0.1016)
		(layer "F.Cu")
		(net "SAS_EXT_CONN_RX18_N")
	)
	(segment
		(start 16.884904 -98.522282)
		(end 16.886682 -98.520504)
		(width 0.1016)
		(layer "B.Cu")
		(net "SAS_EXT_CONN_RX18_N")
	)
	(segment
		(start 16.884904 -99.956366)
		(end 16.884904 -98.522282)
		(width 0.1016)
		(layer "B.Cu")
		(net "SAS_EXT_CONN_RX18_N")
	)
	(segment
		(start 181.065932 -34.235136)
		(end 181.065932 -35.15106)
		(width 0.1778)
		(layer "F.Cu")
		(net "PHY_TEST_EN")
	)
	(segment
		(start 178.997864 -36.406074)
		(end 179.532788 -35.87115)
		(width 0.1778)
		(layer "F.Cu")
		(net "PHY_TEST_EN")
	)
	(segment
		(start 179.697888 -35.70605)
		(end 179.532788 -35.87115)
		(width 0.1778)
		(layer "F.Cu")
		(net "PHY_TEST_EN")
	)
	(segment
		(start 181.065932 -35.15106)
		(end 180.510942 -35.70605)
		(width 0.1778)
		(layer "F.Cu")
		(net "PHY_TEST_EN")
	)
	(segment
		(start 178.997864 -37.727636)
		(end 178.997864 -36.406074)
		(width 0.1778)
		(layer "F.Cu")
		(net "PHY_TEST_EN")
	)
	(segment
		(start 180.510942 -35.70605)
		(end 179.697888 -35.70605)
		(width 0.1778)
		(layer "F.Cu")
		(net "PHY_TEST_EN")
	)
	(via
		(at 179.532788 -35.87115)
		(size 0.7112)
		(drill 0.3556)
		(layers "F.Cu" "B.Cu")
		(net "PHY_TEST_EN")
	)
	(segment
		(start 292.108382 -201.735182)
		(end 292.50386 -202.13066)
		(width 0.1143)
		(layer "F.Cu")
		(net "MEMDQ_5")
	)
	(segment
		(start 294.02532 -181.440328)
		(end 294.025574 -181.440074)
		(width 0.1143)
		(layer "F.Cu")
		(net "MEMDQ_5")
	)
	(segment
		(start 293.634922 -181.840124)
		(end 294.02532 -181.449726)
		(width 0.1143)
		(layer "F.Cu")
		(net "MEMDQ_5")
	)
	(segment
		(start 292.097968 -201.735182)
		(end 292.108382 -201.735182)
		(width 0.1143)
		(layer "F.Cu")
		(net "MEMDQ_5")
	)
	(segment
		(start 294.02532 -181.449726)
		(end 294.02532 -181.440328)
		(width 0.1143)
		(layer "F.Cu")
		(net "MEMDQ_5")
	)
	(segment
		(start 292.50386 -202.13066)
		(end 293.2938 -202.13066)
		(width 0.1143)
		(layer "F.Cu")
		(net "MEMDQ_5")
	)
	(via
		(at 294.025574 -181.440074)
		(size 0.508)
		(drill 0.254)
		(layers "F.Cu" "B.Cu")
		(net "MEMDQ_5")
	)
	(via
		(at 293.2938 -202.13066)
		(size 0.508)
		(drill 0.254)
		(layers "F.Cu" "B.Cu")
		(net "MEMDQ_5")
	)
	(via
		(at 292.5572 -202.3872)
		(size 0.7112)
		(drill 0.3556)
		(layers "F.Cu" "B.Cu")
		(net "MEMDQ_5")
	)
	(segment
		(start 293.2938 -202.13066)
		(end 292.81374 -202.13066)
		(width 0.1143)
		(layer "B.Cu")
		(net "MEMDQ_5")
	)
	(segment
		(start 292.81374 -202.13066)
		(end 292.5572 -202.3872)
		(width 0.1143)
		(layer "B.Cu")
		(net "MEMDQ_5")
	)
	(segment
		(start 294.2082 -200.655428)
		(end 294.2082 -201.40549)
		(width 0.127)
		(layer "In5.Cu")
		(net "MEMDQ_5")
	)
	(segment
		(start 294.2082 -201.40549)
		(end 293.48303 -202.13066)
		(width 0.127)
		(layer "In5.Cu")
		(net "MEMDQ_5")
	)
	(segment
		(start 293.7002 -189.831472)
		(end 293.7002 -192.768474)
		(width 0.127)
		(layer "In5.Cu")
		(net "MEMDQ_5")
	)
	(segment
		(start 293.7002 -192.768474)
		(end 294.13708 -193.205354)
		(width 0.127)
		(layer "In5.Cu")
		(net "MEMDQ_5")
	)
	(segment
		(start 294.5257 -183.66486)
		(end 295.2623 -184.40146)
		(width 0.127)
		(layer "In5.Cu")
		(net "MEMDQ_5")
	)
	(segment
		(start 294.13708 -193.205354)
		(end 294.13708 -194.85483)
		(width 0.127)
		(layer "In5.Cu")
		(net "MEMDQ_5")
	)
	(segment
		(start 294.461692 -183.600852)
		(end 294.5257 -183.66486)
		(width 0.1016)
		(layer "In5.Cu")
		(net "MEMDQ_5")
	)
	(segment
		(start 294.8686 -196.99605)
		(end 294.455088 -197.409562)
		(width 0.127)
		(layer "In5.Cu")
		(net "MEMDQ_5")
	)
	(segment
		(start 294.455088 -197.409562)
		(end 294.455088 -199.75068)
		(width 0.127)
		(layer "In5.Cu")
		(net "MEMDQ_5")
	)
	(segment
		(start 294.8686 -195.58635)
		(end 294.8686 -196.99605)
		(width 0.127)
		(layer "In5.Cu")
		(net "MEMDQ_5")
	)
	(segment
		(start 294.025574 -181.440074)
		(end 294.461692 -181.876192)
		(width 0.1016)
		(layer "In5.Cu")
		(net "MEMDQ_5")
	)
	(segment
		(start 294.599868 -200.26376)
		(end 294.2082 -200.655428)
		(width 0.127)
		(layer "In5.Cu")
		(net "MEMDQ_5")
	)
	(segment
		(start 294.599868 -199.89546)
		(end 294.599868 -200.26376)
		(width 0.127)
		(layer "In5.Cu")
		(net "MEMDQ_5")
	)
	(segment
		(start 295.2623 -188.269372)
		(end 293.7002 -189.831472)
		(width 0.127)
		(layer "In5.Cu")
		(net "MEMDQ_5")
	)
	(segment
		(start 294.13708 -194.85483)
		(end 294.8686 -195.58635)
		(width 0.127)
		(layer "In5.Cu")
		(net "MEMDQ_5")
	)
	(segment
		(start 294.455088 -199.75068)
		(end 294.599868 -199.89546)
		(width 0.127)
		(layer "In5.Cu")
		(net "MEMDQ_5")
	)
	(segment
		(start 294.461692 -181.876192)
		(end 294.461692 -183.600852)
		(width 0.1016)
		(layer "In5.Cu")
		(net "MEMDQ_5")
	)
	(segment
		(start 295.2623 -184.40146)
		(end 295.2623 -188.269372)
		(width 0.127)
		(layer "In5.Cu")
		(net "MEMDQ_5")
	)
	(segment
		(start 293.48303 -202.13066)
		(end 293.2938 -202.13066)
		(width 0.127)
		(layer "In5.Cu")
		(net "MEMDQ_5")
	)
	(segment
		(start 18.39976 -99.980242)
		(end 18.39976 -98.887534)
		(width 0.1016)
		(layer "F.Cu")
		(net "SAS_EXT_CONN_RX19_P")
	)
	(via
		(at 18.258282 -98.545904)
		(size 0.5588)
		(drill 0.3048)
		(layers "F.Cu" "B.Cu")
		(net "SAS_EXT_CONN_RX19_P")
	)
	(arc
		(start 18.39976 -98.887534)
		(mid 18.362986 -98.702657)
		(end 18.258282 -98.545904)
		(width 0.1016)
		(layer "F.Cu")
		(net "SAS_EXT_CONN_RX19_P")
	)
	(segment
		(start 18.281904 -99.956366)
		(end 18.281904 -98.603054)
		(width 0.1016)
		(layer "B.Cu")
		(net "SAS_EXT_CONN_RX19_P")
	)
	(arc
		(start 18.281904 -98.603054)
		(mid 18.275756 -98.572144)
		(end 18.258282 -98.545904)
		(width 0.1016)
		(layer "B.Cu")
		(net "SAS_EXT_CONN_RX19_P")
	)
	(segment
		(start 179.767992 -25.9588)
		(end 179.767992 -24.511)
		(width 0.1143)
		(layer "F.Cu")
		(net "PHY_LNKLED_N")
	)
	(segment
		(start 172.586142 -14.852142)
		(end 172.586142 -9.92632)
		(width 0.1143)
		(layer "F.Cu")
		(net "PHY_LNKLED_N")
	)
	(segment
		(start 179.767992 -24.511)
		(end 178.428142 -23.17115)
		(width 0.1143)
		(layer "F.Cu")
		(net "PHY_LNKLED_N")
	)
	(segment
		(start 178.428142 -23.17115)
		(end 178.428142 -22.098)
		(width 0.1143)
		(layer "F.Cu")
		(net "PHY_LNKLED_N")
	)
	(segment
		(start 180.565806 -27.250136)
		(end 180.565806 -26.756614)
		(width 0.1143)
		(layer "F.Cu")
		(net "PHY_LNKLED_N")
	)
	(segment
		(start 178.428142 -22.098)
		(end 178.428142 -20.694142)
		(width 0.1143)
		(layer "F.Cu")
		(net "PHY_LNKLED_N")
	)
	(segment
		(start 180.565806 -26.756614)
		(end 179.767992 -25.9588)
		(width 0.1143)
		(layer "F.Cu")
		(net "PHY_LNKLED_N")
	)
	(segment
		(start 172.586142 -9.92632)
		(end 164.979858 -2.320036)
		(width 0.1143)
		(layer "F.Cu")
		(net "PHY_LNKLED_N")
	)
	(segment
		(start 178.428142 -20.694142)
		(end 172.586142 -14.852142)
		(width 0.1143)
		(layer "F.Cu")
		(net "PHY_LNKLED_N")
	)
	(via
		(at 178.428142 -22.098)
		(size 0.7112)
		(drill 0.3556)
		(layers "F.Cu" "B.Cu")
		(net "PHY_LNKLED_N")
	)
	(segment
		(start 15.99946 -99.980242)
		(end 15.99946 -98.622104)
		(width 0.1016)
		(layer "F.Cu")
		(net "SAS_EXT_CONN_RX18_P")
	)
	(via
		(at 15.946882 -98.495104)
		(size 0.5588)
		(drill 0.3048)
		(layers "F.Cu" "B.Cu")
		(net "SAS_EXT_CONN_RX18_P")
	)
	(arc
		(start 15.99946 -98.622104)
		(mid 15.98579 -98.553382)
		(end 15.946882 -98.495104)
		(width 0.1016)
		(layer "F.Cu")
		(net "SAS_EXT_CONN_RX18_P")
	)
	(segment
		(start 15.995904 -99.956366)
		(end 15.995904 -98.613468)
		(width 0.1016)
		(layer "B.Cu")
		(net "SAS_EXT_CONN_RX18_P")
	)
	(arc
		(start 15.995904 -98.613468)
		(mid 15.983162 -98.549412)
		(end 15.946882 -98.495104)
		(width 0.1016)
		(layer "B.Cu")
		(net "SAS_EXT_CONN_RX18_P")
	)
	(segment
		(start 186.065922 -34.362136)
		(end 186.879992 -34.362136)
		(width 0.1143)
		(layer "F.Cu")
		(net "RMII_BMC_CRS_DV_R")
	)
	(segment
		(start 186.879992 -34.362136)
		(end 188.149992 -35.632136)
		(width 0.1143)
		(layer "F.Cu")
		(net "RMII_BMC_CRS_DV_R")
	)
	(segment
		(start 188.149992 -35.632136)
		(end 188.149992 -35.687)
		(width 0.1143)
		(layer "F.Cu")
		(net "RMII_BMC_CRS_DV_R")
	)
	(segment
		(start 188.149992 -37.7825)
		(end 188.149992 -35.687)
		(width 0.1143)
		(layer "F.Cu")
		(net "RMII_BMC_CRS_DV_R")
	)
	(via
		(at 188.149992 -35.687)
		(size 0.7112)
		(drill 0.3556)
		(layers "F.Cu" "B.Cu")
		(net "RMII_BMC_CRS_DV_R")
	)
	(segment
		(start 11.20013 -99.980242)
		(end 11.20013 -98.623374)
		(width 0.1016)
		(layer "F.Cu")
		(net "SAS_EXT_CONN_RX16_P")
	)
	(via
		(at 11.146282 -98.493326)
		(size 0.5588)
		(drill 0.3048)
		(layers "F.Cu" "B.Cu")
		(net "SAS_EXT_CONN_RX16_P")
	)
	(arc
		(start 11.20013 -98.623374)
		(mid 11.186132 -98.553)
		(end 11.146282 -98.493326)
		(width 0.1016)
		(layer "F.Cu")
		(net "SAS_EXT_CONN_RX16_P")
	)
	(segment
		(start 11.169904 -98.516948)
		(end 11.146282 -98.493326)
		(width 0.1016)
		(layer "B.Cu")
		(net "SAS_EXT_CONN_RX16_P")
	)
	(segment
		(start 11.169904 -99.956366)
		(end 11.169904 -98.516948)
		(width 0.1016)
		(layer "B.Cu")
		(net "SAS_EXT_CONN_RX16_P")
	)
	(segment
		(start 180.648864 -22.995636)
		(end 181.791864 -22.995636)
		(width 0.1143)
		(layer "F.Cu")
		(net "PHY_ANEN")
	)
	(segment
		(start 182.06593 -26.224738)
		(end 181.876192 -26.035)
		(width 0.1143)
		(layer "F.Cu")
		(net "PHY_ANEN")
	)
	(segment
		(start 181.876192 -26.035)
		(end 181.876192 -24.3586)
		(width 0.1143)
		(layer "F.Cu")
		(net "PHY_ANEN")
	)
	(segment
		(start 181.876192 -23.079964)
		(end 181.876192 -24.3586)
		(width 0.1143)
		(layer "F.Cu")
		(net "PHY_ANEN")
	)
	(segment
		(start 182.06593 -27.377136)
		(end 182.06593 -26.224738)
		(width 0.1143)
		(layer "F.Cu")
		(net "PHY_ANEN")
	)
	(segment
		(start 181.791864 -22.995636)
		(end 181.876192 -23.079964)
		(width 0.1143)
		(layer "F.Cu")
		(net "PHY_ANEN")
	)
	(via
		(at 181.876192 -24.3586)
		(size 0.7112)
		(drill 0.3556)
		(layers "F.Cu" "B.Cu")
		(net "PHY_ANEN")
	)
	(segment
		(start 12.00023 -99.980242)
		(end 12.00023 -98.641154)
		(width 0.1016)
		(layer "F.Cu")
		(net "SAS_EXT_CONN_RX16_N")
	)
	(via
		(at 12.060682 -98.495104)
		(size 0.5588)
		(drill 0.3048)
		(layers "F.Cu" "B.Cu")
		(net "SAS_EXT_CONN_RX16_N")
	)
	(arc
		(start 12.00023 -98.641154)
		(mid 12.015949 -98.562129)
		(end 12.060682 -98.495104)
		(width 0.1016)
		(layer "F.Cu")
		(net "SAS_EXT_CONN_RX16_N")
	)
	(segment
		(start 12.060682 -99.954588)
		(end 12.060682 -98.495104)
		(width 0.1016)
		(layer "B.Cu")
		(net "SAS_EXT_CONN_RX16_N")
	)
	(segment
		(start 12.058904 -99.956366)
		(end 12.060682 -99.954588)
		(width 0.1016)
		(layer "B.Cu")
		(net "SAS_EXT_CONN_RX16_N")
	)
	(segment
		(start 183.968898 -36.033202)
		(end 183.968898 -35.315906)
		(width 0.127)
		(layer "F.Cu")
		(net "PHY_RESET#")
	)
	(segment
		(start 185.855864 -37.727636)
		(end 186.952128 -37.727636)
		(width 0.127)
		(layer "F.Cu")
		(net "PHY_RESET#")
	)
	(segment
		(start 186.952128 -37.727636)
		(end 187.006992 -37.7825)
		(width 0.127)
		(layer "F.Cu")
		(net "PHY_RESET#")
	)
	(segment
		(start 184.712864 -36.777168)
		(end 183.968898 -36.033202)
		(width 0.127)
		(layer "F.Cu")
		(net "PHY_RESET#")
	)
	(segment
		(start 185.855864 -36.825936)
		(end 185.855864 -37.727636)
		(width 0.127)
		(layer "F.Cu")
		(net "PHY_RESET#")
	)
	(segment
		(start 183.968898 -35.315906)
		(end 183.5658 -34.912808)
		(width 0.127)
		(layer "F.Cu")
		(net "PHY_RESET#")
	)
	(segment
		(start 184.712864 -37.727636)
		(end 184.712864 -36.777168)
		(width 0.127)
		(layer "F.Cu")
		(net "PHY_RESET#")
	)
	(segment
		(start 185.855864 -37.727636)
		(end 184.712864 -37.727636)
		(width 0.127)
		(layer "F.Cu")
		(net "PHY_RESET#")
	)
	(segment
		(start 183.5658 -34.912808)
		(end 183.5658 -34.235136)
		(width 0.127)
		(layer "F.Cu")
		(net "PHY_RESET#")
	)
	(via
		(at 185.855864 -36.825936)
		(size 0.7112)
		(drill 0.3556)
		(layers "F.Cu" "B.Cu")
		(net "PHY_RESET#")
	)
	(segment
		(start 288.83483 -181.840124)
		(end 288.837624 -181.840124)
		(width 0.1143)
		(layer "F.Cu")
		(net "MEMA_12")
	)
	(segment
		(start 287.29813 -197.73519)
		(end 287.29813 -198.77913)
		(width 0.1143)
		(layer "F.Cu")
		(net "MEMA_12")
	)
	(segment
		(start 288.837624 -181.840124)
		(end 289.23742 -182.23992)
		(width 0.1143)
		(layer "F.Cu")
		(net "MEMA_12")
	)
	(segment
		(start 287.6804 -199.1614)
		(end 287.6804 -199.344788)
		(width 0.1143)
		(layer "F.Cu")
		(net "MEMA_12")
	)
	(segment
		(start 287.29813 -198.77913)
		(end 287.6804 -199.1614)
		(width 0.1143)
		(layer "F.Cu")
		(net "MEMA_12")
	)
	(via
		(at 288.870644 -185.674)
		(size 0.7112)
		(drill 0.3556)
		(layers "F.Cu" "B.Cu")
		(net "MEMA_12")
	)
	(via
		(at 289.23742 -182.23992)
		(size 0.508)
		(drill 0.254)
		(layers "F.Cu" "B.Cu")
		(net "MEMA_12")
	)
	(via
		(at 287.6804 -199.344788)
		(size 0.508)
		(drill 0.254)
		(layers "F.Cu" "B.Cu")
		(net "MEMA_12")
	)
	(segment
		(start 288.870644 -186.92622)
		(end 288.870644 -185.674)
		(width 0.1143)
		(layer "B.Cu")
		(net "MEMA_12")
	)
	(segment
		(start 288.7726 -188.080396)
		(end 288.772346 -188.080142)
		(width 0.1143)
		(layer "B.Cu")
		(net "MEMA_12")
	)
	(segment
		(start 288.797746 -194.98691)
		(end 288.797746 -194.384422)
		(width 0.1143)
		(layer "B.Cu")
		(net "MEMA_12")
	)
	(segment
		(start 288.798 -194.987164)
		(end 288.797746 -194.98691)
		(width 0.1143)
		(layer "B.Cu")
		(net "MEMA_12")
	)
	(segment
		(start 287.6804 -197.9422)
		(end 287.909 -197.7136)
		(width 0.1143)
		(layer "B.Cu")
		(net "MEMA_12")
	)
	(segment
		(start 288.81324 -182.869586)
		(end 289.23742 -182.445406)
		(width 0.1143)
		(layer "B.Cu")
		(net "MEMA_12")
	)
	(segment
		(start 289.26917 -189.113922)
		(end 288.7726 -188.617352)
		(width 0.1143)
		(layer "B.Cu")
		(net "MEMA_12")
	)
	(segment
		(start 287.909 -197.7136)
		(end 287.909 -196.5706)
		(width 0.1143)
		(layer "B.Cu")
		(net "MEMA_12")
	)
	(segment
		(start 288.870644 -185.322464)
		(end 288.81324 -185.26506)
		(width 0.1143)
		(layer "B.Cu")
		(net "MEMA_12")
	)
	(segment
		(start 289.23742 -182.445406)
		(end 289.23742 -182.23992)
		(width 0.1143)
		(layer "B.Cu")
		(net "MEMA_12")
	)
	(segment
		(start 288.7726 -187.732924)
		(end 288.7726 -187.024264)
		(width 0.1143)
		(layer "B.Cu")
		(net "MEMA_12")
	)
	(segment
		(start 288.81324 -185.26506)
		(end 288.81324 -182.869586)
		(width 0.1143)
		(layer "B.Cu")
		(net "MEMA_12")
	)
	(segment
		(start 289.26917 -192.658492)
		(end 289.26917 -189.113922)
		(width 0.1143)
		(layer "B.Cu")
		(net "MEMA_12")
	)
	(segment
		(start 288.870644 -185.674)
		(end 288.870644 -185.322464)
		(width 0.1143)
		(layer "B.Cu")
		(net "MEMA_12")
	)
	(segment
		(start 287.6804 -199.344788)
		(end 287.6804 -197.9422)
		(width 0.1143)
		(layer "B.Cu")
		(net "MEMA_12")
	)
	(segment
		(start 288.797746 -194.384422)
		(end 288.66338 -194.250056)
		(width 0.1143)
		(layer "B.Cu")
		(net "MEMA_12")
	)
	(segment
		(start 288.66338 -193.264282)
		(end 289.26917 -192.658492)
		(width 0.1143)
		(layer "B.Cu")
		(net "MEMA_12")
	)
	(segment
		(start 288.798 -195.6816)
		(end 288.798 -194.987164)
		(width 0.1143)
		(layer "B.Cu")
		(net "MEMA_12")
	)
	(segment
		(start 288.66338 -194.250056)
		(end 288.66338 -193.264282)
		(width 0.1143)
		(layer "B.Cu")
		(net "MEMA_12")
	)
	(segment
		(start 288.7726 -187.024264)
		(end 288.870644 -186.92622)
		(width 0.1143)
		(layer "B.Cu")
		(net "MEMA_12")
	)
	(segment
		(start 288.772346 -188.080142)
		(end 288.772346 -187.733178)
		(width 0.1143)
		(layer "B.Cu")
		(net "MEMA_12")
	)
	(segment
		(start 287.909 -196.5706)
		(end 288.798 -195.6816)
		(width 0.1143)
		(layer "B.Cu")
		(net "MEMA_12")
	)
	(segment
		(start 288.7726 -188.617352)
		(end 288.7726 -188.080396)
		(width 0.1143)
		(layer "B.Cu")
		(net "MEMA_12")
	)
	(segment
		(start 288.772346 -187.733178)
		(end 288.7726 -187.732924)
		(width 0.1143)
		(layer "B.Cu")
		(net "MEMA_12")
	)
	(segment
		(start 179.127912 -31.00832)
		(end 179.151788 -31.032196)
		(width 0.1397)
		(layer "F.Cu")
		(net "BCM5221_RX_C_DN")
	)
	(segment
		(start 175.390048 -32.055308)
		(end 175.390048 -31.118556)
		(width 0.1397)
		(layer "F.Cu")
		(net "BCM5221_RX_C_DN")
	)
	(segment
		(start 176.807622 -30.16377)
		(end 177.341022 -30.69717)
		(width 0.1397)
		(layer "F.Cu")
		(net "BCM5221_RX_C_DN")
	)
	(segment
		(start 175.73371 -30.00248)
		(end 176.41824 -30.00248)
		(width 0.1397)
		(layer "F.Cu")
		(net "BCM5221_RX_C_DN")
	)
	(segment
		(start 175.386492 -31.115)
		(end 175.386492 -30.323536)
		(width 0.1397)
		(layer "F.Cu")
		(net "BCM5221_RX_C_DN")
	)
	(segment
		(start 175.390048 -31.118556)
		(end 175.386492 -31.115)
		(width 0.1397)
		(layer "F.Cu")
		(net "BCM5221_RX_C_DN")
	)
	(segment
		(start 175.374808 -32.070548)
		(end 174.353728 -32.070548)
		(width 0.1397)
		(layer "F.Cu")
		(net "BCM5221_RX_C_DN")
	)
	(segment
		(start 179.209446 -31.056072)
		(end 179.886864 -31.056072)
		(width 0.1397)
		(layer "F.Cu")
		(net "BCM5221_RX_C_DN")
	)
	(segment
		(start 175.390048 -32.055308)
		(end 175.374808 -32.070548)
		(width 0.1397)
		(layer "F.Cu")
		(net "BCM5221_RX_C_DN")
	)
	(segment
		(start 178.092608 -31.00832)
		(end 179.127912 -31.00832)
		(width 0.1397)
		(layer "F.Cu")
		(net "BCM5221_RX_C_DN")
	)
	(arc
		(start 179.151788 -31.032196)
		(mid 179.178242 -31.049872)
		(end 179.209446 -31.056072)
		(width 0.1397)
		(layer "F.Cu")
		(net "BCM5221_RX_C_DN")
	)
	(arc
		(start 176.41824 -30.00248)
		(mid 176.628973 -30.044397)
		(end 176.807622 -30.16377)
		(width 0.1397)
		(layer "F.Cu")
		(net "BCM5221_RX_C_DN")
	)
	(arc
		(start 175.494696 -30.062424)
		(mid 175.610506 -30.017703)
		(end 175.73371 -30.00248)
		(width 0.1397)
		(layer "F.Cu")
		(net "BCM5221_RX_C_DN")
	)
	(arc
		(start 175.386492 -30.323536)
		(mid 175.414605 -30.182205)
		(end 175.494696 -30.062424)
		(width 0.1397)
		(layer "F.Cu")
		(net "BCM5221_RX_C_DN")
	)
	(arc
		(start 177.341022 -30.69717)
		(mid 177.685868 -30.927495)
		(end 178.092608 -31.00832)
		(width 0.1397)
		(layer "F.Cu")
		(net "BCM5221_RX_C_DN")
	)
	(segment
		(start 289.2552 -168.65092)
		(end 289.244278 -168.639998)
		(width 0.1143)
		(layer "F.Cu")
		(net "BMC0_PMU_PLTRST_N_BMC")
	)
	(segment
		(start 289.63493 -169.040048)
		(end 289.2552 -168.660318)
		(width 0.1143)
		(layer "F.Cu")
		(net "BMC0_PMU_PLTRST_N_BMC")
	)
	(segment
		(start 289.2552 -168.660318)
		(end 289.2552 -168.65092)
		(width 0.1143)
		(layer "F.Cu")
		(net "BMC0_PMU_PLTRST_N_BMC")
	)
	(via
		(at 289.244278 -168.639998)
		(size 0.508)
		(drill 0.254)
		(layers "F.Cu" "B.Cu")
		(net "BMC0_PMU_PLTRST_N_BMC")
	)
	(via
		(at 288.896044 -167.745156)
		(size 0.7112)
		(drill 0.3556)
		(layers "F.Cu" "B.Cu")
		(net "BMC0_PMU_PLTRST_N_BMC")
	)
	(segment
		(start 288.925 -167.469312)
		(end 288.896044 -167.498268)
		(width 0.1143)
		(layer "B.Cu")
		(net "BMC0_PMU_PLTRST_N_BMC")
	)
	(segment
		(start 288.896044 -167.992044)
		(end 289.244278 -168.340278)
		(width 0.1143)
		(layer "B.Cu")
		(net "BMC0_PMU_PLTRST_N_BMC")
	)
	(segment
		(start 288.896044 -167.745156)
		(end 288.896044 -167.992044)
		(width 0.1143)
		(layer "B.Cu")
		(net "BMC0_PMU_PLTRST_N_BMC")
	)
	(segment
		(start 289.244278 -168.340278)
		(end 289.244278 -168.639998)
		(width 0.1143)
		(layer "B.Cu")
		(net "BMC0_PMU_PLTRST_N_BMC")
	)
	(segment
		(start 288.925 -166.6875)
		(end 288.925 -167.469312)
		(width 0.1143)
		(layer "B.Cu")
		(net "BMC0_PMU_PLTRST_N_BMC")
	)
	(segment
		(start 288.896044 -167.498268)
		(end 288.896044 -167.745156)
		(width 0.1143)
		(layer "B.Cu")
		(net "BMC0_PMU_PLTRST_N_BMC")
	)
	(segment
		(start 46.000416 -253.391162)
		(end 38.032182 -245.422928)
		(width 0.1143)
		(layer "F.Cu")
		(net "SAS_HDD_PWR1_PCIE")
	)
	(segment
		(start 38.032182 -245.422928)
		(end 38.032182 -233.103928)
		(width 0.1143)
		(layer "F.Cu")
		(net "SAS_HDD_PWR1_PCIE")
	)
	(segment
		(start 35.306254 -230.378)
		(end 31.483046 -230.378)
		(width 0.1143)
		(layer "F.Cu")
		(net "SAS_HDD_PWR1_PCIE")
	)
	(segment
		(start 28.334716 -233.52633)
		(end 28.334716 -234.19308)
		(width 0.1143)
		(layer "F.Cu")
		(net "SAS_HDD_PWR1_PCIE")
	)
	(segment
		(start 46.000416 -256.25044)
		(end 46.000416 -253.391162)
		(width 0.1143)
		(layer "F.Cu")
		(net "SAS_HDD_PWR1_PCIE")
	)
	(segment
		(start 28.334716 -236.14888)
		(end 28.334716 -234.19308)
		(width 0.1143)
		(layer "F.Cu")
		(net "SAS_HDD_PWR1_PCIE")
	)
	(segment
		(start 38.032182 -233.103928)
		(end 35.306254 -230.378)
		(width 0.1143)
		(layer "F.Cu")
		(net "SAS_HDD_PWR1_PCIE")
	)
	(segment
		(start 31.483046 -230.378)
		(end 28.334716 -233.52633)
		(width 0.1143)
		(layer "F.Cu")
		(net "SAS_HDD_PWR1_PCIE")
	)
	(via
		(at 27.127962 -235.539534)
		(size 0.7112)
		(drill 0.3556)
		(layers "F.Cu" "B.Cu")
		(net "SAS_HDD_PWR1_PCIE")
	)
	(via
		(at 28.334716 -236.14888)
		(size 0.5588)
		(drill 0.3048)
		(layers "F.Cu" "B.Cu")
		(net "SAS_HDD_PWR1_PCIE")
	)
	(segment
		(start 27.737308 -236.14888)
		(end 27.127962 -235.539534)
		(width 0.1143)
		(layer "B.Cu")
		(net "SAS_HDD_PWR1_PCIE")
	)
	(segment
		(start 28.334716 -236.14888)
		(end 27.737308 -236.14888)
		(width 0.1143)
		(layer "B.Cu")
		(net "SAS_HDD_PWR1_PCIE")
	)
	(segment
		(start 26.366216 -234.777788)
		(end 27.127962 -235.539534)
		(width 0.1143)
		(layer "B.Cu")
		(net "SAS_HDD_PWR1_PCIE")
	)
	(segment
		(start 26.366216 -232.78338)
		(end 26.366216 -234.777788)
		(width 0.1143)
		(layer "B.Cu")
		(net "SAS_HDD_PWR1_PCIE")
	)
	(segment
		(start 175.733456 -29.65958)
		(end 176.418494 -29.65958)
		(width 0.1397)
		(layer "F.Cu")
		(net "BCM5221_RX_C_DP")
	)
	(segment
		(start 179.23637 -30.5562)
		(end 179.886864 -30.5562)
		(width 0.1397)
		(layer "F.Cu")
		(net "BCM5221_RX_C_DP")
	)
	(segment
		(start 178.092608 -30.66542)
		(end 179.021994 -30.66542)
		(width 0.1397)
		(layer "F.Cu")
		(net "BCM5221_RX_C_DP")
	)
	(segment
		(start 172.306488 -31.163768)
		(end 173.325028 -31.163768)
		(width 0.1397)
		(layer "F.Cu")
		(net "BCM5221_RX_C_DP")
	)
	(segment
		(start 173.373796 -31.115)
		(end 174.497492 -31.115)
		(width 0.1397)
		(layer "F.Cu")
		(net "BCM5221_RX_C_DP")
	)
	(segment
		(start 174.66056 -30.380432)
		(end 175.132492 -29.9085)
		(width 0.1397)
		(layer "F.Cu")
		(net "BCM5221_RX_C_DP")
	)
	(segment
		(start 172.268388 -31.201868)
		(end 172.306488 -31.163768)
		(width 0.1397)
		(layer "F.Cu")
		(net "BCM5221_RX_C_DP")
	)
	(segment
		(start 179.111656 -30.628336)
		(end 179.146708 -30.593284)
		(width 0.1397)
		(layer "F.Cu")
		(net "BCM5221_RX_C_DP")
	)
	(segment
		(start 174.497492 -31.115)
		(end 174.497492 -30.774132)
		(width 0.1397)
		(layer "F.Cu")
		(net "BCM5221_RX_C_DP")
	)
	(segment
		(start 173.325028 -31.163768)
		(end 173.373796 -31.115)
		(width 0.1397)
		(layer "F.Cu")
		(net "BCM5221_RX_C_DP")
	)
	(segment
		(start 177.050192 -29.9212)
		(end 177.583592 -30.4546)
		(width 0.1397)
		(layer "F.Cu")
		(net "BCM5221_RX_C_DP")
	)
	(arc
		(start 174.497492 -30.774132)
		(mid 174.539873 -30.561066)
		(end 174.66056 -30.380432)
		(width 0.1397)
		(layer "F.Cu")
		(net "BCM5221_RX_C_DP")
	)
	(arc
		(start 179.146708 -30.593284)
		(mid 179.187859 -30.565851)
		(end 179.23637 -30.5562)
		(width 0.1397)
		(layer "F.Cu")
		(net "BCM5221_RX_C_DP")
	)
	(arc
		(start 177.583592 -30.4546)
		(mid 177.817131 -30.610645)
		(end 178.092608 -30.66542)
		(width 0.1397)
		(layer "F.Cu")
		(net "BCM5221_RX_C_DP")
	)
	(arc
		(start 175.132492 -29.9085)
		(mid 175.408231 -29.72432)
		(end 175.733456 -29.65958)
		(width 0.1397)
		(layer "F.Cu")
		(net "BCM5221_RX_C_DP")
	)
	(arc
		(start 179.021994 -30.66542)
		(mid 179.070512 -30.655787)
		(end 179.111656 -30.628336)
		(width 0.1397)
		(layer "F.Cu")
		(net "BCM5221_RX_C_DP")
	)
	(arc
		(start 176.418494 -29.65958)
		(mid 176.760366 -29.727565)
		(end 177.050192 -29.9212)
		(width 0.1397)
		(layer "F.Cu")
		(net "BCM5221_RX_C_DP")
	)
	(segment
		(start 288.83483 -183.44007)
		(end 288.83483 -183.539638)
		(width 0.1143)
		(layer "F.Cu")
		(net "MEMA_9")
	)
	(segment
		(start 286.617156 -186.47156)
		(end 285.622238 -186.47156)
		(width 0.1143)
		(layer "F.Cu")
		(net "MEMA_9")
	)
	(segment
		(start 287.547558 -185.541158)
		(end 286.617156 -186.47156)
		(width 0.1143)
		(layer "F.Cu")
		(net "MEMA_9")
	)
	(segment
		(start 288.371534 -184.384442)
		(end 287.547558 -185.208418)
		(width 0.1143)
		(layer "F.Cu")
		(net "MEMA_9")
	)
	(segment
		(start 288.83483 -183.539638)
		(end 288.371534 -184.00268)
		(width 0.1143)
		(layer "F.Cu")
		(net "MEMA_9")
	)
	(segment
		(start 285.698184 -200.935082)
		(end 285.58744 -200.824338)
		(width 0.1143)
		(layer "F.Cu")
		(net "MEMA_9")
	)
	(segment
		(start 287.547558 -185.208418)
		(end 287.547558 -185.541158)
		(width 0.1143)
		(layer "F.Cu")
		(net "MEMA_9")
	)
	(segment
		(start 288.371534 -184.00268)
		(end 288.371534 -184.384442)
		(width 0.1143)
		(layer "F.Cu")
		(net "MEMA_9")
	)
	(segment
		(start 285.58744 -200.824338)
		(end 285.58744 -200.25106)
		(width 0.1143)
		(layer "F.Cu")
		(net "MEMA_9")
	)
	(via
		(at 283.8704 -199.898)
		(size 0.7112)
		(drill 0.3556)
		(layers "F.Cu" "B.Cu")
		(net "MEMA_9")
	)
	(via
		(at 285.622238 -186.47156)
		(size 0.508)
		(drill 0.254)
		(layers "F.Cu" "B.Cu")
		(net "MEMA_9")
	)
	(via
		(at 285.58744 -200.25106)
		(size 0.508)
		(drill 0.254)
		(layers "F.Cu" "B.Cu")
		(net "MEMA_9")
	)
	(segment
		(start 283.44495 -199.47255)
		(end 283.8704 -199.898)
		(width 0.1143)
		(layer "B.Cu")
		(net "MEMA_9")
	)
	(segment
		(start 283.88945 -199.978264)
		(end 284.14599 -200.234804)
		(width 0.1143)
		(layer "B.Cu")
		(net "MEMA_9")
	)
	(segment
		(start 282.84805 -198.36765)
		(end 283.16555 -198.68515)
		(width 0.1143)
		(layer "B.Cu")
		(net "MEMA_9")
	)
	(segment
		(start 285.53918 -200.2028)
		(end 285.58744 -200.25106)
		(width 0.1143)
		(layer "B.Cu")
		(net "MEMA_9")
	)
	(segment
		(start 283.42209 -199.47255)
		(end 283.44495 -199.47255)
		(width 0.1143)
		(layer "B.Cu")
		(net "MEMA_9")
	)
	(segment
		(start 283.16555 -199.21601)
		(end 283.42209 -199.47255)
		(width 0.1143)
		(layer "B.Cu")
		(net "MEMA_9")
	)
	(segment
		(start 282.8671 -188.947044)
		(end 282.8671 -194.250056)
		(width 0.1143)
		(layer "B.Cu")
		(net "MEMA_9")
	)
	(segment
		(start 282.8798 -194.262756)
		(end 282.8798 -194.399662)
		(width 0.1143)
		(layer "B.Cu")
		(net "MEMA_9")
	)
	(segment
		(start 282.84805 -194.431412)
		(end 282.84805 -198.36765)
		(width 0.1143)
		(layer "B.Cu")
		(net "MEMA_9")
	)
	(segment
		(start 285.622238 -186.47156)
		(end 285.342584 -186.47156)
		(width 0.1143)
		(layer "B.Cu")
		(net "MEMA_9")
	)
	(segment
		(start 285.342584 -186.47156)
		(end 282.8671 -188.947044)
		(width 0.1143)
		(layer "B.Cu")
		(net "MEMA_9")
	)
	(segment
		(start 283.88945 -199.91705)
		(end 283.88945 -199.978264)
		(width 0.1143)
		(layer "B.Cu")
		(net "MEMA_9")
	)
	(segment
		(start 284.50921 -200.234804)
		(end 284.541214 -200.2028)
		(width 0.1143)
		(layer "B.Cu")
		(net "MEMA_9")
	)
	(segment
		(start 284.14599 -200.234804)
		(end 284.50921 -200.234804)
		(width 0.1143)
		(layer "B.Cu")
		(net "MEMA_9")
	)
	(segment
		(start 284.541214 -200.2028)
		(end 285.53918 -200.2028)
		(width 0.1143)
		(layer "B.Cu")
		(net "MEMA_9")
	)
	(segment
		(start 282.8671 -194.250056)
		(end 282.8798 -194.262756)
		(width 0.1143)
		(layer "B.Cu")
		(net "MEMA_9")
	)
	(segment
		(start 283.16555 -198.68515)
		(end 283.16555 -199.21601)
		(width 0.1143)
		(layer "B.Cu")
		(net "MEMA_9")
	)
	(segment
		(start 282.8798 -194.399662)
		(end 282.84805 -194.431412)
		(width 0.1143)
		(layer "B.Cu")
		(net "MEMA_9")
	)
	(segment
		(start 283.8704 -199.898)
		(end 283.88945 -199.91705)
		(width 0.1143)
		(layer "B.Cu")
		(net "MEMA_9")
	)
	(segment
		(start 44.999656 -253.025148)
		(end 37.583364 -245.608856)
		(width 0.1143)
		(layer "F.Cu")
		(net "SAS_HDD_PWR2_PCIE")
	)
	(segment
		(start 37.583364 -233.289856)
		(end 35.052508 -230.759)
		(width 0.1143)
		(layer "F.Cu")
		(net "SAS_HDD_PWR2_PCIE")
	)
	(segment
		(start 37.583364 -245.608856)
		(end 37.583364 -233.289856)
		(width 0.1143)
		(layer "F.Cu")
		(net "SAS_HDD_PWR2_PCIE")
	)
	(segment
		(start 35.052508 -230.759)
		(end 31.623 -230.759)
		(width 0.1143)
		(layer "F.Cu")
		(net "SAS_HDD_PWR2_PCIE")
	)
	(segment
		(start 44.999656 -256.25044)
		(end 44.999656 -253.025148)
		(width 0.1143)
		(layer "F.Cu")
		(net "SAS_HDD_PWR2_PCIE")
	)
	(segment
		(start 28.969716 -236.84738)
		(end 28.969716 -234.19308)
		(width 0.1143)
		(layer "F.Cu")
		(net "SAS_HDD_PWR2_PCIE")
	)
	(segment
		(start 28.969716 -233.412284)
		(end 28.969716 -234.19308)
		(width 0.1143)
		(layer "F.Cu")
		(net "SAS_HDD_PWR2_PCIE")
	)
	(segment
		(start 31.623 -230.759)
		(end 28.969716 -233.412284)
		(width 0.1143)
		(layer "F.Cu")
		(net "SAS_HDD_PWR2_PCIE")
	)
	(via
		(at 27.382216 -233.86288)
		(size 0.7112)
		(drill 0.3556)
		(layers "F.Cu" "B.Cu")
		(net "SAS_HDD_PWR2_PCIE")
	)
	(via
		(at 28.969716 -236.84738)
		(size 0.5588)
		(drill 0.3048)
		(layers "F.Cu" "B.Cu")
		(net "SAS_HDD_PWR2_PCIE")
	)
	(segment
		(start 27.382216 -234.49788)
		(end 28.823666 -235.93933)
		(width 0.1143)
		(layer "B.Cu")
		(net "SAS_HDD_PWR2_PCIE")
	)
	(segment
		(start 27.382216 -233.86288)
		(end 27.382216 -232.78338)
		(width 0.1143)
		(layer "B.Cu")
		(net "SAS_HDD_PWR2_PCIE")
	)
	(segment
		(start 28.823666 -236.70133)
		(end 28.969716 -236.84738)
		(width 0.1143)
		(layer "B.Cu")
		(net "SAS_HDD_PWR2_PCIE")
	)
	(segment
		(start 28.823666 -235.93933)
		(end 28.823666 -236.70133)
		(width 0.1143)
		(layer "B.Cu")
		(net "SAS_HDD_PWR2_PCIE")
	)
	(segment
		(start 27.382216 -233.86288)
		(end 27.382216 -234.49788)
		(width 0.1143)
		(layer "B.Cu")
		(net "SAS_HDD_PWR2_PCIE")
	)
	(segment
		(start 182.565802 -27.377136)
		(end 182.565802 -25.70861)
		(width 0.1778)
		(layer "F.Cu")
		(net "PHY_FDX")
	)
	(segment
		(start 182.934864 -22.995636)
		(end 182.934864 -24.569928)
		(width 0.1778)
		(layer "F.Cu")
		(net "PHY_FDX")
	)
	(segment
		(start 182.565802 -25.70861)
		(end 182.485792 -25.6286)
		(width 0.1778)
		(layer "F.Cu")
		(net "PHY_FDX")
	)
	(segment
		(start 182.934864 -24.569928)
		(end 182.485792 -25.019)
		(width 0.1778)
		(layer "F.Cu")
		(net "PHY_FDX")
	)
	(segment
		(start 182.485792 -25.019)
		(end 182.485792 -25.6286)
		(width 0.1778)
		(layer "F.Cu")
		(net "PHY_FDX")
	)
	(via
		(at 182.485792 -25.6286)
		(size 0.7112)
		(drill 0.3556)
		(layers "F.Cu" "B.Cu")
		(net "PHY_FDX")
	)
	(segment
		(start 186.879992 -26.035)
		(end 186.065922 -26.84907)
		(width 0.1143)
		(layer "F.Cu")
		(net "RMII_PHY_BMC_RXD0_R")
	)
	(segment
		(start 188.595 -25.273)
		(end 189.4205 -25.273)
		(width 0.1143)
		(layer "F.Cu")
		(net "RMII_PHY_BMC_RXD0_R")
	)
	(segment
		(start 188.341 -25.527)
		(end 187.833 -26.035)
		(width 0.1143)
		(layer "F.Cu")
		(net "RMII_PHY_BMC_RXD0_R")
	)
	(segment
		(start 187.833 -26.035)
		(end 186.879992 -26.035)
		(width 0.1143)
		(layer "F.Cu")
		(net "RMII_PHY_BMC_RXD0_R")
	)
	(segment
		(start 186.065922 -26.84907)
		(end 186.065922 -27.250136)
		(width 0.1143)
		(layer "F.Cu")
		(net "RMII_PHY_BMC_RXD0_R")
	)
	(segment
		(start 188.341 -25.527)
		(end 188.595 -25.273)
		(width 0.1143)
		(layer "F.Cu")
		(net "RMII_PHY_BMC_RXD0_R")
	)
	(via
		(at 188.341 -25.527)
		(size 0.7112)
		(drill 0.3556)
		(layers "F.Cu" "B.Cu")
		(net "RMII_PHY_BMC_RXD0_R")
	)
	(segment
		(start 286.844232 -173.449488)
		(end 286.844232 -173.439836)
		(width 0.1143)
		(layer "F.Cu")
		(net "BMC0_SMB2_CLK")
	)
	(segment
		(start 287.234884 -173.84014)
		(end 286.844232 -173.449488)
		(width 0.1143)
		(layer "F.Cu")
		(net "BMC0_SMB2_CLK")
	)
	(segment
		(start 286.844232 -173.439836)
		(end 286.836612 -173.432216)
		(width 0.1143)
		(layer "F.Cu")
		(net "BMC0_SMB2_CLK")
	)
	(via
		(at 286.836612 -173.432216)
		(size 0.508)
		(drill 0.254)
		(layers "F.Cu" "B.Cu")
		(net "BMC0_SMB2_CLK")
	)
	(via
		(at 275.59 -169.545)
		(size 0.7112)
		(drill 0.3556)
		(layers "F.Cu" "B.Cu")
		(net "BMC0_SMB2_CLK")
	)
	(segment
		(start 284.464506 -174.114206)
		(end 284.122114 -174.114206)
		(width 0.1143)
		(layer "B.Cu")
		(net "BMC0_SMB2_CLK")
	)
	(segment
		(start 286.836612 -173.432216)
		(end 285.146496 -173.432216)
		(width 0.1143)
		(layer "B.Cu")
		(net "BMC0_SMB2_CLK")
	)
	(segment
		(start 275.59 -169.545)
		(end 274.6375 -169.545)
		(width 0.1143)
		(layer "B.Cu")
		(net "BMC0_SMB2_CLK")
	)
	(segment
		(start 280.383488 -173.4439)
		(end 278.402288 -171.4627)
		(width 0.1143)
		(layer "B.Cu")
		(net "BMC0_SMB2_CLK")
	)
	(segment
		(start 277.5077 -171.4627)
		(end 275.59 -169.545)
		(width 0.1143)
		(layer "B.Cu")
		(net "BMC0_SMB2_CLK")
	)
	(segment
		(start 278.402288 -171.4627)
		(end 277.5077 -171.4627)
		(width 0.1143)
		(layer "B.Cu")
		(net "BMC0_SMB2_CLK")
	)
	(segment
		(start 283.451808 -173.4439)
		(end 280.383488 -173.4439)
		(width 0.1143)
		(layer "B.Cu")
		(net "BMC0_SMB2_CLK")
	)
	(segment
		(start 285.146496 -173.432216)
		(end 284.464506 -174.114206)
		(width 0.1143)
		(layer "B.Cu")
		(net "BMC0_SMB2_CLK")
	)
	(segment
		(start 284.122114 -174.114206)
		(end 283.451808 -173.4439)
		(width 0.1143)
		(layer "B.Cu")
		(net "BMC0_SMB2_CLK")
	)
	(segment
		(start 177.862992 -21.017992)
		(end 177.862992 -25.273)
		(width 0.1143)
		(layer "F.Cu")
		(net "PHY_ACTLED_N")
	)
	(segment
		(start 169.418 -14.605)
		(end 170.053 -15.24)
		(width 0.1143)
		(layer "F.Cu")
		(net "PHY_ACTLED_N")
	)
	(segment
		(start 178.987196 -28.556204)
		(end 179.886864 -28.556204)
		(width 0.1143)
		(layer "F.Cu")
		(net "PHY_ACTLED_N")
	)
	(segment
		(start 172.085 -15.24)
		(end 177.292 -20.447)
		(width 0.1143)
		(layer "F.Cu")
		(net "PHY_ACTLED_N")
	)
	(segment
		(start 151.74214 -8.255)
		(end 163.511992 -8.255)
		(width 0.1143)
		(layer "F.Cu")
		(net "PHY_ACTLED_N")
	)
	(segment
		(start 177.862992 -25.273)
		(end 178.116992 -25.527)
		(width 0.1143)
		(layer "F.Cu")
		(net "PHY_ACTLED_N")
	)
	(segment
		(start 163.765992 -8.509)
		(end 167.626284 -8.509)
		(width 0.1143)
		(layer "F.Cu")
		(net "PHY_ACTLED_N")
	)
	(segment
		(start 177.292 -20.447)
		(end 177.862992 -21.017992)
		(width 0.1143)
		(layer "F.Cu")
		(net "PHY_ACTLED_N")
	)
	(segment
		(start 149.94001 -4.860036)
		(end 149.94001 -6.45287)
		(width 0.1143)
		(layer "F.Cu")
		(net "PHY_ACTLED_N")
	)
	(segment
		(start 149.94001 -6.45287)
		(end 151.74214 -8.255)
		(width 0.1143)
		(layer "F.Cu")
		(net "PHY_ACTLED_N")
	)
	(segment
		(start 163.511992 -8.255)
		(end 163.765992 -8.509)
		(width 0.1143)
		(layer "F.Cu")
		(net "PHY_ACTLED_N")
	)
	(segment
		(start 178.116992 -27.686)
		(end 178.987196 -28.556204)
		(width 0.1143)
		(layer "F.Cu")
		(net "PHY_ACTLED_N")
	)
	(segment
		(start 169.418 -10.300716)
		(end 169.418 -14.605)
		(width 0.1143)
		(layer "F.Cu")
		(net "PHY_ACTLED_N")
	)
	(segment
		(start 178.116992 -25.527)
		(end 178.116992 -27.686)
		(width 0.1143)
		(layer "F.Cu")
		(net "PHY_ACTLED_N")
	)
	(segment
		(start 167.626284 -8.509)
		(end 169.418 -10.300716)
		(width 0.1143)
		(layer "F.Cu")
		(net "PHY_ACTLED_N")
	)
	(segment
		(start 170.053 -15.24)
		(end 172.085 -15.24)
		(width 0.1143)
		(layer "F.Cu")
		(net "PHY_ACTLED_N")
	)
	(via
		(at 177.292 -20.447)
		(size 0.7112)
		(drill 0.3556)
		(layers "F.Cu" "B.Cu")
		(net "PHY_ACTLED_N")
	)
	(segment
		(start 19.5453 -237.746032)
		(end 19.5453 -233.525314)
		(width 0.1143)
		(layer "F.Cu")
		(net "SAS_HDD_PWR14_PCIE")
	)
	(segment
		(start 15.30858 -236.013244)
		(end 15.30858 -234.184952)
		(width 0.1143)
		(layer "F.Cu")
		(net "SAS_HDD_PWR14_PCIE")
	)
	(segment
		(start 15.795498 -232.870502)
		(end 15.30858 -233.35742)
		(width 0.1143)
		(layer "F.Cu")
		(net "SAS_HDD_PWR14_PCIE")
	)
	(segment
		(start 18.890488 -232.870502)
		(end 15.795498 -232.870502)
		(width 0.1143)
		(layer "F.Cu")
		(net "SAS_HDD_PWR14_PCIE")
	)
	(segment
		(start 31.000446 -249.201178)
		(end 19.5453 -237.746032)
		(width 0.1143)
		(layer "F.Cu")
		(net "SAS_HDD_PWR14_PCIE")
	)
	(segment
		(start 19.5453 -233.525314)
		(end 18.890488 -232.870502)
		(width 0.1143)
		(layer "F.Cu")
		(net "SAS_HDD_PWR14_PCIE")
	)
	(segment
		(start 15.30858 -233.35742)
		(end 15.30858 -234.184952)
		(width 0.1143)
		(layer "F.Cu")
		(net "SAS_HDD_PWR14_PCIE")
	)
	(segment
		(start 31.000446 -256.25044)
		(end 31.000446 -249.201178)
		(width 0.1143)
		(layer "F.Cu")
		(net "SAS_HDD_PWR14_PCIE")
	)
	(via
		(at 15.30858 -233.38028)
		(size 0.7112)
		(drill 0.3556)
		(layers "F.Cu" "B.Cu")
		(net "SAS_HDD_PWR14_PCIE")
	)
	(via
		(at 15.30858 -236.013244)
		(size 0.5588)
		(drill 0.3048)
		(layers "F.Cu" "B.Cu")
		(net "SAS_HDD_PWR14_PCIE")
	)
	(segment
		(start 15.30858 -236.013244)
		(end 15.30858 -233.38028)
		(width 0.1143)
		(layer "B.Cu")
		(net "SAS_HDD_PWR14_PCIE")
	)
	(segment
		(start 15.30858 -232.584752)
		(end 15.30858 -233.38028)
		(width 0.1143)
		(layer "B.Cu")
		(net "SAS_HDD_PWR14_PCIE")
	)
	(segment
		(start 15.62608 -232.267252)
		(end 15.30858 -232.584752)
		(width 0.1143)
		(layer "B.Cu")
		(net "SAS_HDD_PWR14_PCIE")
	)
	(segment
		(start 180.565806 -35.016186)
		(end 180.275992 -35.306)
		(width 0.1143)
		(layer "F.Cu")
		(net "PHY_LOW_PWR")
	)
	(segment
		(start 177.854864 -37.727636)
		(end 177.854864 -36.711128)
		(width 0.1143)
		(layer "F.Cu")
		(net "PHY_LOW_PWR")
	)
	(segment
		(start 180.565806 -34.362136)
		(end 180.565806 -35.016186)
		(width 0.1143)
		(layer "F.Cu")
		(net "PHY_LOW_PWR")
	)
	(segment
		(start 179.259992 -35.306)
		(end 177.989992 -36.576)
		(width 0.1143)
		(layer "F.Cu")
		(net "PHY_LOW_PWR")
	)
	(segment
		(start 180.275992 -35.306)
		(end 179.259992 -35.306)
		(width 0.1143)
		(layer "F.Cu")
		(net "PHY_LOW_PWR")
	)
	(segment
		(start 177.854864 -36.711128)
		(end 177.989992 -36.576)
		(width 0.1143)
		(layer "F.Cu")
		(net "PHY_LOW_PWR")
	)
	(via
		(at 177.989992 -36.576)
		(size 0.7112)
		(drill 0.3556)
		(layers "F.Cu" "B.Cu")
		(net "PHY_LOW_PWR")
	)
	(segment
		(start 22.57298 -227.877116)
		(end 24.283162 -226.166934)
		(width 0.1143)
		(layer "F.Cu")
		(net "SAS_HDD_PWR15")
	)
	(segment
		(start 15.30858 -229.517956)
		(end 15.30858 -228.952552)
		(width 0.1143)
		(layer "F.Cu")
		(net "SAS_HDD_PWR15")
	)
	(segment
		(start 16.460216 -230.56088)
		(end 16.351504 -230.56088)
		(width 0.1143)
		(layer "F.Cu")
		(net "SAS_HDD_PWR15")
	)
	(segment
		(start 15.818612 -227.877116)
		(end 22.57298 -227.877116)
		(width 0.1143)
		(layer "F.Cu")
		(net "SAS_HDD_PWR15")
	)
	(segment
		(start 15.317216 -228.943916)
		(end 15.317216 -228.378512)
		(width 0.1143)
		(layer "F.Cu")
		(net "SAS_HDD_PWR15")
	)
	(segment
		(start 15.317216 -228.378512)
		(end 15.818612 -227.877116)
		(width 0.1143)
		(layer "F.Cu")
		(net "SAS_HDD_PWR15")
	)
	(segment
		(start 15.30858 -228.952552)
		(end 15.317216 -228.943916)
		(width 0.1143)
		(layer "F.Cu")
		(net "SAS_HDD_PWR15")
	)
	(segment
		(start 24.283162 -222.325438)
		(end 24.283162 -226.166934)
		(width 0.1143)
		(layer "F.Cu")
		(net "SAS_HDD_PWR15")
	)
	(segment
		(start 16.351504 -230.56088)
		(end 15.30858 -229.517956)
		(width 0.1143)
		(layer "F.Cu")
		(net "SAS_HDD_PWR15")
	)
	(via
		(at 16.460216 -230.56088)
		(size 0.5588)
		(drill 0.3048)
		(layers "F.Cu" "B.Cu")
		(net "SAS_HDD_PWR15")
	)
	(via
		(at 24.283162 -226.166934)
		(size 0.7112)
		(drill 0.3556)
		(layers "F.Cu" "B.Cu")
		(net "SAS_HDD_PWR15")
	)
	(segment
		(start 16.460216 -231.069388)
		(end 16.460216 -230.56088)
		(width 0.1143)
		(layer "B.Cu")
		(net "SAS_HDD_PWR15")
	)
	(segment
		(start 16.76908 -231.378252)
		(end 16.460216 -231.069388)
		(width 0.1143)
		(layer "B.Cu")
		(net "SAS_HDD_PWR15")
	)
	(segment
		(start 188.756798 -29.556202)
		(end 188.976 -29.337)
		(width 0.1778)
		(layer "F.Cu")
		(net "PHY_TX_ER_PD")
	)
	(segment
		(start 191.253364 -29.663136)
		(end 190.927228 -29.337)
		(width 0.1778)
		(layer "F.Cu")
		(net "PHY_TX_ER_PD")
	)
	(segment
		(start 186.744864 -29.556202)
		(end 188.756798 -29.556202)
		(width 0.1778)
		(layer "F.Cu")
		(net "PHY_TX_ER_PD")
	)
	(segment
		(start 190.927228 -29.337)
		(end 188.976 -29.337)
		(width 0.1778)
		(layer "F.Cu")
		(net "PHY_TX_ER_PD")
	)
	(via
		(at 188.976 -29.337)
		(size 0.7112)
		(drill 0.3556)
		(layers "F.Cu" "B.Cu")
		(net "PHY_TX_ER_PD")
	)
	(segment
		(start 291.298122 -196.647308)
		(end 290.859972 -196.209158)
		(width 0.1143)
		(layer "F.Cu")
		(net "MEMDQ_6")
	)
	(segment
		(start 293.634922 -181.040024)
		(end 293.233856 -181.44109)
		(width 0.1143)
		(layer "F.Cu")
		(net "MEMDQ_6")
	)
	(segment
		(start 289.9664 -194.9196)
		(end 290.2458 -194.6402)
		(width 0.1143)
		(layer "F.Cu")
		(net "MEMDQ_6")
	)
	(segment
		(start 290.859972 -195.98513)
		(end 290.648136 -195.773294)
		(width 0.1143)
		(layer "F.Cu")
		(net "MEMDQ_6")
	)
	(segment
		(start 290.859972 -196.209158)
		(end 290.859972 -195.98513)
		(width 0.1143)
		(layer "F.Cu")
		(net "MEMDQ_6")
	)
	(segment
		(start 293.233856 -181.44109)
		(end 293.226236 -181.44109)
		(width 0.1143)
		(layer "F.Cu")
		(net "MEMDQ_6")
	)
	(segment
		(start 290.2458 -194.6402)
		(end 291.1348 -194.6402)
		(width 0.1143)
		(layer "F.Cu")
		(net "MEMDQ_6")
	)
	(segment
		(start 290.648136 -195.773294)
		(end 290.388294 -195.773294)
		(width 0.1143)
		(layer "F.Cu")
		(net "MEMDQ_6")
	)
	(segment
		(start 290.388294 -195.773294)
		(end 289.9664 -195.3514)
		(width 0.1143)
		(layer "F.Cu")
		(net "MEMDQ_6")
	)
	(segment
		(start 291.298122 -196.93509)
		(end 291.298122 -196.647308)
		(width 0.1143)
		(layer "F.Cu")
		(net "MEMDQ_6")
	)
	(segment
		(start 289.9664 -195.3514)
		(end 289.9664 -194.9196)
		(width 0.1143)
		(layer "F.Cu")
		(net "MEMDQ_6")
	)
	(via
		(at 291.1348 -194.6402)
		(size 0.508)
		(drill 0.254)
		(layers "F.Cu" "B.Cu")
		(net "MEMDQ_6")
	)
	(via
		(at 293.27094 -180.68036)
		(size 0.7112)
		(drill 0.3556)
		(layers "F.Cu" "B.Cu")
		(net "MEMDQ_6")
	)
	(via
		(at 293.226236 -181.44109)
		(size 0.508)
		(drill 0.254)
		(layers "F.Cu" "B.Cu")
		(net "MEMDQ_6")
	)
	(segment
		(start 293.226236 -180.725064)
		(end 293.27094 -180.68036)
		(width 0.1143)
		(layer "B.Cu")
		(net "MEMDQ_6")
	)
	(segment
		(start 293.226236 -181.44109)
		(end 293.226236 -180.725064)
		(width 0.1143)
		(layer "B.Cu")
		(net "MEMDQ_6")
	)
	(segment
		(start 293.226236 -181.44109)
		(end 293.53129 -181.44109)
		(width 0.1016)
		(layer "In5.Cu")
		(net "MEMDQ_6")
	)
	(segment
		(start 290.9951 -185.21045)
		(end 290.9951 -185.57875)
		(width 0.127)
		(layer "In5.Cu")
		(net "MEMDQ_6")
	)
	(segment
		(start 293.63162 -182.408576)
		(end 293.16426 -182.875936)
		(width 0.1016)
		(layer "In5.Cu")
		(net "MEMDQ_6")
	)
	(segment
		(start 290.13912 -189.859158)
		(end 289.83813 -190.160148)
		(width 0.127)
		(layer "In5.Cu")
		(net "MEMDQ_6")
	)
	(segment
		(start 290.9951 -185.57875)
		(end 290.13912 -186.43473)
		(width 0.127)
		(layer "In5.Cu")
		(net "MEMDQ_6")
	)
	(segment
		(start 293.63162 -181.54142)
		(end 293.63162 -182.408576)
		(width 0.1016)
		(layer "In5.Cu")
		(net "MEMDQ_6")
	)
	(segment
		(start 290.13912 -186.43473)
		(end 290.13912 -189.859158)
		(width 0.127)
		(layer "In5.Cu")
		(net "MEMDQ_6")
	)
	(segment
		(start 293.53129 -181.44109)
		(end 293.63162 -181.54142)
		(width 0.1016)
		(layer "In5.Cu")
		(net "MEMDQ_6")
	)
	(segment
		(start 289.83813 -194.48653)
		(end 289.9918 -194.6402)
		(width 0.127)
		(layer "In5.Cu")
		(net "MEMDQ_6")
	)
	(segment
		(start 293.16426 -183.04129)
		(end 290.9951 -185.21045)
		(width 0.127)
		(layer "In5.Cu")
		(net "MEMDQ_6")
	)
	(segment
		(start 293.16426 -182.875936)
		(end 293.16426 -183.04129)
		(width 0.1016)
		(layer "In5.Cu")
		(net "MEMDQ_6")
	)
	(segment
		(start 289.83813 -190.160148)
		(end 289.83813 -194.48653)
		(width 0.127)
		(layer "In5.Cu")
		(net "MEMDQ_6")
	)
	(segment
		(start 289.9918 -194.6402)
		(end 291.1348 -194.6402)
		(width 0.127)
		(layer "In5.Cu")
		(net "MEMDQ_6")
	)
	(segment
		(start 30.46095 -249.182636)
		(end 19.177 -237.898686)
		(width 0.1143)
		(layer "F.Cu")
		(net "SAS_HDD_PWR15_PCIE")
	)
	(segment
		(start 16.062198 -233.238802)
		(end 15.94358 -233.35742)
		(width 0.1143)
		(layer "F.Cu")
		(net "SAS_HDD_PWR15_PCIE")
	)
	(segment
		(start 29.999686 -256.25044)
		(end 29.999686 -253.337314)
		(width 0.1143)
		(layer "F.Cu")
		(net "SAS_HDD_PWR15_PCIE")
	)
	(segment
		(start 19.177 -237.898686)
		(end 19.177 -233.677968)
		(width 0.1143)
		(layer "F.Cu")
		(net "SAS_HDD_PWR15_PCIE")
	)
	(segment
		(start 30.46095 -252.87605)
		(end 30.46095 -249.182636)
		(width 0.1143)
		(layer "F.Cu")
		(net "SAS_HDD_PWR15_PCIE")
	)
	(segment
		(start 15.94358 -233.35742)
		(end 15.94358 -234.184952)
		(width 0.1143)
		(layer "F.Cu")
		(net "SAS_HDD_PWR15_PCIE")
	)
	(segment
		(start 18.737834 -233.238802)
		(end 16.062198 -233.238802)
		(width 0.1143)
		(layer "F.Cu")
		(net "SAS_HDD_PWR15_PCIE")
	)
	(segment
		(start 29.999686 -253.337314)
		(end 30.46095 -252.87605)
		(width 0.1143)
		(layer "F.Cu")
		(net "SAS_HDD_PWR15_PCIE")
	)
	(segment
		(start 15.94358 -236.902244)
		(end 15.94358 -234.184952)
		(width 0.1143)
		(layer "F.Cu")
		(net "SAS_HDD_PWR15_PCIE")
	)
	(segment
		(start 19.177 -233.677968)
		(end 18.737834 -233.238802)
		(width 0.1143)
		(layer "F.Cu")
		(net "SAS_HDD_PWR15_PCIE")
	)
	(via
		(at 15.94358 -236.902244)
		(size 0.5588)
		(drill 0.3048)
		(layers "F.Cu" "B.Cu")
		(net "SAS_HDD_PWR15_PCIE")
	)
	(via
		(at 15.94358 -235.3056)
		(size 0.7112)
		(drill 0.3556)
		(layers "F.Cu" "B.Cu")
		(net "SAS_HDD_PWR15_PCIE")
	)
	(segment
		(start 15.94358 -233.092752)
		(end 16.76908 -232.267252)
		(width 0.1143)
		(layer "B.Cu")
		(net "SAS_HDD_PWR15_PCIE")
	)
	(segment
		(start 15.94358 -235.3056)
		(end 15.94358 -233.092752)
		(width 0.1143)
		(layer "B.Cu")
		(net "SAS_HDD_PWR15_PCIE")
	)
	(segment
		(start 15.94358 -236.902244)
		(end 15.94358 -235.3056)
		(width 0.1143)
		(layer "B.Cu")
		(net "SAS_HDD_PWR15_PCIE")
	)
	(segment
		(start 180.529992 -37.338508)
		(end 180.529992 -36.576)
		(width 0.127)
		(layer "F.Cu")
		(net "PHY_AD4")
	)
	(segment
		(start 181.565804 -35.413188)
		(end 180.529992 -36.449)
		(width 0.127)
		(layer "F.Cu")
		(net "PHY_AD4")
	)
	(segment
		(start 181.565804 -34.235136)
		(end 181.565804 -35.413188)
		(width 0.127)
		(layer "F.Cu")
		(net "PHY_AD4")
	)
	(segment
		(start 180.140864 -37.727636)
		(end 180.529992 -37.338508)
		(width 0.127)
		(layer "F.Cu")
		(net "PHY_AD4")
	)
	(segment
		(start 180.529992 -36.449)
		(end 180.529992 -36.576)
		(width 0.127)
		(layer "F.Cu")
		(net "PHY_AD4")
	)
	(via
		(at 180.529992 -36.576)
		(size 0.7112)
		(drill 0.3556)
		(layers "F.Cu" "B.Cu")
		(net "PHY_AD4")
	)
	(segment
		(start 288.034984 -173.84014)
		(end 287.641284 -173.44644)
		(width 0.1143)
		(layer "F.Cu")
		(net "BMC0_SMB2_DAT")
	)
	(segment
		(start 287.641284 -173.44644)
		(end 287.638236 -173.44644)
		(width 0.1143)
		(layer "F.Cu")
		(net "BMC0_SMB2_DAT")
	)
	(via
		(at 276.352 -171.958)
		(size 0.7112)
		(drill 0.3556)
		(layers "F.Cu" "B.Cu")
		(net "BMC0_SMB2_DAT")
	)
	(via
		(at 287.638236 -173.44644)
		(size 0.508)
		(drill 0.254)
		(layers "F.Cu" "B.Cu")
		(net "BMC0_SMB2_DAT")
	)
	(segment
		(start 285.849822 -173.831758)
		(end 285.83636 -173.84522)
		(width 0.0889)
		(layer "B.Cu")
		(net "BMC0_SMB2_DAT")
	)
	(segment
		(start 284.022038 -174.355506)
		(end 283.605732 -173.9392)
		(width 0.1143)
		(layer "B.Cu")
		(net "BMC0_SMB2_DAT")
	)
	(segment
		(start 285.83636 -173.84522)
		(end 285.074868 -173.84522)
		(width 0.1143)
		(layer "B.Cu")
		(net "BMC0_SMB2_DAT")
	)
	(segment
		(start 285.074868 -173.84522)
		(end 284.564582 -174.355506)
		(width 0.1143)
		(layer "B.Cu")
		(net "BMC0_SMB2_DAT")
	)
	(segment
		(start 284.564582 -174.355506)
		(end 284.022038 -174.355506)
		(width 0.1143)
		(layer "B.Cu")
		(net "BMC0_SMB2_DAT")
	)
	(segment
		(start 283.605732 -173.9392)
		(end 280.178256 -173.9392)
		(width 0.1143)
		(layer "B.Cu")
		(net "BMC0_SMB2_DAT")
	)
	(segment
		(start 286.218122 -173.832266)
		(end 286.217614 -173.831758)
		(width 0.0889)
		(layer "B.Cu")
		(net "BMC0_SMB2_DAT")
	)
	(segment
		(start 287.25241 -173.832266)
		(end 286.218122 -173.832266)
		(width 0.0889)
		(layer "B.Cu")
		(net "BMC0_SMB2_DAT")
	)
	(segment
		(start 274.701 -172.593)
		(end 275.336 -171.958)
		(width 0.1143)
		(layer "B.Cu")
		(net "BMC0_SMB2_DAT")
	)
	(segment
		(start 275.336 -171.958)
		(end 276.352 -171.958)
		(width 0.1143)
		(layer "B.Cu")
		(net "BMC0_SMB2_DAT")
	)
	(segment
		(start 286.217614 -173.831758)
		(end 285.849822 -173.831758)
		(width 0.0889)
		(layer "B.Cu")
		(net "BMC0_SMB2_DAT")
	)
	(segment
		(start 278.197056 -171.958)
		(end 276.352 -171.958)
		(width 0.1143)
		(layer "B.Cu")
		(net "BMC0_SMB2_DAT")
	)
	(segment
		(start 274.6375 -172.593)
		(end 274.701 -172.593)
		(width 0.1143)
		(layer "B.Cu")
		(net "BMC0_SMB2_DAT")
	)
	(segment
		(start 287.638236 -173.44644)
		(end 287.25241 -173.832266)
		(width 0.0889)
		(layer "B.Cu")
		(net "BMC0_SMB2_DAT")
	)
	(segment
		(start 280.178256 -173.9392)
		(end 278.197056 -171.958)
		(width 0.1143)
		(layer "B.Cu")
		(net "BMC0_SMB2_DAT")
	)
	(segment
		(start 189.4205 -24.003)
		(end 187.325 -24.003)
		(width 0.1143)
		(layer "F.Cu")
		(net "RMII_PHY_BMC_RXD1_R")
	)
	(segment
		(start 185.550048 -27.361388)
		(end 185.565796 -27.377136)
		(width 0.1143)
		(layer "F.Cu")
		(net "RMII_PHY_BMC_RXD1_R")
	)
	(segment
		(start 186.436 -25.589992)
		(end 185.550048 -26.475944)
		(width 0.1143)
		(layer "F.Cu")
		(net "RMII_PHY_BMC_RXD1_R")
	)
	(segment
		(start 185.550048 -26.475944)
		(end 185.550048 -27.361388)
		(width 0.1143)
		(layer "F.Cu")
		(net "RMII_PHY_BMC_RXD1_R")
	)
	(segment
		(start 187.325 -24.003)
		(end 186.563 -24.765)
		(width 0.1143)
		(layer "F.Cu")
		(net "RMII_PHY_BMC_RXD1_R")
	)
	(segment
		(start 186.436 -24.892)
		(end 186.436 -25.589992)
		(width 0.1143)
		(layer "F.Cu")
		(net "RMII_PHY_BMC_RXD1_R")
	)
	(segment
		(start 186.563 -24.765)
		(end 186.436 -24.892)
		(width 0.1143)
		(layer "F.Cu")
		(net "RMII_PHY_BMC_RXD1_R")
	)
	(via
		(at 186.563 -24.765)
		(size 0.7112)
		(drill 0.3556)
		(layers "F.Cu" "B.Cu")
		(net "RMII_PHY_BMC_RXD1_R")
	)
	(segment
		(start 21.819616 -220.17228)
		(end 26.544524 -220.17228)
		(width 0.1143)
		(layer "F.Cu")
		(net "SAS_HDD_PWR2")
	)
	(segment
		(start 20.382992 -216.714578)
		(end 20.382992 -218.735656)
		(width 0.1143)
		(layer "F.Cu")
		(net "SAS_HDD_PWR2")
	)
	(segment
		(start 20.382992 -218.735656)
		(end 21.819616 -220.17228)
		(width 0.1143)
		(layer "F.Cu")
		(net "SAS_HDD_PWR2")
	)
	(segment
		(start 26.544524 -220.17228)
		(end 28.334716 -221.962472)
		(width 0.1143)
		(layer "F.Cu")
		(net "SAS_HDD_PWR2")
	)
	(segment
		(start 28.334716 -221.962472)
		(end 28.334716 -227.63988)
		(width 0.1143)
		(layer "F.Cu")
		(net "SAS_HDD_PWR2")
	)
	(segment
		(start 28.334716 -227.63988)
		(end 28.334716 -228.96068)
		(width 0.1143)
		(layer "F.Cu")
		(net "SAS_HDD_PWR2")
	)
	(via
		(at 28.334716 -227.63988)
		(size 0.5588)
		(drill 0.3048)
		(layers "F.Cu" "B.Cu")
		(net "SAS_HDD_PWR2")
	)
	(via
		(at 27.382216 -230.84028)
		(size 0.7112)
		(drill 0.3556)
		(layers "F.Cu" "B.Cu")
		(net "SAS_HDD_PWR2")
	)
	(segment
		(start 28.334716 -227.63988)
		(end 28.334716 -229.60838)
		(width 0.1143)
		(layer "B.Cu")
		(net "SAS_HDD_PWR2")
	)
	(segment
		(start 27.382216 -230.56088)
		(end 27.382216 -230.84028)
		(width 0.1143)
		(layer "B.Cu")
		(net "SAS_HDD_PWR2")
	)
	(segment
		(start 28.334716 -229.60838)
		(end 27.382216 -230.56088)
		(width 0.1143)
		(layer "B.Cu")
		(net "SAS_HDD_PWR2")
	)
	(segment
		(start 27.382216 -230.84028)
		(end 27.382216 -231.89438)
		(width 0.1143)
		(layer "B.Cu")
		(net "SAS_HDD_PWR2")
	)
	(segment
		(start 187.198 -22.86)
		(end 186.171586 -22.86)
		(width 0.1143)
		(layer "F.Cu")
		(net "RMII_BMC_MDC_R")
	)
	(segment
		(start 186.171586 -22.86)
		(end 183.586628 -25.444958)
		(width 0.1143)
		(layer "F.Cu")
		(net "RMII_BMC_MDC_R")
	)
	(segment
		(start 183.5658 -25.555956)
		(end 183.5658 -27.377136)
		(width 0.1143)
		(layer "F.Cu")
		(net "RMII_BMC_MDC_R")
	)
	(segment
		(start 187.198 -22.86)
		(end 187.579 -22.479)
		(width 0.1143)
		(layer "F.Cu")
		(net "RMII_BMC_MDC_R")
	)
	(segment
		(start 187.579 -22.479)
		(end 189.4205 -22.479)
		(width 0.1143)
		(layer "F.Cu")
		(net "RMII_BMC_MDC_R")
	)
	(segment
		(start 183.586628 -25.535128)
		(end 183.5658 -25.555956)
		(width 0.1143)
		(layer "F.Cu")
		(net "RMII_BMC_MDC_R")
	)
	(segment
		(start 183.586628 -25.444958)
		(end 183.586628 -25.535128)
		(width 0.1143)
		(layer "F.Cu")
		(net "RMII_BMC_MDC_R")
	)
	(segment
		(start 286.893254 -197.339966)
		(end 286.49803 -197.73519)
		(width 0.1143)
		(layer "F.Cu")
		(net "MEMA_1")
	)
	(segment
		(start 290.425378 -181.840124)
		(end 290.02736 -181.442106)
		(width 0.1143)
		(layer "F.Cu")
		(net "MEMA_1")
	)
	(segment
		(start 290.434776 -181.840124)
		(end 290.425378 -181.840124)
		(width 0.1143)
		(layer "F.Cu")
		(net "MEMA_1")
	)
	(via
		(at 287.757108 -189.5856)
		(size 0.7112)
		(drill 0.3556)
		(layers "F.Cu" "B.Cu")
		(net "MEMA_1")
	)
	(via
		(at 286.893254 -197.339966)
		(size 0.508)
		(drill 0.254)
		(layers "F.Cu" "B.Cu")
		(net "MEMA_1")
	)
	(via
		(at 290.02736 -181.442106)
		(size 0.508)
		(drill 0.254)
		(layers "F.Cu" "B.Cu")
		(net "MEMA_1")
	)
	(segment
		(start 287.9344 -187.385452)
		(end 287.9344 -187.024264)
		(width 0.1143)
		(layer "B.Cu")
		(net "MEMA_1")
	)
	(segment
		(start 288.33064 -183.879236)
		(end 288.33064 -182.221378)
		(width 0.1143)
		(layer "B.Cu")
		(net "MEMA_1")
	)
	(segment
		(start 286.6898 -192.386204)
		(end 286.8041 -192.500504)
		(width 0.1143)
		(layer "B.Cu")
		(net "MEMA_1")
	)
	(segment
		(start 286.8041 -192.500504)
		(end 287.16859 -192.500504)
		(width 0.1143)
		(layer "B.Cu")
		(net "MEMA_1")
	)
	(segment
		(start 287.9344 -188.740796)
		(end 287.9344 -188.427868)
		(width 0.1143)
		(layer "B.Cu")
		(net "MEMA_1")
	)
	(segment
		(start 287.934146 -187.385706)
		(end 287.9344 -187.385452)
		(width 0.1143)
		(layer "B.Cu")
		(net "MEMA_1")
	)
	(segment
		(start 287.1851 -196.270372)
		(end 287.1851 -197.04812)
		(width 0.1143)
		(layer "B.Cu")
		(net "MEMA_1")
	)
	(segment
		(start 287.28289 -191.929004)
		(end 287.16859 -192.043304)
		(width 0.1143)
		(layer "B.Cu")
		(net "MEMA_1")
	)
	(segment
		(start 289.408362 -181.03469)
		(end 289.815778 -181.442106)
		(width 0.1143)
		(layer "B.Cu")
		(net "MEMA_1")
	)
	(segment
		(start 286.6898 -193.300604)
		(end 286.8041 -193.414904)
		(width 0.1143)
		(layer "B.Cu")
		(net "MEMA_1")
	)
	(segment
		(start 286.6898 -193.072004)
		(end 286.6898 -193.300604)
		(width 0.1143)
		(layer "B.Cu")
		(net "MEMA_1")
	)
	(segment
		(start 287.933892 -188.42736)
		(end 287.933892 -188.080396)
		(width 0.1143)
		(layer "B.Cu")
		(net "MEMA_1")
	)
	(segment
		(start 287.28289 -193.84391)
		(end 286.81045 -194.31635)
		(width 0.1143)
		(layer "B.Cu")
		(net "MEMA_1")
	)
	(segment
		(start 287.28289 -191.040258)
		(end 287.28289 -191.929004)
		(width 0.1143)
		(layer "B.Cu")
		(net "MEMA_1")
	)
	(segment
		(start 286.8041 -192.957704)
		(end 286.6898 -193.072004)
		(width 0.1143)
		(layer "B.Cu")
		(net "MEMA_1")
	)
	(segment
		(start 287.9344 -188.427868)
		(end 287.933892 -188.42736)
		(width 0.1143)
		(layer "B.Cu")
		(net "MEMA_1")
	)
	(segment
		(start 287.757108 -189.5856)
		(end 287.757108 -188.918088)
		(width 0.1143)
		(layer "B.Cu")
		(net "MEMA_1")
	)
	(segment
		(start 286.8041 -193.414904)
		(end 287.16859 -193.414904)
		(width 0.1143)
		(layer "B.Cu")
		(net "MEMA_1")
	)
	(segment
		(start 287.934146 -188.080142)
		(end 287.934146 -187.385706)
		(width 0.1143)
		(layer "B.Cu")
		(net "MEMA_1")
	)
	(segment
		(start 287.2232 -195.336414)
		(end 287.2232 -196.232272)
		(width 0.1143)
		(layer "B.Cu")
		(net "MEMA_1")
	)
	(segment
		(start 286.6898 -192.157604)
		(end 286.6898 -192.386204)
		(width 0.1143)
		(layer "B.Cu")
		(net "MEMA_1")
	)
	(segment
		(start 287.757108 -190.56604)
		(end 287.28289 -191.040258)
		(width 0.1143)
		(layer "B.Cu")
		(net "MEMA_1")
	)
	(segment
		(start 287.933892 -188.080396)
		(end 287.934146 -188.080142)
		(width 0.1143)
		(layer "B.Cu")
		(net "MEMA_1")
	)
	(segment
		(start 287.16859 -193.414904)
		(end 287.28289 -193.529204)
		(width 0.1143)
		(layer "B.Cu")
		(net "MEMA_1")
	)
	(segment
		(start 288.824416 -181.276244)
		(end 289.06597 -181.03469)
		(width 0.1143)
		(layer "B.Cu")
		(net "MEMA_1")
	)
	(segment
		(start 288.824416 -181.727602)
		(end 288.824416 -181.276244)
		(width 0.1143)
		(layer "B.Cu")
		(net "MEMA_1")
	)
	(segment
		(start 289.06597 -181.03469)
		(end 289.408362 -181.03469)
		(width 0.1143)
		(layer "B.Cu")
		(net "MEMA_1")
	)
	(segment
		(start 289.815778 -181.442106)
		(end 290.02736 -181.442106)
		(width 0.1143)
		(layer "B.Cu")
		(net "MEMA_1")
	)
	(segment
		(start 286.81045 -194.923664)
		(end 287.2232 -195.336414)
		(width 0.1143)
		(layer "B.Cu")
		(net "MEMA_1")
	)
	(segment
		(start 288.032444 -186.92622)
		(end 288.032444 -184.177432)
		(width 0.1143)
		(layer "B.Cu")
		(net "MEMA_1")
	)
	(segment
		(start 287.2232 -196.232272)
		(end 287.1851 -196.270372)
		(width 0.1143)
		(layer "B.Cu")
		(net "MEMA_1")
	)
	(segment
		(start 286.8041 -192.043304)
		(end 286.6898 -192.157604)
		(width 0.1143)
		(layer "B.Cu")
		(net "MEMA_1")
	)
	(segment
		(start 287.1851 -197.04812)
		(end 286.893254 -197.339966)
		(width 0.1143)
		(layer "B.Cu")
		(net "MEMA_1")
	)
	(segment
		(start 287.9344 -187.024264)
		(end 288.032444 -186.92622)
		(width 0.1143)
		(layer "B.Cu")
		(net "MEMA_1")
	)
	(segment
		(start 286.81045 -194.31635)
		(end 286.81045 -194.923664)
		(width 0.1143)
		(layer "B.Cu")
		(net "MEMA_1")
	)
	(segment
		(start 287.28289 -192.843404)
		(end 287.16859 -192.957704)
		(width 0.1143)
		(layer "B.Cu")
		(net "MEMA_1")
	)
	(segment
		(start 287.28289 -193.529204)
		(end 287.28289 -193.84391)
		(width 0.1143)
		(layer "B.Cu")
		(net "MEMA_1")
	)
	(segment
		(start 288.032444 -184.177432)
		(end 288.33064 -183.879236)
		(width 0.1143)
		(layer "B.Cu")
		(net "MEMA_1")
	)
	(segment
		(start 288.33064 -182.221378)
		(end 288.824416 -181.727602)
		(width 0.1143)
		(layer "B.Cu")
		(net "MEMA_1")
	)
	(segment
		(start 287.16859 -192.500504)
		(end 287.28289 -192.614804)
		(width 0.1143)
		(layer "B.Cu")
		(net "MEMA_1")
	)
	(segment
		(start 287.16859 -192.957704)
		(end 286.8041 -192.957704)
		(width 0.1143)
		(layer "B.Cu")
		(net "MEMA_1")
	)
	(segment
		(start 287.28289 -192.614804)
		(end 287.28289 -192.843404)
		(width 0.1143)
		(layer "B.Cu")
		(net "MEMA_1")
	)
	(segment
		(start 287.757108 -189.5856)
		(end 287.757108 -190.56604)
		(width 0.1143)
		(layer "B.Cu")
		(net "MEMA_1")
	)
	(segment
		(start 287.757108 -188.918088)
		(end 287.9344 -188.740796)
		(width 0.1143)
		(layer "B.Cu")
		(net "MEMA_1")
	)
	(segment
		(start 287.16859 -192.043304)
		(end 286.8041 -192.043304)
		(width 0.1143)
		(layer "B.Cu")
		(net "MEMA_1")
	)
	(segment
		(start 22.086316 -219.80398)
		(end 26.697178 -219.80398)
		(width 0.1143)
		(layer "F.Cu")
		(net "SAS_HDD_PWR3")
	)
	(segment
		(start 21.033232 -216.714578)
		(end 21.033232 -218.750896)
		(width 0.1143)
		(layer "F.Cu")
		(net "SAS_HDD_PWR3")
	)
	(segment
		(start 21.033232 -218.750896)
		(end 22.086316 -219.80398)
		(width 0.1143)
		(layer "F.Cu")
		(net "SAS_HDD_PWR3")
	)
	(segment
		(start 26.697178 -219.80398)
		(end 28.969716 -222.076518)
		(width 0.1143)
		(layer "F.Cu")
		(net "SAS_HDD_PWR3")
	)
	(segment
		(start 28.969716 -226.75088)
		(end 28.969716 -228.96068)
		(width 0.1143)
		(layer "F.Cu")
		(net "SAS_HDD_PWR3")
	)
	(segment
		(start 28.969716 -222.076518)
		(end 28.969716 -226.75088)
		(width 0.1143)
		(layer "F.Cu")
		(net "SAS_HDD_PWR3")
	)
	(via
		(at 28.969716 -228.65588)
		(size 0.7112)
		(drill 0.3556)
		(layers "F.Cu" "B.Cu")
		(net "SAS_HDD_PWR3")
	)
	(via
		(at 28.969716 -226.75088)
		(size 0.5588)
		(drill 0.3048)
		(layers "F.Cu" "B.Cu")
		(net "SAS_HDD_PWR3")
	)
	(segment
		(start 28.398216 -231.89438)
		(end 28.398216 -230.30688)
		(width 0.1143)
		(layer "B.Cu")
		(net "SAS_HDD_PWR3")
	)
	(segment
		(start 28.969716 -226.75088)
		(end 28.969716 -228.65588)
		(width 0.1143)
		(layer "B.Cu")
		(net "SAS_HDD_PWR3")
	)
	(segment
		(start 28.969716 -229.73538)
		(end 28.969716 -228.65588)
		(width 0.1143)
		(layer "B.Cu")
		(net "SAS_HDD_PWR3")
	)
	(segment
		(start 28.398216 -230.30688)
		(end 28.969716 -229.73538)
		(width 0.1143)
		(layer "B.Cu")
		(net "SAS_HDD_PWR3")
	)
	(segment
		(start 179.759864 -27.423872)
		(end 179.759864 -28.056078)
		(width 0.127)
		(layer "F.Cu")
		(net "NC_PHY_BMC_INTR_N")
	)
	(segment
		(start 179.052982 -26.71699)
		(end 179.759864 -27.423872)
		(width 0.127)
		(layer "F.Cu")
		(net "NC_PHY_BMC_INTR_N")
	)
	(segment
		(start 179.052982 -24.929338)
		(end 179.052982 -26.71699)
		(width 0.127)
		(layer "F.Cu")
		(net "NC_PHY_BMC_INTR_N")
	)
	(segment
		(start 300.03496 -169.840148)
		(end 300.03496 -169.73804)
		(width 0.1143)
		(layer "F.Cu")
		(net "BMC0_SMB3_CLK")
	)
	(segment
		(start 300.355 -169.418)
		(end 301.752 -169.418)
		(width 0.1143)
		(layer "F.Cu")
		(net "BMC0_SMB3_CLK")
	)
	(segment
		(start 302.387 -169.545)
		(end 302.514 -169.418)
		(width 0.1143)
		(layer "F.Cu")
		(net "BMC0_SMB3_CLK")
	)
	(segment
		(start 300.03496 -169.73804)
		(end 300.355 -169.418)
		(width 0.1143)
		(layer "F.Cu")
		(net "BMC0_SMB3_CLK")
	)
	(segment
		(start 301.879 -169.545)
		(end 302.387 -169.545)
		(width 0.1143)
		(layer "F.Cu")
		(net "BMC0_SMB3_CLK")
	)
	(segment
		(start 301.752 -169.418)
		(end 301.879 -169.545)
		(width 0.1143)
		(layer "F.Cu")
		(net "BMC0_SMB3_CLK")
	)
	(via
		(at 302.514 -169.418)
		(size 0.5588)
		(drill 0.3048)
		(layers "F.Cu" "B.Cu")
		(net "BMC0_SMB3_CLK")
	)
	(via
		(at 308.864 -168.783)
		(size 0.7112)
		(drill 0.3556)
		(layers "F.Cu" "B.Cu")
		(net "BMC0_SMB3_CLK")
	)
	(segment
		(start 308.991 -168.656)
		(end 314.962032 -168.656)
		(width 0.1143)
		(layer "B.Cu")
		(net "BMC0_SMB3_CLK")
	)
	(segment
		(start 304.812192 -168.99255)
		(end 308.65445 -168.99255)
		(width 0.1143)
		(layer "B.Cu")
		(net "BMC0_SMB3_CLK")
	)
	(segment
		(start 304.367692 -168.54805)
		(end 304.812192 -168.99255)
		(width 0.1143)
		(layer "B.Cu")
		(net "BMC0_SMB3_CLK")
	)
	(segment
		(start 308.864 -168.783)
		(end 308.991 -168.656)
		(width 0.1143)
		(layer "B.Cu")
		(net "BMC0_SMB3_CLK")
	)
	(segment
		(start 314.962032 -168.656)
		(end 316.740032 -166.878)
		(width 0.1143)
		(layer "B.Cu")
		(net "BMC0_SMB3_CLK")
	)
	(segment
		(start 303.38395 -168.54805)
		(end 304.367692 -168.54805)
		(width 0.1143)
		(layer "B.Cu")
		(net "BMC0_SMB3_CLK")
	)
	(segment
		(start 316.740032 -166.878)
		(end 317.5635 -166.878)
		(width 0.1143)
		(layer "B.Cu")
		(net "BMC0_SMB3_CLK")
	)
	(segment
		(start 308.65445 -168.99255)
		(end 308.864 -168.783)
		(width 0.1143)
		(layer "B.Cu")
		(net "BMC0_SMB3_CLK")
	)
	(segment
		(start 302.514 -169.418)
		(end 303.38395 -168.54805)
		(width 0.1143)
		(layer "B.Cu")
		(net "BMC0_SMB3_CLK")
	)
	(segment
		(start 18.111216 -223.57588)
		(end 16.587216 -225.09988)
		(width 0.1143)
		(layer "F.Cu")
		(net "SAS_HDD_PWR10")
	)
	(segment
		(start 19.129756 -223.57588)
		(end 18.111216 -223.57588)
		(width 0.1143)
		(layer "F.Cu")
		(net "SAS_HDD_PWR10")
	)
	(segment
		(start 19.732752 -222.325438)
		(end 19.732752 -222.972884)
		(width 0.1143)
		(layer "F.Cu")
		(net "SAS_HDD_PWR10")
	)
	(segment
		(start 13.920216 -225.09988)
		(end 12.964922 -226.055174)
		(width 0.1143)
		(layer "F.Cu")
		(net "SAS_HDD_PWR10")
	)
	(segment
		(start 11.126216 -230.56088)
		(end 12.13358 -229.553516)
		(width 0.1143)
		(layer "F.Cu")
		(net "SAS_HDD_PWR10")
	)
	(segment
		(start 16.587216 -225.09988)
		(end 13.920216 -225.09988)
		(width 0.1143)
		(layer "F.Cu")
		(net "SAS_HDD_PWR10")
	)
	(segment
		(start 12.13358 -229.553516)
		(end 12.13358 -228.952552)
		(width 0.1143)
		(layer "F.Cu")
		(net "SAS_HDD_PWR10")
	)
	(segment
		(start 12.13358 -228.952552)
		(end 12.13358 -226.886516)
		(width 0.1143)
		(layer "F.Cu")
		(net "SAS_HDD_PWR10")
	)
	(segment
		(start 19.732752 -222.972884)
		(end 19.129756 -223.57588)
		(width 0.1143)
		(layer "F.Cu")
		(net "SAS_HDD_PWR10")
	)
	(segment
		(start 12.13358 -226.886516)
		(end 12.964922 -226.055174)
		(width 0.1143)
		(layer "F.Cu")
		(net "SAS_HDD_PWR10")
	)
	(via
		(at 11.126216 -230.56088)
		(size 0.5588)
		(drill 0.3048)
		(layers "F.Cu" "B.Cu")
		(net "SAS_HDD_PWR10")
	)
	(via
		(at 12.964922 -226.055174)
		(size 0.7112)
		(drill 0.3556)
		(layers "F.Cu" "B.Cu")
		(net "SAS_HDD_PWR10")
	)
	(segment
		(start 11.05408 -231.378252)
		(end 11.05408 -230.633016)
		(width 0.1143)
		(layer "B.Cu")
		(net "SAS_HDD_PWR10")
	)
	(segment
		(start 11.05408 -230.633016)
		(end 11.126216 -230.56088)
		(width 0.1143)
		(layer "B.Cu")
		(net "SAS_HDD_PWR10")
	)
	(segment
		(start 173.325028 -33.005776)
		(end 173.334172 -33.01492)
		(width 0.1397)
		(layer "F.Cu")
		(net "BCM5221_MB_RX_DP")
	)
	(segment
		(start 173.325028 -32.052768)
		(end 173.325028 -33.005776)
		(width 0.1397)
		(layer "F.Cu")
		(net "BCM5221_MB_RX_DP")
	)
	(via
		(at 173.334172 -33.01492)
		(size 0.7112)
		(drill 0.4064)
		(layers "F.Cu" "B.Cu")
		(net "BCM5221_MB_RX_DP")
	)
	(segment
		(start 164.555678 -17.276826)
		(end 164.892736 -17.613884)
		(width 0.1397)
		(layer "B.Cu")
		(net "BCM5221_MB_RX_DP")
	)
	(segment
		(start 163.185602 -15.906496)
		(end 163.205922 -15.92707)
		(width 0.1397)
		(layer "B.Cu")
		(net "BCM5221_MB_RX_DP")
	)
	(segment
		(start 164.383466 -17.2466)
		(end 164.465 -17.2466)
		(width 0.1397)
		(layer "B.Cu")
		(net "BCM5221_MB_RX_DP")
	)
	(segment
		(start 176.121822 -30.84703)
		(end 175.59401 -31.374842)
		(width 0.1397)
		(layer "B.Cu")
		(net "BCM5221_MB_RX_DP")
	)
	(segment
		(start 158.21406 -15.82166)
		(end 158.63316 -15.82166)
		(width 0.1397)
		(layer "B.Cu")
		(net "BCM5221_MB_RX_DP")
	)
	(segment
		(start 169.55262 -22.273768)
		(end 169.898822 -22.61997)
		(width 0.1397)
		(layer "B.Cu")
		(net "BCM5221_MB_RX_DP")
	)
	(segment
		(start 173.068742 -22.9489)
		(end 173.76775 -22.9489)
		(width 0.1397)
		(layer "B.Cu")
		(net "BCM5221_MB_RX_DP")
	)
	(segment
		(start 165.75659 -18.477738)
		(end 166.053008 -18.774156)
		(width 0.1397)
		(layer "B.Cu")
		(net "BCM5221_MB_RX_DP")
	)
	(segment
		(start 164.465 -17.2466)
		(end 164.555678 -17.276826)
		(width 0.1397)
		(layer "B.Cu")
		(net "BCM5221_MB_RX_DP")
	)
	(segment
		(start 163.205922 -15.92707)
		(end 163.732464 -16.453612)
		(width 0.1397)
		(layer "B.Cu")
		(net "BCM5221_MB_RX_DP")
	)
	(segment
		(start 166.19474 -19.19986)
		(end 166.491158 -19.496024)
		(width 0.1397)
		(layer "B.Cu")
		(net "BCM5221_MB_RX_DP")
	)
	(segment
		(start 156.15031 -15.621)
		(end 157.81274 -15.621)
		(width 0.1397)
		(layer "B.Cu")
		(net "BCM5221_MB_RX_DP")
	)
	(segment
		(start 165.034722 -18.039588)
		(end 165.330886 -18.335752)
		(width 0.1397)
		(layer "B.Cu")
		(net "BCM5221_MB_RX_DP")
	)
	(segment
		(start 176.377092 -25.522174)
		(end 176.377092 -30.230826)
		(width 0.1397)
		(layer "B.Cu")
		(net "BCM5221_MB_RX_DP")
	)
	(segment
		(start 168.830752 -21.835618)
		(end 169.126916 -22.132036)
		(width 0.1397)
		(layer "B.Cu")
		(net "BCM5221_MB_RX_DP")
	)
	(segment
		(start 160.67532 -15.621)
		(end 162.495992 -15.621)
		(width 0.1397)
		(layer "B.Cu")
		(net "BCM5221_MB_RX_DP")
	)
	(segment
		(start 168.077134 -20.798282)
		(end 168.688766 -21.409914)
		(width 0.1397)
		(layer "B.Cu")
		(net "BCM5221_MB_RX_DP")
	)
	(segment
		(start 156.44495 -17.809972)
		(end 156.435044 -17.809972)
		(width 0.1397)
		(layer "B.Cu")
		(net "BCM5221_MB_RX_DP")
	)
	(segment
		(start 175.168306 -31.516828)
		(end 174.871888 -31.813246)
		(width 0.1397)
		(layer "B.Cu")
		(net "BCM5221_MB_RX_DP")
	)
	(segment
		(start 166.916862 -19.63801)
		(end 167.21328 -19.934428)
		(width 0.1397)
		(layer "B.Cu")
		(net "BCM5221_MB_RX_DP")
	)
	(segment
		(start 172.248322 -23.14956)
		(end 172.667422 -23.14956)
		(width 0.1397)
		(layer "B.Cu")
		(net "BCM5221_MB_RX_DP")
	)
	(segment
		(start 174.445422 -23.22957)
		(end 176.121822 -24.90597)
		(width 0.1397)
		(layer "B.Cu")
		(net "BCM5221_MB_RX_DP")
	)
	(segment
		(start 174.730156 -32.238696)
		(end 173.940724 -33.028128)
		(width 0.1397)
		(layer "B.Cu")
		(net "BCM5221_MB_RX_DP")
	)
	(segment
		(start 159.8549 -15.82166)
		(end 160.274 -15.82166)
		(width 0.1397)
		(layer "B.Cu")
		(net "BCM5221_MB_RX_DP")
	)
	(segment
		(start 159.03448 -15.621)
		(end 159.45358 -15.621)
		(width 0.1397)
		(layer "B.Cu")
		(net "BCM5221_MB_RX_DP")
	)
	(segment
		(start 156.435044 -17.809972)
		(end 155.716732 -17.09166)
		(width 0.1397)
		(layer "B.Cu")
		(net "BCM5221_MB_RX_DP")
	)
	(segment
		(start 173.34738 -33.028128)
		(end 173.334172 -33.01492)
		(width 0.1397)
		(layer "B.Cu")
		(net "BCM5221_MB_RX_DP")
	)
	(segment
		(start 163.87445 -16.879316)
		(end 164.170614 -17.175734)
		(width 0.1397)
		(layer "B.Cu")
		(net "BCM5221_MB_RX_DP")
	)
	(segment
		(start 155.59151 -16.7894)
		(end 155.59151 -16.1798)
		(width 0.1397)
		(layer "B.Cu")
		(net "BCM5221_MB_RX_DP")
	)
	(segment
		(start 167.355012 -20.360132)
		(end 167.65143 -20.656296)
		(width 0.1397)
		(layer "B.Cu")
		(net "BCM5221_MB_RX_DP")
	)
	(segment
		(start 170.693334 -22.9489)
		(end 171.847002 -22.9489)
		(width 0.1397)
		(layer "B.Cu")
		(net "BCM5221_MB_RX_DP")
	)
	(arc
		(start 176.121822 -24.90597)
		(mid 176.310727 -25.188687)
		(end 176.377092 -25.522174)
		(width 0.1397)
		(layer "B.Cu")
		(net "BCM5221_MB_RX_DP")
	)
	(arc
		(start 173.76775 -22.9489)
		(mid 174.134492 -23.021849)
		(end 174.445422 -23.22957)
		(width 0.1397)
		(layer "B.Cu")
		(net "BCM5221_MB_RX_DP")
	)
	(arc
		(start 168.759632 -21.622766)
		(mid 168.770156 -21.737549)
		(end 168.830752 -21.835618)
		(width 0.1397)
		(layer "B.Cu")
		(net "BCM5221_MB_RX_DP")
	)
	(arc
		(start 168.688766 -21.409914)
		(mid 168.749273 -21.507996)
		(end 168.759632 -21.622766)
		(width 0.1397)
		(layer "B.Cu")
		(net "BCM5221_MB_RX_DP")
	)
	(arc
		(start 167.864282 -20.727416)
		(mid 167.97904 -20.737809)
		(end 168.077134 -20.798282)
		(width 0.1397)
		(layer "B.Cu")
		(net "BCM5221_MB_RX_DP")
	)
	(arc
		(start 163.732464 -16.453612)
		(mid 163.792971 -16.551694)
		(end 163.80333 -16.666464)
		(width 0.1397)
		(layer "B.Cu")
		(net "BCM5221_MB_RX_DP")
	)
	(arc
		(start 174.871888 -31.813246)
		(mid 174.811381 -31.911328)
		(end 174.801022 -32.026098)
		(width 0.1397)
		(layer "B.Cu")
		(net "BCM5221_MB_RX_DP")
	)
	(arc
		(start 166.123874 -18.987008)
		(mid 166.13426 -19.101777)
		(end 166.19474 -19.19986)
		(width 0.1397)
		(layer "B.Cu")
		(net "BCM5221_MB_RX_DP")
	)
	(arc
		(start 175.381158 -31.445962)
		(mid 175.2664 -31.456355)
		(end 175.168306 -31.516828)
		(width 0.1397)
		(layer "B.Cu")
		(net "BCM5221_MB_RX_DP")
	)
	(arc
		(start 155.59151 -16.1798)
		(mid 155.755179 -15.784669)
		(end 156.15031 -15.621)
		(width 0.1397)
		(layer "B.Cu")
		(net "BCM5221_MB_RX_DP")
	)
	(arc
		(start 176.377092 -30.230826)
		(mid 176.310755 -30.564325)
		(end 176.121822 -30.84703)
		(width 0.1397)
		(layer "B.Cu")
		(net "BCM5221_MB_RX_DP")
	)
	(arc
		(start 158.83382 -15.72133)
		(mid 158.922346 -15.64757)
		(end 159.03448 -15.621)
		(width 0.1397)
		(layer "B.Cu")
		(net "BCM5221_MB_RX_DP")
	)
	(arc
		(start 164.170614 -17.175734)
		(mid 164.268696 -17.236241)
		(end 164.383466 -17.2466)
		(width 0.1397)
		(layer "B.Cu")
		(net "BCM5221_MB_RX_DP")
	)
	(arc
		(start 172.868082 -23.04923)
		(mid 172.956608 -22.97547)
		(end 173.068742 -22.9489)
		(width 0.1397)
		(layer "B.Cu")
		(net "BCM5221_MB_RX_DP")
	)
	(arc
		(start 172.047662 -23.04923)
		(mid 172.136188 -23.12299)
		(end 172.248322 -23.14956)
		(width 0.1397)
		(layer "B.Cu")
		(net "BCM5221_MB_RX_DP")
	)
	(arc
		(start 167.284146 -20.14728)
		(mid 167.294539 -20.262038)
		(end 167.355012 -20.360132)
		(width 0.1397)
		(layer "B.Cu")
		(net "BCM5221_MB_RX_DP")
	)
	(arc
		(start 171.847002 -22.9489)
		(mid 171.959159 -22.975424)
		(end 172.047662 -23.04923)
		(width 0.1397)
		(layer "B.Cu")
		(net "BCM5221_MB_RX_DP")
	)
	(arc
		(start 158.63316 -15.82166)
		(mid 158.745317 -15.795136)
		(end 158.83382 -15.72133)
		(width 0.1397)
		(layer "B.Cu")
		(net "BCM5221_MB_RX_DP")
	)
	(arc
		(start 164.963602 -17.826736)
		(mid 164.974126 -17.941519)
		(end 165.034722 -18.039588)
		(width 0.1397)
		(layer "B.Cu")
		(net "BCM5221_MB_RX_DP")
	)
	(arc
		(start 159.65424 -15.72133)
		(mid 159.742766 -15.79509)
		(end 159.8549 -15.82166)
		(width 0.1397)
		(layer "B.Cu")
		(net "BCM5221_MB_RX_DP")
	)
	(arc
		(start 166.491158 -19.496024)
		(mid 166.589205 -19.556688)
		(end 166.70401 -19.567144)
		(width 0.1397)
		(layer "B.Cu")
		(net "BCM5221_MB_RX_DP")
	)
	(arc
		(start 165.543738 -18.406872)
		(mid 165.658496 -18.417265)
		(end 165.75659 -18.477738)
		(width 0.1397)
		(layer "B.Cu")
		(net "BCM5221_MB_RX_DP")
	)
	(arc
		(start 163.80333 -16.666464)
		(mid 163.813854 -16.781247)
		(end 163.87445 -16.879316)
		(width 0.1397)
		(layer "B.Cu")
		(net "BCM5221_MB_RX_DP")
	)
	(arc
		(start 158.0134 -15.72133)
		(mid 158.101926 -15.79509)
		(end 158.21406 -15.82166)
		(width 0.1397)
		(layer "B.Cu")
		(net "BCM5221_MB_RX_DP")
	)
	(arc
		(start 167.21328 -19.934428)
		(mid 167.273787 -20.03251)
		(end 167.284146 -20.14728)
		(width 0.1397)
		(layer "B.Cu")
		(net "BCM5221_MB_RX_DP")
	)
	(arc
		(start 160.274 -15.82166)
		(mid 160.386157 -15.795136)
		(end 160.47466 -15.72133)
		(width 0.1397)
		(layer "B.Cu")
		(net "BCM5221_MB_RX_DP")
	)
	(arc
		(start 173.940724 -33.028128)
		(mid 173.644052 -33.151014)
		(end 173.34738 -33.028128)
		(width 0.1397)
		(layer "B.Cu")
		(net "BCM5221_MB_RX_DP")
	)
	(arc
		(start 175.59401 -31.374842)
		(mid 175.495952 -31.435445)
		(end 175.381158 -31.445962)
		(width 0.1397)
		(layer "B.Cu")
		(net "BCM5221_MB_RX_DP")
	)
	(arc
		(start 157.81274 -15.621)
		(mid 157.924897 -15.647524)
		(end 158.0134 -15.72133)
		(width 0.1397)
		(layer "B.Cu")
		(net "BCM5221_MB_RX_DP")
	)
	(arc
		(start 164.892736 -17.613884)
		(mid 164.953243 -17.711966)
		(end 164.963602 -17.826736)
		(width 0.1397)
		(layer "B.Cu")
		(net "BCM5221_MB_RX_DP")
	)
	(arc
		(start 159.45358 -15.621)
		(mid 159.565737 -15.647524)
		(end 159.65424 -15.72133)
		(width 0.1397)
		(layer "B.Cu")
		(net "BCM5221_MB_RX_DP")
	)
	(arc
		(start 162.495992 -15.621)
		(mid 162.869203 -15.695143)
		(end 163.185602 -15.906496)
		(width 0.1397)
		(layer "B.Cu")
		(net "BCM5221_MB_RX_DP")
	)
	(arc
		(start 160.47466 -15.72133)
		(mid 160.563186 -15.64757)
		(end 160.67532 -15.621)
		(width 0.1397)
		(layer "B.Cu")
		(net "BCM5221_MB_RX_DP")
	)
	(arc
		(start 174.801022 -32.026098)
		(mid 174.790555 -32.14071)
		(end 174.730156 -32.238696)
		(width 0.1397)
		(layer "B.Cu")
		(net "BCM5221_MB_RX_DP")
	)
	(arc
		(start 167.65143 -20.656296)
		(mid 167.749477 -20.71696)
		(end 167.864282 -20.727416)
		(width 0.1397)
		(layer "B.Cu")
		(net "BCM5221_MB_RX_DP")
	)
	(arc
		(start 155.716732 -17.09166)
		(mid 155.62407 -16.952982)
		(end 155.59151 -16.7894)
		(width 0.1397)
		(layer "B.Cu")
		(net "BCM5221_MB_RX_DP")
	)
	(arc
		(start 166.053008 -18.774156)
		(mid 166.113515 -18.872238)
		(end 166.123874 -18.987008)
		(width 0.1397)
		(layer "B.Cu")
		(net "BCM5221_MB_RX_DP")
	)
	(arc
		(start 172.667422 -23.14956)
		(mid 172.779579 -23.123036)
		(end 172.868082 -23.04923)
		(width 0.1397)
		(layer "B.Cu")
		(net "BCM5221_MB_RX_DP")
	)
	(arc
		(start 169.126916 -22.132036)
		(mid 169.224998 -22.192543)
		(end 169.339768 -22.202902)
		(width 0.1397)
		(layer "B.Cu")
		(net "BCM5221_MB_RX_DP")
	)
	(arc
		(start 165.330886 -18.335752)
		(mid 165.428933 -18.396416)
		(end 165.543738 -18.406872)
		(width 0.1397)
		(layer "B.Cu")
		(net "BCM5221_MB_RX_DP")
	)
	(arc
		(start 166.70401 -19.567144)
		(mid 166.818768 -19.577537)
		(end 166.916862 -19.63801)
		(width 0.1397)
		(layer "B.Cu")
		(net "BCM5221_MB_RX_DP")
	)
	(arc
		(start 169.898822 -22.61997)
		(mid 170.263362 -22.863455)
		(end 170.693334 -22.9489)
		(width 0.1397)
		(layer "B.Cu")
		(net "BCM5221_MB_RX_DP")
	)
	(arc
		(start 169.339768 -22.202902)
		(mid 169.454526 -22.213295)
		(end 169.55262 -22.273768)
		(width 0.1397)
		(layer "B.Cu")
		(net "BCM5221_MB_RX_DP")
	)
	(segment
		(start 37.382958 -251.106178)
		(end 33.41878 -247.142)
		(width 0.1143)
		(layer "F.Cu")
		(net "SAS_HDD_PWR10_PCIE")
	)
	(segment
		(start 36.999926 -256.25044)
		(end 36.999926 -253.621032)
		(width 0.1143)
		(layer "F.Cu")
		(net "SAS_HDD_PWR10_PCIE")
	)
	(segment
		(start 21.082 -237.109)
		(end 21.082 -232.537)
		(width 0.1143)
		(layer "F.Cu")
		(net "SAS_HDD_PWR10_PCIE")
	)
	(segment
		(start 12.76858 -236.013244)
		(end 12.76858 -234.184952)
		(width 0.1143)
		(layer "F.Cu")
		(net "SAS_HDD_PWR10_PCIE")
	)
	(segment
		(start 33.41878 -247.142)
		(end 31.115 -247.142)
		(width 0.1143)
		(layer "F.Cu")
		(net "SAS_HDD_PWR10_PCIE")
	)
	(segment
		(start 19.685 -231.14)
		(end 15.214092 -231.14)
		(width 0.1143)
		(layer "F.Cu")
		(net "SAS_HDD_PWR10_PCIE")
	)
	(segment
		(start 12.76858 -233.585512)
		(end 12.76858 -234.184952)
		(width 0.1143)
		(layer "F.Cu")
		(net "SAS_HDD_PWR10_PCIE")
	)
	(segment
		(start 36.999926 -253.621032)
		(end 37.382958 -253.238)
		(width 0.1143)
		(layer "F.Cu")
		(net "SAS_HDD_PWR10_PCIE")
	)
	(segment
		(start 37.382958 -253.238)
		(end 37.382958 -251.106178)
		(width 0.1143)
		(layer "F.Cu")
		(net "SAS_HDD_PWR10_PCIE")
	)
	(segment
		(start 15.214092 -231.14)
		(end 12.76858 -233.585512)
		(width 0.1143)
		(layer "F.Cu")
		(net "SAS_HDD_PWR10_PCIE")
	)
	(segment
		(start 21.082 -232.537)
		(end 19.685 -231.14)
		(width 0.1143)
		(layer "F.Cu")
		(net "SAS_HDD_PWR10_PCIE")
	)
	(segment
		(start 31.115 -247.142)
		(end 21.082 -237.109)
		(width 0.1143)
		(layer "F.Cu")
		(net "SAS_HDD_PWR10_PCIE")
	)
	(via
		(at 12.76858 -236.013244)
		(size 0.5588)
		(drill 0.3048)
		(layers "F.Cu" "B.Cu")
		(net "SAS_HDD_PWR10_PCIE")
	)
	(via
		(at 12.16152 -233.374692)
		(size 0.7112)
		(drill 0.3556)
		(layers "F.Cu" "B.Cu")
		(net "SAS_HDD_PWR10_PCIE")
	)
	(segment
		(start 11.05408 -232.267252)
		(end 12.16152 -233.374692)
		(width 0.1143)
		(layer "B.Cu")
		(net "SAS_HDD_PWR10_PCIE")
	)
	(segment
		(start 12.16152 -233.374692)
		(end 12.76858 -233.981752)
		(width 0.1143)
		(layer "B.Cu")
		(net "SAS_HDD_PWR10_PCIE")
	)
	(segment
		(start 12.76858 -233.981752)
		(end 12.76858 -236.013244)
		(width 0.1143)
		(layer "B.Cu")
		(net "SAS_HDD_PWR10_PCIE")
	)
	(segment
		(start 168.845992 -29.345128)
		(end 169.99712 -28.194)
		(width 0.127)
		(layer "F.Cu")
		(net "MOD_IMC_FAB_D_COP")
	)
	(segment
		(start 175.390048 -32.944308)
		(end 175.390048 -33.816544)
		(width 0.127)
		(layer "F.Cu")
		(net "MOD_IMC_FAB_D_COP")
	)
	(segment
		(start 172.162724 -24.113236)
		(end 172.063664 -24.014176)
		(width 0.127)
		(layer "F.Cu")
		(net "MOD_IMC_FAB_D_COP")
	)
	(segment
		(start 169.99712 -28.194)
		(end 171.24934 -28.194)
		(width 0.127)
		(layer "F.Cu")
		(net "MOD_IMC_FAB_D_COP")
	)
	(segment
		(start 173.120304 -27.366976)
		(end 173.186344 -27.366976)
		(width 0.127)
		(layer "F.Cu")
		(net "MOD_IMC_FAB_D_COP")
	)
	(segment
		(start 172.358812 -32.181292)
		(end 172.268388 -32.090868)
		(width 0.127)
		(layer "F.Cu")
		(net "MOD_IMC_FAB_D_COP")
	)
	(segment
		(start 174.555912 -34.65068)
		(end 173.778672 -34.65068)
		(width 0.127)
		(layer "F.Cu")
		(net "MOD_IMC_FAB_D_COP")
	)
	(segment
		(start 169.99712 -28.194)
		(end 168.909492 -27.106372)
		(width 0.127)
		(layer "F.Cu")
		(net "MOD_IMC_FAB_D_COP")
	)
	(segment
		(start 172.14088 -27.30246)
		(end 173.055788 -27.30246)
		(width 0.127)
		(layer "F.Cu")
		(net "MOD_IMC_FAB_D_COP")
	)
	(segment
		(start 173.055788 -27.30246)
		(end 173.120304 -27.366976)
		(width 0.127)
		(layer "F.Cu")
		(net "MOD_IMC_FAB_D_COP")
	)
	(segment
		(start 168.909492 -23.90648)
		(end 169.881296 -22.934676)
		(width 0.127)
		(layer "F.Cu")
		(net "MOD_IMC_FAB_D_COP")
	)
	(segment
		(start 173.778672 -34.65068)
		(end 173.163992 -34.036)
		(width 0.127)
		(layer "F.Cu")
		(net "MOD_IMC_FAB_D_COP")
	)
	(segment
		(start 171.313348 -32.090868)
		(end 171.226988 -32.177228)
		(width 0.127)
		(layer "F.Cu")
		(net "MOD_IMC_FAB_D_COP")
	)
	(segment
		(start 168.845992 -30.988)
		(end 168.845992 -29.345128)
		(width 0.127)
		(layer "F.Cu")
		(net "MOD_IMC_FAB_D_COP")
	)
	(segment
		(start 173.183804 -24.113236)
		(end 172.162724 -24.113236)
		(width 0.127)
		(layer "F.Cu")
		(net "MOD_IMC_FAB_D_COP")
	)
	(segment
		(start 171.226988 -32.177228)
		(end 170.03522 -32.177228)
		(width 0.127)
		(layer "F.Cu")
		(net "MOD_IMC_FAB_D_COP")
	)
	(segment
		(start 172.268388 -32.090868)
		(end 171.313348 -32.090868)
		(width 0.127)
		(layer "F.Cu")
		(net "MOD_IMC_FAB_D_COP")
	)
	(segment
		(start 172.063664 -24.014176)
		(end 171.365164 -23.315676)
		(width 0.127)
		(layer "F.Cu")
		(net "MOD_IMC_FAB_D_COP")
	)
	(segment
		(start 172.358812 -33.23082)
		(end 172.358812 -32.181292)
		(width 0.127)
		(layer "F.Cu")
		(net "MOD_IMC_FAB_D_COP")
	)
	(segment
		(start 168.909492 -27.106372)
		(end 168.909492 -23.90648)
		(width 0.127)
		(layer "F.Cu")
		(net "MOD_IMC_FAB_D_COP")
	)
	(segment
		(start 171.365164 -23.315676)
		(end 171.365164 -22.934676)
		(width 0.127)
		(layer "F.Cu")
		(net "MOD_IMC_FAB_D_COP")
	)
	(segment
		(start 171.24934 -28.194)
		(end 172.043344 -27.399996)
		(width 0.127)
		(layer "F.Cu")
		(net "MOD_IMC_FAB_D_COP")
	)
	(segment
		(start 175.390048 -33.816544)
		(end 174.555912 -34.65068)
		(width 0.127)
		(layer "F.Cu")
		(net "MOD_IMC_FAB_D_COP")
	)
	(segment
		(start 169.881296 -22.934676)
		(end 171.365164 -22.934676)
		(width 0.127)
		(layer "F.Cu")
		(net "MOD_IMC_FAB_D_COP")
	)
	(segment
		(start 172.043344 -27.399996)
		(end 172.14088 -27.30246)
		(width 0.127)
		(layer "F.Cu")
		(net "MOD_IMC_FAB_D_COP")
	)
	(segment
		(start 173.163992 -34.036)
		(end 172.358812 -33.23082)
		(width 0.127)
		(layer "F.Cu")
		(net "MOD_IMC_FAB_D_COP")
	)
	(segment
		(start 170.03522 -32.177228)
		(end 168.845992 -30.988)
		(width 0.127)
		(layer "F.Cu")
		(net "MOD_IMC_FAB_D_COP")
	)
	(via
		(at 173.163992 -34.036)
		(size 0.7112)
		(drill 0.3556)
		(layers "F.Cu" "B.Cu")
		(net "MOD_IMC_FAB_D_COP")
	)
	(segment
		(start 294.904668 -183.90997)
		(end 294.904668 -185.478166)
		(width 0.1016)
		(layer "F.Cu")
		(net "MEMDQS_N0")
	)
	(segment
		(start 292.097968 -200.935082)
		(end 292.453568 -200.579482)
		(width 0.1016)
		(layer "F.Cu")
		(net "MEMDQS_N0")
	)
	(segment
		(start 293.878 -186.504834)
		(end 293.878 -186.563)
		(width 0.1016)
		(layer "F.Cu")
		(net "MEMDQS_N0")
	)
	(segment
		(start 292.453568 -200.579482)
		(end 292.967918 -200.579482)
		(width 0.1016)
		(layer "F.Cu")
		(net "MEMDQS_N0")
	)
	(segment
		(start 294.434768 -183.44007)
		(end 294.904668 -183.90997)
		(width 0.1016)
		(layer "F.Cu")
		(net "MEMDQS_N0")
	)
	(segment
		(start 292.967918 -200.579482)
		(end 293.1668 -200.3806)
		(width 0.1016)
		(layer "F.Cu")
		(net "MEMDQS_N0")
	)
	(segment
		(start 294.904668 -185.478166)
		(end 293.878 -186.504834)
		(width 0.1016)
		(layer "F.Cu")
		(net "MEMDQS_N0")
	)
	(via
		(at 293.1668 -200.3806)
		(size 0.508)
		(drill 0.254)
		(layers "F.Cu" "B.Cu")
		(net "MEMDQS_N0")
	)
	(via
		(at 293.878 -186.563)
		(size 0.508)
		(drill 0.254)
		(layers "F.Cu" "B.Cu")
		(net "MEMDQS_N0")
	)
	(via
		(at 294.005 -187.7568)
		(size 0.7112)
		(drill 0.3556)
		(layers "F.Cu" "B.Cu")
		(net "MEMDQS_N0")
	)
	(segment
		(start 294.0558 -186.8932)
		(end 293.878 -186.7154)
		(width 0.1016)
		(layer "B.Cu")
		(net "MEMDQS_N0")
	)
	(segment
		(start 293.878 -186.7154)
		(end 293.878 -186.563)
		(width 0.1016)
		(layer "B.Cu")
		(net "MEMDQS_N0")
	)
	(segment
		(start 294.005 -187.7568)
		(end 294.0558 -187.706)
		(width 0.1016)
		(layer "B.Cu")
		(net "MEMDQS_N0")
	)
	(segment
		(start 294.0558 -187.706)
		(end 294.0558 -186.8932)
		(width 0.1016)
		(layer "B.Cu")
		(net "MEMDQS_N0")
	)
	(segment
		(start 293.878 -187.695586)
		(end 293.878 -186.563)
		(width 0.1016)
		(layer "In5.Cu")
		(net "MEMDQS_N0")
	)
	(segment
		(start 293.603426 -197.61454)
		(end 293.2557 -197.266814)
		(width 0.1016)
		(layer "In5.Cu")
		(net "MEMDQS_N0")
	)
	(segment
		(start 293.48684 -188.086746)
		(end 293.878 -187.695586)
		(width 0.1016)
		(layer "In5.Cu")
		(net "MEMDQS_N0")
	)
	(segment
		(start 293.468806 -188.086746)
		(end 293.48684 -188.086746)
		(width 0.1016)
		(layer "In5.Cu")
		(net "MEMDQS_N0")
	)
	(segment
		(start 292.1 -193.12636)
		(end 292.1 -189.042294)
		(width 0.1016)
		(layer "In5.Cu")
		(net "MEMDQS_N0")
	)
	(segment
		(start 292.75278 -193.77914)
		(end 292.1 -193.12636)
		(width 0.1016)
		(layer "In5.Cu")
		(net "MEMDQS_N0")
	)
	(segment
		(start 292.1 -189.042294)
		(end 292.483794 -188.6585)
		(width 0.1016)
		(layer "In5.Cu")
		(net "MEMDQS_N0")
	)
	(segment
		(start 293.2557 -197.266814)
		(end 293.2557 -196.039232)
		(width 0.1016)
		(layer "In5.Cu")
		(net "MEMDQS_N0")
	)
	(segment
		(start 293.1414 -195.365624)
		(end 292.75278 -194.977004)
		(width 0.1016)
		(layer "In5.Cu")
		(net "MEMDQS_N0")
	)
	(segment
		(start 293.2557 -196.039232)
		(end 293.1414 -195.924932)
		(width 0.1016)
		(layer "In5.Cu")
		(net "MEMDQS_N0")
	)
	(segment
		(start 292.75278 -194.977004)
		(end 292.75278 -193.77914)
		(width 0.1016)
		(layer "In5.Cu")
		(net "MEMDQS_N0")
	)
	(segment
		(start 293.1668 -200.3806)
		(end 293.393368 -200.154032)
		(width 0.1016)
		(layer "In5.Cu")
		(net "MEMDQS_N0")
	)
	(segment
		(start 293.393368 -200.154032)
		(end 293.393368 -199.427084)
		(width 0.1016)
		(layer "In5.Cu")
		(net "MEMDQS_N0")
	)
	(segment
		(start 293.3954 -199.424544)
		(end 293.603426 -199.216518)
		(width 0.1016)
		(layer "In5.Cu")
		(net "MEMDQS_N0")
	)
	(segment
		(start 293.603426 -199.216518)
		(end 293.603426 -197.61454)
		(width 0.1016)
		(layer "In5.Cu")
		(net "MEMDQS_N0")
	)
	(segment
		(start 293.393368 -199.427084)
		(end 293.3954 -199.424544)
		(width 0.1016)
		(layer "In5.Cu")
		(net "MEMDQS_N0")
	)
	(segment
		(start 292.483794 -188.6585)
		(end 292.897052 -188.6585)
		(width 0.1016)
		(layer "In5.Cu")
		(net "MEMDQS_N0")
	)
	(segment
		(start 292.897052 -188.6585)
		(end 293.468806 -188.086746)
		(width 0.1016)
		(layer "In5.Cu")
		(net "MEMDQS_N0")
	)
	(segment
		(start 293.1414 -195.924932)
		(end 293.1414 -195.365624)
		(width 0.1016)
		(layer "In5.Cu")
		(net "MEMDQS_N0")
	)
	(segment
		(start 189.357 -27.94)
		(end 188.240924 -29.056076)
		(width 0.1143)
		(layer "F.Cu")
		(net "RMII_BMC_RX_ER_R")
	)
	(segment
		(start 190.373 -27.94)
		(end 189.357 -27.94)
		(width 0.1143)
		(layer "F.Cu")
		(net "RMII_BMC_RX_ER_R")
	)
	(segment
		(start 190.953136 -28.520136)
		(end 191.253364 -28.520136)
		(width 0.1143)
		(layer "F.Cu")
		(net "RMII_BMC_RX_ER_R")
	)
	(segment
		(start 190.373 -27.94)
		(end 190.953136 -28.520136)
		(width 0.1143)
		(layer "F.Cu")
		(net "RMII_BMC_RX_ER_R")
	)
	(segment
		(start 188.240924 -29.056076)
		(end 186.744864 -29.056076)
		(width 0.1143)
		(layer "F.Cu")
		(net "RMII_BMC_RX_ER_R")
	)
	(via
		(at 190.373 -27.94)
		(size 0.7112)
		(drill 0.3556)
		(layers "F.Cu" "B.Cu")
		(net "RMII_BMC_RX_ER_R")
	)
	(segment
		(start 32.893 -249.458988)
		(end 20.701 -237.266988)
		(width 0.1143)
		(layer "F.Cu")
		(net "SAS_HDD_PWR11_PCIE")
	)
	(segment
		(start 20.701 -237.266988)
		(end 20.701 -233.118152)
		(width 0.1143)
		(layer "F.Cu")
		(net "SAS_HDD_PWR11_PCIE")
	)
	(segment
		(start 32.893 -252.095)
		(end 32.893 -249.458988)
		(width 0.1143)
		(layer "F.Cu")
		(net "SAS_HDD_PWR11_PCIE")
	)
	(segment
		(start 19.34845 -231.765602)
		(end 15.109444 -231.765602)
		(width 0.1143)
		(layer "F.Cu")
		(net "SAS_HDD_PWR11_PCIE")
	)
	(segment
		(start 20.701 -233.118152)
		(end 19.34845 -231.765602)
		(width 0.1143)
		(layer "F.Cu")
		(net "SAS_HDD_PWR11_PCIE")
	)
	(segment
		(start 13.40358 -233.471466)
		(end 13.40358 -234.184952)
		(width 0.1143)
		(layer "F.Cu")
		(net "SAS_HDD_PWR11_PCIE")
	)
	(segment
		(start 34.000186 -253.202186)
		(end 32.893 -252.095)
		(width 0.1143)
		(layer "F.Cu")
		(net "SAS_HDD_PWR11_PCIE")
	)
	(segment
		(start 15.109444 -231.765602)
		(end 13.40358 -233.471466)
		(width 0.1143)
		(layer "F.Cu")
		(net "SAS_HDD_PWR11_PCIE")
	)
	(segment
		(start 34.000186 -256.25044)
		(end 34.000186 -253.202186)
		(width 0.1143)
		(layer "F.Cu")
		(net "SAS_HDD_PWR11_PCIE")
	)
	(segment
		(start 13.40358 -236.902244)
		(end 13.40358 -234.184952)
		(width 0.1143)
		(layer "F.Cu")
		(net "SAS_HDD_PWR11_PCIE")
	)
	(via
		(at 13.40358 -236.902244)
		(size 0.5588)
		(drill 0.3048)
		(layers "F.Cu" "B.Cu")
		(net "SAS_HDD_PWR11_PCIE")
	)
	(via
		(at 13.40358 -235.56468)
		(size 0.7112)
		(drill 0.3556)
		(layers "F.Cu" "B.Cu")
		(net "SAS_HDD_PWR11_PCIE")
	)
	(segment
		(start 13.40358 -233.473752)
		(end 13.40358 -235.56468)
		(width 0.1143)
		(layer "B.Cu")
		(net "SAS_HDD_PWR11_PCIE")
	)
	(segment
		(start 13.40358 -236.902244)
		(end 13.40358 -235.56468)
		(width 0.1143)
		(layer "B.Cu")
		(net "SAS_HDD_PWR11_PCIE")
	)
	(segment
		(start 12.19708 -232.267252)
		(end 13.40358 -233.473752)
		(width 0.1143)
		(layer "B.Cu")
		(net "SAS_HDD_PWR11_PCIE")
	)
	(segment
		(start 183.065928 -35.047936)
		(end 183.587898 -35.569906)
		(width 0.127)
		(layer "F.Cu")
		(net "PHY_AD0")
	)
	(segment
		(start 183.587898 -35.569906)
		(end 183.587898 -36.19119)
		(width 0.127)
		(layer "F.Cu")
		(net "PHY_AD0")
	)
	(segment
		(start 183.065928 -34.235136)
		(end 183.065928 -35.047936)
		(width 0.127)
		(layer "F.Cu")
		(net "PHY_AD0")
	)
	(segment
		(start 183.704992 -37.592508)
		(end 183.704992 -36.703)
		(width 0.127)
		(layer "F.Cu")
		(net "PHY_AD0")
	)
	(segment
		(start 183.587898 -36.19119)
		(end 183.704992 -36.308284)
		(width 0.127)
		(layer "F.Cu")
		(net "PHY_AD0")
	)
	(segment
		(start 183.704992 -36.308284)
		(end 183.704992 -36.703)
		(width 0.127)
		(layer "F.Cu")
		(net "PHY_AD0")
	)
	(segment
		(start 183.569864 -37.727636)
		(end 183.704992 -37.592508)
		(width 0.127)
		(layer "F.Cu")
		(net "PHY_AD0")
	)
	(via
		(at 183.704992 -36.703)
		(size 0.7112)
		(drill 0.3556)
		(layers "F.Cu" "B.Cu")
		(net "PHY_AD0")
	)
	(segment
		(start 301.634906 -169.040048)
		(end 301.764954 -168.91)
		(width 0.1143)
		(layer "F.Cu")
		(net "BMC0_SMB6_CLK")
	)
	(segment
		(start 313.764676 -166.803324)
		(end 313.891676 -166.803324)
		(width 0.1143)
		(layer "F.Cu")
		(net "BMC0_SMB6_CLK")
	)
	(segment
		(start 303.403 -168.529)
		(end 312.039 -168.529)
		(width 0.1143)
		(layer "F.Cu")
		(net "BMC0_SMB6_CLK")
	)
	(segment
		(start 315.341 -165.354)
		(end 317.5635 -165.354)
		(width 0.1143)
		(layer "F.Cu")
		(net "BMC0_SMB6_CLK")
	)
	(segment
		(start 314.664852 -166.030148)
		(end 315.341 -165.354)
		(width 0.1143)
		(layer "F.Cu")
		(net "BMC0_SMB6_CLK")
	)
	(segment
		(start 303.022 -168.91)
		(end 303.403 -168.529)
		(width 0.1143)
		(layer "F.Cu")
		(net "BMC0_SMB6_CLK")
	)
	(segment
		(start 313.891676 -166.803324)
		(end 314.664852 -166.030148)
		(width 0.1143)
		(layer "F.Cu")
		(net "BMC0_SMB6_CLK")
	)
	(segment
		(start 312.039 -168.529)
		(end 313.764676 -166.803324)
		(width 0.1143)
		(layer "F.Cu")
		(net "BMC0_SMB6_CLK")
	)
	(segment
		(start 301.764954 -168.91)
		(end 303.022 -168.91)
		(width 0.1143)
		(layer "F.Cu")
		(net "BMC0_SMB6_CLK")
	)
	(via
		(at 314.664852 -166.030148)
		(size 0.7112)
		(drill 0.3556)
		(layers "F.Cu" "B.Cu")
		(net "BMC0_SMB6_CLK")
	)
	(segment
		(start 19.396964 -223.86163)
		(end 19.36496 -223.86163)
		(width 0.1143)
		(layer "F.Cu")
		(net "SAS_HDD_PWR11")
	)
	(segment
		(start 19.26971 -223.95688)
		(end 18.25117 -223.95688)
		(width 0.1143)
		(layer "F.Cu")
		(net "SAS_HDD_PWR11")
	)
	(segment
		(start 19.36496 -223.86163)
		(end 19.26971 -223.95688)
		(width 0.1143)
		(layer "F.Cu")
		(net "SAS_HDD_PWR11")
	)
	(segment
		(start 12.76858 -229.680516)
		(end 12.142216 -230.30688)
		(width 0.1143)
		(layer "F.Cu")
		(net "SAS_HDD_PWR11")
	)
	(segment
		(start 12.777216 -227.25888)
		(end 12.777216 -228.943916)
		(width 0.1143)
		(layer "F.Cu")
		(net "SAS_HDD_PWR11")
	)
	(segment
		(start 16.60017 -225.60788)
		(end 14.428216 -225.60788)
		(width 0.1143)
		(layer "F.Cu")
		(net "SAS_HDD_PWR11")
	)
	(segment
		(start 12.76858 -228.952552)
		(end 12.76858 -229.680516)
		(width 0.1143)
		(layer "F.Cu")
		(net "SAS_HDD_PWR11")
	)
	(segment
		(start 20.382992 -222.325438)
		(end 20.382992 -222.875602)
		(width 0.1143)
		(layer "F.Cu")
		(net "SAS_HDD_PWR11")
	)
	(segment
		(start 12.777216 -228.943916)
		(end 12.76858 -228.952552)
		(width 0.1143)
		(layer "F.Cu")
		(net "SAS_HDD_PWR11")
	)
	(segment
		(start 14.428216 -225.60788)
		(end 14.301216 -225.73488)
		(width 0.1143)
		(layer "F.Cu")
		(net "SAS_HDD_PWR11")
	)
	(segment
		(start 14.301216 -225.73488)
		(end 12.777216 -227.25888)
		(width 0.1143)
		(layer "F.Cu")
		(net "SAS_HDD_PWR11")
	)
	(segment
		(start 18.25117 -223.95688)
		(end 16.60017 -225.60788)
		(width 0.1143)
		(layer "F.Cu")
		(net "SAS_HDD_PWR11")
	)
	(segment
		(start 20.382992 -222.875602)
		(end 19.396964 -223.86163)
		(width 0.1143)
		(layer "F.Cu")
		(net "SAS_HDD_PWR11")
	)
	(via
		(at 12.142216 -230.30688)
		(size 0.5588)
		(drill 0.3048)
		(layers "F.Cu" "B.Cu")
		(net "SAS_HDD_PWR11")
	)
	(via
		(at 14.301216 -225.73488)
		(size 0.7112)
		(drill 0.3556)
		(layers "F.Cu" "B.Cu")
		(net "SAS_HDD_PWR11")
	)
	(segment
		(start 12.19708 -231.378252)
		(end 12.142216 -231.323388)
		(width 0.1143)
		(layer "B.Cu")
		(net "SAS_HDD_PWR11")
	)
	(segment
		(start 12.142216 -231.323388)
		(end 12.142216 -230.30688)
		(width 0.1143)
		(layer "B.Cu")
		(net "SAS_HDD_PWR11")
	)
	(segment
		(start 178.80965 -31.556198)
		(end 178.716432 -31.46298)
		(width 0.1778)
		(layer "F.Cu")
		(net "BMC_PHY_RDAC")
	)
	(segment
		(start 179.886864 -31.556198)
		(end 178.80965 -31.556198)
		(width 0.1778)
		(layer "F.Cu")
		(net "BMC_PHY_RDAC")
	)
	(segment
		(start 176.394364 -31.821628)
		(end 176.394364 -33.853628)
		(width 0.1778)
		(layer "F.Cu")
		(net "BMC_PHY_RDAC")
	)
	(segment
		(start 176.394364 -33.853628)
		(end 176.394364 -34.997136)
		(width 0.1778)
		(layer "F.Cu")
		(net "BMC_PHY_RDAC")
	)
	(segment
		(start 176.753012 -31.46298)
		(end 176.394364 -31.821628)
		(width 0.1778)
		(layer "F.Cu")
		(net "BMC_PHY_RDAC")
	)
	(segment
		(start 178.716432 -31.46298)
		(end 176.753012 -31.46298)
		(width 0.1778)
		(layer "F.Cu")
		(net "BMC_PHY_RDAC")
	)
	(via
		(at 176.394364 -33.853628)
		(size 0.7112)
		(drill 0.3556)
		(layers "F.Cu" "B.Cu")
		(net "BMC_PHY_RDAC")
	)
	(segment
		(start 291.00145 -186.49315)
		(end 293.497 -188.9887)
		(width 0.1143)
		(layer "F.Cu")
		(net "MEMCASN")
	)
	(segment
		(start 295.5925 -188.9887)
		(end 295.7068 -189.103)
		(width 0.1143)
		(layer "F.Cu")
		(net "MEMCASN")
	)
	(segment
		(start 289.698176 -200.92797)
		(end 290.089844 -200.536302)
		(width 0.1143)
		(layer "F.Cu")
		(net "MEMCASN")
	)
	(segment
		(start 291.25799 -184.95645)
		(end 291.00145 -185.21299)
		(width 0.1143)
		(layer "F.Cu")
		(net "MEMCASN")
	)
	(segment
		(start 293.497 -188.9887)
		(end 295.5925 -188.9887)
		(width 0.1143)
		(layer "F.Cu")
		(net "MEMCASN")
	)
	(segment
		(start 291.00145 -185.21299)
		(end 291.00145 -186.49315)
		(width 0.1143)
		(layer "F.Cu")
		(net "MEMCASN")
	)
	(segment
		(start 291.335968 -184.95645)
		(end 291.25799 -184.95645)
		(width 0.1143)
		(layer "F.Cu")
		(net "MEMCASN")
	)
	(segment
		(start 292.034976 -184.257442)
		(end 291.335968 -184.95645)
		(width 0.1143)
		(layer "F.Cu")
		(net "MEMCASN")
	)
	(segment
		(start 289.698176 -200.935082)
		(end 289.698176 -200.92797)
		(width 0.1143)
		(layer "F.Cu")
		(net "MEMCASN")
	)
	(segment
		(start 292.034976 -184.24017)
		(end 292.034976 -184.257442)
		(width 0.1143)
		(layer "F.Cu")
		(net "MEMCASN")
	)
	(via
		(at 290.089844 -200.536302)
		(size 0.508)
		(drill 0.254)
		(layers "F.Cu" "B.Cu")
		(net "MEMCASN")
	)
	(via
		(at 295.701212 -192.015618)
		(size 0.7112)
		(drill 0.3556)
		(layers "F.Cu" "B.Cu")
		(net "MEMCASN")
	)
	(via
		(at 295.7068 -189.103)
		(size 0.508)
		(drill 0.254)
		(layers "F.Cu" "B.Cu")
		(net "MEMCASN")
	)
	(segment
		(start 296.07637 -190.224664)
		(end 296.07637 -189.629542)
		(width 0.1143)
		(layer "B.Cu")
		(net "MEMCASN")
	)
	(segment
		(start 296.075354 -190.22568)
		(end 296.07637 -190.224664)
		(width 0.1143)
		(layer "B.Cu")
		(net "MEMCASN")
	)
	(segment
		(start 296.075354 -189.471554)
		(end 295.7068 -189.103)
		(width 0.1143)
		(layer "B.Cu")
		(net "MEMCASN")
	)
	(segment
		(start 291.99713 -198.65721)
		(end 292.041834 -198.65721)
		(width 0.1143)
		(layer "B.Cu")
		(net "MEMCASN")
	)
	(segment
		(start 293.38016 -197.416928)
		(end 293.38016 -195.319904)
		(width 0.1143)
		(layer "B.Cu")
		(net "MEMCASN")
	)
	(segment
		(start 295.701212 -192.015618)
		(end 296.075354 -191.641476)
		(width 0.1143)
		(layer "B.Cu")
		(net "MEMCASN")
	)
	(segment
		(start 296.07637 -189.629542)
		(end 296.075354 -189.628526)
		(width 0.1143)
		(layer "B.Cu")
		(net "MEMCASN")
	)
	(segment
		(start 292.685978 -198.013066)
		(end 292.784022 -198.013066)
		(width 0.1143)
		(layer "B.Cu")
		(net "MEMCASN")
	)
	(segment
		(start 291.421058 -199.233282)
		(end 291.99713 -198.65721)
		(width 0.1143)
		(layer "B.Cu")
		(net "MEMCASN")
	)
	(segment
		(start 295.701212 -193.036952)
		(end 295.701212 -192.015618)
		(width 0.1143)
		(layer "B.Cu")
		(net "MEMCASN")
	)
	(segment
		(start 290.089844 -200.536302)
		(end 290.264596 -200.36155)
		(width 0.1143)
		(layer "B.Cu")
		(net "MEMCASN")
	)
	(segment
		(start 296.075354 -191.641476)
		(end 296.075354 -190.22568)
		(width 0.1143)
		(layer "B.Cu")
		(net "MEMCASN")
	)
	(segment
		(start 292.784022 -198.013066)
		(end 293.38016 -197.416928)
		(width 0.1143)
		(layer "B.Cu")
		(net "MEMCASN")
	)
	(segment
		(start 292.041834 -198.65721)
		(end 292.685978 -198.013066)
		(width 0.1143)
		(layer "B.Cu")
		(net "MEMCASN")
	)
	(segment
		(start 290.351464 -200.36155)
		(end 291.421058 -199.291956)
		(width 0.1143)
		(layer "B.Cu")
		(net "MEMCASN")
	)
	(segment
		(start 294.204644 -194.49542)
		(end 294.243252 -194.49542)
		(width 0.1143)
		(layer "B.Cu")
		(net "MEMCASN")
	)
	(segment
		(start 293.38016 -195.319904)
		(end 294.204644 -194.49542)
		(width 0.1143)
		(layer "B.Cu")
		(net "MEMCASN")
	)
	(segment
		(start 296.075354 -189.628526)
		(end 296.075354 -189.471554)
		(width 0.1143)
		(layer "B.Cu")
		(net "MEMCASN")
	)
	(segment
		(start 290.264596 -200.36155)
		(end 290.351464 -200.36155)
		(width 0.1143)
		(layer "B.Cu")
		(net "MEMCASN")
	)
	(segment
		(start 294.243252 -194.49542)
		(end 295.491662 -193.24701)
		(width 0.1143)
		(layer "B.Cu")
		(net "MEMCASN")
	)
	(segment
		(start 295.491662 -193.24701)
		(end 295.701212 -193.036952)
		(width 0.1143)
		(layer "B.Cu")
		(net "MEMCASN")
	)
	(segment
		(start 291.421058 -199.291956)
		(end 291.421058 -199.233282)
		(width 0.1143)
		(layer "B.Cu")
		(net "MEMCASN")
	)
	(segment
		(start 14.244066 -226.68103)
		(end 21.610066 -226.68103)
		(width 0.1143)
		(layer "F.Cu")
		(net "SAS_HDD_PWR12")
	)
	(segment
		(start 13.40358 -227.521516)
		(end 14.244066 -226.68103)
		(width 0.1143)
		(layer "F.Cu")
		(net "SAS_HDD_PWR12")
	)
	(segment
		(start 13.40358 -230.188516)
		(end 13.40358 -228.952552)
		(width 0.1143)
		(layer "F.Cu")
		(net "SAS_HDD_PWR12")
	)
	(segment
		(start 13.40358 -228.952552)
		(end 13.40358 -227.521516)
		(width 0.1143)
		(layer "F.Cu")
		(net "SAS_HDD_PWR12")
	)
	(segment
		(start 22.333712 -225.957384)
		(end 21.71573 -226.575366)
		(width 0.1143)
		(layer "F.Cu")
		(net "SAS_HDD_PWR12")
	)
	(segment
		(start 22.333712 -222.325438)
		(end 22.333712 -225.957384)
		(width 0.1143)
		(layer "F.Cu")
		(net "SAS_HDD_PWR12")
	)
	(segment
		(start 13.285216 -230.30688)
		(end 13.40358 -230.188516)
		(width 0.1143)
		(layer "F.Cu")
		(net "SAS_HDD_PWR12")
	)
	(segment
		(start 21.610066 -226.68103)
		(end 21.71573 -226.575366)
		(width 0.1143)
		(layer "F.Cu")
		(net "SAS_HDD_PWR12")
	)
	(via
		(at 13.285216 -230.30688)
		(size 0.5588)
		(drill 0.3048)
		(layers "F.Cu" "B.Cu")
		(net "SAS_HDD_PWR12")
	)
	(via
		(at 21.71573 -226.575366)
		(size 0.7112)
		(drill 0.3556)
		(layers "F.Cu" "B.Cu")
		(net "SAS_HDD_PWR12")
	)
	(segment
		(start 13.285216 -231.323388)
		(end 13.285216 -230.30688)
		(width 0.1143)
		(layer "B.Cu")
		(net "SAS_HDD_PWR12")
	)
	(segment
		(start 13.34008 -231.378252)
		(end 13.285216 -231.323388)
		(width 0.1143)
		(layer "B.Cu")
		(net "SAS_HDD_PWR12")
	)
	(segment
		(start 177.556922 -32.05607)
		(end 177.100992 -32.512)
		(width 0.3048)
		(layer "F.Cu")
		(net "PHY_AVDD")
	)
	(segment
		(start 151.35987 -19.333464)
		(end 151.35987 -20.349972)
		(width 0.508)
		(layer "F.Cu")
		(net "PHY_AVDD")
	)
	(segment
		(start 179.886864 -32.05607)
		(end 177.556922 -32.05607)
		(width 0.3048)
		(layer "F.Cu")
		(net "PHY_AVDD")
	)
	(segment
		(start 152.385014 -17.809972)
		(end 152.385014 -18.82648)
		(width 0.508)
		(layer "F.Cu")
		(net "PHY_AVDD")
	)
	(segment
		(start 179.886864 -30.056074)
		(end 178.295046 -30.056074)
		(width 0.3048)
		(layer "F.Cu")
		(net "PHY_AVDD")
	)
	(segment
		(start 150.343362 -20.349972)
		(end 151.35987 -20.349972)
		(width 0.508)
		(layer "F.Cu")
		(net "PHY_AVDD")
	)
	(segment
		(start 151.368506 -17.809972)
		(end 152.385014 -17.809972)
		(width 0.508)
		(layer "F.Cu")
		(net "PHY_AVDD")
	)
	(segment
		(start 151.35987 -20.349972)
		(end 151.35987 -21.36648)
		(width 0.508)
		(layer "F.Cu")
		(net "PHY_AVDD")
	)
	(segment
		(start 152.385014 -16.793464)
		(end 152.385014 -17.809972)
		(width 0.508)
		(layer "F.Cu")
		(net "PHY_AVDD")
	)
	(via
		(at 177.100992 -32.512)
		(size 0.7112)
		(drill 0.4064)
		(layers "F.Cu" "B.Cu")
		(net "PHY_AVDD")
	)
	(via
		(at 178.295046 -30.056074)
		(size 0.7112)
		(drill 0.4064)
		(layers "F.Cu" "B.Cu")
		(net "PHY_AVDD")
	)
	(via
		(at 178.243992 -31.8516)
		(size 0.7112)
		(drill 0.3556)
		(layers "F.Cu" "B.Cu")
		(net "PHY_AVDD")
	)
	(segment
		(start 177.100992 -32.512)
		(end 177.761392 -31.8516)
		(width 0.508)
		(layer "B.Cu")
		(net "PHY_AVDD")
	)
	(segment
		(start 177.761392 -31.8516)
		(end 178.243992 -31.8516)
		(width 0.508)
		(layer "B.Cu")
		(net "PHY_AVDD")
	)
	(segment
		(start 151.368506 -17.809972)
		(end 152.385014 -17.809972)
		(width 0.508)
		(layer "B.Cu")
		(net "PHY_AVDD")
	)
	(segment
		(start 150.343362 -20.349972)
		(end 151.35987 -20.349972)
		(width 0.508)
		(layer "B.Cu")
		(net "PHY_AVDD")
	)
	(segment
		(start 179.569364 -32.076136)
		(end 178.874928 -32.076136)
		(width 0.508)
		(layer "B.Cu")
		(net "PHY_AVDD")
	)
	(segment
		(start 178.874928 -32.076136)
		(end 178.650392 -31.8516)
		(width 0.508)
		(layer "B.Cu")
		(net "PHY_AVDD")
	)
	(segment
		(start 179.569364 -29.773372)
		(end 179.569364 -31.187136)
		(width 0.508)
		(layer "B.Cu")
		(net "PHY_AVDD")
	)
	(segment
		(start 178.650392 -31.8516)
		(end 178.243992 -31.8516)
		(width 0.508)
		(layer "B.Cu")
		(net "PHY_AVDD")
	)
	(segment
		(start 179.513992 -29.718)
		(end 178.63312 -29.718)
		(width 0.508)
		(layer "B.Cu")
		(net "PHY_AVDD")
	)
	(segment
		(start 151.35987 -20.349972)
		(end 151.35987 -21.36648)
		(width 0.508)
		(layer "B.Cu")
		(net "PHY_AVDD")
	)
	(segment
		(start 179.513992 -29.718)
		(end 179.569364 -29.773372)
		(width 0.508)
		(layer "B.Cu")
		(net "PHY_AVDD")
	)
	(segment
		(start 152.385014 -17.809972)
		(end 152.385014 -18.82648)
		(width 0.508)
		(layer "B.Cu")
		(net "PHY_AVDD")
	)
	(segment
		(start 179.569364 -31.187136)
		(end 179.569364 -32.076136)
		(width 0.508)
		(layer "B.Cu")
		(net "PHY_AVDD")
	)
	(segment
		(start 178.63312 -29.718)
		(end 178.295046 -30.056074)
		(width 0.508)
		(layer "B.Cu")
		(net "PHY_AVDD")
	)
	(segment
		(start 152.385014 -16.793464)
		(end 152.385014 -17.809972)
		(width 0.508)
		(layer "B.Cu")
		(net "PHY_AVDD")
	)
	(segment
		(start 151.35987 -19.333464)
		(end 151.35987 -20.349972)
		(width 0.508)
		(layer "B.Cu")
		(net "PHY_AVDD")
	)
	(segment
		(start 288.396934 -183.2864)
		(end 288.396934 -183.585866)
		(width 0.1143)
		(layer "F.Cu")
		(net "MEMA_13")
	)
	(segment
		(start 288.103564 -183.879236)
		(end 287.919922 -183.879236)
		(width 0.1143)
		(layer "F.Cu")
		(net "MEMA_13")
	)
	(segment
		(start 287.571434 -184.227724)
		(end 287.571434 -184.379616)
		(width 0.1143)
		(layer "F.Cu")
		(net "MEMA_13")
	)
	(segment
		(start 288.83483 -182.640224)
		(end 288.83483 -182.848504)
		(width 0.1143)
		(layer "F.Cu")
		(net "MEMA_13")
	)
	(segment
		(start 288.396934 -183.585866)
		(end 288.103564 -183.879236)
		(width 0.1143)
		(layer "F.Cu")
		(net "MEMA_13")
	)
	(segment
		(start 284.898084 -200.935082)
		(end 284.24124 -200.935082)
		(width 0.1143)
		(layer "F.Cu")
		(net "MEMA_13")
	)
	(segment
		(start 286.755586 -185.195464)
		(end 286.755586 -185.407808)
		(width 0.1143)
		(layer "F.Cu")
		(net "MEMA_13")
	)
	(segment
		(start 287.571434 -184.379616)
		(end 286.755586 -185.195464)
		(width 0.1143)
		(layer "F.Cu")
		(net "MEMA_13")
	)
	(segment
		(start 288.83483 -182.848504)
		(end 288.396934 -183.2864)
		(width 0.1143)
		(layer "F.Cu")
		(net "MEMA_13")
	)
	(segment
		(start 287.919922 -183.879236)
		(end 287.571434 -184.227724)
		(width 0.1143)
		(layer "F.Cu")
		(net "MEMA_13")
	)
	(via
		(at 286.755586 -185.407808)
		(size 0.508)
		(drill 0.254)
		(layers "F.Cu" "B.Cu")
		(net "MEMA_13")
	)
	(via
		(at 282.0416 -195.453)
		(size 0.7112)
		(drill 0.3556)
		(layers "F.Cu" "B.Cu")
		(net "MEMA_13")
	)
	(via
		(at 284.24124 -200.935082)
		(size 0.508)
		(drill 0.254)
		(layers "F.Cu" "B.Cu")
		(net "MEMA_13")
	)
	(segment
		(start 284.954472 -185.674)
		(end 282.0289 -188.599572)
		(width 0.1143)
		(layer "B.Cu")
		(net "MEMA_13")
	)
	(segment
		(start 282.0416 -195.453)
		(end 282.0416 -198.743062)
		(width 0.1143)
		(layer "B.Cu")
		(net "MEMA_13")
	)
	(segment
		(start 282.0416 -198.743062)
		(end 282.03525 -198.749412)
		(width 0.1143)
		(layer "B.Cu")
		(net "MEMA_13")
	)
	(segment
		(start 286.755586 -185.407808)
		(end 286.016192 -185.407808)
		(width 0.1143)
		(layer "B.Cu")
		(net "MEMA_13")
	)
	(segment
		(start 283.752544 -200.935082)
		(end 284.24124 -200.935082)
		(width 0.1143)
		(layer "B.Cu")
		(net "MEMA_13")
	)
	(segment
		(start 282.0416 -194.262756)
		(end 282.0416 -195.453)
		(width 0.1143)
		(layer "B.Cu")
		(net "MEMA_13")
	)
	(segment
		(start 286.016192 -185.407808)
		(end 285.75 -185.674)
		(width 0.1143)
		(layer "B.Cu")
		(net "MEMA_13")
	)
	(segment
		(start 282.03525 -198.749412)
		(end 282.03525 -199.217788)
		(width 0.1143)
		(layer "B.Cu")
		(net "MEMA_13")
	)
	(segment
		(start 282.0289 -188.599572)
		(end 282.0289 -194.250056)
		(width 0.1143)
		(layer "B.Cu")
		(net "MEMA_13")
	)
	(segment
		(start 285.75 -185.674)
		(end 284.954472 -185.674)
		(width 0.1143)
		(layer "B.Cu")
		(net "MEMA_13")
	)
	(segment
		(start 282.03525 -199.217788)
		(end 283.752544 -200.935082)
		(width 0.1143)
		(layer "B.Cu")
		(net "MEMA_13")
	)
	(segment
		(start 282.0289 -194.250056)
		(end 282.0416 -194.262756)
		(width 0.1143)
		(layer "B.Cu")
		(net "MEMA_13")
	)
	(segment
		(start 37.134546 -245.794784)
		(end 44.000166 -252.660404)
		(width 0.1143)
		(layer "F.Cu")
		(net "SAS_HDD_PWR3_PCIE")
	)
	(segment
		(start 29.604716 -234.19308)
		(end 29.604716 -233.412284)
		(width 0.1143)
		(layer "F.Cu")
		(net "SAS_HDD_PWR3_PCIE")
	)
	(segment
		(start 29.604716 -233.412284)
		(end 31.877 -231.14)
		(width 0.1143)
		(layer "F.Cu")
		(net "SAS_HDD_PWR3_PCIE")
	)
	(segment
		(start 37.134546 -233.476546)
		(end 37.134546 -245.794784)
		(width 0.1143)
		(layer "F.Cu")
		(net "SAS_HDD_PWR3_PCIE")
	)
	(segment
		(start 44.000166 -252.660404)
		(end 44.000166 -256.25044)
		(width 0.1143)
		(layer "F.Cu")
		(net "SAS_HDD_PWR3_PCIE")
	)
	(segment
		(start 34.798 -231.14)
		(end 37.134546 -233.476546)
		(width 0.1143)
		(layer "F.Cu")
		(net "SAS_HDD_PWR3_PCIE")
	)
	(segment
		(start 31.877 -231.14)
		(end 34.798 -231.14)
		(width 0.1143)
		(layer "F.Cu")
		(net "SAS_HDD_PWR3_PCIE")
	)
	(segment
		(start 29.6164 -236.200696)
		(end 29.604716 -236.189012)
		(width 0.1143)
		(layer "F.Cu")
		(net "SAS_HDD_PWR3_PCIE")
	)
	(segment
		(start 29.604716 -236.189012)
		(end 29.604716 -234.19308)
		(width 0.1143)
		(layer "F.Cu")
		(net "SAS_HDD_PWR3_PCIE")
	)
	(via
		(at 28.568904 -234.884976)
		(size 0.7112)
		(drill 0.3556)
		(layers "F.Cu" "B.Cu")
		(net "SAS_HDD_PWR3_PCIE")
	)
	(via
		(at 29.6164 -236.200696)
		(size 0.5588)
		(drill 0.3048)
		(layers "F.Cu" "B.Cu")
		(net "SAS_HDD_PWR3_PCIE")
	)
	(segment
		(start 29.6164 -235.932472)
		(end 28.568904 -234.884976)
		(width 0.1143)
		(layer "B.Cu")
		(net "SAS_HDD_PWR3_PCIE")
	)
	(segment
		(start 28.398216 -234.714288)
		(end 28.568904 -234.884976)
		(width 0.1143)
		(layer "B.Cu")
		(net "SAS_HDD_PWR3_PCIE")
	)
	(segment
		(start 29.6164 -236.200696)
		(end 29.6164 -235.932472)
		(width 0.1143)
		(layer "B.Cu")
		(net "SAS_HDD_PWR3_PCIE")
	)
	(segment
		(start 28.398216 -232.78338)
		(end 28.398216 -234.714288)
		(width 0.1143)
		(layer "B.Cu")
		(net "SAS_HDD_PWR3_PCIE")
	)
	(segment
		(start 292.083236 -147.681188)
		(end 292.317424 -147.447)
		(width 0.1143)
		(layer "F.Cu")
		(net "FM_OSC_50M_EN")
	)
	(segment
		(start 291.0586 -147.2692)
		(end 291.470588 -147.681188)
		(width 0.1143)
		(layer "F.Cu")
		(net "FM_OSC_50M_EN")
	)
	(segment
		(start 292.317424 -147.447)
		(end 292.354 -147.447)
		(width 0.1143)
		(layer "F.Cu")
		(net "FM_OSC_50M_EN")
	)
	(segment
		(start 291.470588 -147.681188)
		(end 292.083236 -147.681188)
		(width 0.1143)
		(layer "F.Cu")
		(net "FM_OSC_50M_EN")
	)
	(segment
		(start 292.354 -147.447)
		(end 294.188896 -145.612104)
		(width 0.1143)
		(layer "F.Cu")
		(net "FM_OSC_50M_EN")
	)
	(segment
		(start 294.188896 -145.612104)
		(end 294.623236 -145.612104)
		(width 0.1143)
		(layer "F.Cu")
		(net "FM_OSC_50M_EN")
	)
	(via
		(at 291.0332 -146.3548)
		(size 0.7112)
		(drill 0.3556)
		(layers "F.Cu" "B.Cu")
		(net "FM_OSC_50M_EN")
	)
	(via
		(at 291.0586 -147.2692)
		(size 0.5588)
		(drill 0.3048)
		(layers "F.Cu" "B.Cu")
		(net "FM_OSC_50M_EN")
	)
	(segment
		(start 291.0332 -146.3548)
		(end 291.0332 -147.2438)
		(width 0.1143)
		(layer "B.Cu")
		(net "FM_OSC_50M_EN")
	)
	(segment
		(start 291.0332 -147.2438)
		(end 291.0586 -147.2692)
		(width 0.1143)
		(layer "B.Cu")
		(net "FM_OSC_50M_EN")
	)
	(segment
		(start 172.231304 -26.295096)
		(end 171.504102 -26.295096)
		(width 0.1397)
		(layer "F.Cu")
		(net "BCM5221_MB_TX_DN")
	)
	(via
		(at 171.286932 -26.20518)
		(size 0.5588)
		(drill 0.3048)
		(layers "F.Cu" "B.Cu")
		(net "BCM5221_MB_TX_DN")
	)
	(arc
		(start 171.504102 -26.295096)
		(mid 171.386585 -26.27172)
		(end 171.286932 -26.20518)
		(width 0.1397)
		(layer "F.Cu")
		(net "BCM5221_MB_TX_DN")
	)
	(segment
		(start 173.199044 -27.3431)
		(end 174.600362 -27.3431)
		(width 0.1397)
		(layer "B.Cu")
		(net "BCM5221_MB_TX_DN")
	)
	(segment
		(start 168.3131 -27.3431)
		(end 169.526458 -27.3431)
		(width 0.1397)
		(layer "B.Cu")
		(net "BCM5221_MB_TX_DN")
	)
	(segment
		(start 154.977592 -20.349972)
		(end 154.583892 -20.743672)
		(width 0.1397)
		(layer "B.Cu")
		(net "BCM5221_MB_TX_DN")
	)
	(segment
		(start 174.712884 -25.834086)
		(end 171.436792 -25.834086)
		(width 0.1397)
		(layer "B.Cu")
		(net "BCM5221_MB_TX_DN")
	)
	(segment
		(start 155.702 -22.606)
		(end 163.576 -22.606)
		(width 0.1397)
		(layer "B.Cu")
		(net "BCM5221_MB_TX_DN")
	)
	(segment
		(start 175.107092 -26.800556)
		(end 175.107092 -26.177748)
		(width 0.1397)
		(layer "B.Cu")
		(net "BCM5221_MB_TX_DN")
	)
	(segment
		(start 170.764962 -27.3431)
		(end 171.977304 -27.3431)
		(width 0.1397)
		(layer "B.Cu")
		(net "BCM5221_MB_TX_DN")
	)
	(segment
		(start 163.576 -22.606)
		(end 168.3131 -27.3431)
		(width 0.1397)
		(layer "B.Cu")
		(net "BCM5221_MB_TX_DN")
	)
	(segment
		(start 155.419806 -20.349972)
		(end 154.977592 -20.349972)
		(width 0.1397)
		(layer "B.Cu")
		(net "BCM5221_MB_TX_DN")
	)
	(segment
		(start 154.583892 -20.743672)
		(end 154.583892 -21.487892)
		(width 0.1397)
		(layer "B.Cu")
		(net "BCM5221_MB_TX_DN")
	)
	(segment
		(start 169.944542 -27.14244)
		(end 170.363642 -27.14244)
		(width 0.1397)
		(layer "B.Cu")
		(net "BCM5221_MB_TX_DN")
	)
	(segment
		(start 171.286932 -25.983946)
		(end 171.286932 -26.20518)
		(width 0.1397)
		(layer "B.Cu")
		(net "BCM5221_MB_TX_DN")
	)
	(segment
		(start 154.583892 -21.487892)
		(end 155.702 -22.606)
		(width 0.1397)
		(layer "B.Cu")
		(net "BCM5221_MB_TX_DN")
	)
	(segment
		(start 172.378624 -27.14244)
		(end 172.797724 -27.14244)
		(width 0.1397)
		(layer "B.Cu")
		(net "BCM5221_MB_TX_DN")
	)
	(arc
		(start 175.107092 -26.177748)
		(mid 175.083658 -26.05994)
		(end 175.016922 -25.96007)
		(width 0.1397)
		(layer "B.Cu")
		(net "BCM5221_MB_TX_DN")
	)
	(arc
		(start 170.363642 -27.14244)
		(mid 170.475799 -27.168964)
		(end 170.564302 -27.24277)
		(width 0.1397)
		(layer "B.Cu")
		(net "BCM5221_MB_TX_DN")
	)
	(arc
		(start 169.743882 -27.24277)
		(mid 169.832408 -27.16901)
		(end 169.944542 -27.14244)
		(width 0.1397)
		(layer "B.Cu")
		(net "BCM5221_MB_TX_DN")
	)
	(arc
		(start 174.600362 -27.3431)
		(mid 174.784559 -27.306461)
		(end 174.940722 -27.20213)
		(width 0.1397)
		(layer "B.Cu")
		(net "BCM5221_MB_TX_DN")
	)
	(arc
		(start 172.177964 -27.24277)
		(mid 172.26649 -27.16901)
		(end 172.378624 -27.14244)
		(width 0.1397)
		(layer "B.Cu")
		(net "BCM5221_MB_TX_DN")
	)
	(arc
		(start 171.977304 -27.3431)
		(mid 172.089461 -27.316576)
		(end 172.177964 -27.24277)
		(width 0.1397)
		(layer "B.Cu")
		(net "BCM5221_MB_TX_DN")
	)
	(arc
		(start 172.797724 -27.14244)
		(mid 172.909881 -27.168964)
		(end 172.998384 -27.24277)
		(width 0.1397)
		(layer "B.Cu")
		(net "BCM5221_MB_TX_DN")
	)
	(arc
		(start 174.940722 -27.20213)
		(mid 175.06383 -27.017886)
		(end 175.107092 -26.800556)
		(width 0.1397)
		(layer "B.Cu")
		(net "BCM5221_MB_TX_DN")
	)
	(arc
		(start 171.436792 -25.834086)
		(mid 171.330825 -25.877979)
		(end 171.286932 -25.983946)
		(width 0.1397)
		(layer "B.Cu")
		(net "BCM5221_MB_TX_DN")
	)
	(arc
		(start 172.998384 -27.24277)
		(mid 173.08691 -27.31653)
		(end 173.199044 -27.3431)
		(width 0.1397)
		(layer "B.Cu")
		(net "BCM5221_MB_TX_DN")
	)
	(arc
		(start 170.564302 -27.24277)
		(mid 170.570494 -27.250646)
		(end 170.577002 -27.258264)
		(width 0.1397)
		(layer "B.Cu")
		(net "BCM5221_MB_TX_DN")
	)
	(arc
		(start 169.731182 -27.258264)
		(mid 169.737689 -27.250646)
		(end 169.743882 -27.24277)
		(width 0.1397)
		(layer "B.Cu")
		(net "BCM5221_MB_TX_DN")
	)
	(arc
		(start 170.577002 -27.258264)
		(mid 170.661893 -27.320796)
		(end 170.764962 -27.3431)
		(width 0.1397)
		(layer "B.Cu")
		(net "BCM5221_MB_TX_DN")
	)
	(arc
		(start 175.016922 -25.96007)
		(mid 174.877428 -25.866863)
		(end 174.712884 -25.834086)
		(width 0.1397)
		(layer "B.Cu")
		(net "BCM5221_MB_TX_DN")
	)
	(arc
		(start 169.526458 -27.3431)
		(mid 169.637268 -27.321059)
		(end 169.731182 -27.258264)
		(width 0.1397)
		(layer "B.Cu")
		(net "BCM5221_MB_TX_DN")
	)
	(segment
		(start 291.211 -210.058)
		(end 290.0045 -210.058)
		(width 0.1143)
		(layer "F.Cu")
		(net "DDR_VREF")
	)
	(segment
		(start 287.66008 -194.53352)
		(end 287.68675 -194.56019)
		(width 0.1143)
		(layer "F.Cu")
		(net "DDR_VREF")
	)
	(segment
		(start 290.0045 -208.915)
		(end 291.5285 -208.915)
		(width 0.1143)
		(layer "F.Cu")
		(net "DDR_VREF")
	)
	(segment
		(start 292.034976 -181.040024)
		(end 292.025324 -181.040024)
		(width 0.1143)
		(layer "F.Cu")
		(net "DDR_VREF")
	)
	(segment
		(start 291.5285 -208.915)
		(end 291.5285 -207.772)
		(width 0.1143)
		(layer "F.Cu")
		(net "DDR_VREF")
	)
	(segment
		(start 286.74949 -191.544702)
		(end 286.74949 -190.53683)
		(width 0.1143)
		(layer "F.Cu")
		(net "DDR_VREF")
	)
	(segment
		(start 291.298122 -202.535028)
		(end 291.298122 -206.525622)
		(width 0.1143)
		(layer "F.Cu")
		(net "DDR_VREF")
	)
	(segment
		(start 291.5285 -208.915)
		(end 291.211 -209.2325)
		(width 0.1143)
		(layer "F.Cu")
		(net "DDR_VREF")
	)
	(segment
		(start 290.0045 -210.058)
		(end 290.0045 -211.0613)
		(width 0.1143)
		(layer "F.Cu")
		(net "DDR_VREF")
	)
	(segment
		(start 283.93644 -190.40856)
		(end 283.0322 -191.3128)
		(width 0.1143)
		(layer "F.Cu")
		(net "DDR_VREF")
	)
	(segment
		(start 287.66008 -194.95008)
		(end 287.66008 -196.209412)
		(width 0.1143)
		(layer "F.Cu")
		(net "DDR_VREF")
	)
	(segment
		(start 291.298122 -206.525622)
		(end 291.5285 -206.756)
		(width 0.1143)
		(layer "F.Cu")
		(net "DDR_VREF")
	)
	(segment
		(start 287.491424 -192.286636)
		(end 287.441894 -192.237106)
		(width 0.1143)
		(layer "F.Cu")
		(net "DDR_VREF")
	)
	(segment
		(start 287.66008 -194.249548)
		(end 287.66008 -194.53352)
		(width 0.1143)
		(layer "F.Cu")
		(net "DDR_VREF")
	)
	(segment
		(start 291.5285 -207.772)
		(end 291.5285 -206.756)
		(width 0.1143)
		(layer "F.Cu")
		(net "DDR_VREF")
	)
	(segment
		(start 287.441894 -192.237106)
		(end 286.74949 -191.544702)
		(width 0.1143)
		(layer "F.Cu")
		(net "DDR_VREF")
	)
	(segment
		(start 283.0322 -191.3128)
		(end 283.0322 -199.644)
		(width 0.1143)
		(layer "F.Cu")
		(net "DDR_VREF")
	)
	(segment
		(start 288.987992 -192.921636)
		(end 287.66008 -194.249548)
		(width 0.1143)
		(layer "F.Cu")
		(net "DDR_VREF")
	)
	(segment
		(start 286.74949 -190.53683)
		(end 286.62122 -190.40856)
		(width 0.1143)
		(layer "F.Cu")
		(net "DDR_VREF")
	)
	(segment
		(start 287.68675 -194.56019)
		(end 287.68675 -194.92341)
		(width 0.1143)
		(layer "F.Cu")
		(net "DDR_VREF")
	)
	(segment
		(start 287.66008 -196.209412)
		(end 288.097976 -196.647308)
		(width 0.1143)
		(layer "F.Cu")
		(net "DDR_VREF")
	)
	(segment
		(start 290.0045 -211.0613)
		(end 289.8394 -211.2264)
		(width 0.1143)
		(layer "F.Cu")
		(net "DDR_VREF")
	)
	(segment
		(start 288.987992 -192.286636)
		(end 288.987992 -192.921636)
		(width 0.1143)
		(layer "F.Cu")
		(net "DDR_VREF")
	)
	(segment
		(start 288.987992 -192.286636)
		(end 287.491424 -192.286636)
		(width 0.1143)
		(layer "F.Cu")
		(net "DDR_VREF")
	)
	(segment
		(start 288.097976 -196.647308)
		(end 288.097976 -196.93509)
		(width 0.1143)
		(layer "F.Cu")
		(net "DDR_VREF")
	)
	(segment
		(start 287.68675 -194.92341)
		(end 287.66008 -194.95008)
		(width 0.1143)
		(layer "F.Cu")
		(net "DDR_VREF")
	)
	(segment
		(start 292.025324 -181.040024)
		(end 291.634926 -180.649626)
		(width 0.1143)
		(layer "F.Cu")
		(net "DDR_VREF")
	)
	(segment
		(start 291.211 -209.2325)
		(end 291.211 -210.058)
		(width 0.1143)
		(layer "F.Cu")
		(net "DDR_VREF")
	)
	(segment
		(start 283.0322 -199.644)
		(end 282.0162 -200.66)
		(width 0.1143)
		(layer "F.Cu")
		(net "DDR_VREF")
	)
	(segment
		(start 286.62122 -190.40856)
		(end 283.93644 -190.40856)
		(width 0.1143)
		(layer "F.Cu")
		(net "DDR_VREF")
	)
	(via
		(at 289.8394 -211.2264)
		(size 0.508)
		(drill 0.254)
		(layers "F.Cu" "B.Cu")
		(net "DDR_VREF")
	)
	(via
		(at 287.441894 -192.237106)
		(size 0.7112)
		(drill 0.3556)
		(layers "F.Cu" "B.Cu")
		(net "DDR_VREF")
	)
	(via
		(at 282.0162 -200.66)
		(size 0.5588)
		(drill 0.3048)
		(layers "F.Cu" "B.Cu")
		(net "DDR_VREF")
	)
	(via
		(at 286.62122 -190.40856)
		(size 0.5588)
		(drill 0.3048)
		(layers "F.Cu" "B.Cu")
		(net "DDR_VREF")
	)
	(via
		(at 291.634926 -180.649626)
		(size 0.508)
		(drill 0.254)
		(layers "F.Cu" "B.Cu")
		(net "DDR_VREF")
	)
	(segment
		(start 286.696658 -190.333122)
		(end 286.62122 -190.40856)
		(width 0.1143)
		(layer "B.Cu")
		(net "DDR_VREF")
	)
	(segment
		(start 287.198308 -183.20004)
		(end 287.198308 -186.814206)
		(width 0.1143)
		(layer "B.Cu")
		(net "DDR_VREF")
	)
	(segment
		(start 282.0162 -200.66)
		(end 282.0162 -205.0796)
		(width 0.1143)
		(layer "B.Cu")
		(net "DDR_VREF")
	)
	(segment
		(start 287.23209 -181.286658)
		(end 287.23209 -181.610762)
		(width 0.0889)
		(layer "B.Cu")
		(net "DDR_VREF")
	)
	(segment
		(start 289.549332 -180.18887)
		(end 289.304476 -179.944014)
		(width 0.1143)
		(layer "B.Cu")
		(net "DDR_VREF")
	)
	(segment
		(start 288.674048 -180.23205)
		(end 288.25571 -180.23205)
		(width 0.1143)
		(layer "B.Cu")
		(net "DDR_VREF")
	)
	(segment
		(start 289.304476 -179.944014)
		(end 288.962084 -179.944014)
		(width 0.1143)
		(layer "B.Cu")
		(net "DDR_VREF")
	)
	(segment
		(start 286.696658 -188.502036)
		(end 286.696658 -190.333122)
		(width 0.1143)
		(layer "B.Cu")
		(net "DDR_VREF")
	)
	(segment
		(start 287.798256 -181.04358)
		(end 287.475168 -181.04358)
		(width 0.0889)
		(layer "B.Cu")
		(net "DDR_VREF")
	)
	(segment
		(start 288.03473 -180.807106)
		(end 287.798256 -181.04358)
		(width 0.0889)
		(layer "B.Cu")
		(net "DDR_VREF")
	)
	(segment
		(start 288.962084 -179.944014)
		(end 288.674048 -180.23205)
		(width 0.1143)
		(layer "B.Cu")
		(net "DDR_VREF")
	)
	(segment
		(start 287.019492 -188.179202)
		(end 286.696658 -188.502036)
		(width 0.1143)
		(layer "B.Cu")
		(net "DDR_VREF")
	)
	(segment
		(start 288.03473 -180.452776)
		(end 288.03473 -180.807106)
		(width 0.0889)
		(layer "B.Cu")
		(net "DDR_VREF")
	)
	(segment
		(start 287.198308 -186.814206)
		(end 287.019492 -186.993022)
		(width 0.1143)
		(layer "B.Cu")
		(net "DDR_VREF")
	)
	(segment
		(start 291.634926 -180.649626)
		(end 291.418772 -180.649626)
		(width 0.1143)
		(layer "B.Cu")
		(net "DDR_VREF")
	)
	(segment
		(start 288.3662 -209.7532)
		(end 289.8394 -211.2264)
		(width 0.1143)
		(layer "B.Cu")
		(net "DDR_VREF")
	)
	(segment
		(start 284.626558 -209.7532)
		(end 288.3662 -209.7532)
		(width 0.1143)
		(layer "B.Cu")
		(net "DDR_VREF")
	)
	(segment
		(start 287.23209 -181.610762)
		(end 287.198308 -181.644544)
		(width 0.0889)
		(layer "B.Cu")
		(net "DDR_VREF")
	)
	(segment
		(start 288.154618 -180.332888)
		(end 288.056066 -180.43144)
		(width 0.1143)
		(layer "B.Cu")
		(net "DDR_VREF")
	)
	(segment
		(start 282.0162 -205.0796)
		(end 281.594814 -205.500986)
		(width 0.1143)
		(layer "B.Cu")
		(net "DDR_VREF")
	)
	(segment
		(start 287.475168 -181.04358)
		(end 287.23209 -181.286658)
		(width 0.0889)
		(layer "B.Cu")
		(net "DDR_VREF")
	)
	(segment
		(start 290.958016 -180.18887)
		(end 289.549332 -180.18887)
		(width 0.1143)
		(layer "B.Cu")
		(net "DDR_VREF")
	)
	(segment
		(start 281.594814 -205.500986)
		(end 281.594814 -206.721456)
		(width 0.1143)
		(layer "B.Cu")
		(net "DDR_VREF")
	)
	(segment
		(start 288.056066 -180.43144)
		(end 288.03473 -180.452776)
		(width 0.0889)
		(layer "B.Cu")
		(net "DDR_VREF")
	)
	(segment
		(start 287.019492 -186.993022)
		(end 287.019492 -188.179202)
		(width 0.1143)
		(layer "B.Cu")
		(net "DDR_VREF")
	)
	(segment
		(start 291.418772 -180.649626)
		(end 290.958016 -180.18887)
		(width 0.1143)
		(layer "B.Cu")
		(net "DDR_VREF")
	)
	(segment
		(start 281.594814 -206.721456)
		(end 284.626558 -209.7532)
		(width 0.1143)
		(layer "B.Cu")
		(net "DDR_VREF")
	)
	(segment
		(start 287.198308 -181.644544)
		(end 287.198308 -183.20004)
		(width 0.0889)
		(layer "B.Cu")
		(net "DDR_VREF")
	)
	(segment
		(start 288.25571 -180.23205)
		(end 288.154618 -180.332888)
		(width 0.1143)
		(layer "B.Cu")
		(net "DDR_VREF")
	)
	(segment
		(start 29.604716 -222.190564)
		(end 29.604716 -227.51288)
		(width 0.1143)
		(layer "F.Cu")
		(net "SAS_HDD_PWR4")
	)
	(segment
		(start 22.983952 -218.796616)
		(end 23.623016 -219.43568)
		(width 0.1143)
		(layer "F.Cu")
		(net "SAS_HDD_PWR4")
	)
	(segment
		(start 26.849832 -219.43568)
		(end 29.604716 -222.190564)
		(width 0.1143)
		(layer "F.Cu")
		(net "SAS_HDD_PWR4")
	)
	(segment
		(start 22.983952 -216.714578)
		(end 22.983952 -218.796616)
		(width 0.1143)
		(layer "F.Cu")
		(net "SAS_HDD_PWR4")
	)
	(segment
		(start 29.604716 -227.51288)
		(end 29.604716 -228.96068)
		(width 0.1143)
		(layer "F.Cu")
		(net "SAS_HDD_PWR4")
	)
	(segment
		(start 23.623016 -219.43568)
		(end 26.849832 -219.43568)
		(width 0.1143)
		(layer "F.Cu")
		(net "SAS_HDD_PWR4")
	)
	(via
		(at 29.604716 -230.89108)
		(size 0.7112)
		(drill 0.3556)
		(layers "F.Cu" "B.Cu")
		(net "SAS_HDD_PWR4")
	)
	(via
		(at 29.604716 -227.51288)
		(size 0.5588)
		(drill 0.3048)
		(layers "F.Cu" "B.Cu")
		(net "SAS_HDD_PWR4")
	)
	(segment
		(start 29.414216 -231.89438)
		(end 29.604716 -231.70388)
		(width 0.1143)
		(layer "B.Cu")
		(net "SAS_HDD_PWR4")
	)
	(segment
		(start 29.604716 -227.51288)
		(end 29.604716 -230.89108)
		(width 0.1143)
		(layer "B.Cu")
		(net "SAS_HDD_PWR4")
	)
	(segment
		(start 29.604716 -231.70388)
		(end 29.604716 -230.89108)
		(width 0.1143)
		(layer "B.Cu")
		(net "SAS_HDD_PWR4")
	)
	(segment
		(start 182.565802 -34.235136)
		(end 182.565802 -35.4076)
		(width 0.127)
		(layer "F.Cu")
		(net "PHY_AD1")
	)
	(segment
		(start 182.834026 -37.320474)
		(end 182.834026 -35.689032)
		(width 0.127)
		(layer "F.Cu")
		(net "PHY_AD1")
	)
	(segment
		(start 182.565802 -35.4076)
		(end 182.834026 -35.675824)
		(width 0.127)
		(layer "F.Cu")
		(net "PHY_AD1")
	)
	(segment
		(start 182.834026 -35.678872)
		(end 182.839106 -35.683952)
		(width 0.127)
		(layer "F.Cu")
		(net "PHY_AD1")
	)
	(segment
		(start 182.834026 -35.689032)
		(end 182.839106 -35.683952)
		(width 0.127)
		(layer "F.Cu")
		(net "PHY_AD1")
	)
	(segment
		(start 182.426864 -37.727636)
		(end 182.834026 -37.320474)
		(width 0.127)
		(layer "F.Cu")
		(net "PHY_AD1")
	)
	(segment
		(start 182.834026 -35.675824)
		(end 182.834026 -35.678872)
		(width 0.127)
		(layer "F.Cu")
		(net "PHY_AD1")
	)
	(via
		(at 182.839106 -35.683952)
		(size 0.7112)
		(drill 0.3556)
		(layers "F.Cu" "B.Cu")
		(net "PHY_AD1")
	)
	(segment
		(start 291.571426 -183.90362)
		(end 291.571426 -184.379616)
		(width 0.1143)
		(layer "F.Cu")
		(net "MEMCSN")
	)
	(segment
		(start 295.587674 -189.9412)
		(end 295.61282 -189.966346)
		(width 0.1143)
		(layer "F.Cu")
		(net "MEMCSN")
	)
	(segment
		(start 290.76015 -185.112914)
		(end 290.76015 -186.844686)
		(width 0.1143)
		(layer "F.Cu")
		(net "MEMCSN")
	)
	(segment
		(start 293.856664 -189.9412)
		(end 295.587674 -189.9412)
		(width 0.1143)
		(layer "F.Cu")
		(net "MEMCSN")
	)
	(segment
		(start 291.157914 -184.71515)
		(end 290.76015 -185.112914)
		(width 0.1143)
		(layer "F.Cu")
		(net "MEMCSN")
	)
	(segment
		(start 288.898076 -201.735182)
		(end 288.898076 -201.72553)
		(width 0.1143)
		(layer "F.Cu")
		(net "MEMCSN")
	)
	(segment
		(start 288.898076 -201.72553)
		(end 289.288474 -201.335132)
		(width 0.1143)
		(layer "F.Cu")
		(net "MEMCSN")
	)
	(segment
		(start 291.235892 -184.71515)
		(end 291.157914 -184.71515)
		(width 0.1143)
		(layer "F.Cu")
		(net "MEMCSN")
	)
	(segment
		(start 291.571426 -184.379616)
		(end 291.235892 -184.71515)
		(width 0.1143)
		(layer "F.Cu")
		(net "MEMCSN")
	)
	(segment
		(start 290.76015 -186.844686)
		(end 293.856664 -189.9412)
		(width 0.1143)
		(layer "F.Cu")
		(net "MEMCSN")
	)
	(segment
		(start 292.034976 -183.44007)
		(end 291.571426 -183.90362)
		(width 0.1143)
		(layer "F.Cu")
		(net "MEMCSN")
	)
	(via
		(at 294.926512 -192.957196)
		(size 0.7112)
		(drill 0.3556)
		(layers "F.Cu" "B.Cu")
		(net "MEMCSN")
	)
	(via
		(at 289.288474 -201.335132)
		(size 0.508)
		(drill 0.254)
		(layers "F.Cu" "B.Cu")
		(net "MEMCSN")
	)
	(via
		(at 295.61282 -189.966346)
		(size 0.508)
		(drill 0.254)
		(layers "F.Cu" "B.Cu")
		(net "MEMCSN")
	)
	(segment
		(start 291.179504 -199.13346)
		(end 291.897054 -198.41591)
		(width 0.1143)
		(layer "B.Cu")
		(net "MEMCSN")
	)
	(segment
		(start 292.586156 -197.771512)
		(end 292.6842 -197.771512)
		(width 0.1143)
		(layer "B.Cu")
		(net "MEMCSN")
	)
	(segment
		(start 294.7543 -193.129408)
		(end 294.926512 -192.957196)
		(width 0.1143)
		(layer "B.Cu")
		(net "MEMCSN")
	)
	(segment
		(start 291.897054 -198.41591)
		(end 291.941758 -198.41591)
		(width 0.1143)
		(layer "B.Cu")
		(net "MEMCSN")
	)
	(segment
		(start 290.273486 -200.098152)
		(end 291.179504 -199.192134)
		(width 0.1143)
		(layer "B.Cu")
		(net "MEMCSN")
	)
	(segment
		(start 293.0144 -197.441312)
		(end 293.0144 -195.150994)
		(width 0.1143)
		(layer "B.Cu")
		(net "MEMCSN")
	)
	(segment
		(start 291.179504 -199.192134)
		(end 291.179504 -199.13346)
		(width 0.1143)
		(layer "B.Cu")
		(net "MEMCSN")
	)
	(segment
		(start 289.288474 -200.717912)
		(end 289.908234 -200.098152)
		(width 0.1143)
		(layer "B.Cu")
		(net "MEMCSN")
	)
	(segment
		(start 291.941758 -198.41591)
		(end 292.586156 -197.771512)
		(width 0.1143)
		(layer "B.Cu")
		(net "MEMCSN")
	)
	(segment
		(start 294.7543 -193.391536)
		(end 294.7543 -193.129408)
		(width 0.1143)
		(layer "B.Cu")
		(net "MEMCSN")
	)
	(segment
		(start 289.908234 -200.098152)
		(end 290.273486 -200.098152)
		(width 0.1143)
		(layer "B.Cu")
		(net "MEMCSN")
	)
	(segment
		(start 294.089582 -194.056254)
		(end 294.7543 -193.391536)
		(width 0.1143)
		(layer "B.Cu")
		(net "MEMCSN")
	)
	(segment
		(start 295.136062 -191.694562)
		(end 295.61282 -191.217804)
		(width 0.1143)
		(layer "B.Cu")
		(net "MEMCSN")
	)
	(segment
		(start 292.6842 -197.771512)
		(end 293.0144 -197.441312)
		(width 0.1143)
		(layer "B.Cu")
		(net "MEMCSN")
	)
	(segment
		(start 295.136062 -192.747646)
		(end 295.136062 -191.694562)
		(width 0.1143)
		(layer "B.Cu")
		(net "MEMCSN")
	)
	(segment
		(start 295.61282 -191.217804)
		(end 295.61282 -189.966346)
		(width 0.1143)
		(layer "B.Cu")
		(net "MEMCSN")
	)
	(segment
		(start 289.288474 -201.335132)
		(end 289.288474 -200.717912)
		(width 0.1143)
		(layer "B.Cu")
		(net "MEMCSN")
	)
	(segment
		(start 293.0144 -195.150994)
		(end 294.089582 -194.075812)
		(width 0.1143)
		(layer "B.Cu")
		(net "MEMCSN")
	)
	(segment
		(start 294.926512 -192.957196)
		(end 295.136062 -192.747646)
		(width 0.1143)
		(layer "B.Cu")
		(net "MEMCSN")
	)
	(segment
		(start 294.089582 -194.075812)
		(end 294.089582 -194.056254)
		(width 0.1143)
		(layer "B.Cu")
		(net "MEMCSN")
	)
	(segment
		(start 30.251146 -236.859064)
		(end 30.239716 -236.847634)
		(width 0.1143)
		(layer "F.Cu")
		(net "SAS_HDD_PWR4_PCIE")
	)
	(segment
		(start 42.999406 -256.25044)
		(end 42.999406 -252.29439)
		(width 0.1143)
		(layer "F.Cu")
		(net "SAS_HDD_PWR4_PCIE")
	)
	(segment
		(start 30.239716 -233.412284)
		(end 30.239716 -234.19308)
		(width 0.1143)
		(layer "F.Cu")
		(net "SAS_HDD_PWR4_PCIE")
	)
	(segment
		(start 30.239716 -236.847634)
		(end 30.239716 -234.19308)
		(width 0.1143)
		(layer "F.Cu")
		(net "SAS_HDD_PWR4_PCIE")
	)
	(segment
		(start 36.685728 -233.662474)
		(end 34.544254 -231.521)
		(width 0.1143)
		(layer "F.Cu")
		(net "SAS_HDD_PWR4_PCIE")
	)
	(segment
		(start 42.999406 -252.29439)
		(end 36.685728 -245.980712)
		(width 0.1143)
		(layer "F.Cu")
		(net "SAS_HDD_PWR4_PCIE")
	)
	(segment
		(start 34.544254 -231.521)
		(end 32.131 -231.521)
		(width 0.1143)
		(layer "F.Cu")
		(net "SAS_HDD_PWR4_PCIE")
	)
	(segment
		(start 36.685728 -245.980712)
		(end 36.685728 -233.662474)
		(width 0.1143)
		(layer "F.Cu")
		(net "SAS_HDD_PWR4_PCIE")
	)
	(segment
		(start 32.131 -231.521)
		(end 30.239716 -233.412284)
		(width 0.1143)
		(layer "F.Cu")
		(net "SAS_HDD_PWR4_PCIE")
	)
	(via
		(at 30.251146 -236.859064)
		(size 0.5588)
		(drill 0.3048)
		(layers "F.Cu" "B.Cu")
		(net "SAS_HDD_PWR4_PCIE")
	)
	(via
		(at 29.769308 -235.285788)
		(size 0.7112)
		(drill 0.3556)
		(layers "F.Cu" "B.Cu")
		(net "SAS_HDD_PWR4_PCIE")
	)
	(segment
		(start 29.769308 -235.285788)
		(end 30.251146 -235.767626)
		(width 0.1143)
		(layer "B.Cu")
		(net "SAS_HDD_PWR4_PCIE")
	)
	(segment
		(start 29.414216 -232.78338)
		(end 29.414216 -234.930696)
		(width 0.1143)
		(layer "B.Cu")
		(net "SAS_HDD_PWR4_PCIE")
	)
	(segment
		(start 30.251146 -235.767626)
		(end 30.251146 -236.859064)
		(width 0.1143)
		(layer "B.Cu")
		(net "SAS_HDD_PWR4_PCIE")
	)
	(segment
		(start 29.414216 -234.930696)
		(end 29.769308 -235.285788)
		(width 0.1143)
		(layer "B.Cu")
		(net "SAS_HDD_PWR4_PCIE")
	)
	(segment
		(start 174.218092 -33.274)
		(end 174.218092 -33.87852)
		(width 0.1397)
		(layer "F.Cu")
		(net "BCM5221_MB_RX_DN")
	)
	(segment
		(start 174.353728 -32.959548)
		(end 174.344584 -32.968692)
		(width 0.1397)
		(layer "F.Cu")
		(net "BCM5221_MB_RX_DN")
	)
	(via
		(at 174.218092 -33.87852)
		(size 0.7112)
		(drill 0.4064)
		(layers "F.Cu" "B.Cu")
		(net "BCM5221_MB_RX_DN")
	)
	(arc
		(start 174.344584 -32.968692)
		(mid 174.250988 -33.108769)
		(end 174.218092 -33.274)
		(width 0.1397)
		(layer "F.Cu")
		(net "BCM5221_MB_RX_DN")
	)
	(segment
		(start 176.364392 -31.0896)
		(end 174.306992 -33.147)
		(width 0.1397)
		(layer "B.Cu")
		(net "BCM5221_MB_RX_DN")
	)
	(segment
		(start 176.719992 -25.52192)
		(end 176.719992 -30.23108)
		(width 0.1397)
		(layer "B.Cu")
		(net "BCM5221_MB_RX_DN")
	)
	(segment
		(start 163.450016 -15.686024)
		(end 164.740844 -16.976598)
		(width 0.1397)
		(layer "B.Cu")
		(net "BCM5221_MB_RX_DN")
	)
	(segment
		(start 174.218092 -33.36163)
		(end 174.218092 -33.87852)
		(width 0.1397)
		(layer "B.Cu")
		(net "BCM5221_MB_RX_DN")
	)
	(segment
		(start 156.15031 -15.2781)
		(end 162.495992 -15.2781)
		(width 0.1397)
		(layer "B.Cu")
		(net "BCM5221_MB_RX_DN")
	)
	(segment
		(start 155.24861 -16.792194)
		(end 155.24861 -16.1798)
		(width 0.1397)
		(layer "B.Cu")
		(net "BCM5221_MB_RX_DN")
	)
	(segment
		(start 162.495992 -15.2781)
		(end 162.495992 -15.277846)
		(width 0.1397)
		(layer "B.Cu")
		(net "BCM5221_MB_RX_DN")
	)
	(segment
		(start 154.414982 -17.809972)
		(end 154.414982 -17.800066)
		(width 0.1397)
		(layer "B.Cu")
		(net "BCM5221_MB_RX_DN")
	)
	(segment
		(start 164.740844 -16.976598)
		(end 165.13556 -17.371314)
		(width 0.1397)
		(layer "B.Cu")
		(net "BCM5221_MB_RX_DN")
	)
	(segment
		(start 174.687992 -22.987)
		(end 176.364392 -24.6634)
		(width 0.1397)
		(layer "B.Cu")
		(net "BCM5221_MB_RX_DN")
	)
	(segment
		(start 154.414982 -17.800066)
		(end 155.12542 -17.089628)
		(width 0.1397)
		(layer "B.Cu")
		(net "BCM5221_MB_RX_DN")
	)
	(segment
		(start 163.428934 -15.664688)
		(end 163.450016 -15.686024)
		(width 0.1397)
		(layer "B.Cu")
		(net "BCM5221_MB_RX_DN")
	)
	(segment
		(start 165.145466 -17.38122)
		(end 170.141392 -22.3774)
		(width 0.1397)
		(layer "B.Cu")
		(net "BCM5221_MB_RX_DN")
	)
	(segment
		(start 170.693334 -22.606)
		(end 173.76775 -22.606)
		(width 0.1397)
		(layer "B.Cu")
		(net "BCM5221_MB_RX_DN")
	)
	(arc
		(start 176.719992 -30.23108)
		(mid 176.627588 -30.695718)
		(end 176.364392 -31.0896)
		(width 0.1397)
		(layer "B.Cu")
		(net "BCM5221_MB_RX_DN")
	)
	(arc
		(start 176.364392 -24.6634)
		(mid 176.627529 -25.057307)
		(end 176.719992 -25.52192)
		(width 0.1397)
		(layer "B.Cu")
		(net "BCM5221_MB_RX_DN")
	)
	(arc
		(start 170.141392 -22.3774)
		(mid 170.394625 -22.546605)
		(end 170.693334 -22.606)
		(width 0.1397)
		(layer "B.Cu")
		(net "BCM5221_MB_RX_DN")
	)
	(arc
		(start 173.76775 -22.606)
		(mid 174.265767 -22.704968)
		(end 174.687992 -22.987)
		(width 0.1397)
		(layer "B.Cu")
		(net "BCM5221_MB_RX_DN")
	)
	(arc
		(start 162.495992 -15.277846)
		(mid 163.000966 -15.378399)
		(end 163.428934 -15.664688)
		(width 0.1397)
		(layer "B.Cu")
		(net "BCM5221_MB_RX_DN")
	)
	(arc
		(start 174.306992 -33.147)
		(mid 174.241194 -33.245473)
		(end 174.218092 -33.36163)
		(width 0.1397)
		(layer "B.Cu")
		(net "BCM5221_MB_RX_DN")
	)
	(arc
		(start 155.24861 -16.1798)
		(mid 155.512712 -15.542202)
		(end 156.15031 -15.2781)
		(width 0.1397)
		(layer "B.Cu")
		(net "BCM5221_MB_RX_DN")
	)
	(arc
		(start 155.12542 -17.089628)
		(mid 155.216602 -16.953164)
		(end 155.24861 -16.792194)
		(width 0.1397)
		(layer "B.Cu")
		(net "BCM5221_MB_RX_DN")
	)
	(arc
		(start 165.13556 -17.371314)
		(mid 165.140542 -17.376238)
		(end 165.145466 -17.38122)
		(width 0.1397)
		(layer "B.Cu")
		(net "BCM5221_MB_RX_DN")
	)
	(segment
		(start 172.231304 -25.152096)
		(end 171.533312 -25.152096)
		(width 0.1397)
		(layer "F.Cu")
		(net "BCM5221_MB_TX_DP")
	)
	(via
		(at 171.315126 -25.24252)
		(size 0.5588)
		(drill 0.3048)
		(layers "F.Cu" "B.Cu")
		(net "BCM5221_MB_TX_DP")
	)
	(arc
		(start 171.533312 -25.152096)
		(mid 171.415212 -25.175588)
		(end 171.315126 -25.24252)
		(width 0.1397)
		(layer "F.Cu")
		(net "BCM5221_MB_TX_DP")
	)
	(segment
		(start 153.864564 -20.349972)
		(end 154.198828 -20.553172)
		(width 0.1397)
		(layer "B.Cu")
		(net "BCM5221_MB_TX_DP")
	)
	(segment
		(start 155.34386 -22.733)
		(end 155.55976 -22.9489)
		(width 0.1397)
		(layer "B.Cu")
		(net "BCM5221_MB_TX_DP")
	)
	(segment
		(start 153.389838 -20.349972)
		(end 153.864564 -20.349972)
		(width 0.1397)
		(layer "B.Cu")
		(net "BCM5221_MB_TX_DP")
	)
	(segment
		(start 155.321 -22.733)
		(end 155.34386 -22.733)
		(width 0.1397)
		(layer "B.Cu")
		(net "BCM5221_MB_TX_DP")
	)
	(segment
		(start 168.17086 -27.686)
		(end 174.600362 -27.686)
		(width 0.1397)
		(layer "B.Cu")
		(net "BCM5221_MB_TX_DP")
	)
	(segment
		(start 154.198828 -20.553172)
		(end 154.198828 -21.610828)
		(width 0.1397)
		(layer "B.Cu")
		(net "BCM5221_MB_TX_DP")
	)
	(segment
		(start 154.198828 -21.610828)
		(end 155.321 -22.733)
		(width 0.1397)
		(layer "B.Cu")
		(net "BCM5221_MB_TX_DP")
	)
	(segment
		(start 155.55976 -22.9489)
		(end 163.43376 -22.9489)
		(width 0.1397)
		(layer "B.Cu")
		(net "BCM5221_MB_TX_DP")
	)
	(segment
		(start 175.449992 -26.80081)
		(end 175.449992 -26.177494)
		(width 0.1397)
		(layer "B.Cu")
		(net "BCM5221_MB_TX_DP")
	)
	(segment
		(start 163.43376 -22.9489)
		(end 168.17086 -27.686)
		(width 0.1397)
		(layer "B.Cu")
		(net "BCM5221_MB_TX_DP")
	)
	(segment
		(start 174.713138 -25.491186)
		(end 171.915582 -25.491186)
		(width 0.1397)
		(layer "B.Cu")
		(net "BCM5221_MB_TX_DP")
	)
	(arc
		(start 171.915582 -25.491186)
		(mid 171.590637 -25.42655)
		(end 171.315126 -25.24252)
		(width 0.1397)
		(layer "B.Cu")
		(net "BCM5221_MB_TX_DP")
	)
	(arc
		(start 175.183292 -27.4447)
		(mid 175.380631 -27.149267)
		(end 175.449992 -26.80081)
		(width 0.1397)
		(layer "B.Cu")
		(net "BCM5221_MB_TX_DP")
	)
	(arc
		(start 175.259492 -25.7175)
		(mid 175.008823 -25.549979)
		(end 174.713138 -25.491186)
		(width 0.1397)
		(layer "B.Cu")
		(net "BCM5221_MB_TX_DP")
	)
	(arc
		(start 174.600362 -27.686)
		(mid 174.915835 -27.623342)
		(end 175.183292 -27.4447)
		(width 0.1397)
		(layer "B.Cu")
		(net "BCM5221_MB_TX_DP")
	)
	(arc
		(start 175.449992 -26.177494)
		(mid 175.400491 -25.928546)
		(end 175.259492 -25.7175)
		(width 0.1397)
		(layer "B.Cu")
		(net "BCM5221_MB_TX_DP")
	)
	(segment
		(start 291.234876 -181.830472)
		(end 290.843462 -181.439058)
		(width 0.1143)
		(layer "F.Cu")
		(net "MEMBA_0")
	)
	(segment
		(start 288.097976 -201.725784)
		(end 287.701736 -201.329544)
		(width 0.1143)
		(layer "F.Cu")
		(net "MEMBA_0")
	)
	(segment
		(start 288.097976 -201.735182)
		(end 288.097976 -201.725784)
		(width 0.1143)
		(layer "F.Cu")
		(net "MEMBA_0")
	)
	(segment
		(start 291.234876 -181.840124)
		(end 291.234876 -181.830472)
		(width 0.1143)
		(layer "F.Cu")
		(net "MEMBA_0")
	)
	(via
		(at 287.701736 -201.329544)
		(size 0.508)
		(drill 0.254)
		(layers "F.Cu" "B.Cu")
		(net "MEMBA_0")
	)
	(via
		(at 290.843462 -181.439058)
		(size 0.508)
		(drill 0.254)
		(layers "F.Cu" "B.Cu")
		(net "MEMBA_0")
	)
	(via
		(at 290.540948 -195.823078)
		(size 0.7112)
		(drill 0.3556)
		(layers "F.Cu" "B.Cu")
		(net "MEMBA_0")
	)
	(segment
		(start 290.540948 -195.874132)
		(end 290.540948 -195.823078)
		(width 0.1143)
		(layer "B.Cu")
		(net "MEMBA_0")
	)
	(segment
		(start 288.51098 -199.826372)
		(end 289.042094 -199.295258)
		(width 0.1143)
		(layer "B.Cu")
		(net "MEMBA_0")
	)
	(segment
		(start 290.95319 -194.20205)
		(end 291.095684 -194.20205)
		(width 0.1143)
		(layer "B.Cu")
		(net "MEMBA_0")
	)
	(segment
		(start 291.177472 -186.276488)
		(end 291.87775 -185.57621)
		(width 0.1143)
		(layer "B.Cu")
		(net "MEMBA_0")
	)
	(segment
		(start 291.177472 -186.980322)
		(end 291.177472 -186.276488)
		(width 0.1143)
		(layer "B.Cu")
		(net "MEMBA_0")
	)
	(segment
		(start 291.13353 -187.024264)
		(end 291.177472 -186.980322)
		(width 0.1143)
		(layer "B.Cu")
		(net "MEMBA_0")
	)
	(segment
		(start 291.87775 -184.217818)
		(end 290.97224 -183.312308)
		(width 0.1143)
		(layer "B.Cu")
		(net "MEMBA_0")
	)
	(segment
		(start 290.97224 -183.312308)
		(end 290.97224 -181.567836)
		(width 0.1143)
		(layer "B.Cu")
		(net "MEMBA_0")
	)
	(segment
		(start 289.042094 -199.295258)
		(end 289.042094 -198.23811)
		(width 0.1143)
		(layer "B.Cu")
		(net "MEMBA_0")
	)
	(segment
		(start 290.540948 -194.614292)
		(end 290.95319 -194.20205)
		(width 0.1143)
		(layer "B.Cu")
		(net "MEMBA_0")
	)
	(segment
		(start 288.51098 -200.5203)
		(end 288.51098 -199.826372)
		(width 0.1143)
		(layer "B.Cu")
		(net "MEMBA_0")
	)
	(segment
		(start 290.53028 -196.749924)
		(end 290.53028 -195.8848)
		(width 0.1143)
		(layer "B.Cu")
		(net "MEMBA_0")
	)
	(segment
		(start 291.87775 -185.57621)
		(end 291.87775 -184.217818)
		(width 0.1143)
		(layer "B.Cu")
		(net "MEMBA_0")
	)
	(segment
		(start 288.27984 -200.75144)
		(end 288.51098 -200.5203)
		(width 0.1143)
		(layer "B.Cu")
		(net "MEMBA_0")
	)
	(segment
		(start 291.5793 -188.057536)
		(end 291.13353 -187.611766)
		(width 0.1143)
		(layer "B.Cu")
		(net "MEMBA_0")
	)
	(segment
		(start 290.53028 -195.8848)
		(end 290.540948 -195.874132)
		(width 0.1143)
		(layer "B.Cu")
		(net "MEMBA_0")
	)
	(segment
		(start 290.97224 -181.567836)
		(end 290.843462 -181.439058)
		(width 0.1143)
		(layer "B.Cu")
		(net "MEMBA_0")
	)
	(segment
		(start 287.669478 -200.903078)
		(end 287.821116 -200.75144)
		(width 0.1143)
		(layer "B.Cu")
		(net "MEMBA_0")
	)
	(segment
		(start 289.042094 -198.23811)
		(end 290.53028 -196.749924)
		(width 0.1143)
		(layer "B.Cu")
		(net "MEMBA_0")
	)
	(segment
		(start 291.095684 -194.20205)
		(end 291.5793 -193.718434)
		(width 0.1143)
		(layer "B.Cu")
		(net "MEMBA_0")
	)
	(segment
		(start 291.5793 -193.718434)
		(end 291.5793 -188.057536)
		(width 0.1143)
		(layer "B.Cu")
		(net "MEMBA_0")
	)
	(segment
		(start 290.540948 -195.823078)
		(end 290.540948 -194.614292)
		(width 0.1143)
		(layer "B.Cu")
		(net "MEMBA_0")
	)
	(segment
		(start 287.701736 -201.329544)
		(end 287.669478 -201.297286)
		(width 0.1143)
		(layer "B.Cu")
		(net "MEMBA_0")
	)
	(segment
		(start 287.669478 -201.297286)
		(end 287.669478 -200.903078)
		(width 0.1143)
		(layer "B.Cu")
		(net "MEMBA_0")
	)
	(segment
		(start 291.13353 -187.611766)
		(end 291.13353 -187.024264)
		(width 0.1143)
		(layer "B.Cu")
		(net "MEMBA_0")
	)
	(segment
		(start 287.821116 -200.75144)
		(end 288.27984 -200.75144)
		(width 0.1143)
		(layer "B.Cu")
		(net "MEMBA_0")
	)
	(segment
		(start 53.848 -225.3615)
		(end 53.848 -226.441)
		(width 0.508)
		(layer "F.Cu")
		(net "P12V_PCIE")
	)
	(segment
		(start 53.975 -203.581)
		(end 55.372 -203.581)
		(width 0.508)
		(layer "F.Cu")
		(net "P12V_PCIE")
	)
	(segment
		(start 50.546 -225.3615)
		(end 50.546 -226.441)
		(width 0.508)
		(layer "F.Cu")
		(net "P12V_PCIE")
	)
	(segment
		(start 54.864 -225.425)
		(end 53.848 -226.441)
		(width 0.508)
		(layer "F.Cu")
		(net "P12V_PCIE")
	)
	(segment
		(start 10.808716 -226.30638)
		(end 10.808716 -226.49688)
		(width 0.508)
		(layer "F.Cu")
		(net "P12V_PCIE")
	)
	(segment
		(start 282.020772 -71.073772)
		(end 282.020772 -70.0024)
		(width 0.254)
		(layer "F.Cu")
		(net "P12V_PCIE")
	)
	(segment
		(start 55.654956 -231.537256)
		(end 55.654956 -227.584508)
		(width 0.508)
		(layer "F.Cu")
		(net "P12V_PCIE")
	)
	(segment
		(start 54.991 -226.9363)
		(end 54.4957 -226.441)
		(width 0.508)
		(layer "F.Cu")
		(net "P12V_PCIE")
	)
	(segment
		(start 273.558 -64.897)
		(end 273.558 -66.04)
		(width 0.254)
		(layer "F.Cu")
		(net "P12V_PCIE")
	)
	(segment
		(start 274.0914 -64.3636)
		(end 273.558 -64.897)
		(width 0.254)
		(layer "F.Cu")
		(net "P12V_PCIE")
	)
	(segment
		(start 282.067 -71.12)
		(end 282.020772 -71.073772)
		(width 0.254)
		(layer "F.Cu")
		(net "P12V_PCIE")
	)
	(segment
		(start 54.864 -225.3615)
		(end 54.864 -225.425)
		(width 0.508)
		(layer "F.Cu")
		(net "P12V_PCIE")
	)
	(segment
		(start 279.836626 -69.016626)
		(end 275.1836 -64.3636)
		(width 0.254)
		(layer "F.Cu")
		(net "P12V_PCIE")
	)
	(segment
		(start 275.1836 -64.3636)
		(end 274.0914 -64.3636)
		(width 0.254)
		(layer "F.Cu")
		(net "P12V_PCIE")
	)
	(segment
		(start 56.637936 -220.5355)
		(end 56.637936 -221.991936)
		(width 0.254)
		(layer "F.Cu")
		(net "P12V_PCIE")
	)
	(segment
		(start 55.006748 -226.9363)
		(end 54.991 -226.9363)
		(width 0.508)
		(layer "F.Cu")
		(net "P12V_PCIE")
	)
	(segment
		(start 9.856216 -226.17938)
		(end 10.681716 -226.17938)
		(width 0.508)
		(layer "F.Cu")
		(net "P12V_PCIE")
	)
	(segment
		(start 54.4957 -226.441)
		(end 53.848 -226.441)
		(width 0.508)
		(layer "F.Cu")
		(net "P12V_PCIE")
	)
	(segment
		(start 290.1315 -69.723)
		(end 290.957 -69.723)
		(width 0.508)
		(layer "F.Cu")
		(net "P12V_PCIE")
	)
	(segment
		(start 282.020772 -69.016626)
		(end 279.836626 -69.016626)
		(width 0.254)
		(layer "F.Cu")
		(net "P12V_PCIE")
	)
	(segment
		(start 56.637936 -221.991936)
		(end 56.896 -222.25)
		(width 0.254)
		(layer "F.Cu")
		(net "P12V_PCIE")
	)
	(segment
		(start 282.020772 -70.0024)
		(end 282.020772 -69.016626)
		(width 0.254)
		(layer "F.Cu")
		(net "P12V_PCIE")
	)
	(segment
		(start 53.975 -202.311)
		(end 53.975 -203.581)
		(width 0.508)
		(layer "F.Cu")
		(net "P12V_PCIE")
	)
	(segment
		(start 55.654956 -227.584508)
		(end 55.006748 -226.9363)
		(width 0.508)
		(layer "F.Cu")
		(net "P12V_PCIE")
	)
	(segment
		(start 290.957 -69.723)
		(end 291.211 -69.977)
		(width 0.508)
		(layer "F.Cu")
		(net "P12V_PCIE")
	)
	(segment
		(start 10.681716 -226.17938)
		(end 10.808716 -226.30638)
		(width 0.508)
		(layer "F.Cu")
		(net "P12V_PCIE")
	)
	(via
		(at 286.766 -127.635)
		(size 0.7112)
		(drill 0.4064)
		(layers "F.Cu" "B.Cu")
		(net "P12V_PCIE")
	)
	(via
		(at 59.300872 -244.801136)
		(size 0.7112)
		(drill 0.4064)
		(layers "F.Cu" "B.Cu")
		(net "P12V_PCIE")
	)
	(via
		(at 46.228 -238.633)
		(size 0.7112)
		(drill 0.4064)
		(layers "F.Cu" "B.Cu")
		(net "P12V_PCIE")
	)
	(via
		(at 45.085 -238.633)
		(size 0.7112)
		(drill 0.4064)
		(layers "F.Cu" "B.Cu")
		(net "P12V_PCIE")
	)
	(via
		(at 60.951872 -244.801136)
		(size 0.7112)
		(drill 0.4064)
		(layers "F.Cu" "B.Cu")
		(net "P12V_PCIE")
	)
	(via
		(at 288.417 -127.635)
		(size 0.7112)
		(drill 0.4064)
		(layers "F.Cu" "B.Cu")
		(net "P12V_PCIE")
	)
	(via
		(at 57.785 -244.729)
		(size 0.7112)
		(drill 0.4064)
		(layers "F.Cu" "B.Cu")
		(net "P12V_PCIE")
	)
	(via
		(at 50.673 -238.633)
		(size 0.7112)
		(drill 0.4064)
		(layers "F.Cu" "B.Cu")
		(net "P12V_PCIE")
	)
	(via
		(at 64.008 -243.205)
		(size 0.7112)
		(drill 0.4064)
		(layers "F.Cu" "B.Cu")
		(net "P12V_PCIE")
	)
	(via
		(at 193.7004 -244.7544)
		(size 0.7112)
		(drill 0.4064)
		(layers "F.Cu" "B.Cu")
		(net "P12V_PCIE")
	)
	(via
		(at 195.961 -244.729)
		(size 0.7112)
		(drill 0.4064)
		(layers "F.Cu" "B.Cu")
		(net "P12V_PCIE")
	)
	(via
		(at 246.126 -166.3954)
		(size 0.7112)
		(drill 0.4064)
		(layers "F.Cu" "B.Cu")
		(net "P12V_PCIE")
	)
	(via
		(at 194.818 -246.1006)
		(size 0.7112)
		(drill 0.4064)
		(layers "F.Cu" "B.Cu")
		(net "P12V_PCIE")
	)
	(via
		(at 60.951872 -243.277136)
		(size 0.7112)
		(drill 0.4064)
		(layers "F.Cu" "B.Cu")
		(net "P12V_PCIE")
	)
	(via
		(at 282.020772 -70.0024)
		(size 0.5588)
		(drill 0.3048)
		(layers "F.Cu" "B.Cu")
		(net "P12V_PCIE")
	)
	(via
		(at 70.485 -248.158)
		(size 0.7112)
		(drill 0.3556)
		(layers "F.Cu" "B.Cu")
		(net "P12V_PCIE")
	)
	(via
		(at 246.126 -167.513)
		(size 0.7112)
		(drill 0.4064)
		(layers "F.Cu" "B.Cu")
		(net "P12V_PCIE")
	)
	(via
		(at 62.729872 -243.277136)
		(size 0.7112)
		(drill 0.4064)
		(layers "F.Cu" "B.Cu")
		(net "P12V_PCIE")
	)
	(via
		(at 286.766 -128.905)
		(size 0.7112)
		(drill 0.4064)
		(layers "F.Cu" "B.Cu")
		(net "P12V_PCIE")
	)
	(via
		(at 289.814 -127.635)
		(size 0.7112)
		(drill 0.4064)
		(layers "F.Cu" "B.Cu")
		(net "P12V_PCIE")
	)
	(via
		(at 57.15 -233.807)
		(size 0.7112)
		(drill 0.4064)
		(layers "F.Cu" "B.Cu")
		(net "P12V_PCIE")
	)
	(via
		(at 50.546 -226.441)
		(size 0.5588)
		(drill 0.3048)
		(layers "F.Cu" "B.Cu")
		(net "P12V_PCIE")
	)
	(via
		(at 70.485 -246.253)
		(size 0.7112)
		(drill 0.4064)
		(layers "F.Cu" "B.Cu")
		(net "P12V_PCIE")
	)
	(via
		(at 59.300872 -243.150136)
		(size 0.7112)
		(drill 0.4064)
		(layers "F.Cu" "B.Cu")
		(net "P12V_PCIE")
	)
	(via
		(at 10.808716 -226.49688)
		(size 0.5588)
		(drill 0.3048)
		(layers "F.Cu" "B.Cu")
		(net "P12V_PCIE")
	)
	(via
		(at 53.848 -226.441)
		(size 0.5588)
		(drill 0.3048)
		(layers "F.Cu" "B.Cu")
		(net "P12V_PCIE")
	)
	(via
		(at 291.211 -69.977)
		(size 0.5588)
		(drill 0.3048)
		(layers "F.Cu" "B.Cu")
		(net "P12V_PCIE")
	)
	(via
		(at 247.523 -166.3954)
		(size 0.7112)
		(drill 0.4064)
		(layers "F.Cu" "B.Cu")
		(net "P12V_PCIE")
	)
	(via
		(at 289.814 -128.905)
		(size 0.7112)
		(drill 0.4064)
		(layers "F.Cu" "B.Cu")
		(net "P12V_PCIE")
	)
	(via
		(at 70.739 -245.11)
		(size 0.7112)
		(drill 0.4064)
		(layers "F.Cu" "B.Cu")
		(net "P12V_PCIE")
	)
	(via
		(at 194.8434 -244.729)
		(size 0.7112)
		(drill 0.4064)
		(layers "F.Cu" "B.Cu")
		(net "P12V_PCIE")
	)
	(via
		(at 52.832 -235.077)
		(size 0.7112)
		(drill 0.3556)
		(layers "F.Cu" "B.Cu")
		(net "P12V_PCIE")
	)
	(via
		(at 243.332 -167.513)
		(size 0.7112)
		(drill 0.4064)
		(layers "F.Cu" "B.Cu")
		(net "P12V_PCIE")
	)
	(via
		(at 194.7164 -243.459)
		(size 0.7112)
		(drill 0.4064)
		(layers "F.Cu" "B.Cu")
		(net "P12V_PCIE")
	)
	(via
		(at 47.752 -238.633)
		(size 0.7112)
		(drill 0.4064)
		(layers "F.Cu" "B.Cu")
		(net "P12V_PCIE")
	)
	(via
		(at 247.523 -167.513)
		(size 0.7112)
		(drill 0.4064)
		(layers "F.Cu" "B.Cu")
		(net "P12V_PCIE")
	)
	(via
		(at 41.148 -238.633)
		(size 0.7112)
		(drill 0.4064)
		(layers "F.Cu" "B.Cu")
		(net "P12V_PCIE")
	)
	(via
		(at 69.215 -246.253)
		(size 0.7112)
		(drill 0.4064)
		(layers "F.Cu" "B.Cu")
		(net "P12V_PCIE")
	)
	(via
		(at 195.9356 -246.1006)
		(size 0.7112)
		(drill 0.4064)
		(layers "F.Cu" "B.Cu")
		(net "P12V_PCIE")
	)
	(via
		(at 56.896 -222.25)
		(size 0.7112)
		(drill 0.4064)
		(layers "F.Cu" "B.Cu")
		(net "P12V_PCIE")
	)
	(via
		(at 193.675 -246.126)
		(size 0.7112)
		(drill 0.4064)
		(layers "F.Cu" "B.Cu")
		(net "P12V_PCIE")
	)
	(via
		(at 285.369 -127.635)
		(size 0.7112)
		(drill 0.4064)
		(layers "F.Cu" "B.Cu")
		(net "P12V_PCIE")
	)
	(via
		(at 243.332 -166.243)
		(size 0.7112)
		(drill 0.4064)
		(layers "F.Cu" "B.Cu")
		(net "P12V_PCIE")
	)
	(via
		(at 195.834 -243.459)
		(size 0.7112)
		(drill 0.4064)
		(layers "F.Cu" "B.Cu")
		(net "P12V_PCIE")
	)
	(via
		(at 244.729 -167.513)
		(size 0.7112)
		(drill 0.4064)
		(layers "F.Cu" "B.Cu")
		(net "P12V_PCIE")
	)
	(via
		(at 39.751 -238.633)
		(size 0.7112)
		(drill 0.4064)
		(layers "F.Cu" "B.Cu")
		(net "P12V_PCIE")
	)
	(via
		(at 244.729 -166.243)
		(size 0.7112)
		(drill 0.4064)
		(layers "F.Cu" "B.Cu")
		(net "P12V_PCIE")
	)
	(via
		(at 193.5734 -243.4844)
		(size 0.7112)
		(drill 0.4064)
		(layers "F.Cu" "B.Cu")
		(net "P12V_PCIE")
	)
	(via
		(at 49.149 -238.633)
		(size 0.7112)
		(drill 0.4064)
		(layers "F.Cu" "B.Cu")
		(net "P12V_PCIE")
	)
	(via
		(at 42.545 -238.633)
		(size 0.7112)
		(drill 0.4064)
		(layers "F.Cu" "B.Cu")
		(net "P12V_PCIE")
	)
	(via
		(at 43.815 -238.633)
		(size 0.7112)
		(drill 0.4064)
		(layers "F.Cu" "B.Cu")
		(net "P12V_PCIE")
	)
	(via
		(at 57.785 -243.205)
		(size 0.7112)
		(drill 0.4064)
		(layers "F.Cu" "B.Cu")
		(net "P12V_PCIE")
	)
	(via
		(at 195.5292 -248.2342)
		(size 0.7112)
		(drill 0.3556)
		(layers "F.Cu" "B.Cu")
		(net "P12V_PCIE")
	)
	(via
		(at 55.372 -203.581)
		(size 0.5588)
		(drill 0.3048)
		(layers "F.Cu" "B.Cu")
		(net "P12V_PCIE")
	)
	(via
		(at 62.729872 -244.801136)
		(size 0.7112)
		(drill 0.4064)
		(layers "F.Cu" "B.Cu")
		(net "P12V_PCIE")
	)
	(via
		(at 288.417 -128.905)
		(size 0.7112)
		(drill 0.4064)
		(layers "F.Cu" "B.Cu")
		(net "P12V_PCIE")
	)
	(via
		(at 68.072 -246.253)
		(size 0.7112)
		(drill 0.4064)
		(layers "F.Cu" "B.Cu")
		(net "P12V_PCIE")
	)
	(via
		(at 64.135 -244.729)
		(size 0.7112)
		(drill 0.4064)
		(layers "F.Cu" "B.Cu")
		(net "P12V_PCIE")
	)
	(via
		(at 285.369 -128.905)
		(size 0.7112)
		(drill 0.4064)
		(layers "F.Cu" "B.Cu")
		(net "P12V_PCIE")
	)
	(segment
		(start 200.800462 -254.066294)
		(end 200.800462 -256.50444)
		(width 0.635)
		(layer "B.Cu")
		(net "P12V_PCIE")
	)
	(segment
		(start 68.000372 -251.32284)
		(end 68.000372 -256.50444)
		(width 0.635)
		(layer "B.Cu")
		(net "P12V_PCIE")
	)
	(segment
		(start 56.896 -222.25)
		(end 56.515 -222.631)
		(width 0.381)
		(layer "B.Cu")
		(net "P12V_PCIE")
	)
	(segment
		(start 57.404 -233.553)
		(end 57.15 -233.807)
		(width 0.381)
		(layer "B.Cu")
		(net "P12V_PCIE")
	)
	(segment
		(start 57.404 -225.232722)
		(end 57.404 -233.553)
		(width 0.381)
		(layer "B.Cu")
		(net "P12V_PCIE")
	)
	(segment
		(start 199.799702 -254.155702)
		(end 199.799702 -256.50444)
		(width 0.635)
		(layer "B.Cu")
		(net "P12V_PCIE")
	)
	(segment
		(start 53.10759 -225.70059)
		(end 53.848 -226.441)
		(width 0.508)
		(layer "B.Cu")
		(net "P12V_PCIE")
	)
	(segment
		(start 53.848 -205.105)
		(end 55.372 -203.581)
		(width 0.508)
		(layer "B.Cu")
		(net "P12V_PCIE")
	)
	(segment
		(start 199.47763 -253.83363)
		(end 199.799702 -254.155702)
		(width 0.635)
		(layer "B.Cu")
		(net "P12V_PCIE")
	)
	(segment
		(start 197.799452 -253.933452)
		(end 197.799452 -256.50444)
		(width 0.635)
		(layer "B.Cu")
		(net "P12V_PCIE")
	)
	(segment
		(start 197.477126 -253.611126)
		(end 197.799452 -253.933452)
		(width 0.635)
		(layer "B.Cu")
		(net "P12V_PCIE")
	)
	(segment
		(start 198.800212 -254.081788)
		(end 198.800212 -256.50444)
		(width 0.635)
		(layer "B.Cu")
		(net "P12V_PCIE")
	)
	(segment
		(start 68.999862 -252.35535)
		(end 68.999862 -256.50444)
		(width 0.635)
		(layer "B.Cu")
		(net "P12V_PCIE")
	)
	(segment
		(start 51.28641 -225.70059)
		(end 53.10759 -225.70059)
		(width 0.508)
		(layer "B.Cu")
		(net "P12V_PCIE")
	)
	(segment
		(start 195.800472 -256.50444)
		(end 195.800472 -253.652528)
		(width 0.635)
		(layer "B.Cu")
		(net "P12V_PCIE")
	)
	(segment
		(start 56.515 -222.631)
		(end 56.515 -224.343722)
		(width 0.381)
		(layer "B.Cu")
		(net "P12V_PCIE")
	)
	(segment
		(start 69.999352 -256.50444)
		(end 69.999352 -253.03734)
		(width 0.635)
		(layer "B.Cu")
		(net "P12V_PCIE")
	)
	(segment
		(start 200.41235 -253.678182)
		(end 200.800462 -254.066294)
		(width 0.635)
		(layer "B.Cu")
		(net "P12V_PCIE")
	)
	(segment
		(start 196.799962 -253.873)
		(end 196.799962 -256.50444)
		(width 0.635)
		(layer "B.Cu")
		(net "P12V_PCIE")
	)
	(segment
		(start 194.799712 -256.50444)
		(end 194.799712 -253.873)
		(width 0.635)
		(layer "B.Cu")
		(net "P12V_PCIE")
	)
	(segment
		(start 56.515 -224.343722)
		(end 57.404 -225.232722)
		(width 0.381)
		(layer "B.Cu")
		(net "P12V_PCIE")
	)
	(segment
		(start 50.546 -226.441)
		(end 51.28641 -225.70059)
		(width 0.508)
		(layer "B.Cu")
		(net "P12V_PCIE")
	)
	(segment
		(start 199.04837 -253.83363)
		(end 198.800212 -254.081788)
		(width 0.635)
		(layer "B.Cu")
		(net "P12V_PCIE")
	)
	(segment
		(start 53.848 -226.441)
		(end 53.848 -205.105)
		(width 0.508)
		(layer "B.Cu")
		(net "P12V_PCIE")
	)
	(segment
		(start 282.147772 -69.977)
		(end 291.211 -69.977)
		(width 0.508)
		(layer "In2.Cu")
		(net "P12V_PCIE")
	)
	(segment
		(start 11.61288 -226.49688)
		(end 10.808716 -226.49688)
		(width 0.508)
		(layer "In2.Cu")
		(net "P12V_PCIE")
	)
	(segment
		(start 39.751 -238.633)
		(end 39.751 -237.4646)
		(width 0.508)
		(layer "In2.Cu")
		(net "P12V_PCIE")
	)
	(segment
		(start 13.77188 -228.65588)
		(end 11.61288 -226.49688)
		(width 0.508)
		(layer "In2.Cu")
		(net "P12V_PCIE")
	)
	(segment
		(start 30.94228 -228.65588)
		(end 13.77188 -228.65588)
		(width 0.508)
		(layer "In2.Cu")
		(net "P12V_PCIE")
	)
	(segment
		(start 39.751 -237.4646)
		(end 30.94228 -228.65588)
		(width 0.508)
		(layer "In2.Cu")
		(net "P12V_PCIE")
	)
	(segment
		(start 282.122372 -70.0024)
		(end 282.147772 -69.977)
		(width 0.508)
		(layer "In2.Cu")
		(net "P12V_PCIE")
	)
	(segment
		(start 282.020772 -70.0024)
		(end 282.122372 -70.0024)
		(width 0.508)
		(layer "In2.Cu")
		(net "P12V_PCIE")
	)
	(segment
		(start 299.703236 -150.884636)
		(end 300.0629 -151.2443)
		(width 0.1143)
		(layer "F.Cu")
		(net "50M_CLK_OUT")
	)
	(segment
		(start 299.703236 -149.623272)
		(end 299.703236 -150.884636)
		(width 0.1143)
		(layer "F.Cu")
		(net "50M_CLK_OUT")
	)
	(segment
		(start 300.5201 -151.7015)
		(end 300.0629 -151.2443)
		(width 0.1143)
		(layer "F.Cu")
		(net "50M_CLK_OUT")
	)
	(segment
		(start 301.371 -151.7015)
		(end 300.5201 -151.7015)
		(width 0.1143)
		(layer "F.Cu")
		(net "50M_CLK_OUT")
	)
	(via
		(at 300.0756 -150.3934)
		(size 0.7112)
		(drill 0.3556)
		(layers "F.Cu" "B.Cu")
		(net "50M_CLK_OUT")
	)
	(via
		(at 300.0629 -151.2443)
		(size 0.5588)
		(drill 0.3048)
		(layers "F.Cu" "B.Cu")
		(net "50M_CLK_OUT")
	)
	(segment
		(start 300.0756 -151.2316)
		(end 300.0629 -151.2443)
		(width 0.1143)
		(layer "B.Cu")
		(net "50M_CLK_OUT")
	)
	(segment
		(start 300.0756 -150.3934)
		(end 300.0756 -151.2316)
		(width 0.1143)
		(layer "B.Cu")
		(net "50M_CLK_OUT")
	)
	(segment
		(start 292.034976 -181.84876)
		(end 291.634418 -182.249318)
		(width 0.1143)
		(layer "F.Cu")
		(net "MEMRASN")
	)
	(segment
		(start 290.991544 -200.44156)
		(end 291.01796 -200.44156)
		(width 0.1143)
		(layer "F.Cu")
		(net "MEMRASN")
	)
	(segment
		(start 292.034976 -181.840124)
		(end 292.034976 -181.84876)
		(width 0.1143)
		(layer "F.Cu")
		(net "MEMRASN")
	)
	(segment
		(start 290.498022 -200.935082)
		(end 290.991544 -200.44156)
		(width 0.1143)
		(layer "F.Cu")
		(net "MEMRASN")
	)
	(via
		(at 291.634418 -182.249318)
		(size 0.508)
		(drill 0.254)
		(layers "F.Cu" "B.Cu")
		(net "MEMRASN")
	)
	(via
		(at 291.01796 -200.44156)
		(size 0.508)
		(drill 0.254)
		(layers "F.Cu" "B.Cu")
		(net "MEMRASN")
	)
	(via
		(at 295.6814 -187.96)
		(size 0.7112)
		(drill 0.3556)
		(layers "F.Cu" "B.Cu")
		(net "MEMRASN")
	)
	(segment
		(start 293.656512 -195.77431)
		(end 293.656258 -195.777866)
		(width 0.1143)
		(layer "B.Cu")
		(net "MEMRASN")
	)
	(segment
		(start 291.21989 -200.175876)
		(end 291.21989 -200.23963)
		(width 0.1143)
		(layer "B.Cu")
		(net "MEMRASN")
	)
	(segment
		(start 294.068754 -184.9882)
		(end 294.210994 -184.9882)
		(width 0.1143)
		(layer "B.Cu")
		(net "MEMRASN")
	)
	(segment
		(start 296.494454 -189.45479)
		(end 296.49547 -189.455806)
		(width 0.1143)
		(layer "B.Cu")
		(net "MEMRASN")
	)
	(segment
		(start 291.21989 -200.23963)
		(end 291.01796 -200.44156)
		(width 0.1143)
		(layer "B.Cu")
		(net "MEMRASN")
	)
	(segment
		(start 294.361108 -194.9704)
		(end 294.07104 -194.9704)
		(width 0.1143)
		(layer "B.Cu")
		(net "MEMRASN")
	)
	(segment
		(start 293.7002 -195.715128)
		(end 293.696136 -195.734432)
		(width 0.1143)
		(layer "B.Cu")
		(net "MEMRASN")
	)
	(segment
		(start 296.494454 -192.837054)
		(end 294.361108 -194.9704)
		(width 0.1143)
		(layer "B.Cu")
		(net "MEMRASN")
	)
	(segment
		(start 295.4909 -187.7695)
		(end 295.6814 -187.96)
		(width 0.1143)
		(layer "B.Cu")
		(net "MEMRASN")
	)
	(segment
		(start 292.0492 -182.968646)
		(end 294.068754 -184.9882)
		(width 0.1143)
		(layer "B.Cu")
		(net "MEMRASN")
	)
	(segment
		(start 293.181024 -199.64781)
		(end 291.747956 -199.64781)
		(width 0.1143)
		(layer "B.Cu")
		(net "MEMRASN")
	)
	(segment
		(start 296.494454 -188.773054)
		(end 296.494454 -189.45479)
		(width 0.1143)
		(layer "B.Cu")
		(net "MEMRASN")
	)
	(segment
		(start 293.696136 -195.734432)
		(end 293.656512 -195.77431)
		(width 0.1143)
		(layer "B.Cu")
		(net "MEMRASN")
	)
	(segment
		(start 295.4909 -186.268106)
		(end 295.4909 -187.7695)
		(width 0.1143)
		(layer "B.Cu")
		(net "MEMRASN")
	)
	(segment
		(start 295.6814 -187.96)
		(end 296.494454 -188.773054)
		(width 0.1143)
		(layer "B.Cu")
		(net "MEMRASN")
	)
	(segment
		(start 296.49547 -190.3984)
		(end 296.494454 -190.399416)
		(width 0.1143)
		(layer "B.Cu")
		(net "MEMRASN")
	)
	(segment
		(start 293.656258 -198.956168)
		(end 293.526464 -199.085962)
		(width 0.1143)
		(layer "B.Cu")
		(net "MEMRASN")
	)
	(segment
		(start 292.0492 -182.6641)
		(end 292.0492 -182.968646)
		(width 0.1143)
		(layer "B.Cu")
		(net "MEMRASN")
	)
	(segment
		(start 293.656258 -195.777866)
		(end 293.656258 -198.956168)
		(width 0.1143)
		(layer "B.Cu")
		(net "MEMRASN")
	)
	(segment
		(start 291.634418 -182.249318)
		(end 292.0492 -182.6641)
		(width 0.1143)
		(layer "B.Cu")
		(net "MEMRASN")
	)
	(segment
		(start 294.07104 -194.9704)
		(end 293.7002 -195.34124)
		(width 0.1143)
		(layer "B.Cu")
		(net "MEMRASN")
	)
	(segment
		(start 296.49547 -189.455806)
		(end 296.49547 -190.3984)
		(width 0.1143)
		(layer "B.Cu")
		(net "MEMRASN")
	)
	(segment
		(start 294.210994 -184.9882)
		(end 295.4909 -186.268106)
		(width 0.1143)
		(layer "B.Cu")
		(net "MEMRASN")
	)
	(segment
		(start 293.526464 -199.085962)
		(end 293.526464 -199.30237)
		(width 0.1143)
		(layer "B.Cu")
		(net "MEMRASN")
	)
	(segment
		(start 293.526464 -199.30237)
		(end 293.181024 -199.64781)
		(width 0.1143)
		(layer "B.Cu")
		(net "MEMRASN")
	)
	(segment
		(start 296.494454 -190.399416)
		(end 296.494454 -192.837054)
		(width 0.1143)
		(layer "B.Cu")
		(net "MEMRASN")
	)
	(segment
		(start 293.7002 -195.34124)
		(end 293.7002 -195.715128)
		(width 0.1143)
		(layer "B.Cu")
		(net "MEMRASN")
	)
	(segment
		(start 291.747956 -199.64781)
		(end 291.21989 -200.175876)
		(width 0.1143)
		(layer "B.Cu")
		(net "MEMRASN")
	)
	(segment
		(start 24.207216 -219.06738)
		(end 27.002486 -219.06738)
		(width 0.1143)
		(layer "F.Cu")
		(net "SAS_HDD_PWR5")
	)
	(segment
		(start 30.239716 -222.30461)
		(end 30.239716 -226.75088)
		(width 0.1143)
		(layer "F.Cu")
		(net "SAS_HDD_PWR5")
	)
	(segment
		(start 30.239716 -226.75088)
		(end 30.239716 -228.96068)
		(width 0.1143)
		(layer "F.Cu")
		(net "SAS_HDD_PWR5")
	)
	(segment
		(start 23.632922 -216.714578)
		(end 23.632922 -218.493086)
		(width 0.1143)
		(layer "F.Cu")
		(net "SAS_HDD_PWR5")
	)
	(segment
		(start 23.632922 -218.493086)
		(end 24.207216 -219.06738)
		(width 0.1143)
		(layer "F.Cu")
		(net "SAS_HDD_PWR5")
	)
	(segment
		(start 27.002486 -219.06738)
		(end 30.239716 -222.30461)
		(width 0.1143)
		(layer "F.Cu")
		(net "SAS_HDD_PWR5")
	)
	(via
		(at 30.239716 -226.75088)
		(size 0.5588)
		(drill 0.3048)
		(layers "F.Cu" "B.Cu")
		(net "SAS_HDD_PWR5")
	)
	(via
		(at 30.239716 -228.98608)
		(size 0.7112)
		(drill 0.3556)
		(layers "F.Cu" "B.Cu")
		(net "SAS_HDD_PWR5")
	)
	(segment
		(start 30.430216 -231.89438)
		(end 30.430216 -230.81488)
		(width 0.1143)
		(layer "B.Cu")
		(net "SAS_HDD_PWR5")
	)
	(segment
		(start 30.239716 -226.75088)
		(end 30.239716 -228.98608)
		(width 0.1143)
		(layer "B.Cu")
		(net "SAS_HDD_PWR5")
	)
	(segment
		(start 30.239716 -230.62438)
		(end 30.239716 -228.98608)
		(width 0.1143)
		(layer "B.Cu")
		(net "SAS_HDD_PWR5")
	)
	(segment
		(start 30.430216 -230.81488)
		(end 30.239716 -230.62438)
		(width 0.1143)
		(layer "B.Cu")
		(net "SAS_HDD_PWR5")
	)
	(segment
		(start 187.1345 -21.0185)
		(end 184.077864 -24.075136)
		(width 0.1143)
		(layer "F.Cu")
		(net "RMII_BMC_MDIO_R")
	)
	(segment
		(start 183.065928 -25.087072)
		(end 184.077864 -24.075136)
		(width 0.1143)
		(layer "F.Cu")
		(net "RMII_BMC_MDIO_R")
	)
	(segment
		(start 188.087 -21.0185)
		(end 187.1345 -21.0185)
		(width 0.1143)
		(layer "F.Cu")
		(net "RMII_BMC_MDIO_R")
	)
	(segment
		(start 188.1505 -20.955)
		(end 188.087 -21.0185)
		(width 0.1143)
		(layer "F.Cu")
		(net "RMII_BMC_MDIO_R")
	)
	(segment
		(start 183.065928 -27.377136)
		(end 183.065928 -25.087072)
		(width 0.1143)
		(layer "F.Cu")
		(net "RMII_BMC_MDIO_R")
	)
	(segment
		(start 189.4205 -20.955)
		(end 188.1505 -20.955)
		(width 0.1143)
		(layer "F.Cu")
		(net "RMII_BMC_MDIO_R")
	)
	(segment
		(start 296.0116 -184.953402)
		(end 296.249598 -185.1914)
		(width 0.1016)
		(layer "F.Cu")
		(net "MEMDQS_N1")
	)
	(segment
		(start 296.0116 -197.838568)
		(end 296.0116 -198.33971)
		(width 0.1016)
		(layer "F.Cu")
		(net "MEMDQS_N1")
	)
	(segment
		(start 296.0116 -184.4294)
		(end 296.0116 -184.953402)
		(width 0.1016)
		(layer "F.Cu")
		(net "MEMDQS_N1")
	)
	(segment
		(start 296.034968 -184.406032)
		(end 296.0116 -184.4294)
		(width 0.1016)
		(layer "F.Cu")
		(net "MEMDQS_N1")
	)
	(segment
		(start 296.09796 -197.752208)
		(end 296.0116 -197.838568)
		(width 0.1016)
		(layer "F.Cu")
		(net "MEMDQS_N1")
	)
	(segment
		(start 296.09796 -197.73519)
		(end 296.09796 -197.752208)
		(width 0.1016)
		(layer "F.Cu")
		(net "MEMDQS_N1")
	)
	(segment
		(start 296.249598 -185.1914)
		(end 296.843196 -185.1914)
		(width 0.1016)
		(layer "F.Cu")
		(net "MEMDQS_N1")
	)
	(segment
		(start 296.843196 -185.1914)
		(end 296.997628 -185.345832)
		(width 0.1016)
		(layer "F.Cu")
		(net "MEMDQS_N1")
	)
	(segment
		(start 296.0116 -198.33971)
		(end 296.034968 -198.363078)
		(width 0.1016)
		(layer "F.Cu")
		(net "MEMDQS_N1")
	)
	(segment
		(start 296.034968 -184.24017)
		(end 296.034968 -184.406032)
		(width 0.1016)
		(layer "F.Cu")
		(net "MEMDQS_N1")
	)
	(via
		(at 296.997628 -185.345832)
		(size 0.508)
		(drill 0.254)
		(layers "F.Cu" "B.Cu")
		(net "MEMDQS_N1")
	)
	(via
		(at 296.034968 -198.363078)
		(size 0.508)
		(drill 0.254)
		(layers "F.Cu" "B.Cu")
		(net "MEMDQS_N1")
	)
	(via
		(at 296.79011 -198.071232)
		(size 0.7112)
		(drill 0.3556)
		(layers "F.Cu" "B.Cu")
		(net "MEMDQS_N1")
	)
	(segment
		(start 296.746168 -198.071232)
		(end 296.454322 -198.363078)
		(width 0.1016)
		(layer "B.Cu")
		(net "MEMDQS_N1")
	)
	(segment
		(start 296.79011 -198.071232)
		(end 296.746168 -198.071232)
		(width 0.1016)
		(layer "B.Cu")
		(net "MEMDQS_N1")
	)
	(segment
		(start 296.454322 -198.363078)
		(end 296.034968 -198.363078)
		(width 0.1016)
		(layer "B.Cu")
		(net "MEMDQS_N1")
	)
	(segment
		(start 295.656 -197.98411)
		(end 295.656 -197.574916)
		(width 0.1016)
		(layer "In5.Cu")
		(net "MEMDQS_N1")
	)
	(segment
		(start 296.000678 -197.229984)
		(end 296.000678 -196.794628)
		(width 0.1016)
		(layer "In5.Cu")
		(net "MEMDQS_N1")
	)
	(segment
		(start 297.1292 -191.053212)
		(end 297.1292 -186.954922)
		(width 0.1016)
		(layer "In5.Cu")
		(net "MEMDQS_N1")
	)
	(segment
		(start 296.834306 -191.348106)
		(end 297.1292 -191.053212)
		(width 0.1016)
		(layer "In5.Cu")
		(net "MEMDQS_N1")
	)
	(segment
		(start 297.5102 -194.4624)
		(end 296.885106 -193.837306)
		(width 0.1016)
		(layer "In5.Cu")
		(net "MEMDQS_N1")
	)
	(segment
		(start 296.034968 -198.363078)
		(end 295.656 -197.98411)
		(width 0.1016)
		(layer "In5.Cu")
		(net "MEMDQS_N1")
	)
	(segment
		(start 295.656 -197.574916)
		(end 296.000678 -197.229984)
		(width 0.1016)
		(layer "In5.Cu")
		(net "MEMDQS_N1")
	)
	(segment
		(start 296.834306 -193.227706)
		(end 297.1292 -192.932812)
		(width 0.1016)
		(layer "In5.Cu")
		(net "MEMDQS_N1")
	)
	(segment
		(start 297.1292 -192.2526)
		(end 296.834306 -191.957706)
		(width 0.1016)
		(layer "In5.Cu")
		(net "MEMDQS_N1")
	)
	(segment
		(start 295.9608 -193.715894)
		(end 295.9608 -193.329306)
		(width 0.1016)
		(layer "In5.Cu")
		(net "MEMDQS_N1")
	)
	(segment
		(start 297.1292 -192.932812)
		(end 297.1292 -192.2526)
		(width 0.1016)
		(layer "In5.Cu")
		(net "MEMDQS_N1")
	)
	(segment
		(start 296.172382 -191.819276)
		(end 296.172382 -191.466724)
		(width 0.1016)
		(layer "In5.Cu")
		(net "MEMDQS_N1")
	)
	(segment
		(start 296.113962 -196.681344)
		(end 296.549572 -196.681344)
		(width 0.1016)
		(layer "In5.Cu")
		(net "MEMDQS_N1")
	)
	(segment
		(start 297.5102 -195.720716)
		(end 297.5102 -194.4624)
		(width 0.1016)
		(layer "In5.Cu")
		(net "MEMDQS_N1")
	)
	(segment
		(start 296.291 -191.348106)
		(end 296.834306 -191.348106)
		(width 0.1016)
		(layer "In5.Cu")
		(net "MEMDQS_N1")
	)
	(segment
		(start 296.926 -186.751468)
		(end 296.926 -185.41746)
		(width 0.1016)
		(layer "In5.Cu")
		(net "MEMDQS_N1")
	)
	(segment
		(start 296.0624 -193.227706)
		(end 296.834306 -193.227706)
		(width 0.1016)
		(layer "In5.Cu")
		(net "MEMDQS_N1")
	)
	(segment
		(start 296.000678 -196.794628)
		(end 296.113962 -196.681344)
		(width 0.1016)
		(layer "In5.Cu")
		(net "MEMDQS_N1")
	)
	(segment
		(start 296.172382 -191.466724)
		(end 296.291 -191.348106)
		(width 0.1016)
		(layer "In5.Cu")
		(net "MEMDQS_N1")
	)
	(segment
		(start 295.9608 -193.329306)
		(end 296.0624 -193.227706)
		(width 0.1016)
		(layer "In5.Cu")
		(net "MEMDQS_N1")
	)
	(segment
		(start 296.082212 -193.837306)
		(end 295.9608 -193.715894)
		(width 0.1016)
		(layer "In5.Cu")
		(net "MEMDQS_N1")
	)
	(segment
		(start 296.926 -185.41746)
		(end 296.997628 -185.345832)
		(width 0.1016)
		(layer "In5.Cu")
		(net "MEMDQS_N1")
	)
	(segment
		(start 296.834306 -191.957706)
		(end 296.310812 -191.957706)
		(width 0.1016)
		(layer "In5.Cu")
		(net "MEMDQS_N1")
	)
	(segment
		(start 296.310812 -191.957706)
		(end 296.172382 -191.819276)
		(width 0.1016)
		(layer "In5.Cu")
		(net "MEMDQS_N1")
	)
	(segment
		(start 296.549572 -196.681344)
		(end 297.5102 -195.720716)
		(width 0.1016)
		(layer "In5.Cu")
		(net "MEMDQS_N1")
	)
	(segment
		(start 297.03268 -186.858148)
		(end 296.926 -186.751468)
		(width 0.1016)
		(layer "In5.Cu")
		(net "MEMDQS_N1")
	)
	(segment
		(start 296.885106 -193.837306)
		(end 296.082212 -193.837306)
		(width 0.1016)
		(layer "In5.Cu")
		(net "MEMDQS_N1")
	)
	(segment
		(start 297.1292 -186.954922)
		(end 297.03268 -186.858148)
		(width 0.1016)
		(layer "In5.Cu")
		(net "MEMDQS_N1")
	)
	(segment
		(start 14.03858 -236.013244)
		(end 14.03858 -234.184952)
		(width 0.1143)
		(layer "F.Cu")
		(net "SAS_HDD_PWR12_PCIE")
	)
	(segment
		(start 32.999426 -252.836426)
		(end 32.512 -252.349)
		(width 0.1143)
		(layer "F.Cu")
		(net "SAS_HDD_PWR12_PCIE")
	)
	(segment
		(start 32.512 -252.349)
		(end 32.512 -249.616976)
		(width 0.1143)
		(layer "F.Cu")
		(net "SAS_HDD_PWR12_PCIE")
	)
	(segment
		(start 32.999426 -256.25044)
		(end 32.999426 -252.836426)
		(width 0.1143)
		(layer "F.Cu")
		(net "SAS_HDD_PWR12_PCIE")
	)
	(segment
		(start 19.195796 -232.133902)
		(end 15.262098 -232.133902)
		(width 0.1143)
		(layer "F.Cu")
		(net "SAS_HDD_PWR12_PCIE")
	)
	(segment
		(start 14.03858 -233.35742)
		(end 14.03858 -234.184952)
		(width 0.1143)
		(layer "F.Cu")
		(net "SAS_HDD_PWR12_PCIE")
	)
	(segment
		(start 15.262098 -232.133902)
		(end 14.03858 -233.35742)
		(width 0.1143)
		(layer "F.Cu")
		(net "SAS_HDD_PWR12_PCIE")
	)
	(segment
		(start 32.512 -249.616976)
		(end 20.32 -237.424976)
		(width 0.1143)
		(layer "F.Cu")
		(net "SAS_HDD_PWR12_PCIE")
	)
	(segment
		(start 20.32 -237.424976)
		(end 20.32 -233.258106)
		(width 0.1143)
		(layer "F.Cu")
		(net "SAS_HDD_PWR12_PCIE")
	)
	(segment
		(start 20.32 -233.258106)
		(end 19.195796 -232.133902)
		(width 0.1143)
		(layer "F.Cu")
		(net "SAS_HDD_PWR12_PCIE")
	)
	(via
		(at 14.03858 -236.013244)
		(size 0.5588)
		(drill 0.3048)
		(layers "F.Cu" "B.Cu")
		(net "SAS_HDD_PWR12_PCIE")
	)
	(via
		(at 14.03858 -233.73588)
		(size 0.7112)
		(drill 0.3556)
		(layers "F.Cu" "B.Cu")
		(net "SAS_HDD_PWR12_PCIE")
	)
	(segment
		(start 14.03858 -232.965752)
		(end 14.03858 -233.73588)
		(width 0.1143)
		(layer "B.Cu")
		(net "SAS_HDD_PWR12_PCIE")
	)
	(segment
		(start 13.34008 -232.267252)
		(end 14.03858 -232.965752)
		(width 0.1143)
		(layer "B.Cu")
		(net "SAS_HDD_PWR12_PCIE")
	)
	(segment
		(start 14.03858 -236.013244)
		(end 14.03858 -233.73588)
		(width 0.1143)
		(layer "B.Cu")
		(net "SAS_HDD_PWR12_PCIE")
	)
	(segment
		(start 294.623236 -152.316688)
		(end 293.413688 -152.316688)
		(width 0.1143)
		(layer "F.Cu")
		(net "50M_CLK_OE")
	)
	(segment
		(start 293.413688 -152.316688)
		(end 293.116 -152.019)
		(width 0.1143)
		(layer "F.Cu")
		(net "50M_CLK_OE")
	)
	(segment
		(start 292.0365 -151.638)
		(end 292.735 -151.638)
		(width 0.1143)
		(layer "F.Cu")
		(net "50M_CLK_OE")
	)
	(segment
		(start 292.735 -151.638)
		(end 293.116 -152.019)
		(width 0.1143)
		(layer "F.Cu")
		(net "50M_CLK_OE")
	)
	(via
		(at 293.116 -152.019)
		(size 0.7112)
		(drill 0.3556)
		(layers "F.Cu" "B.Cu")
		(net "50M_CLK_OE")
	)
	(segment
		(start 293.187882 -200.935082)
		(end 293.2938 -201.041)
		(width 0.1016)
		(layer "F.Cu")
		(net "MEMDQS_P0")
	)
	(segment
		(start 292.898068 -200.935082)
		(end 293.187882 -200.935082)
		(width 0.1016)
		(layer "F.Cu")
		(net "MEMDQS_P0")
	)
	(segment
		(start 293.2938 -201.041)
		(end 293.2938 -201.340212)
		(width 0.1016)
		(layer "F.Cu")
		(net "MEMDQS_P0")
	)
	(segment
		(start 294.561768 -185.335926)
		(end 294.045386 -185.852308)
		(width 0.1016)
		(layer "F.Cu")
		(net "MEMDQS_P0")
	)
	(segment
		(start 294.561768 -184.36717)
		(end 294.561768 -185.335926)
		(width 0.1016)
		(layer "F.Cu")
		(net "MEMDQS_P0")
	)
	(segment
		(start 294.434768 -184.24017)
		(end 294.561768 -184.36717)
		(width 0.1016)
		(layer "F.Cu")
		(net "MEMDQS_P0")
	)
	(segment
		(start 294.045386 -185.852308)
		(end 293.906448 -185.852308)
		(width 0.1016)
		(layer "F.Cu")
		(net "MEMDQS_P0")
	)
	(segment
		(start 293.2938 -201.340212)
		(end 293.296848 -201.34326)
		(width 0.1016)
		(layer "F.Cu")
		(net "MEMDQS_P0")
	)
	(via
		(at 294.64 -186.55792)
		(size 0.7112)
		(drill 0.3556)
		(layers "F.Cu" "B.Cu")
		(net "MEMDQS_P0")
	)
	(via
		(at 293.906448 -185.852308)
		(size 0.508)
		(drill 0.254)
		(layers "F.Cu" "B.Cu")
		(net "MEMDQS_P0")
	)
	(via
		(at 293.296848 -201.34326)
		(size 0.508)
		(drill 0.254)
		(layers "F.Cu" "B.Cu")
		(net "MEMDQS_P0")
	)
	(segment
		(start 294.64 -186.55792)
		(end 294.45712 -186.55792)
		(width 0.1016)
		(layer "B.Cu")
		(net "MEMDQS_P0")
	)
	(segment
		(start 293.906448 -186.007248)
		(end 293.906448 -185.852308)
		(width 0.1016)
		(layer "B.Cu")
		(net "MEMDQS_P0")
	)
	(segment
		(start 294.45712 -186.55792)
		(end 293.906448 -186.007248)
		(width 0.1016)
		(layer "B.Cu")
		(net "MEMDQS_P0")
	)
	(segment
		(start 293.4716 -195.228718)
		(end 293.08298 -194.840098)
		(width 0.1016)
		(layer "In5.Cu")
		(net "MEMDQS_P0")
	)
	(segment
		(start 293.723568 -200.9902)
		(end 293.5478 -200.814432)
		(width 0.1016)
		(layer "In5.Cu")
		(net "MEMDQS_P0")
	)
	(segment
		(start 294.2844 -186.914536)
		(end 294.2844 -186.23026)
		(width 0.1016)
		(layer "In5.Cu")
		(net "MEMDQS_P0")
	)
	(segment
		(start 292.6207 -188.9887)
		(end 293.033958 -188.9887)
		(width 0.1016)
		(layer "In5.Cu")
		(net "MEMDQS_P0")
	)
	(segment
		(start 293.623746 -188.416946)
		(end 294.2082 -187.832492)
		(width 0.1016)
		(layer "In5.Cu")
		(net "MEMDQS_P0")
	)
	(segment
		(start 293.5478 -200.6854)
		(end 293.723568 -200.509632)
		(width 0.1016)
		(layer "In5.Cu")
		(net "MEMDQS_P0")
	)
	(segment
		(start 293.5478 -200.814432)
		(end 293.5478 -200.6854)
		(width 0.1016)
		(layer "In5.Cu")
		(net "MEMDQS_P0")
	)
	(segment
		(start 293.723568 -199.563482)
		(end 293.93388 -199.35317)
		(width 0.1016)
		(layer "In5.Cu")
		(net "MEMDQS_P0")
	)
	(segment
		(start 294.2844 -186.23026)
		(end 293.906448 -185.852308)
		(width 0.1016)
		(layer "In5.Cu")
		(net "MEMDQS_P0")
	)
	(segment
		(start 293.933626 -199.079612)
		(end 293.933626 -197.477634)
		(width 0.1016)
		(layer "In5.Cu")
		(net "MEMDQS_P0")
	)
	(segment
		(start 294.2082 -187.832492)
		(end 294.2082 -186.990736)
		(width 0.1016)
		(layer "In5.Cu")
		(net "MEMDQS_P0")
	)
	(segment
		(start 293.605712 -188.416946)
		(end 293.623746 -188.416946)
		(width 0.1016)
		(layer "In5.Cu")
		(net "MEMDQS_P0")
	)
	(segment
		(start 293.033958 -188.9887)
		(end 293.605712 -188.416946)
		(width 0.1016)
		(layer "In5.Cu")
		(net "MEMDQS_P0")
	)
	(segment
		(start 293.08298 -193.642234)
		(end 292.4302 -192.989454)
		(width 0.1016)
		(layer "In5.Cu")
		(net "MEMDQS_P0")
	)
	(segment
		(start 293.723568 -201.243692)
		(end 293.723568 -200.9902)
		(width 0.1016)
		(layer "In5.Cu")
		(net "MEMDQS_P0")
	)
	(segment
		(start 293.4716 -195.788026)
		(end 293.4716 -195.228718)
		(width 0.1016)
		(layer "In5.Cu")
		(net "MEMDQS_P0")
	)
	(segment
		(start 292.4302 -192.989454)
		(end 292.4302 -189.1792)
		(width 0.1016)
		(layer "In5.Cu")
		(net "MEMDQS_P0")
	)
	(segment
		(start 292.4302 -189.1792)
		(end 292.6207 -188.9887)
		(width 0.1016)
		(layer "In5.Cu")
		(net "MEMDQS_P0")
	)
	(segment
		(start 293.08298 -194.840098)
		(end 293.08298 -193.642234)
		(width 0.1016)
		(layer "In5.Cu")
		(net "MEMDQS_P0")
	)
	(segment
		(start 293.296848 -201.34326)
		(end 293.624 -201.34326)
		(width 0.1016)
		(layer "In5.Cu")
		(net "MEMDQS_P0")
	)
	(segment
		(start 293.5859 -195.902326)
		(end 293.4716 -195.788026)
		(width 0.1016)
		(layer "In5.Cu")
		(net "MEMDQS_P0")
	)
	(segment
		(start 293.93388 -199.079866)
		(end 293.933626 -199.079612)
		(width 0.1016)
		(layer "In5.Cu")
		(net "MEMDQS_P0")
	)
	(segment
		(start 293.723568 -200.509632)
		(end 293.723568 -199.563482)
		(width 0.1016)
		(layer "In5.Cu")
		(net "MEMDQS_P0")
	)
	(segment
		(start 293.5859 -197.129908)
		(end 293.5859 -195.902326)
		(width 0.1016)
		(layer "In5.Cu")
		(net "MEMDQS_P0")
	)
	(segment
		(start 294.2082 -186.990736)
		(end 294.2844 -186.914536)
		(width 0.1016)
		(layer "In5.Cu")
		(net "MEMDQS_P0")
	)
	(segment
		(start 293.933626 -197.477634)
		(end 293.5859 -197.129908)
		(width 0.1016)
		(layer "In5.Cu")
		(net "MEMDQS_P0")
	)
	(segment
		(start 293.93388 -199.35317)
		(end 293.93388 -199.079866)
		(width 0.1016)
		(layer "In5.Cu")
		(net "MEMDQS_P0")
	)
	(segment
		(start 293.624 -201.34326)
		(end 293.723568 -201.243692)
		(width 0.1016)
		(layer "In5.Cu")
		(net "MEMDQS_P0")
	)
	(segment
		(start 14.03858 -228.952552)
		(end 14.03858 -230.044244)
		(width 0.1143)
		(layer "F.Cu")
		(net "SAS_HDD_PWR13")
	)
	(segment
		(start 14.03858 -230.044244)
		(end 14.428216 -230.43388)
		(width 0.1143)
		(layer "F.Cu")
		(net "SAS_HDD_PWR13")
	)
	(segment
		(start 21.949918 -227.140516)
		(end 14.46403 -227.140516)
		(width 0.1143)
		(layer "F.Cu")
		(net "SAS_HDD_PWR13")
	)
	(segment
		(start 22.983952 -225.73488)
		(end 22.983952 -226.106482)
		(width 0.1143)
		(layer "F.Cu")
		(net "SAS_HDD_PWR13")
	)
	(segment
		(start 22.983952 -226.106482)
		(end 21.949918 -227.140516)
		(width 0.1143)
		(layer "F.Cu")
		(net "SAS_HDD_PWR13")
	)
	(segment
		(start 22.983952 -225.73488)
		(end 22.983952 -222.325438)
		(width 0.1143)
		(layer "F.Cu")
		(net "SAS_HDD_PWR13")
	)
	(segment
		(start 14.03858 -227.565966)
		(end 14.03858 -228.952552)
		(width 0.1143)
		(layer "F.Cu")
		(net "SAS_HDD_PWR13")
	)
	(segment
		(start 14.46403 -227.140516)
		(end 14.03858 -227.565966)
		(width 0.1143)
		(layer "F.Cu")
		(net "SAS_HDD_PWR13")
	)
	(via
		(at 14.428216 -230.43388)
		(size 0.5588)
		(drill 0.3048)
		(layers "F.Cu" "B.Cu")
		(net "SAS_HDD_PWR13")
	)
	(via
		(at 22.983952 -225.73488)
		(size 0.7112)
		(drill 0.3556)
		(layers "F.Cu" "B.Cu")
		(net "SAS_HDD_PWR13")
	)
	(segment
		(start 14.428216 -231.323388)
		(end 14.428216 -230.43388)
		(width 0.1143)
		(layer "B.Cu")
		(net "SAS_HDD_PWR13")
	)
	(segment
		(start 14.48308 -231.378252)
		(end 14.428216 -231.323388)
		(width 0.1143)
		(layer "B.Cu")
		(net "SAS_HDD_PWR13")
	)
	(segment
		(start 290.068 -158.0515)
		(end 290.068 -157.1625)
		(width 0.381)
		(layer "F.Cu")
		(net "P3V3_STBY")
	)
	(segment
		(start 338.455 -13.7795)
		(end 338.6074 -13.9319)
		(width 0.508)
		(layer "F.Cu")
		(net "P3V3_STBY")
	)
	(segment
		(start 225.13036 -88.42502)
		(end 225.5393 -88.83396)
		(width 0.508)
		(layer "F.Cu")
		(net "P3V3_STBY")
	)
	(segment
		(start 302.777652 -193.303652)
		(end 302.777652 -193.416174)
		(width 0.508)
		(layer "F.Cu")
		(net "P3V3_STBY")
	)
	(segment
		(start 337.684872 -163.483036)
		(end 337.684872 -164.473128)
		(width 0.3048)
		(layer "F.Cu")
		(net "P3V3_STBY")
	)
	(segment
		(start 25.13838 -236.84738)
		(end 25.858216 -236.84738)
		(width 0.508)
		(layer "F.Cu")
		(net "P3V3_STBY")
	)
	(segment
		(start 219.1893 -157.9118)
		(end 219.075 -157.7975)
		(width 0.508)
		(layer "F.Cu")
		(net "P3V3_STBY")
	)
	(segment
		(start 340.0425 -77.7875)
		(end 336.423 -77.7875)
		(width 0.508)
		(layer "F.Cu")
		(net "P3V3_STBY")
	)
	(segment
		(start 172.106844 -29.200856)
		(end 170.699176 -29.200856)
		(width 0.6096)
		(layer "F.Cu")
		(net "P3V3_STBY")
	)
	(segment
		(start 278.765 -201.3585)
		(end 279.7683 -201.3585)
		(width 0.508)
		(layer "F.Cu")
		(net "P3V3_STBY")
	)
	(segment
		(start 88.39327 -138.8618)
		(end 88.192102 -138.8618)
		(width 0.2032)
		(layer "F.Cu")
		(net "P3V3_STBY")
	)
	(segment
		(start 143.14297 -85.471)
		(end 143.14297 -84.582)
		(width 0.3048)
		(layer "F.Cu")
		(net "P3V3_STBY")
	)
	(segment
		(start 38.9128 -169.2656)
		(end 38.9128 -170.2943)
		(width 0.508)
		(layer "F.Cu")
		(net "P3V3_STBY")
	)
	(segment
		(start 27.026616 -194.45478)
		(end 26.366216 -193.79438)
		(width 0.508)
		(layer "F.Cu")
		(net "P3V3_STBY")
	)
	(segment
		(start 203.6445 -218.567)
		(end 202.565 -218.567)
		(width 0.381)
		(layer "F.Cu")
		(net "P3V3_STBY")
	)
	(segment
		(start 273.431 -172.593)
		(end 272.796 -171.958)
		(width 0.508)
		(layer "F.Cu")
		(net "P3V3_STBY")
	)
	(segment
		(start 336.28584 -151.234648)
		(end 336.53984 -150.980648)
		(width 0.508)
		(layer "F.Cu")
		(net "P3V3_STBY")
	)
	(segment
		(start 185.221372 -202.560936)
		(end 185.970672 -202.560936)
		(width 0.508)
		(layer "F.Cu")
		(net "P3V3_STBY")
	)
	(segment
		(start 24.765 -235.556552)
		(end 24.488648 -235.2802)
		(width 0.635)
		(layer "F.Cu")
		(net "P3V3_STBY")
	)
	(segment
		(start 179.451 -219.2655)
		(end 179.46624 -219.28074)
		(width 0.381)
		(layer "F.Cu")
		(net "P3V3_STBY")
	)
	(segment
		(start 256.19964 -135.04672)
		(end 256.19964 -133.7056)
		(width 0.3556)
		(layer "F.Cu")
		(net "P3V3_STBY")
	)
	(segment
		(start 24.425148 -174.517812)
		(end 24.207216 -174.29988)
		(width 0.2032)
		(layer "F.Cu")
		(net "P3V3_STBY")
	)
	(segment
		(start 295.234868 -171.440094)
		(end 295.288462 -171.440094)
		(width 0.3556)
		(layer "F.Cu")
		(net "P3V3_STBY")
	)
	(segment
		(start 290.068 -157.1625)
		(end 289.8775 -156.972)
		(width 0.381)
		(layer "F.Cu")
		(net "P3V3_STBY")
	)
	(segment
		(start 194.7545 -217.932)
		(end 194.7545 -216.789)
		(width 0.508)
		(layer "F.Cu")
		(net "P3V3_STBY")
	)
	(segment
		(start 14.936216 -180.39588)
		(end 14.936216 -181.47538)
		(width 0.508)
		(layer "F.Cu")
		(net "P3V3_STBY")
	)
	(segment
		(start 332.006702 -219.744798)
		(end 332.006702 -221.097856)
		(width 0.3048)
		(layer "F.Cu")
		(net "P3V3_STBY")
	)
	(segment
		(start 332.2955 -216.4715)
		(end 331.851 -216.027)
		(width 0.508)
		(layer "F.Cu")
		(net "P3V3_STBY")
	)
	(segment
		(start 244.729 -136.271)
		(end 244.729 -123.952)
		(width 1.016)
		(layer "F.Cu")
		(net "P3V3_STBY")
	)
	(segment
		(start 91.128342 -122.626882)
		(end 91.128342 -121.483882)
		(width 0.508)
		(layer "F.Cu")
		(net "P3V3_STBY")
	)
	(segment
		(start 336.53984 -150.980648)
		(end 336.960718 -150.980648)
		(width 0.508)
		(layer "F.Cu")
		(net "P3V3_STBY")
	)
	(segment
		(start 38.41877 -136.616186)
		(end 38.41877 -139.00277)
		(width 0.508)
		(layer "F.Cu")
		(net "P3V3_STBY")
	)
	(segment
		(start 288.83483 -177.030634)
		(end 288.439606 -176.63541)
		(width 0.3556)
		(layer "F.Cu")
		(net "P3V3_STBY")
	)
	(segment
		(start 347.374718 -144.783048)
		(end 347.374718 -143.678148)
		(width 0.508)
		(layer "F.Cu")
		(net "P3V3_STBY")
	)
	(segment
		(start 344.402918 -150.726648)
		(end 346.485718 -150.726648)
		(width 0.3048)
		(layer "F.Cu")
		(net "P3V3_STBY")
	)
	(segment
		(start 102.743 -222.885)
		(end 102.743 -222.8342)
		(width 0.508)
		(layer "F.Cu")
		(net "P3V3_STBY")
	)
	(segment
		(start 294.835072 -171.83989)
		(end 295.234868 -171.440094)
		(width 0.3556)
		(layer "F.Cu")
		(net "P3V3_STBY")
	)
	(segment
		(start 271.2085 -188.341)
		(end 271.5387 -188.341)
		(width 0.508)
		(layer "F.Cu")
		(net "P3V3_STBY")
	)
	(segment
		(start 107.44327 -71.9328)
		(end 106.6546 -71.9328)
		(width 0.508)
		(layer "F.Cu")
		(net "P3V3_STBY")
	)
	(segment
		(start 190.3222 -17.145)
		(end 189.9412 -16.764)
		(width 0.3048)
		(layer "F.Cu")
		(net "P3V3_STBY")
	)
	(segment
		(start 25.985216 -226.17938)
		(end 25.985216 -227.38588)
		(width 0.508)
		(layer "F.Cu")
		(net "P3V3_STBY")
	)
	(segment
		(start 273.03603 -179.761896)
		(end 272.9484 -179.761896)
		(width 0.508)
		(layer "F.Cu")
		(net "P3V3_STBY")
	)
	(segment
		(start 346.612718 -157.09646)
		(end 345.97086 -156.454602)
		(width 0.508)
		(layer "F.Cu")
		(net "P3V3_STBY")
	)
	(segment
		(start 302.092868 -177.840132)
		(end 302.26 -177.673)
		(width 0.3556)
		(layer "F.Cu")
		(net "P3V3_STBY")
	)
	(segment
		(start 214.00897 -68.6435)
		(end 214.00897 -66.548)
		(width 0.508)
		(layer "F.Cu")
		(net "P3V3_STBY")
	)
	(segment
		(start 142.257018 -86.356952)
		(end 143.14297 -85.471)
		(width 0.3048)
		(layer "F.Cu")
		(net "P3V3_STBY")
	)
	(segment
		(start 286.8295 -72.9615)
		(end 286.512 -73.279)
		(width 0.508)
		(layer "F.Cu")
		(net "P3V3_STBY")
	)
	(segment
		(start 87.3125 -224.663)
		(end 86.36 -224.663)
		(width 0.4572)
		(layer "F.Cu")
		(net "P3V3_STBY")
	)
	(segment
		(start 313.125104 -53.200046)
		(end 314.96 -53.200046)
		(width 0.508)
		(layer "F.Cu")
		(net "P3V3_STBY")
	)
	(segment
		(start 340.961218 -157.330648)
		(end 341.977218 -157.330648)
		(width 0.508)
		(layer "F.Cu")
		(net "P3V3_STBY")
	)
	(segment
		(start 32.639 -135.282432)
		(end 41.048432 -126.873)
		(width 0.635)
		(layer "F.Cu")
		(net "P3V3_STBY")
	)
	(segment
		(start 80.528414 -115.410742)
		(end 80.518254 -115.400582)
		(width 0.508)
		(layer "F.Cu")
		(net "P3V3_STBY")
	)
	(segment
		(start 186.377072 -202.967336)
		(end 186.377072 -203.386436)
		(width 0.508)
		(layer "F.Cu")
		(net "P3V3_STBY")
	)
	(segment
		(start 269.113 -57.730136)
		(end 268.405864 -57.023)
		(width 0.508)
		(layer "F.Cu")
		(net "P3V3_STBY")
	)
	(segment
		(start 141.85773 -86.356952)
		(end 142.257018 -86.356952)
		(width 0.3048)
		(layer "F.Cu")
		(net "P3V3_STBY")
	)
	(segment
		(start 294.623236 -149.623272)
		(end 293.133272 -149.623272)
		(width 0.508)
		(layer "F.Cu")
		(net "P3V3_STBY")
	)
	(segment
		(start 292.834822 -171.723812)
		(end 292.63086 -171.927774)
		(width 0.3556)
		(layer "F.Cu")
		(net "P3V3_STBY")
	)
	(segment
		(start 319.278 -9.2075)
		(end 319.278 -8.382)
		(width 0.508)
		(layer "F.Cu")
		(net "P3V3_STBY")
	)
	(segment
		(start 202.144376 -147.184872)
		(end 202.144376 -146.041872)
		(width 0.508)
		(layer "F.Cu")
		(net "P3V3_STBY")
	)
	(segment
		(start 333.468218 -156.695648)
		(end 332.363064 -156.695648)
		(width 0.508)
		(layer "F.Cu")
		(net "P3V3_STBY")
	)
	(segment
		(start 282.829 -209.423)
		(end 282.7655 -209.3595)
		(width 0.508)
		(layer "F.Cu")
		(net "P3V3_STBY")
	)
	(segment
		(start 91.128342 -120.340882)
		(end 91.128342 -121.483882)
		(width 0.508)
		(layer "F.Cu")
		(net "P3V3_STBY")
	)
	(segment
		(start 270.8275 -169.672)
		(end 270.758412 -168.800272)
		(width 0.3556)
		(layer "F.Cu")
		(net "P3V3_STBY")
	)
	(segment
		(start 213.923372 -175.586136)
		(end 213.923372 -179.252372)
		(width 0.508)
		(layer "F.Cu")
		(net "P3V3_STBY")
	)
	(segment
		(start 343.152984 -84.7725)
		(end 349.3135 -84.7725)
		(width 0.508)
		(layer "F.Cu")
		(net "P3V3_STBY")
	)
	(segment
		(start 171.893992 -16.129)
		(end 171.893992 -17.030192)
		(width 0.508)
		(layer "F.Cu")
		(net "P3V3_STBY")
	)
	(segment
		(start 317.246 -193.8655)
		(end 317.246 -194.31)
		(width 0.508)
		(layer "F.Cu")
		(net "P3V3_STBY")
	)
	(segment
		(start 182.934864 -22.106636)
		(end 182.934864 -20.863052)
		(width 0.6096)
		(layer "F.Cu")
		(net "P3V3_STBY")
	)
	(segment
		(start 332.312518 -150.091648)
		(end 331.931518 -150.472648)
		(width 0.508)
		(layer "F.Cu")
		(net "P3V3_STBY")
	)
	(segment
		(start 302.514 -106.553)
		(end 302.006 -107.061)
		(width 0.508)
		(layer "F.Cu")
		(net "P3V3_STBY")
	)
	(segment
		(start 15.185898 -176.602898)
		(end 15.367 -176.784)
		(width 0.2032)
		(layer "F.Cu")
		(net "P3V3_STBY")
	)
	(segment
		(start 219.075 -123.444)
		(end 219.71 -124.079)
		(width 0.508)
		(layer "F.Cu")
		(net "P3V3_STBY")
	)
	(segment
		(start 202.144376 -144.898872)
		(end 202.937872 -144.898872)
		(width 0.508)
		(layer "F.Cu")
		(net "P3V3_STBY")
	)
	(segment
		(start 333.468218 -150.091648)
		(end 332.312518 -150.091648)
		(width 0.508)
		(layer "F.Cu")
		(net "P3V3_STBY")
	)
	(segment
		(start 10.89152 -215.84412)
		(end 11.303 -216.2556)
		(width 0.4064)
		(layer "F.Cu")
		(net "P3V3_STBY")
	)
	(segment
		(start 107.44327 -70.9168)
		(end 107.44327 -71.9328)
		(width 0.508)
		(layer "F.Cu")
		(net "P3V3_STBY")
	)
	(segment
		(start 333.384652 -145.646648)
		(end 331.978 -145.646648)
		(width 0.508)
		(layer "F.Cu")
		(net "P3V3_STBY")
	)
	(segment
		(start 26.112216 -198.17588)
		(end 27.026616 -197.26148)
		(width 0.508)
		(layer "F.Cu")
		(net "P3V3_STBY")
	)
	(segment
		(start 109.4105 -240.157)
		(end 109.4105 -244.2845)
		(width 0.508)
		(layer "F.Cu")
		(net "P3V3_STBY")
	)
	(segment
		(start 198.0565 -170.956224)
		(end 198.0565 -169.672)
		(width 0.508)
		(layer "F.Cu")
		(net "P3V3_STBY")
	)
	(segment
		(start 350.0628 -83.027774)
		(end 350.033336 -82.99831)
		(width 0.508)
		(layer "F.Cu")
		(net "P3V3_STBY")
	)
	(segment
		(start 189.9285 -177.419)
		(end 192.2145 -175.133)
		(width 0.508)
		(layer "F.Cu")
		(net "P3V3_STBY")
	)
	(segment
		(start 10.427716 -236.84738)
		(end 11.126216 -236.84738)
		(width 0.508)
		(layer "F.Cu")
		(net "P3V3_STBY")
	)
	(segment
		(start 184.395872 -206.053436)
		(end 182.351172 -206.053436)
		(width 0.508)
		(layer "F.Cu")
		(net "P3V3_STBY")
	)
	(segment
		(start 179.451 -146.431)
		(end 180.2765 -146.431)
		(width 0.508)
		(layer "F.Cu")
		(net "P3V3_STBY")
	)
	(segment
		(start 185.065924 -26.125424)
		(end 185.065924 -27.377136)
		(width 0.3048)
		(layer "F.Cu")
		(net "P3V3_STBY")
	)
	(segment
		(start 245.077996 -92.615004)
		(end 245.11 -92.583)
		(width 0.508)
		(layer "F.Cu")
		(net "P3V3_STBY")
	)
	(segment
		(start 222.6945 -161.671)
		(end 221.615 -161.671)
		(width 0.508)
		(layer "F.Cu")
		(net "P3V3_STBY")
	)
	(segment
		(start 257.556 -122.7455)
		(end 256.8575 -122.047)
		(width 0.508)
		(layer "F.Cu")
		(net "P3V3_STBY")
	)
	(segment
		(start 109.4105 -239.141)
		(end 109.4105 -240.157)
		(width 0.508)
		(layer "F.Cu")
		(net "P3V3_STBY")
	)
	(segment
		(start 15.585948 -177.079148)
		(end 14.936216 -177.72888)
		(width 0.2032)
		(layer "F.Cu")
		(net "P3V3_STBY")
	)
	(segment
		(start 273.423634 -167.767)
		(end 272.796 -167.767)
		(width 0.3048)
		(layer "F.Cu")
		(net "P3V3_STBY")
	)
	(segment
		(start 305.181 -190.246)
		(end 304.038 -191.389)
		(width 0.508)
		(layer "F.Cu")
		(net "P3V3_STBY")
	)
	(segment
		(start 256.159 -135.08736)
		(end 256.19964 -135.04672)
		(width 0.3556)
		(layer "F.Cu")
		(net "P3V3_STBY")
	)
	(segment
		(start 203.62926 -217.43924)
		(end 200.4695 -217.43924)
		(width 0.381)
		(layer "F.Cu")
		(net "P3V3_STBY")
	)
	(segment
		(start 46.863 -126.873)
		(end 54.737 -118.999)
		(width 0.635)
		(layer "F.Cu")
		(net "P3V3_STBY")
	)
	(segment
		(start 321.3989 -212.1154)
		(end 322.4276 -212.1154)
		(width 0.508)
		(layer "F.Cu")
		(net "P3V3_STBY")
	)
	(segment
		(start 279.05202 -215.646)
		(end 278.765 -215.646)
		(width 0.508)
		(layer "F.Cu")
		(net "P3V3_STBY")
	)
	(segment
		(start 287.65246 -181.4576)
		(end 287.65246 -181.45506)
		(width 0.3556)
		(layer "F.Cu")
		(net "P3V3_STBY")
	)
	(segment
		(start 331.7875 -10.9855)
		(end 331.724 -10.922)
		(width 0.508)
		(layer "F.Cu")
		(net "P3V3_STBY")
	)
	(segment
		(start 331.851 -216.027)
		(end 331.47 -216.027)
		(width 0.508)
		(layer "F.Cu")
		(net "P3V3_STBY")
	)
	(segment
		(start 311.3405 -185.674)
		(end 312.166 -184.8485)
		(width 0.508)
		(layer "F.Cu")
		(net "P3V3_STBY")
	)
	(segment
		(start 202.565 -218.567)
		(end 201.4855 -219.6465)
		(width 0.381)
		(layer "F.Cu")
		(net "P3V3_STBY")
	)
	(segment
		(start 189.738 -53.34)
		(end 186.7662 -53.34)
		(width 0.3048)
		(layer "F.Cu")
		(net "P3V3_STBY")
	)
	(segment
		(start 38.41877 -139.00277)
		(end 39.18966 -139.77366)
		(width 0.508)
		(layer "F.Cu")
		(net "P3V3_STBY")
	)
	(segment
		(start 307.20538 -144.46504)
		(end 308.09438 -144.46504)
		(width 0.508)
		(layer "F.Cu")
		(net "P3V3_STBY")
	)
	(segment
		(start 340.032594 -147.856448)
		(end 340.032594 -147.246594)
		(width 0.3048)
		(layer "F.Cu")
		(net "P3V3_STBY")
	)
	(segment
		(start 10.491216 -235.51388)
		(end 10.110216 -235.89488)
		(width 0.635)
		(layer "F.Cu")
		(net "P3V3_STBY")
	)
	(segment
		(start 264.8966 -173.99)
		(end 264.7696 -173.863)
		(width 0.508)
		(layer "F.Cu")
		(net "P3V3_STBY")
	)
	(segment
		(start 295.647872 -179.832)
		(end 295.647872 -179.836572)
		(width 0.3556)
		(layer "F.Cu")
		(net "P3V3_STBY")
	)
	(segment
		(start 54.737 -118.999)
		(end 57.116726 -118.999)
		(width 0.635)
		(layer "F.Cu")
		(net "P3V3_STBY")
	)
	(segment
		(start 143.20647 -83.439)
		(end 143.20647 -84.12353)
		(width 0.3048)
		(layer "F.Cu")
		(net "P3V3_STBY")
	)
	(segment
		(start 223.40697 -88.10371)
		(end 223.72828 -88.42502)
		(width 0.254)
		(layer "F.Cu")
		(net "P3V3_STBY")
	)
	(segment
		(start 288.83483 -173.04004)
		(end 288.83483 -173.049692)
		(width 0.3556)
		(layer "F.Cu")
		(net "P3V3_STBY")
	)
	(segment
		(start 326.4535 -80.8355)
		(end 328.168 -79.121)
		(width 0.508)
		(layer "F.Cu")
		(net "P3V3_STBY")
	)
	(segment
		(start 311.277 -201.4855)
		(end 311.277 -202.311)
		(width 0.508)
		(layer "F.Cu")
		(net "P3V3_STBY")
	)
	(segment
		(start 276.348952 -189.324996)
		(end 278.124412 -189.324996)
		(width 0.3556)
		(layer "F.Cu")
		(net "P3V3_STBY")
	)
	(segment
		(start 265.6205 -173.99)
		(end 264.8966 -173.99)
		(width 0.508)
		(layer "F.Cu")
		(net "P3V3_STBY")
	)
	(segment
		(start 171.893992 -17.030192)
		(end 173.786038 -18.922238)
		(width 0.508)
		(layer "F.Cu")
		(net "P3V3_STBY")
	)
	(segment
		(start 185.284872 -206.053436)
		(end 184.395872 -206.053436)
		(width 0.508)
		(layer "F.Cu")
		(net "P3V3_STBY")
	)
	(segment
		(start 87.3125 -226.822)
		(end 86.36 -226.822)
		(width 0.4572)
		(layer "F.Cu")
		(net "P3V3_STBY")
	)
	(segment
		(start 326.263 -80.8355)
		(end 326.4535 -80.8355)
		(width 0.508)
		(layer "F.Cu")
		(net "P3V3_STBY")
	)
	(segment
		(start 180.648864 -22.106636)
		(end 180.648864 -20.930108)
		(width 0.6096)
		(layer "F.Cu")
		(net "P3V3_STBY")
	)
	(segment
		(start 143.14297 -84.18703)
		(end 143.14297 -84.582)
		(width 0.3048)
		(layer "F.Cu")
		(net "P3V3_STBY")
	)
	(segment
		(start 18.428716 -194.68338)
		(end 18.746216 -194.68338)
		(width 0.508)
		(layer "F.Cu")
		(net "P3V3_STBY")
	)
	(segment
		(start 16.714216 -213.35238)
		(end 16.650716 -213.41588)
		(width 0.508)
		(layer "F.Cu")
		(net "P3V3_STBY")
	)
	(segment
		(start 213.923372 -179.252372)
		(end 215.011 -180.34)
		(width 0.508)
		(layer "F.Cu")
		(net "P3V3_STBY")
	)
	(segment
		(start 219.9005 -119.4435)
		(end 219.075 -120.269)
		(width 0.508)
		(layer "F.Cu")
		(net "P3V3_STBY")
	)
	(segment
		(start 294.434768 -171.440094)
		(end 294.435276 -171.440094)
		(width 0.3556)
		(layer "F.Cu")
		(net "P3V3_STBY")
	)
	(segment
		(start 297.942 -99.1235)
		(end 297.98264 -99.08286)
		(width 0.3048)
		(layer "F.Cu")
		(net "P3V3_STBY")
	)
	(segment
		(start 307.4035 -109.855)
		(end 307.411628 -109.863128)
		(width 0.508)
		(layer "F.Cu")
		(net "P3V3_STBY")
	)
	(segment
		(start 93.345 -221.8055)
		(end 93.7006 -222.1611)
		(width 0.3556)
		(layer "F.Cu")
		(net "P3V3_STBY")
	)
	(segment
		(start 277.550372 -221.433136)
		(end 277.550372 -220.290136)
		(width 0.508)
		(layer "F.Cu")
		(net "P3V3_STBY")
	)
	(segment
		(start 111.77397 -70.75297)
		(end 111.14024 -70.11924)
		(width 0.3048)
		(layer "F.Cu")
		(net "P3V3_STBY")
	)
	(segment
		(start 178.613816 -32.556196)
		(end 178.264312 -32.9057)
		(width 0.3048)
		(layer "F.Cu")
		(net "P3V3_STBY")
	)
	(segment
		(start 306.578 -193.3575)
		(end 306.451 -193.2305)
		(width 0.508)
		(layer "F.Cu")
		(net "P3V3_STBY")
	)
	(segment
		(start 333.4893 -145.542)
		(end 333.384652 -145.646648)
		(width 0.508)
		(layer "F.Cu")
		(net "P3V3_STBY")
	)
	(segment
		(start 273.7485 -180.721)
		(end 272.865088 -180.721)
		(width 0.508)
		(layer "F.Cu")
		(net "P3V3_STBY")
	)
	(segment
		(start 211.5185 -214.99576)
		(end 208.77276 -214.99576)
		(width 0.381)
		(layer "F.Cu")
		(net "P3V3_STBY")
	)
	(segment
		(start 334.426306 -153.393648)
		(end 335.182718 -152.637236)
		(width 0.508)
		(layer "F.Cu")
		(net "P3V3_STBY")
	)
	(segment
		(start 340.835742 -87.597742)
		(end 341.489284 -86.9442)
		(width 0.508)
		(layer "F.Cu")
		(net "P3V3_STBY")
	)
	(segment
		(start 282.725876 -207.478376)
		(end 281.204924 -207.478376)
		(width 0.381)
		(layer "F.Cu")
		(net "P3V3_STBY")
	)
	(segment
		(start 320.04 -7.62)
		(end 319.278 -8.382)
		(width 0.508)
		(layer "F.Cu")
		(net "P3V3_STBY")
	)
	(segment
		(start 332.105 -79.121)
		(end 332.232 -78.994)
		(width 0.508)
		(layer "F.Cu")
		(net "P3V3_STBY")
	)
	(segment
		(start 241.5159 -114.22761)
		(end 239.32261 -114.22761)
		(width 0.3048)
		(layer "F.Cu")
		(net "P3V3_STBY")
	)
	(segment
		(start 17.349216 -195.76288)
		(end 18.428716 -194.68338)
		(width 0.508)
		(layer "F.Cu")
		(net "P3V3_STBY")
	)
	(segment
		(start 80.19415 -139.64666)
		(end 80.513428 -139.327382)
		(width 0.508)
		(layer "F.Cu")
		(net "P3V3_STBY")
	)
	(segment
		(start 82.54238 -139.31392)
		(end 82.54238 -137.1854)
		(width 0.2032)
		(layer "F.Cu")
		(net "P3V3_STBY")
	)
	(segment
		(start 186.309 -52.8828)
		(end 186.309 -52.07889)
		(width 0.3048)
		(layer "F.Cu")
		(net "P3V3_STBY")
	)
	(segment
		(start 295.855136 -171.564808)
		(end 295.97985 -171.440094)
		(width 0.3556)
		(layer "F.Cu")
		(net "P3V3_STBY")
	)
	(segment
		(start 179.886864 -32.556196)
		(end 178.613816 -32.556196)
		(width 0.3048)
		(layer "F.Cu")
		(net "P3V3_STBY")
	)
	(segment
		(start 25.858216 -236.14888)
		(end 26.239216 -235.76788)
		(width 0.508)
		(layer "F.Cu")
		(net "P3V3_STBY")
	)
	(segment
		(start 111.77397 -72.09663)
		(end 111.77397 -70.75297)
		(width 0.3048)
		(layer "F.Cu")
		(net "P3V3_STBY")
	)
	(segment
		(start 339.170518 -146.384518)
		(end 339.170518 -146.154648)
		(width 0.3048)
		(layer "F.Cu")
		(net "P3V3_STBY")
	)
	(segment
		(start 173.042072 -203.830936)
		(end 172.330872 -204.542136)
		(width 0.508)
		(layer "F.Cu")
		(net "P3V3_STBY")
	)
	(segment
		(start 302.514 -102.5525)
		(end 302.514 -106.553)
		(width 0.508)
		(layer "F.Cu")
		(net "P3V3_STBY")
	)
	(segment
		(start 39.06647 -134.62)
		(end 39.06647 -135.968486)
		(width 0.508)
		(layer "F.Cu")
		(net "P3V3_STBY")
	)
	(segment
		(start 185.792872 -198.052436)
		(end 184.776872 -198.052436)
		(width 0.508)
		(layer "F.Cu")
		(net "P3V3_STBY")
	)
	(segment
		(start 273.7485 -172.593)
		(end 273.431 -172.593)
		(width 0.508)
		(layer "F.Cu")
		(net "P3V3_STBY")
	)
	(segment
		(start 182.351172 -206.053436)
		(end 182.236872 -205.939136)
		(width 0.508)
		(layer "F.Cu")
		(net "P3V3_STBY")
	)
	(segment
		(start 197.039992 -46.7995)
		(end 197.039992 -47.879)
		(width 0.508)
		(layer "F.Cu")
		(net "P3V3_STBY")
	)
	(segment
		(start 88.725502 -138.529568)
		(end 88.39327 -138.8618)
		(width 0.2032)
		(layer "F.Cu")
		(net "P3V3_STBY")
	)
	(segment
		(start 19.159728 -192.809368)
		(end 18.746216 -193.22288)
		(width 0.381)
		(layer "F.Cu")
		(net "P3V3_STBY")
	)
	(segment
		(start 214.8205 -220.599)
		(end 214.8205 -219.7735)
		(width 0.508)
		(layer "F.Cu")
		(net "P3V3_STBY")
	)
	(segment
		(start 252.603 -136.3345)
		(end 252.603 -135.128)
		(width 0.508)
		(layer "F.Cu")
		(net "P3V3_STBY")
	)
	(segment
		(start 185.609992 -25.273)
		(end 185.347864 -25.535128)
		(width 0.508)
		(layer "F.Cu")
		(net "P3V3_STBY")
	)
	(segment
		(start 92.3925 -222.22714)
		(end 92.81414 -221.8055)
		(width 0.508)
		(layer "F.Cu")
		(net "P3V3_STBY")
	)
	(segment
		(start 350.033336 -80.137)
		(end 350.040702 -80.108298)
		(width 0.508)
		(layer "F.Cu")
		(net "P3V3_STBY")
	)
	(segment
		(start 300.03496 -179.440078)
		(end 300.430184 -179.835302)
		(width 0.3556)
		(layer "F.Cu")
		(net "P3V3_STBY")
	)
	(segment
		(start 298.45 -102.616)
		(end 298.323 -102.616)
		(width 0.508)
		(layer "F.Cu")
		(net "P3V3_STBY")
	)
	(segment
		(start 24.025098 -175.746156)
		(end 24.025098 -174.481998)
		(width 0.2032)
		(layer "F.Cu")
		(net "P3V3_STBY")
	)
	(segment
		(start 34.036 -169.6085)
		(end 34.036 -170.4975)
		(width 0.508)
		(layer "F.Cu")
		(net "P3V3_STBY")
	)
	(segment
		(start 80.587342 -116.784882)
		(end 80.188308 -116.784882)
		(width 0.508)
		(layer "F.Cu")
		(net "P3V3_STBY")
	)
	(segment
		(start 19.825716 -224.97288)
		(end 20.333716 -224.97288)
		(width 0.508)
		(layer "F.Cu")
		(net "P3V3_STBY")
	)
	(segment
		(start 268.714728 -56.714136)
		(end 268.405864 -57.023)
		(width 0.508)
		(layer "F.Cu")
		(net "P3V3_STBY")
	)
	(segment
		(start 225.5393 -92.17914)
		(end 225.53676 -92.18168)
		(width 0.508)
		(layer "F.Cu")
		(net "P3V3_STBY")
	)
	(segment
		(start 298.5135 -102.5525)
		(end 298.45 -102.616)
		(width 0.508)
		(layer "F.Cu")
		(net "P3V3_STBY")
	)
	(segment
		(start 264.715244 -179.07)
		(end 264.51814 -178.872896)
		(width 0.3556)
		(layer "F.Cu")
		(net "P3V3_STBY")
	)
	(segment
		(start 183.9595 -219.456)
		(end 182.8165 -219.456)
		(width 0.508)
		(layer "F.Cu")
		(net "P3V3_STBY")
	)
	(segment
		(start 337.684872 -164.473128)
		(end 337.312 -164.846)
		(width 0.3048)
		(layer "F.Cu")
		(net "P3V3_STBY")
	)
	(segment
		(start 273.7485 -169.545)
		(end 273.431 -169.545)
		(width 0.3556)
		(layer "F.Cu")
		(net "P3V3_STBY")
	)
	(segment
		(start 320.2305 -7.62)
		(end 320.04 -7.62)
		(width 0.508)
		(layer "F.Cu")
		(net "P3V3_STBY")
	)
	(segment
		(start 203.6445 -220.345)
		(end 203.6445 -218.567)
		(width 0.508)
		(layer "F.Cu")
		(net "P3V3_STBY")
	)
	(segment
		(start 272.865088 -180.721)
		(end 272.833592 -180.752496)
		(width 0.508)
		(layer "F.Cu")
		(net "P3V3_STBY")
	)
	(segment
		(start 333.468218 -154.409648)
		(end 331.89545 -154.409648)
		(width 0.508)
		(layer "F.Cu")
		(net "P3V3_STBY")
	)
	(segment
		(start 332.363064 -156.695648)
		(end 331.836522 -157.22219)
		(width 0.508)
		(layer "F.Cu")
		(net "P3V3_STBY")
	)
	(segment
		(start 304.038 -191.389)
		(end 303.81448 -191.389)
		(width 0.508)
		(layer "F.Cu")
		(net "P3V3_STBY")
	)
	(segment
		(start 172.889672 -205.100936)
		(end 172.330872 -204.542136)
		(width 0.508)
		(layer "F.Cu")
		(net "P3V3_STBY")
	)
	(segment
		(start 143.20647 -84.12353)
		(end 143.14297 -84.18703)
		(width 0.3048)
		(layer "F.Cu")
		(net "P3V3_STBY")
	)
	(segment
		(start 98.806 -221.0435)
		(end 98.806 -220.599)
		(width 0.508)
		(layer "F.Cu")
		(net "P3V3_STBY")
	)
	(segment
		(start 211.72297 -68.6435)
		(end 211.72297 -66.548)
		(width 0.508)
		(layer "F.Cu")
		(net "P3V3_STBY")
	)
	(segment
		(start 332.381352 -143.360648)
		(end 333.468218 -143.360648)
		(width 0.508)
		(layer "F.Cu")
		(net "P3V3_STBY")
	)
	(segment
		(start 319.5193 -172.72)
		(end 319.786 -172.4533)
		(width 0.508)
		(layer "F.Cu")
		(net "P3V3_STBY")
	)
	(segment
		(start 40.0685 -169.291)
		(end 40.0431 -169.2656)
		(width 0.508)
		(layer "F.Cu")
		(net "P3V3_STBY")
	)
	(segment
		(start 219.9005 -113.9825)
		(end 219.9005 -118.745)
		(width 0.508)
		(layer "F.Cu")
		(net "P3V3_STBY")
	)
	(segment
		(start 332.4225 -80.391)
		(end 332.4225 -81.0895)
		(width 0.508)
		(layer "F.Cu")
		(net "P3V3_STBY")
	)
	(segment
		(start 333.468218 -147.805648)
		(end 332.158848 -147.805648)
		(width 0.508)
		(layer "F.Cu")
		(net "P3V3_STBY")
	)
	(segment
		(start 310.388 -114.935)
		(end 309.118 -114.935)
		(width 0.508)
		(layer "F.Cu")
		(net "P3V3_STBY")
	)
	(segment
		(start 303.911 -192.4685)
		(end 303.911 -191.58712)
		(width 0.508)
		(layer "F.Cu")
		(net "P3V3_STBY")
	)
	(segment
		(start 334.509872 -233.434128)
		(end 333.883 -234.061)
		(width 0.508)
		(layer "F.Cu")
		(net "P3V3_STBY")
	)
	(segment
		(start 164.020754 -110.880652)
		(end 163.2712 -110.131098)
		(width 0.508)
		(layer "F.Cu")
		(net "P3V3_STBY")
	)
	(segment
		(start 179.505864 -22.106636)
		(end 179.505864 -20.941792)
		(width 0.6096)
		(layer "F.Cu")
		(net "P3V3_STBY")
	)
	(segment
		(start 194.945 -122.366278)
		(end 194.945 -122.555)
		(width 0.508)
		(layer "F.Cu")
		(net "P3V3_STBY")
	)
	(segment
		(start 40.64 -118.364)
		(end 41.48201 -119.20601)
		(width 0.3048)
		(layer "F.Cu")
		(net "P3V3_STBY")
	)
	(segment
		(start 221.24924 -161.78276)
		(end 221.488 -161.544)
		(width 0.3048)
		(layer "F.Cu")
		(net "P3V3_STBY")
	)
	(segment
		(start 313.1947 -196.226938)
		(end 312.050938 -196.226938)
		(width 0.3048)
		(layer "F.Cu")
		(net "P3V3_STBY")
	)
	(segment
		(start 198.374 -192.532)
		(end 194.183 -192.532)
		(width 0.508)
		(layer "F.Cu")
		(net "P3V3_STBY")
	)
	(segment
		(start 317.2333 -195.453)
		(end 317.2333 -196.226938)
		(width 0.3048)
		(layer "F.Cu")
		(net "P3V3_STBY")
	)
	(segment
		(start 245.077996 -94.367858)
		(end 245.077996 -92.615004)
		(width 0.508)
		(layer "F.Cu")
		(net "P3V3_STBY")
	)
	(segment
		(start 185.221372 -203.703936)
		(end 186.123072 -203.703936)
		(width 0.508)
		(layer "F.Cu")
		(net "P3V3_STBY")
	)
	(segment
		(start 272.669 -183.515)
		(end 272.639536 -183.485536)
		(width 0.508)
		(layer "F.Cu")
		(net "P3V3_STBY")
	)
	(segment
		(start 206.502 -216.789)
		(end 205.867 -216.154)
		(width 0.508)
		(layer "F.Cu")
		(net "P3V3_STBY")
	)
	(segment
		(start 307.594 -216.3445)
		(end 307.594 -215.265)
		(width 0.508)
		(layer "F.Cu")
		(net "P3V3_STBY")
	)
	(segment
		(start 337.214718 -158.029148)
		(end 337.214718 -158.702248)
		(width 0.508)
		(layer "F.Cu")
		(net "P3V3_STBY")
	)
	(segment
		(start 306.102512 -202.786488)
		(end 306.11064 -201.2061)
		(width 0.4064)
		(layer "F.Cu")
		(net "P3V3_STBY")
	)
	(segment
		(start 194.945 -122.555)
		(end 196.723 -124.333)
		(width 0.508)
		(layer "F.Cu")
		(net "P3V3_STBY")
	)
	(segment
		(start 22.333712 -216.714578)
		(end 22.333712 -215.419178)
		(width 0.3556)
		(layer "F.Cu")
		(net "P3V3_STBY")
	)
	(segment
		(start 16.968216 -199.44588)
		(end 18.238216 -198.17588)
		(width 0.508)
		(layer "F.Cu")
		(net "P3V3_STBY")
	)
	(segment
		(start 273.7485 -174.625)
		(end 272.966434 -174.625)
		(width 0.508)
		(layer "F.Cu")
		(net "P3V3_STBY")
	)
	(segment
		(start 219.9005 -118.745)
		(end 219.9005 -119.4435)
		(width 0.508)
		(layer "F.Cu")
		(net "P3V3_STBY")
	)
	(segment
		(start 256.6035 -119.26824)
		(end 256.6035 -120.2436)
		(width 0.3048)
		(layer "F.Cu")
		(net "P3V3_STBY")
	)
	(segment
		(start 199.39 -227.584)
		(end 199.39 -226.568)
		(width 0.508)
		(layer "F.Cu")
		(net "P3V3_STBY")
	)
	(segment
		(start 288.925 -155.829)
		(end 289.8775 -156.7815)
		(width 0.381)
		(layer "F.Cu")
		(net "P3V3_STBY")
	)
	(segment
		(start 331.499972 -164.029136)
		(end 333.248 -164.029136)
		(width 0.3048)
		(layer "F.Cu")
		(net "P3V3_STBY")
	)
	(segment
		(start 33.02 -169.291)
		(end 34.3535 -169.291)
		(width 0.508)
		(layer "F.Cu")
		(net "P3V3_STBY")
	)
	(segment
		(start 88.325452 -137.209276)
		(end 88.325452 -138.72845)
		(width 0.2032)
		(layer "F.Cu")
		(net "P3V3_STBY")
	)
	(segment
		(start 92.00134 -222.5548)
		(end 92.329 -222.22714)
		(width 0.508)
		(layer "F.Cu")
		(net "P3V3_STBY")
	)
	(segment
		(start 328.168 -79.121)
		(end 332.105 -79.121)
		(width 0.508)
		(layer "F.Cu")
		(net "P3V3_STBY")
	)
	(segment
		(start 181.485032 -205.187296)
		(end 182.236872 -205.939136)
		(width 0.3048)
		(layer "F.Cu")
		(net "P3V3_STBY")
	)
	(segment
		(start 273.65325 -181.64175)
		(end 272.973038 -181.64175)
		(width 0.508)
		(layer "F.Cu")
		(net "P3V3_STBY")
	)
	(segment
		(start 171.893992 -13.208)
		(end 171.893992 -14.351)
		(width 0.508)
		(layer "F.Cu")
		(net "P3V3_STBY")
	)
	(segment
		(start 332.2955 -217.17)
		(end 332.2955 -216.4715)
		(width 0.508)
		(layer "F.Cu")
		(net "P3V3_STBY")
	)
	(segment
		(start 273.7485 -168.021)
		(end 273.617182 -167.960548)
		(width 0.3048)
		(layer "F.Cu")
		(net "P3V3_STBY")
	)
	(segment
		(start 311.277 -202.311)
		(end 310.769 -202.819)
		(width 0.508)
		(layer "F.Cu")
		(net "P3V3_STBY")
	)
	(segment
		(start 22.175216 -206.04988)
		(end 21.540216 -205.41488)
		(width 0.508)
		(layer "F.Cu")
		(net "P3V3_STBY")
	)
	(segment
		(start 338.662518 -150.726648)
		(end 337.214718 -150.726648)
		(width 0.3048)
		(layer "F.Cu")
		(net "P3V3_STBY")
	)
	(segment
		(start 41.48201 -119.20601)
		(end 42.3418 -119.20601)
		(width 0.3048)
		(layer "F.Cu")
		(net "P3V3_STBY")
	)
	(segment
		(start 216.074752 -179.403248)
		(end 215.138 -180.34)
		(width 0.508)
		(layer "F.Cu")
		(net "P3V3_STBY")
	)
	(segment
		(start 284.988 -156.0195)
		(end 286.0675 -156.0195)
		(width 0.508)
		(layer "F.Cu")
		(net "P3V3_STBY")
	)
	(segment
		(start 336.423 -77.7875)
		(end 336.3595 -77.851)
		(width 0.508)
		(layer "F.Cu")
		(net "P3V3_STBY")
	)
	(segment
		(start 77.370432 -115.410742)
		(end 76.04633 -114.08664)
		(width 0.508)
		(layer "F.Cu")
		(net "P3V3_STBY")
	)
	(segment
		(start 305.363372 -204.288136)
		(end 305.363372 -203.525628)
		(width 0.4064)
		(layer "F.Cu")
		(net "P3V3_STBY")
	)
	(segment
		(start 219.075 -120.720358)
		(end 219.049346 -120.746012)
		(width 0.508)
		(layer "F.Cu")
		(net "P3V3_STBY")
	)
	(segment
		(start 303.53 -102.5525)
		(end 302.514 -102.5525)
		(width 0.508)
		(layer "F.Cu")
		(net "P3V3_STBY")
	)
	(segment
		(start 331.372972 -172.030136)
		(end 332.994 -172.030136)
		(width 0.3048)
		(layer "F.Cu")
		(net "P3V3_STBY")
	)
	(segment
		(start 316.9793 -195.199)
		(end 317.2333 -195.453)
		(width 0.3048)
		(layer "F.Cu")
		(net "P3V3_STBY")
	)
	(segment
		(start 338.6074 -13.9319)
		(end 338.6074 -14.8844)
		(width 0.508)
		(layer "F.Cu")
		(net "P3V3_STBY")
	)
	(segment
		(start 264.926064 -177.038)
		(end 264.51814 -176.630076)
		(width 0.3556)
		(layer "F.Cu")
		(net "P3V3_STBY")
	)
	(segment
		(start 343.408 -20.7645)
		(end 343.408 -21.717)
		(width 0.508)
		(layer "F.Cu")
		(net "P3V3_STBY")
	)
	(segment
		(start 297.634914 -173.04004)
		(end 297.36796 -173.04004)
		(width 0.3048)
		(layer "F.Cu")
		(net "P3V3_STBY")
	)
	(segment
		(start 337.214718 -158.702248)
		(end 337.646518 -159.134048)
		(width 0.508)
		(layer "F.Cu")
		(net "P3V3_STBY")
	)
	(segment
		(start 15.367 -176.784)
		(end 15.585948 -176.784)
		(width 0.2032)
		(layer "F.Cu")
		(net "P3V3_STBY")
	)
	(segment
		(start 287.65246 -181.45506)
		(end 287.64103 -181.44363)
		(width 0.3556)
		(layer "F.Cu")
		(net "P3V3_STBY")
	)
	(segment
		(start 307.411628 -109.863128)
		(end 308.491636 -109.863128)
		(width 0.508)
		(layer "F.Cu")
		(net "P3V3_STBY")
	)
	(segment
		(start 194.183 -192.532)
		(end 192.663064 -194.051936)
		(width 0.508)
		(layer "F.Cu")
		(net "P3V3_STBY")
	)
	(segment
		(start 186.123072 -203.703936)
		(end 186.377072 -203.449936)
		(width 0.508)
		(layer "F.Cu")
		(net "P3V3_STBY")
	)
	(segment
		(start 182.8165 -218.6305)
		(end 183.007 -218.44)
		(width 0.508)
		(layer "F.Cu")
		(net "P3V3_STBY")
	)
	(segment
		(start 80.587342 -117.927882)
		(end 79.920592 -117.927882)
		(width 0.508)
		(layer "F.Cu")
		(net "P3V3_STBY")
	)
	(segment
		(start 330.835 -142.113)
		(end 331.089 -142.113)
		(width 0.508)
		(layer "F.Cu")
		(net "P3V3_STBY")
	)
	(segment
		(start 224.409 -179.705)
		(end 223.774 -180.34)
		(width 0.508)
		(layer "F.Cu")
		(net "P3V3_STBY")
	)
	(segment
		(start 308.229 -193.1035)
		(end 308.229 -192.024)
		(width 0.508)
		(layer "F.Cu")
		(net "P3V3_STBY")
	)
	(segment
		(start 330.399136 -211.018628)
		(end 330.399136 -209.858864)
		(width 0.635)
		(layer "F.Cu")
		(net "P3V3_STBY")
	)
	(segment
		(start 265.6205 -177.038)
		(end 264.926064 -177.038)
		(width 0.3556)
		(layer "F.Cu")
		(net "P3V3_STBY")
	)
	(segment
		(start 332.867 -10.9855)
		(end 331.7875 -10.9855)
		(width 0.508)
		(layer "F.Cu")
		(net "P3V3_STBY")
	)
	(segment
		(start 215.138 -180.34)
		(end 215.011 -180.34)
		(width 0.508)
		(layer "F.Cu")
		(net "P3V3_STBY")
	)
	(segment
		(start 181.728872 -191.702436)
		(end 182.859172 -191.702436)
		(width 0.508)
		(layer "F.Cu")
		(net "P3V3_STBY")
	)
	(segment
		(start 306.6415 -223.139)
		(end 306.6415 -222.5675)
		(width 0.508)
		(layer "F.Cu")
		(net "P3V3_STBY")
	)
	(segment
		(start 256.8575 -120.4976)
		(end 256.8575 -122.047)
		(width 0.508)
		(layer "F.Cu")
		(net "P3V3_STBY")
	)
	(segment
		(start 111.7092 -72.1614)
		(end 111.77397 -72.09663)
		(width 0.3048)
		(layer "F.Cu")
		(net "P3V3_STBY")
	)
	(segment
		(start 110.1725 -68.199)
		(end 110.1725 -70.11543)
		(width 0.3048)
		(layer "F.Cu")
		(net "P3V3_STBY")
	)
	(segment
		(start 289.8775 -156.7815)
		(end 289.8775 -156.972)
		(width 0.381)
		(layer "F.Cu")
		(net "P3V3_STBY")
	)
	(segment
		(start 273.7485 -173.609)
		(end 272.923 -173.609)
		(width 0.508)
		(layer "F.Cu")
		(net "P3V3_STBY")
	)
	(segment
		(start 257.039364 -229.226872)
		(end 255.913128 -229.226872)
		(width 0.508)
		(layer "F.Cu")
		(net "P3V3_STBY")
	)
	(segment
		(start 350.033336 -81.435194)
		(end 350.033336 -81.256378)
		(width 0.508)
		(layer "F.Cu")
		(net "P3V3_STBY")
	)
	(segment
		(start 279.772872 -215.146636)
		(end 279.645872 -215.273636)
		(width 0.508)
		(layer "F.Cu")
		(net "P3V3_STBY")
	)
	(segment
		(start 184.776872 -198.052436)
		(end 184.230772 -198.052436)
		(width 0.508)
		(layer "F.Cu")
		(net "P3V3_STBY")
	)
	(segment
		(start 329.311 -211.018628)
		(end 330.399136 -211.018628)
		(width 0.508)
		(layer "F.Cu")
		(net "P3V3_STBY")
	)
	(segment
		(start 179.197 -146.2024)
		(end 179.2224 -146.2024)
		(width 0.508)
		(layer "F.Cu")
		(net "P3V3_STBY")
	)
	(segment
		(start 82.555842 -139.327382)
		(end 82.54238 -139.31392)
		(width 0.2032)
		(layer "F.Cu")
		(net "P3V3_STBY")
	)
	(segment
		(start 184.9755 -122.4915)
		(end 185.039 -122.555)
		(width 0.508)
		(layer "F.Cu")
		(net "P3V3_STBY")
	)
	(segment
		(start 110.1725 -70.11543)
		(end 110.17631 -70.11924)
		(width 0.3048)
		(layer "F.Cu")
		(net "P3V3_STBY")
	)
	(segment
		(start 189.9412 -16.764)
		(end 189.9412 -16.21536)
		(width 0.3048)
		(layer "F.Cu")
		(net "P3V3_STBY")
	)
	(segment
		(start 183.913272 -197.734936)
		(end 182.236872 -197.734936)
		(width 0.508)
		(layer "F.Cu")
		(net "P3V3_STBY")
	)
	(segment
		(start 320.9925 -141.00175)
		(end 320.9925 -139.7635)
		(width 0.508)
		(layer "F.Cu")
		(net "P3V3_STBY")
	)
	(segment
		(start 269.295372 -56.714136)
		(end 268.714728 -56.714136)
		(width 0.508)
		(layer "F.Cu")
		(net "P3V3_STBY")
	)
	(segment
		(start 3.942842 -215.843612)
		(end 3.942588 -215.843866)
		(width 0.508)
		(layer "F.Cu")
		(net "P3V3_STBY")
	)
	(segment
		(start 293.634922 -171.433744)
		(end 293.23538 -171.034202)
		(width 0.3556)
		(layer "F.Cu")
		(net "P3V3_STBY")
	)
	(segment
		(start 173.786038 -18.922238)
		(end 173.786038 -18.974562)
		(width 0.508)
		(layer "F.Cu")
		(net "P3V3_STBY")
	)
	(segment
		(start 26.429716 -235.57738)
		(end 26.429716 -234.19308)
		(width 0.3048)
		(layer "F.Cu")
		(net "P3V3_STBY")
	)
	(segment
		(start 186.377072 -203.449936)
		(end 186.377072 -203.386436)
		(width 0.508)
		(layer "F.Cu")
		(net "P3V3_STBY")
	)
	(segment
		(start 19.159728 -192.746376)
		(end 19.159728 -192.809368)
		(width 0.381)
		(layer "F.Cu")
		(net "P3V3_STBY")
	)
	(segment
		(start 296.034968 -180.240178)
		(end 295.647872 -179.853082)
		(width 0.3556)
		(layer "F.Cu")
		(net "P3V3_STBY")
	)
	(segment
		(start 303.911 -191.58712)
		(end 303.76368 -191.4398)
		(width 0.508)
		(layer "F.Cu")
		(net "P3V3_STBY")
	)
	(segment
		(start 192.7225 -17.145)
		(end 191.643 -17.145)
		(width 0.508)
		(layer "F.Cu")
		(net "P3V3_STBY")
	)
	(segment
		(start 326.261222 -168.543986)
		(end 325.893938 -168.543986)
		(width 0.508)
		(layer "F.Cu")
		(net "P3V3_STBY")
	)
	(segment
		(start 194.9704 -227.75545)
		(end 199.05345 -227.75545)
		(width 0.3048)
		(layer "F.Cu")
		(net "P3V3_STBY")
	)
	(segment
		(start 271.5387 -188.341)
		(end 272.0467 -188.849)
		(width 0.508)
		(layer "F.Cu")
		(net "P3V3_STBY")
	)
	(segment
		(start 24.765 -236.474)
		(end 24.765 -235.556552)
		(width 0.635)
		(layer "F.Cu")
		(net "P3V3_STBY")
	)
	(segment
		(start 219.049346 -121.569988)
		(end 219.075 -121.595642)
		(width 0.508)
		(layer "F.Cu")
		(net "P3V3_STBY")
	)
	(segment
		(start 24.488648 -235.2802)
		(end 24.3078 -235.2802)
		(width 0.635)
		(layer "F.Cu")
		(net "P3V3_STBY")
	)
	(segment
		(start 182.888128 -16.628364)
		(end 181.982364 -16.628364)
		(width 0.508)
		(layer "F.Cu")
		(net "P3V3_STBY")
	)
	(segment
		(start 257.556 -123.698)
		(end 257.556 -122.7455)
		(width 0.508)
		(layer "F.Cu")
		(net "P3V3_STBY")
	)
	(segment
		(start 350.040702 -80.108298)
		(end 350.393 -79.756)
		(width 0.508)
		(layer "F.Cu")
		(net "P3V3_STBY")
	)
	(segment
		(start 343.532714 -147.767548)
		(end 343.933018 -147.767548)
		(width 0.3048)
		(layer "F.Cu")
		(net "P3V3_STBY")
	)
	(segment
		(start 305.3715 -190.246)
		(end 305.181 -190.246)
		(width 0.508)
		(layer "F.Cu")
		(net "P3V3_STBY")
	)
	(segment
		(start 265.6205 -176.022)
		(end 265.103864 -176.022)
		(width 0.3556)
		(layer "F.Cu")
		(net "P3V3_STBY")
	)
	(segment
		(start 32.512 -138.1887)
		(end 32.639 -138.0617)
		(width 0.635)
		(layer "F.Cu")
		(net "P3V3_STBY")
	)
	(segment
		(start 239.0648 -113.601246)
		(end 239.0648 -113.9698)
		(width 0.508)
		(layer "F.Cu")
		(net "P3V3_STBY")
	)
	(segment
		(start 185.970672 -202.560936)
		(end 186.377072 -202.967336)
		(width 0.508)
		(layer "F.Cu")
		(net "P3V3_STBY")
	)
	(segment
		(start 220.0148 -161.78276)
		(end 221.24924 -161.78276)
		(width 0.3048)
		(layer "F.Cu")
		(net "P3V3_STBY")
	)
	(segment
		(start 225.5393 -91.37142)
		(end 225.5393 -92.17914)
		(width 0.508)
		(layer "F.Cu")
		(net "P3V3_STBY")
	)
	(segment
		(start 348.390718 -143.767048)
		(end 347.374718 -144.783048)
		(width 0.508)
		(layer "F.Cu")
		(net "P3V3_STBY")
	)
	(segment
		(start 262.182864 -231.449372)
		(end 261.039864 -231.449372)
		(width 0.508)
		(layer "F.Cu")
		(net "P3V3_STBY")
	)
	(segment
		(start 192.663064 -194.051936)
		(end 188.155072 -194.051936)
		(width 0.508)
		(layer "F.Cu")
		(net "P3V3_STBY")
	)
	(segment
		(start 23.445216 -213.35238)
		(end 23.445216 -212.27288)
		(width 0.508)
		(layer "F.Cu")
		(net "P3V3_STBY")
	)
	(segment
		(start 286.8295 -70.612)
		(end 286.8295 -72.9615)
		(width 0.508)
		(layer "F.Cu")
		(net "P3V3_STBY")
	)
	(segment
		(start 307.975 -110.744)
		(end 308.491636 -110.227364)
		(width 0.508)
		(layer "F.Cu")
		(net "P3V3_STBY")
	)
	(segment
		(start 107.21467 -75.5015)
		(end 106.54157 -74.8284)
		(width 0.508)
		(layer "F.Cu")
		(net "P3V3_STBY")
	)
	(segment
		(start 194.7545 -216.789)
		(end 194.7545 -215.7095)
		(width 0.508)
		(layer "F.Cu")
		(net "P3V3_STBY")
	)
	(segment
		(start 316.9285 -193.548)
		(end 317.246 -193.8655)
		(width 0.508)
		(layer "F.Cu")
		(net "P3V3_STBY")
	)
	(segment
		(start 207.7085 -216.789)
		(end 206.502 -216.789)
		(width 0.508)
		(layer "F.Cu")
		(net "P3V3_STBY")
	)
	(segment
		(start 171.365164 -22.045676)
		(end 172.368464 -22.045676)
		(width 0.6096)
		(layer "F.Cu")
		(net "P3V3_STBY")
	)
	(segment
		(start 11.126216 -236.84738)
		(end 11.49858 -236.475016)
		(width 0.3556)
		(layer "F.Cu")
		(net "P3V3_STBY")
	)
	(segment
		(start 270.0274 -170.942)
		(end 269.9258 -170.8404)
		(width 0.3556)
		(layer "F.Cu")
		(net "P3V3_STBY")
	)
	(segment
		(start 279.7683 -201.3585)
		(end 280.289 -201.8792)
		(width 0.508)
		(layer "F.Cu")
		(net "P3V3_STBY")
	)
	(segment
		(start 256.6035 -120.2436)
		(end 256.8575 -120.4976)
		(width 0.508)
		(layer "F.Cu")
		(net "P3V3_STBY")
	)
	(segment
		(start 269.930372 -57.730136)
		(end 269.113 -57.730136)
		(width 0.508)
		(layer "F.Cu")
		(net "P3V3_STBY")
	)
	(segment
		(start 339.728048 -146.942048)
		(end 339.170518 -146.384518)
		(width 0.3048)
		(layer "F.Cu")
		(net "P3V3_STBY")
	)
	(segment
		(start 311.3405 -186.817)
		(end 311.3405 -185.674)
		(width 0.508)
		(layer "F.Cu")
		(net "P3V3_STBY")
	)
	(segment
		(start 342.040718 -156.822648)
		(end 341.032592 -155.814522)
		(width 0.508)
		(layer "F.Cu")
		(net "P3V3_STBY")
	)
	(segment
		(start 332.2955 -218.059)
		(end 332.2955 -219.456)
		(width 0.508)
		(layer "F.Cu")
		(net "P3V3_STBY")
	)
	(segment
		(start 2.9972 -216.789)
		(end 2.032 -216.789)
		(width 0.508)
		(layer "F.Cu")
		(net "P3V3_STBY")
	)
	(segment
		(start 335.182718 -151.934926)
		(end 335.882996 -151.234648)
		(width 0.508)
		(layer "F.Cu")
		(net "P3V3_STBY")
	)
	(segment
		(start 273.7485 -181.737)
		(end 273.65325 -181.64175)
		(width 0.508)
		(layer "F.Cu")
		(net "P3V3_STBY")
	)
	(segment
		(start 350.033336 -81.256378)
		(end 350.033336 -80.137)
		(width 0.508)
		(layer "F.Cu")
		(net "P3V3_STBY")
	)
	(segment
		(start 301.634906 -177.840132)
		(end 302.092868 -177.840132)
		(width 0.3556)
		(layer "F.Cu")
		(net "P3V3_STBY")
	)
	(segment
		(start 349.3135 -84.7725)
		(end 350.0628 -84.0232)
		(width 0.508)
		(layer "F.Cu")
		(net "P3V3_STBY")
	)
	(segment
		(start 303.76876 -220.6625)
		(end 303.76876 -222.10776)
		(width 0.508)
		(layer "F.Cu")
		(net "P3V3_STBY")
	)
	(segment
		(start 288.034984 -181.840124)
		(end 287.65246 -181.4576)
		(width 0.3556)
		(layer "F.Cu")
		(net "P3V3_STBY")
	)
	(segment
		(start 341.977218 -157.330648)
		(end 342.040718 -157.394148)
		(width 0.508)
		(layer "F.Cu")
		(net "P3V3_STBY")
	)
	(segment
		(start 77.61097 -133.4008)
		(end 77.602842 -133.392672)
		(width 0.3048)
		(layer "F.Cu")
		(net "P3V3_STBY")
	)
	(segment
		(start 39.06647 -135.968486)
		(end 38.41877 -136.616186)
		(width 0.508)
		(layer "F.Cu")
		(net "P3V3_STBY")
	)
	(segment
		(start 348.390718 -143.678148)
		(end 348.390718 -143.767048)
		(width 0.508)
		(layer "F.Cu")
		(net "P3V3_STBY")
	)
	(segment
		(start 20.651216 -224.65538)
		(end 21.667216 -224.65538)
		(width 0.508)
		(layer "F.Cu")
		(net "P3V3_STBY")
	)
	(segment
		(start 220.0275 -111.76)
		(end 220.091 -111.76)
		(width 0.508)
		(layer "F.Cu")
		(net "P3V3_STBY")
	)
	(segment
		(start 334.509872 -232.926636)
		(end 334.509872 -233.434128)
		(width 0.508)
		(layer "F.Cu")
		(net "P3V3_STBY")
	)
	(segment
		(start 14.428216 -214.05088)
		(end 13.094716 -214.05088)
		(width 0.508)
		(layer "F.Cu")
		(net "P3V3_STBY")
	)
	(segment
		(start 265.103864 -176.022)
		(end 264.51814 -175.436276)
		(width 0.3556)
		(layer "F.Cu")
		(net "P3V3_STBY")
	)
	(segment
		(start 99.314 -220.4085)
		(end 99.314 -220.091)
		(width 0.508)
		(layer "F.Cu")
		(net "P3V3_STBY")
	)
	(segment
		(start 98.806 -220.599)
		(end 99.314 -220.091)
		(width 0.508)
		(layer "F.Cu")
		(net "P3V3_STBY")
	)
	(segment
		(start 88.725502 -137.209276)
		(end 88.725502 -138.529568)
		(width 0.2032)
		(layer "F.Cu")
		(net "P3V3_STBY")
	)
	(segment
		(start 199.39 -193.548)
		(end 198.374 -192.532)
		(width 0.508)
		(layer "F.Cu")
		(net "P3V3_STBY")
	)
	(segment
		(start 222.8215 -171.7675)
		(end 224.409 -173.355)
		(width 0.508)
		(layer "F.Cu")
		(net "P3V3_STBY")
	)
	(segment
		(start 309.6895 -160.2105)
		(end 310.261 -160.782)
		(width 0.508)
		(layer "F.Cu")
		(net "P3V3_STBY")
	)
	(segment
		(start 278.124412 -189.324996)
		(end 278.131524 -189.332108)
		(width 0.3556)
		(layer "F.Cu")
		(net "P3V3_STBY")
	)
	(segment
		(start 221.8055 -105.156)
		(end 222.0595 -104.902)
		(width 0.508)
		(layer "F.Cu")
		(net "P3V3_STBY")
	)
	(segment
		(start 272.626836 -185.547)
		(end 272.542 -185.631836)
		(width 0.508)
		(layer "F.Cu")
		(net "P3V3_STBY")
	)
	(segment
		(start 184.230772 -198.052436)
		(end 183.913272 -197.734936)
		(width 0.508)
		(layer "F.Cu")
		(net "P3V3_STBY")
	)
	(segment
		(start 258.699 -125.984)
		(end 257.556 -124.841)
		(width 0.508)
		(layer "F.Cu")
		(net "P3V3_STBY")
	)
	(segment
		(start 38.7985 -213.4235)
		(end 38.735 -213.36)
		(width 0.508)
		(layer "F.Cu")
		(net "P3V3_STBY")
	)
	(segment
		(start 316.463934 -195.199)
		(end 316.9793 -195.199)
		(width 0.3048)
		(layer "F.Cu")
		(net "P3V3_STBY")
	)
	(segment
		(start 22.619716 -206.04988)
		(end 22.175216 -206.04988)
		(width 0.508)
		(layer "F.Cu")
		(net "P3V3_STBY")
	)
	(segment
		(start 332.4225 -81.0895)
		(end 332.105 -81.407)
		(width 0.508)
		(layer "F.Cu")
		(net "P3V3_STBY")
	)
	(segment
		(start 340.032594 -147.246594)
		(end 339.964522 -147.178522)
		(width 0.3048)
		(layer "F.Cu")
		(net "P3V3_STBY")
	)
	(segment
		(start 16.714216 -212.27288)
		(end 16.714216 -213.35238)
		(width 0.508)
		(layer "F.Cu")
		(net "P3V3_STBY")
	)
	(segment
		(start 331.89545 -154.409648)
		(end 331.831442 -154.473656)
		(width 0.508)
		(layer "F.Cu")
		(net "P3V3_STBY")
	)
	(segment
		(start 333.468218 -142.217648)
		(end 333.468218 -143.360648)
		(width 0.508)
		(layer "F.Cu")
		(net "P3V3_STBY")
	)
	(segment
		(start 313.1947 -197.727062)
		(end 312.050938 -197.727062)
		(width 0.3048)
		(layer "F.Cu")
		(net "P3V3_STBY")
	)
	(segment
		(start 334.357218 -153.393648)
		(end 334.426306 -153.393648)
		(width 0.508)
		(layer "F.Cu")
		(net "P3V3_STBY")
	)
	(segment
		(start 273.7485 -183.515)
		(end 272.669 -183.515)
		(width 0.508)
		(layer "F.Cu")
		(net "P3V3_STBY")
	)
	(segment
		(start 278.384 -207.3275)
		(end 278.384 -206.375)
		(width 0.508)
		(layer "F.Cu")
		(net "P3V3_STBY")
	)
	(segment
		(start 333.468218 -157.838648)
		(end 332.45298 -157.838648)
		(width 0.508)
		(layer "F.Cu")
		(net "P3V3_STBY")
	)
	(segment
		(start 297.634914 -177.030634)
		(end 298.03471 -176.630838)
		(width 0.3048)
		(layer "F.Cu")
		(net "P3V3_STBY")
	)
	(segment
		(start 223.012 -102.743)
		(end 221.8055 -102.743)
		(width 0.508)
		(layer "F.Cu")
		(net "P3V3_STBY")
	)
	(segment
		(start 332.096872 -221.188026)
		(end 332.096872 -222.157036)
		(width 0.3048)
		(layer "F.Cu")
		(net "P3V3_STBY")
	)
	(segment
		(start 202.144376 -146.041872)
		(end 202.144376 -144.898872)
		(width 0.508)
		(layer "F.Cu")
		(net "P3V3_STBY")
	)
	(segment
		(start 225.53676 -92.18168)
		(end 225.53676 -96.5708)
		(width 0.508)
		(layer "F.Cu")
		(net "P3V3_STBY")
	)
	(segment
		(start 235.445046 -114.07902)
		(end 236.494066 -113.03)
		(width 0.508)
		(layer "F.Cu")
		(net "P3V3_STBY")
	)
	(segment
		(start 337.214718 -150.726648)
		(end 336.960718 -150.980648)
		(width 0.3048)
		(layer "F.Cu")
		(net "P3V3_STBY")
	)
	(segment
		(start 272.973038 -181.64175)
		(end 272.869152 -181.745636)
		(width 0.508)
		(layer "F.Cu")
		(net "P3V3_STBY")
	)
	(segment
		(start 173.537372 -205.100936)
		(end 172.889672 -205.100936)
		(width 0.508)
		(layer "F.Cu")
		(net "P3V3_STBY")
	)
	(segment
		(start 208.5975 -215.773)
		(end 208.5975 -214.8205)
		(width 0.508)
		(layer "F.Cu")
		(net "P3V3_STBY")
	)
	(segment
		(start 277.550372 -220.290136)
		(end 276.606 -220.290136)
		(width 0.508)
		(layer "F.Cu")
		(net "P3V3_STBY")
	)
	(segment
		(start 306.13096 -144.46504)
		(end 307.20538 -144.46504)
		(width 0.508)
		(layer "F.Cu")
		(net "P3V3_STBY")
	)
	(segment
		(start 223.774 -102.743)
		(end 224.79 -103.759)
		(width 0.508)
		(layer "F.Cu")
		(net "P3V3_STBY")
	)
	(segment
		(start 346.866718 -150.853648)
		(end 346.612718 -150.599648)
		(width 0.508)
		(layer "F.Cu")
		(net "P3V3_STBY")
	)
	(segment
		(start 222.377 -180.404008)
		(end 222.495872 -180.285136)
		(width 0.508)
		(layer "F.Cu")
		(net "P3V3_STBY")
	)
	(segment
		(start 272.923 -173.609)
		(end 272.796 -173.482)
		(width 0.508)
		(layer "F.Cu")
		(net "P3V3_STBY")
	)
	(segment
		(start 221.34068 -88.10371)
		(end 223.40697 -88.10371)
		(width 0.254)
		(layer "F.Cu")
		(net "P3V3_STBY")
	)
	(segment
		(start 184.475628 -25.535128)
		(end 185.065924 -26.125424)
		(width 0.3048)
		(layer "F.Cu")
		(net "P3V3_STBY")
	)
	(segment
		(start 79.444342 -134.589012)
		(end 79.444342 -133.269482)
		(width 0.508)
		(layer "F.Cu")
		(net "P3V3_STBY")
	)
	(segment
		(start 18.238216 -198.17588)
		(end 26.112216 -198.17588)
		(width 0.508)
		(layer "F.Cu")
		(net "P3V3_STBY")
	)
	(segment
		(start 20.333716 -224.97288)
		(end 20.651216 -224.65538)
		(width 0.508)
		(layer "F.Cu")
		(net "P3V3_STBY")
	)
	(segment
		(start 344.453718 -154.790648)
		(end 345.342718 -155.679648)
		(width 0.508)
		(layer "F.Cu")
		(net "P3V3_STBY")
	)
	(segment
		(start 103.0605 -223.2025)
		(end 102.743 -222.885)
		(width 0.508)
		(layer "F.Cu")
		(net "P3V3_STBY")
	)
	(segment
		(start 326.39 -168.4655)
		(end 326.261222 -168.543986)
		(width 0.508)
		(layer "F.Cu")
		(net "P3V3_STBY")
	)
	(segment
		(start 199.39 -224.7265)
		(end 199.39 -226.568)
		(width 0.508)
		(layer "F.Cu")
		(net "P3V3_STBY")
	)
	(segment
		(start 180.2765 -147.828)
		(end 180.2765 -148.6408)
		(width 0.508)
		(layer "F.Cu")
		(net "P3V3_STBY")
	)
	(segment
		(start 219.075 -120.269)
		(end 219.075 -120.720358)
		(width 0.508)
		(layer "F.Cu")
		(net "P3V3_STBY")
	)
	(segment
		(start 297.634914 -176.240186)
		(end 297.644058 -176.240186)
		(width 0.3048)
		(layer "F.Cu")
		(net "P3V3_STBY")
	)
	(segment
		(start 77.602842 -133.392672)
		(end 75.786742 -133.392672)
		(width 0.3048)
		(layer "F.Cu")
		(net "P3V3_STBY")
	)
	(segment
		(start 256.159 -135.4836)
		(end 256.159 -135.08736)
		(width 0.3556)
		(layer "F.Cu")
		(net "P3V3_STBY")
	)
	(segment
		(start 224.79 -103.759)
		(end 224.79 -104.902)
		(width 0.508)
		(layer "F.Cu")
		(net "P3V3_STBY")
	)
	(segment
		(start 223.774 -180.34)
		(end 223.719136 -180.285136)
		(width 0.508)
		(layer "F.Cu")
		(net "P3V3_STBY")
	)
	(segment
		(start 293.634922 -171.440094)
		(end 293.634922 -171.433744)
		(width 0.3556)
		(layer "F.Cu")
		(net "P3V3_STBY")
	)
	(segment
		(start 252.64364 -135.08736)
		(end 252.64364 -133.7056)
		(width 0.3556)
		(layer "F.Cu")
		(net "P3V3_STBY")
	)
	(segment
		(start 307.975 -193.3575)
		(end 308.229 -193.1035)
		(width 0.508)
		(layer "F.Cu")
		(net "P3V3_STBY")
	)
	(segment
		(start 140.45057 -81.6864)
		(end 140.60297 -81.534)
		(width 0.508)
		(layer "F.Cu")
		(net "P3V3_STBY")
	)
	(segment
		(start 297.129454 -173.279054)
		(end 297.1292 -173.2788)
		(width 0.3048)
		(layer "F.Cu")
		(net "P3V3_STBY")
	)
	(segment
		(start 80.513428 -139.327382)
		(end 81.539842 -139.327382)
		(width 0.508)
		(layer "F.Cu")
		(net "P3V3_STBY")
	)
	(segment
		(start 320.7385 -198.882)
		(end 321.945 -198.882)
		(width 0.508)
		(layer "F.Cu")
		(net "P3V3_STBY")
	)
	(segment
		(start 18.746216 -193.22288)
		(end 18.746216 -194.68338)
		(width 0.381)
		(layer "F.Cu")
		(net "P3V3_STBY")
	)
	(segment
		(start 199.136 -227.838)
		(end 199.39 -227.584)
		(width 0.508)
		(layer "F.Cu")
		(net "P3V3_STBY")
	)
	(segment
		(start 331.5208 -147.1676)
		(end 331.5208 -146.103848)
		(width 0.508)
		(layer "F.Cu")
		(net "P3V3_STBY")
	)
	(segment
		(start 273.7485 -177.673)
		(end 272.796 -177.673)
		(width 0.508)
		(layer "F.Cu")
		(net "P3V3_STBY")
	)
	(segment
		(start 347.946218 -150.853648)
		(end 346.866718 -150.853648)
		(width 0.508)
		(layer "F.Cu")
		(net "P3V3_STBY")
	)
	(segment
		(start 304.038 -216.3445)
		(end 304.038 -215.519)
		(width 0.508)
		(layer "F.Cu")
		(net "P3V3_STBY")
	)
	(segment
		(start 106.6546 -71.9328)
		(end 106.5784 -71.8566)
		(width 0.508)
		(layer "F.Cu")
		(net "P3V3_STBY")
	)
	(segment
		(start 345.342718 -155.679648)
		(end 345.342718 -156.011118)
		(width 0.508)
		(layer "F.Cu")
		(net "P3V3_STBY")
	)
	(segment
		(start 305.77282 -144.82318)
		(end 306.13096 -144.46504)
		(width 0.508)
		(layer "F.Cu")
		(net "P3V3_STBY")
	)
	(segment
		(start 94.564454 -233.3625)
		(end 94.5642 -233.362246)
		(width 0.508)
		(layer "F.Cu")
		(net "P3V3_STBY")
	)
	(segment
		(start 309.118 -160.2105)
		(end 309.6895 -160.2105)
		(width 0.508)
		(layer "F.Cu")
		(net "P3V3_STBY")
	)
	(segment
		(start 223.72828 -88.42502)
		(end 225.13036 -88.42502)
		(width 0.508)
		(layer "F.Cu")
		(net "P3V3_STBY")
	)
	(segment
		(start 282.7655 -209.3595)
		(end 282.7655 -207.518)
		(width 0.508)
		(layer "F.Cu")
		(net "P3V3_STBY")
	)
	(segment
		(start 34.3535 -169.291)
		(end 34.036 -169.6085)
		(width 0.508)
		(layer "F.Cu")
		(net "P3V3_STBY")
	)
	(segment
		(start 338.357718 -158.422848)
		(end 337.646518 -159.134048)
		(width 0.508)
		(layer "F.Cu")
		(net "P3V3_STBY")
	)
	(segment
		(start 220.091 -111.76)
		(end 221.107 -112.776)
		(width 0.508)
		(layer "F.Cu")
		(net "P3V3_STBY")
	)
	(segment
		(start 95.377 -233.3625)
		(end 94.564454 -233.3625)
		(width 0.508)
		(layer "F.Cu")
		(net "P3V3_STBY")
	)
	(segment
		(start 307.07076 -222.13824)
		(end 307.07076 -220.6625)
		(width 0.508)
		(layer "F.Cu")
		(net "P3V3_STBY")
	)
	(segment
		(start 342.040718 -157.394148)
		(end 342.040718 -156.822648)
		(width 0.508)
		(layer "F.Cu")
		(net "P3V3_STBY")
	)
	(segment
		(start 331.5208 -146.103848)
		(end 331.978 -145.646648)
		(width 0.508)
		(layer "F.Cu")
		(net "P3V3_STBY")
	)
	(segment
		(start 265.6205 -178.054)
		(end 264.814304 -178.054)
		(width 0.3556)
		(layer "F.Cu")
		(net "P3V3_STBY")
	)
	(segment
		(start 278.384 -206.375)
		(end 278.257 -206.248)
		(width 0.508)
		(layer "F.Cu")
		(net "P3V3_STBY")
	)
	(segment
		(start 273.431 -169.545)
		(end 272.923 -169.037)
		(width 0.3556)
		(layer "F.Cu")
		(net "P3V3_STBY")
	)
	(segment
		(start 181.356 -221.2975)
		(end 182.118 -221.2975)
		(width 0.381)
		(layer "F.Cu")
		(net "P3V3_STBY")
	)
	(segment
		(start 312.1025 -191.262)
		(end 312.1025 -192.405)
		(width 0.508)
		(layer "F.Cu")
		(net "P3V3_STBY")
	)
	(segment
		(start 191.643 -17.145)
		(end 190.3222 -17.145)
		(width 0.508)
		(layer "F.Cu")
		(net "P3V3_STBY")
	)
	(segment
		(start 223.012 -102.743)
		(end 223.774 -102.743)
		(width 0.508)
		(layer "F.Cu")
		(net "P3V3_STBY")
	)
	(segment
		(start 217.43797 -68.6435)
		(end 217.43797 -66.675)
		(width 0.508)
		(layer "F.Cu")
		(net "P3V3_STBY")
	)
	(segment
		(start 141.49197 -83.1215)
		(end 140.47597 -83.1215)
		(width 0.508)
		(layer "F.Cu")
		(net "P3V3_STBY")
	)
	(segment
		(start 295.244266 -180.240178)
		(end 295.647872 -179.836572)
		(width 0.3556)
		(layer "F.Cu")
		(net "P3V3_STBY")
	)
	(segment
		(start 24.425148 -175.746156)
		(end 24.425148 -174.517812)
		(width 0.2032)
		(layer "F.Cu")
		(net "P3V3_STBY")
	)
	(segment
		(start 13.094716 -214.36838)
		(end 13.094716 -214.05088)
		(width 0.508)
		(layer "F.Cu")
		(net "P3V3_STBY")
	)
	(segment
		(start 182.118 -221.2975)
		(end 182.32374 -221.09176)
		(width 0.381)
		(layer "F.Cu")
		(net "P3V3_STBY")
	)
	(segment
		(start 302.768 -192.3415)
		(end 302.768 -193.294)
		(width 0.508)
		(layer "F.Cu")
		(net "P3V3_STBY")
	)
	(segment
		(start 194.7545 -215.7095)
		(end 185.7375 -215.7095)
		(width 0.508)
		(layer "F.Cu")
		(net "P3V3_STBY")
	)
	(segment
		(start 79.604616 -115.410742)
		(end 77.370432 -115.410742)
		(width 0.508)
		(layer "F.Cu")
		(net "P3V3_STBY")
	)
	(segment
		(start 222.377 -183.007)
		(end 222.377 -180.404008)
		(width 0.508)
		(layer "F.Cu")
		(net "P3V3_STBY")
	)
	(segment
		(start 344.021918 -159.159448)
		(end 343.793318 -159.388048)
		(width 0.508)
		(layer "F.Cu")
		(net "P3V3_STBY")
	)
	(segment
		(start 292.834822 -171.440094)
		(end 292.834822 -171.723812)
		(width 0.3556)
		(layer "F.Cu")
		(net "P3V3_STBY")
	)
	(segment
		(start 10.173716 -215.84412)
		(end 10.89152 -215.84412)
		(width 0.4064)
		(layer "F.Cu")
		(net "P3V3_STBY")
	)
	(segment
		(start 214.80526 -220.61424)
		(end 214.8205 -220.599)
		(width 0.381)
		(layer "F.Cu")
		(net "P3V3_STBY")
	)
	(segment
		(start 293.133272 -149.623272)
		(end 293.116 -149.606)
		(width 0.508)
		(layer "F.Cu")
		(net "P3V3_STBY")
	)
	(segment
		(start 182.236872 -197.734936)
		(end 181.639972 -197.138036)
		(width 0.508)
		(layer "F.Cu")
		(net "P3V3_STBY")
	)
	(segment
		(start 39.32809 -139.827)
		(end 39.27475 -139.77366)
		(width 0.508)
		(layer "F.Cu")
		(net "P3V3_STBY")
	)
	(segment
		(start 5.855716 -215.82888)
		(end 4.049776 -215.82888)
		(width 0.508)
		(layer "F.Cu")
		(net "P3V3_STBY")
	)
	(segment
		(start 273.66087 -175.55337)
		(end 272.894806 -175.55337)
		(width 0.508)
		(layer "F.Cu")
		(net "P3V3_STBY")
	)
	(segment
		(start 279.424384 -215.273636)
		(end 279.05202 -215.646)
		(width 0.508)
		(layer "F.Cu")
		(net "P3V3_STBY")
	)
	(segment
		(start 317.246 -194.31)
		(end 317.373 -194.437)
		(width 0.508)
		(layer "F.Cu")
		(net "P3V3_STBY")
	)
	(segment
		(start 273.7485 -178.689)
		(end 272.796 -178.689)
		(width 0.508)
		(layer "F.Cu")
		(net "P3V3_STBY")
	)
	(segment
		(start 103.0605 -223.647)
		(end 103.0605 -223.2025)
		(width 0.508)
		(layer "F.Cu")
		(net "P3V3_STBY")
	)
	(segment
		(start 185.43524 -118.001288)
		(end 186.925712 -118.001288)
		(width 0.3048)
		(layer "F.Cu")
		(net "P3V3_STBY")
	)
	(segment
		(start 311.023 -192.405)
		(end 312.1025 -192.405)
		(width 0.508)
		(layer "F.Cu")
		(net "P3V3_STBY")
	)
	(segment
		(start 65.707514 -110.408212)
		(end 66.270886 -110.408212)
		(width 0.635)
		(layer "F.Cu")
		(net "P3V3_STBY")
	)
	(segment
		(start 19.809968 -185.409586)
		(end 19.809968 -184.079896)
		(width 0.3556)
		(layer "F.Cu")
		(net "P3V3_STBY")
	)
	(segment
		(start 297.36796 -173.04004)
		(end 297.1292 -173.2788)
		(width 0.3048)
		(layer "F.Cu")
		(net "P3V3_STBY")
	)
	(segment
		(start 182.888128 -13.707364)
		(end 181.872636 -13.707364)
		(width 0.508)
		(layer "F.Cu")
		(net "P3V3_STBY")
	)
	(segment
		(start 341.032592 -155.814522)
		(end 341.032592 -155.552648)
		(width 0.508)
		(layer "F.Cu")
		(net "P3V3_STBY")
	)
	(segment
		(start 186.7662 -53.34)
		(end 186.309 -52.8828)
		(width 0.3048)
		(layer "F.Cu")
		(net "P3V3_STBY")
	)
	(segment
		(start 20.016216 -212.520784)
		(end 20.066 -212.471)
		(width 0.508)
		(layer "F.Cu")
		(net "P3V3_STBY")
	)
	(segment
		(start 346.612718 -157.394148)
		(end 346.612718 -157.09646)
		(width 0.508)
		(layer "F.Cu")
		(net "P3V3_STBY")
	)
	(segment
		(start 332.359 -143.383)
		(end 332.381352 -143.360648)
		(width 0.508)
		(layer "F.Cu")
		(net "P3V3_STBY")
	)
	(segment
		(start 203.6445 -218.567)
		(end 203.6445 -217.424)
		(width 0.508)
		(layer "F.Cu")
		(net "P3V3_STBY")
	)
	(segment
		(start 192.2145 -175.133)
		(end 195.834 -175.133)
		(width 0.508)
		(layer "F.Cu")
		(net "P3V3_STBY")
	)
	(segment
		(start 225.5393 -88.83396)
		(end 225.5393 -91.37142)
		(width 0.508)
		(layer "F.Cu")
		(net "P3V3_STBY")
	)
	(segment
		(start 312.1025 -192.405)
		(end 312.1025 -193.548)
		(width 0.508)
		(layer "F.Cu")
		(net "P3V3_STBY")
	)
	(segment
		(start 208.77276 -214.99576)
		(end 208.5975 -214.8205)
		(width 0.381)
		(layer "F.Cu")
		(net "P3V3_STBY")
	)
	(segment
		(start 297.98264 -99.08286)
		(end 300.39564 -99.08286)
		(width 0.3048)
		(layer "F.Cu")
		(net "P3V3_STBY")
	)
	(segment
		(start 32.639 -138.0617)
		(end 32.639 -135.282432)
		(width 0.635)
		(layer "F.Cu")
		(net "P3V3_STBY")
	)
	(segment
		(start 305.363372 -205.177136)
		(end 305.363372 -204.288136)
		(width 0.508)
		(layer "F.Cu")
		(net "P3V3_STBY")
	)
	(segment
		(start 224.79 -104.902)
		(end 224.79 -111.4298)
		(width 0.508)
		(layer "F.Cu")
		(net "P3V3_STBY")
	)
	(segment
		(start 236.494066 -113.03)
		(end 238.493554 -113.03)
		(width 0.508)
		(layer "F.Cu")
		(net "P3V3_STBY")
	)
	(segment
		(start 40.0431 -169.2656)
		(end 38.9128 -169.2656)
		(width 0.508)
		(layer "F.Cu")
		(net "P3V3_STBY")
	)
	(segment
		(start 185.347864 -25.535128)
		(end 184.475628 -25.535128)
		(width 0.508)
		(layer "F.Cu")
		(net "P3V3_STBY")
	)
	(segment
		(start 264.567924 -180.086)
		(end 264.51814 -180.036216)
		(width 0.3556)
		(layer "F.Cu")
		(net "P3V3_STBY")
	)
	(segment
		(start 180.2765 -146.431)
		(end 180.2765 -145.288)
		(width 0.508)
		(layer "F.Cu")
		(net "P3V3_STBY")
	)
	(segment
		(start 346.485718 -150.726648)
		(end 346.612718 -150.599648)
		(width 0.3048)
		(layer "F.Cu")
		(net "P3V3_STBY")
	)
	(segment
		(start 304.038 -215.519)
		(end 303.784 -215.265)
		(width 0.508)
		(layer "F.Cu")
		(net "P3V3_STBY")
	)
	(segment
		(start 312.166 -184.8485)
		(end 312.166 -184.531)
		(width 0.508)
		(layer "F.Cu")
		(net "P3V3_STBY")
	)
	(segment
		(start 81.539842 -139.327382)
		(end 82.555842 -139.327382)
		(width 0.508)
		(layer "F.Cu")
		(net "P3V3_STBY")
	)
	(segment
		(start 194.818 -122.239278)
		(end 194.945 -122.366278)
		(width 0.508)
		(layer "F.Cu")
		(net "P3V3_STBY")
	)
	(segment
		(start 15.585948 -176.784)
		(end 15.585948 -177.079148)
		(width 0.2032)
		(layer "F.Cu")
		(net "P3V3_STBY")
	)
	(segment
		(start 185.7375 -215.7095)
		(end 183.007 -218.44)
		(width 0.508)
		(layer "F.Cu")
		(net "P3V3_STBY")
	)
	(segment
		(start 17.349216 -197.54088)
		(end 17.349216 -195.76288)
		(width 0.508)
		(layer "F.Cu")
		(net "P3V3_STBY")
	)
	(segment
		(start 220.2307 -157.9118)
		(end 219.1893 -157.9118)
		(width 0.508)
		(layer "F.Cu")
		(net "P3V3_STBY")
	)
	(segment
		(start 325.893938 -168.543986)
		(end 325.442072 -168.09212)
		(width 0.508)
		(layer "F.Cu")
		(net "P3V3_STBY")
	)
	(segment
		(start 92.329 -222.22714)
		(end 92.3925 -222.22714)
		(width 0.508)
		(layer "F.Cu")
		(net "P3V3_STBY")
	)
	(segment
		(start 297.634914 -177.040032)
		(end 297.634914 -177.030634)
		(width 0.3048)
		(layer "F.Cu")
		(net "P3V3_STBY")
	)
	(segment
		(start 109.4105 -244.2845)
		(end 109.347 -244.348)
		(width 0.508)
		(layer "F.Cu")
		(net "P3V3_STBY")
	)
	(segment
		(start 21.683472 -224.639124)
		(end 21.683472 -222.325438)
		(width 0.3556)
		(layer "F.Cu")
		(net "P3V3_STBY")
	)
	(segment
		(start 19.508216 -181.47538)
		(end 19.508216 -180.39588)
		(width 0.508)
		(layer "F.Cu")
		(net "P3V3_STBY")
	)
	(segment
		(start 295.647872 -179.853082)
		(end 295.647872 -179.836572)
		(width 0.3556)
		(layer "F.Cu")
		(net "P3V3_STBY")
	)
	(segment
		(start 181.131972 -205.187296)
		(end 181.485032 -205.187296)
		(width 0.3048)
		(layer "F.Cu")
		(net "P3V3_STBY")
	)
	(segment
		(start 272.556224 -184.531)
		(end 272.542 -184.516776)
		(width 0.508)
		(layer "F.Cu")
		(net "P3V3_STBY")
	)
	(segment
		(start 4.049776 -215.82888)
		(end 3.942842 -215.843612)
		(width 0.508)
		(layer "F.Cu")
		(net "P3V3_STBY")
	)
	(segment
		(start 341.489284 -86.9442)
		(end 341.489284 -86.4362)
		(width 0.508)
		(layer "F.Cu")
		(net "P3V3_STBY")
	)
	(segment
		(start 273.7485 -185.547)
		(end 272.626836 -185.547)
		(width 0.508)
		(layer "F.Cu")
		(net "P3V3_STBY")
	)
	(segment
		(start 345.342718 -156.011118)
		(end 345.4908 -156.1592)
		(width 0.508)
		(layer "F.Cu")
		(net "P3V3_STBY")
	)
	(segment
		(start 333.366872 -232.926636)
		(end 333.366872 -233.544872)
		(width 0.508)
		(layer "F.Cu")
		(net "P3V3_STBY")
	)
	(segment
		(start 57.116726 -118.999)
		(end 65.707514 -110.408212)
		(width 0.635)
		(layer "F.Cu")
		(net "P3V3_STBY")
	)
	(segment
		(start 173.473872 -193.607436)
		(end 173.473872 -192.604136)
		(width 0.508)
		(layer "F.Cu")
		(net "P3V3_STBY")
	)
	(segment
		(start 305.363372 -203.525628)
		(end 306.102512 -202.786488)
		(width 0.4064)
		(layer "F.Cu")
		(net "P3V3_STBY")
	)
	(segment
		(start 233.27868 -114.07902)
		(end 235.445046 -114.07902)
		(width 0.508)
		(layer "F.Cu")
		(net "P3V3_STBY")
	)
	(segment
		(start 111.14024 -70.11924)
		(end 110.17631 -70.11924)
		(width 0.3048)
		(layer "F.Cu")
		(net "P3V3_STBY")
	)
	(segment
		(start 26.239216 -235.76788)
		(end 26.429716 -235.57738)
		(width 0.3048)
		(layer "F.Cu")
		(net "P3V3_STBY")
	)
	(segment
		(start 177.537872 -198.814436)
		(end 178.541172 -198.814436)
		(width 0.508)
		(layer "F.Cu")
		(net "P3V3_STBY")
	)
	(segment
		(start 31.230316 -202.87488)
		(end 32.843216 -202.87488)
		(width 0.3048)
		(layer "F.Cu")
		(net "P3V3_STBY")
	)
	(segment
		(start 32.424116 -75.680062)
		(end 32.424116 -74.537062)
		(width 0.508)
		(layer "F.Cu")
		(net "P3V3_STBY")
	)
	(segment
		(start 306.2605 -192.0875)
		(end 306.451 -192.278)
		(width 0.508)
		(layer "F.Cu")
		(net "P3V3_STBY")
	)
	(segment
		(start 288.036 -155.829)
		(end 288.925 -155.829)
		(width 0.381)
		(layer "F.Cu")
		(net "P3V3_STBY")
	)
	(segment
		(start 273.7485 -184.531)
		(end 272.556224 -184.531)
		(width 0.508)
		(layer "F.Cu")
		(net "P3V3_STBY")
	)
	(segment
		(start 279.781 -116.2685)
		(end 278.638 -116.2685)
		(width 0.508)
		(layer "F.Cu")
		(net "P3V3_STBY")
	)
	(segment
		(start 332.2955 -219.456)
		(end 332.006702 -219.744798)
		(width 0.3048)
		(layer "F.Cu")
		(net "P3V3_STBY")
	)
	(segment
		(start 92.81414 -221.8055)
		(end 93.345 -221.8055)
		(width 0.508)
		(layer "F.Cu")
		(net "P3V3_STBY")
	)
	(segment
		(start 295.97985 -171.440094)
		(end 296.034968 -171.440094)
		(width 0.3556)
		(layer "F.Cu")
		(net "P3V3_STBY")
	)
	(segment
		(start 313.964066 -195.199)
		(end 312.674 -195.199)
		(width 0.3048)
		(layer "F.Cu")
		(net "P3V3_STBY")
	)
	(segment
		(start 172.368464 -22.045676)
		(end 172.812964 -22.490176)
		(width 0.6096)
		(layer "F.Cu")
		(net "P3V3_STBY")
	)
	(segment
		(start 199.05345 -227.75545)
		(end 199.136 -227.838)
		(width 0.3048)
		(layer "F.Cu")
		(net "P3V3_STBY")
	)
	(segment
		(start 11.303 -216.2556)
		(end 11.303 -216.281)
		(width 0.4064)
		(layer "F.Cu")
		(net "P3V3_STBY")
	)
	(segment
		(start 66.270886 -109.265212)
		(end 66.270886 -110.408212)
		(width 0.508)
		(layer "F.Cu")
		(net "P3V3_STBY")
	)
	(segment
		(start 185.565796 -35.134804)
		(end 185.990992 -35.56)
		(width 0.3048)
		(layer "F.Cu")
		(net "P3V3_STBY")
	)
	(segment
		(start 339.800946 -146.942048)
		(end 339.728048 -146.942048)
		(width 0.3048)
		(layer "F.Cu")
		(net "P3V3_STBY")
	)
	(segment
		(start 288.83483 -173.049692)
		(end 288.439606 -173.444916)
		(width 0.3556)
		(layer "F.Cu")
		(net "P3V3_STBY")
	)
	(segment
		(start 252.603 -135.128)
		(end 252.64364 -135.08736)
		(width 0.3556)
		(layer "F.Cu")
		(net "P3V3_STBY")
	)
	(segment
		(start 178.3715 -219.329)
		(end 178.435 -219.2655)
		(width 0.508)
		(layer "F.Cu")
		(net "P3V3_STBY")
	)
	(segment
		(start 86.36 -224.663)
		(end 86.106 -224.917)
		(width 0.4572)
		(layer "F.Cu")
		(net "P3V3_STBY")
	)
	(segment
		(start 219.075 -110.8075)
		(end 220.0275 -111.76)
		(width 0.508)
		(layer "F.Cu")
		(net "P3V3_STBY")
	)
	(segment
		(start 179.451 -219.2655)
		(end 180.5305 -219.2655)
		(width 0.508)
		(layer "F.Cu")
		(net "P3V3_STBY")
	)
	(segment
		(start 199.340216 -171.019216)
		(end 198.119492 -171.019216)
		(width 0.508)
		(layer "F.Cu")
		(net "P3V3_STBY")
	)
	(segment
		(start 303.81448 -191.389)
		(end 303.76368 -191.4398)
		(width 0.508)
		(layer "F.Cu")
		(net "P3V3_STBY")
	)
	(segment
		(start 40.5892 -118.1862)
		(end 39.5097 -118.1862)
		(width 0.508)
		(layer "F.Cu")
		(net "P3V3_STBY")
	)
	(segment
		(start 198.119492 -171.019216)
		(end 198.0565 -170.956224)
		(width 0.508)
		(layer "F.Cu")
		(net "P3V3_STBY")
	)
	(segment
		(start 273.112484 -176.657)
		(end 272.923 -176.467516)
		(width 0.508)
		(layer "F.Cu")
		(net "P3V3_STBY")
	)
	(segment
		(start 220.345 -156.7815)
		(end 220.345 -157.7975)
		(width 0.508)
		(layer "F.Cu")
		(net "P3V3_STBY")
	)
	(segment
		(start 173.537372 -203.830936)
		(end 173.042072 -203.830936)
		(width 0.508)
		(layer "F.Cu")
		(net "P3V3_STBY")
	)
	(segment
		(start 107.45597 -75.5015)
		(end 107.21467 -75.5015)
		(width 0.508)
		(layer "F.Cu")
		(net "P3V3_STBY")
	)
	(segment
		(start 332.158848 -147.805648)
		(end 331.5208 -147.1676)
		(width 0.508)
		(layer "F.Cu")
		(net "P3V3_STBY")
	)
	(segment
		(start 297.644058 -176.240186)
		(end 298.03471 -176.630838)
		(width 0.3048)
		(layer "F.Cu")
		(net "P3V3_STBY")
	)
	(segment
		(start 193.2305 -116.6495)
		(end 192.659 -116.078)
		(width 0.508)
		(layer "F.Cu")
		(net "P3V3_STBY")
	)
	(segment
		(start 182.245 -224.155)
		(end 181.483 -224.917)
		(width 0.508)
		(layer "F.Cu")
		(net "P3V3_STBY")
	)
	(segment
		(start 79.444342 -133.269482)
		(end 77.742288 -133.269482)
		(width 0.508)
		(layer "F.Cu")
		(net "P3V3_STBY")
	)
	(segment
		(start 140.47597 -83.1215)
		(end 140.45057 -83.0961)
		(width 0.508)
		(layer "F.Cu")
		(net "P3V3_STBY")
	)
	(segment
		(start 251.6505 -136.3345)
		(end 252.603 -136.3345)
		(width 0.508)
		(layer "F.Cu")
		(net "P3V3_STBY")
	)
	(segment
		(start 320.3575 -169.545)
		(end 320.6242 -169.8117)
		(width 0.508)
		(layer "F.Cu")
		(net "P3V3_STBY")
	)
	(segment
		(start 181.639972 -196.170296)
		(end 181.639972 -197.138036)
		(width 0.3048)
		(layer "F.Cu")
		(net "P3V3_STBY")
	)
	(segment
		(start 271.804892 -193.378836)
		(end 271.804892 -194.183)
		(width 0.508)
		(layer "F.Cu")
		(net "P3V3_STBY")
	)
	(segment
		(start 10.110216 -236.52988)
		(end 10.427716 -236.84738)
		(width 0.508)
		(layer "F.Cu")
		(net "P3V3_STBY")
	)
	(segment
		(start 93.7006 -222.1611)
		(end 93.7006 -224.13468)
		(width 0.3556)
		(layer "F.Cu")
		(net "P3V3_STBY")
	)
	(segment
		(start 292.034976 -171.440094)
		(end 292.555422 -171.96054)
		(width 0.3556)
		(layer "F.Cu")
		(net "P3V3_STBY")
	)
	(segment
		(start 213.0425 -220.61424)
		(end 214.80526 -220.61424)
		(width 0.381)
		(layer "F.Cu")
		(net "P3V3_STBY")
	)
	(segment
		(start 12.205716 -215.82888)
		(end 12.205716 -215.25738)
		(width 0.508)
		(layer "F.Cu")
		(net "P3V3_STBY")
	)
	(segment
		(start 182.8165 -219.456)
		(end 182.8165 -218.6305)
		(width 0.508)
		(layer "F.Cu")
		(net "P3V3_STBY")
	)
	(segment
		(start 282.7655 -207.518)
		(end 282.725876 -207.478376)
		(width 0.381)
		(layer "F.Cu")
		(net "P3V3_STBY")
	)
	(segment
		(start 222.0595 -104.902)
		(end 224.79 -104.902)
		(width 0.508)
		(layer "F.Cu")
		(net "P3V3_STBY")
	)
	(segment
		(start 179.46624 -219.28074)
		(end 179.46624 -221.0435)
		(width 0.381)
		(layer "F.Cu")
		(net "P3V3_STBY")
	)
	(segment
		(start 299.466 -102.5525)
		(end 298.5135 -102.5525)
		(width 0.508)
		(layer "F.Cu")
		(net "P3V3_STBY")
	)
	(segment
		(start 288.439606 -173.444916)
		(end 288.83483 -173.84014)
		(width 0.3556)
		(layer "F.Cu")
		(net "P3V3_STBY")
	)
	(segment
		(start 337.557872 -171.839636)
		(end 337.557872 -172.639736)
		(width 0.508)
		(layer "F.Cu")
		(net "P3V3_STBY")
	)
	(segment
		(start 335.882996 -151.234648)
		(end 336.28584 -151.234648)
		(width 0.508)
		(layer "F.Cu")
		(net "P3V3_STBY")
	)
	(segment
		(start 341.489284 -86.4362)
		(end 343.152984 -84.7725)
		(width 0.508)
		(layer "F.Cu")
		(net "P3V3_STBY")
	)
	(segment
		(start 202.937872 -144.898872)
		(end 203.581 -145.542)
		(width 0.508)
		(layer "F.Cu")
		(net "P3V3_STBY")
	)
	(segment
		(start 273.092926 -179.705)
		(end 273.03603 -179.761896)
		(width 0.508)
		(layer "F.Cu")
		(net "P3V3_STBY")
	)
	(segment
		(start 203.708 -184.9755)
		(end 203.708 -183.896)
		(width 0.508)
		(layer "F.Cu")
		(net "P3V3_STBY")
	)
	(segment
		(start 286.0675 -156.0195)
		(end 286.131 -156.083)
		(width 0.508)
		(layer "F.Cu")
		(net "P3V3_STBY")
	)
	(segment
		(start 80.579722 -115.410742)
		(end 80.528414 -115.410742)
		(width 0.508)
		(layer "F.Cu")
		(net "P3V3_STBY")
	)
	(segment
		(start 343.532714 -153.869644)
		(end 344.453718 -154.790648)
		(width 0.3048)
		(layer "F.Cu")
		(net "P3V3_STBY")
	)
	(segment
		(start 170.699176 -29.200856)
		(end 170.433492 -29.46654)
		(width 0.6096)
		(layer "F.Cu")
		(net "P3V3_STBY")
	)
	(segment
		(start 178.435 -219.2655)
		(end 179.451 -219.2655)
		(width 0.508)
		(layer "F.Cu")
		(net "P3V3_STBY")
	)
	(segment
		(start 265.6205 -180.086)
		(end 264.567924 -180.086)
		(width 0.3556)
		(layer "F.Cu")
		(net "P3V3_STBY")
	)
	(segment
		(start 39.18966 -139.77366)
		(end 39.27475 -139.77366)
		(width 0.508)
		(layer "F.Cu")
		(net "P3V3_STBY")
	)
	(segment
		(start 21.667216 -224.65538)
		(end 21.683472 -224.639124)
		(width 0.3556)
		(layer "F.Cu")
		(net "P3V3_STBY")
	)
	(segment
		(start 20.016216 -213.35238)
		(end 20.016216 -212.520784)
		(width 0.508)
		(layer "F.Cu")
		(net "P3V3_STBY")
	)
	(segment
		(start 273.685 -189.324996)
		(end 276.348952 -189.324996)
		(width 0.508)
		(layer "F.Cu")
		(net "P3V3_STBY")
	)
	(segment
		(start 79.614776 -115.400582)
		(end 79.604616 -115.410742)
		(width 0.508)
		(layer "F.Cu")
		(net "P3V3_STBY")
	)
	(segment
		(start 339.964522 -147.178522)
		(end 339.964522 -147.105624)
		(width 0.3048)
		(layer "F.Cu")
		(net "P3V3_STBY")
	)
	(segment
		(start 295.234868 -180.240178)
		(end 295.244266 -180.240178)
		(width 0.3556)
		(layer "F.Cu")
		(net "P3V3_STBY")
	)
	(segment
		(start 320.9925 -139.7635)
		(end 320.929 -139.7)
		(width 0.508)
		(layer "F.Cu")
		(net "P3V3_STBY")
	)
	(segment
		(start 200.533 -224.7265)
		(end 199.39 -224.7265)
		(width 0.508)
		(layer "F.Cu")
		(net "P3V3_STBY")
	)
	(segment
		(start 340.233 -77.597)
		(end 340.0425 -77.7875)
		(width 0.508)
		(layer "F.Cu")
		(net "P3V3_STBY")
	)
	(segment
		(start 220.345 -157.7975)
		(end 220.2307 -157.9118)
		(width 0.508)
		(layer "F.Cu")
		(net "P3V3_STBY")
	)
	(segment
		(start 338.357718 -158.029148)
		(end 338.357718 -158.422848)
		(width 0.508)
		(layer "F.Cu")
		(net "P3V3_STBY")
	)
	(segment
		(start 273.7485 -176.657)
		(end 273.112484 -176.657)
		(width 0.508)
		(layer "F.Cu")
		(net "P3V3_STBY")
	)
	(segment
		(start 80.188308 -116.784882)
		(end 79.48295 -117.49024)
		(width 0.508)
		(layer "F.Cu")
		(net "P3V3_STBY")
	)
	(segment
		(start 223.719136 -180.285136)
		(end 222.495872 -180.285136)
		(width 0.508)
		(layer "F.Cu")
		(net "P3V3_STBY")
	)
	(segment
		(start 16.650716 -213.41588)
		(end 15.063216 -213.41588)
		(width 0.508)
		(layer "F.Cu")
		(net "P3V3_STBY")
	)
	(segment
		(start 344.021918 -158.283148)
		(end 344.021918 -159.159448)
		(width 0.508)
		(layer "F.Cu")
		(net "P3V3_STBY")
	)
	(segment
		(start 294.435276 -171.440094)
		(end 294.835072 -171.83989)
		(width 0.3556)
		(layer "F.Cu")
		(net "P3V3_STBY")
	)
	(segment
		(start 186.999372 -194.051936)
		(end 188.155072 -194.051936)
		(width 0.508)
		(layer "F.Cu")
		(net "P3V3_STBY")
	)
	(segment
		(start 273.7485 -179.705)
		(end 273.092926 -179.705)
		(width 0.508)
		(layer "F.Cu")
		(net "P3V3_STBY")
	)
	(segment
		(start 273.7485 -175.641)
		(end 273.66087 -175.55337)
		(width 0.508)
		(layer "F.Cu")
		(net "P3V3_STBY")
	)
	(segment
		(start 186.925712 -118.001288)
		(end 186.944 -117.983)
		(width 0.3048)
		(layer "F.Cu")
		(net "P3V3_STBY")
	)
	(segment
		(start 335.182718 -152.637236)
		(end 335.182718 -151.934926)
		(width 0.508)
		(layer "F.Cu")
		(net "P3V3_STBY")
	)
	(segment
		(start 331.161136 -209.096864)
		(end 331.161136 -208.542128)
		(width 0.635)
		(layer "F.Cu")
		(net "P3V3_STBY")
	)
	(segment
		(start 295.288462 -171.440094)
		(end 295.413176 -171.564808)
		(width 0.3556)
		(layer "F.Cu")
		(net "P3V3_STBY")
	)
	(segment
		(start 3.942588 -215.843866)
		(end 2.9972 -216.789)
		(width 0.508)
		(layer "F.Cu")
		(net "P3V3_STBY")
	)
	(segment
		(start 185.565796 -34.235136)
		(end 185.565796 -35.134804)
		(width 0.3048)
		(layer "F.Cu")
		(net "P3V3_STBY")
	)
	(segment
		(start 82.14233 -138.724894)
		(end 82.14233 -137.1854)
		(width 0.2032)
		(layer "F.Cu")
		(net "P3V3_STBY")
	)
	(segment
		(start 272.966434 -174.625)
		(end 272.904204 -174.56277)
		(width 0.508)
		(layer "F.Cu")
		(net "P3V3_STBY")
	)
	(segment
		(start 19.809968 -184.079896)
		(end 19.627088 -183.897016)
		(width 0.3556)
		(layer "F.Cu")
		(net "P3V3_STBY")
	)
	(segment
		(start 270.8275 -170.942)
		(end 270.0274 -170.942)
		(width 0.3556)
		(layer "F.Cu")
		(net "P3V3_STBY")
	)
	(segment
		(start 40.59047 -139.827)
		(end 39.32809 -139.827)
		(width 0.508)
		(layer "F.Cu")
		(net "P3V3_STBY")
	)
	(segment
		(start 22.048216 -204.90688)
		(end 21.540216 -205.41488)
		(width 0.508)
		(layer "F.Cu")
		(net "P3V3_STBY")
	)
	(segment
		(start 239.32261 -114.22761)
		(end 239.0648 -113.9698)
		(width 0.3048)
		(layer "F.Cu")
		(net "P3V3_STBY")
	)
	(segment
		(start 24.765 -236.474)
		(end 25.13838 -236.84738)
		(width 0.508)
		(layer "F.Cu")
		(net "P3V3_STBY")
	)
	(segment
		(start 10.110216 -235.89488)
		(end 10.110216 -236.52988)
		(width 0.635)
		(layer "F.Cu")
		(net "P3V3_STBY")
	)
	(segment
		(start 86.36 -226.822)
		(end 86.106 -227.076)
		(width 0.4572)
		(layer "F.Cu")
		(net "P3V3_STBY")
	)
	(segment
		(start 214.8205 -219.7735)
		(end 214.757 -219.71)
		(width 0.508)
		(layer "F.Cu")
		(net "P3V3_STBY")
	)
	(segment
		(start 265.6205 -179.07)
		(end 264.715244 -179.07)
		(width 0.3556)
		(layer "F.Cu")
		(net "P3V3_STBY")
	)
	(segment
		(start 183.896 -122.4915)
		(end 184.9755 -122.4915)
		(width 0.508)
		(layer "F.Cu")
		(net "P3V3_STBY")
	)
	(segment
		(start 288.83483 -177.040032)
		(end 288.83483 -177.030634)
		(width 0.3556)
		(layer "F.Cu")
		(net "P3V3_STBY")
	)
	(segment
		(start 81.539842 -139.327382)
		(end 82.14233 -138.724894)
		(width 0.2032)
		(layer "F.Cu")
		(net "P3V3_STBY")
	)
	(segment
		(start 303.53 -222.377)
		(end 303.784 -222.123)
		(width 0.508)
		(layer "F.Cu")
		(net "P3V3_STBY")
	)
	(segment
		(start 77.742288 -133.269482)
		(end 77.61097 -133.4008)
		(width 0.508)
		(layer "F.Cu")
		(net "P3V3_STBY")
	)
	(segment
		(start 308.491636 -110.227364)
		(end 308.491636 -109.863128)
		(width 0.508)
		(layer "F.Cu")
		(net "P3V3_STBY")
	)
	(segment
		(start 88.325452 -138.72845)
		(end 88.192102 -138.8618)
		(width 0.2032)
		(layer "F.Cu")
		(net "P3V3_STBY")
	)
	(segment
		(start 15.585948 -175.746156)
		(end 15.585948 -176.784)
		(width 0.2032)
		(layer "F.Cu")
		(net "P3V3_STBY")
	)
	(segment
		(start 165.789356 -110.880652)
		(end 164.020754 -110.880652)
		(width 0.508)
		(layer "F.Cu")
		(net "P3V3_STBY")
	)
	(segment
		(start 79.920592 -117.927882)
		(end 79.48295 -117.49024)
		(width 0.508)
		(layer "F.Cu")
		(net "P3V3_STBY")
	)
	(segment
		(start 224.409 -173.355)
		(end 224.409 -179.705)
		(width 0.508)
		(layer "F.Cu")
		(net "P3V3_STBY")
	)
	(segment
		(start 217.650314 -179.403248)
		(end 216.074752 -179.403248)
		(width 0.508)
		(layer "F.Cu")
		(net "P3V3_STBY")
	)
	(segment
		(start 292.555422 -171.96054)
		(end 292.63086 -171.96054)
		(width 0.3556)
		(layer "F.Cu")
		(net "P3V3_STBY")
	)
	(segment
		(start 256.159 -136.3345)
		(end 256.159 -135.4836)
		(width 0.508)
		(layer "F.Cu")
		(net "P3V3_STBY")
	)
	(segment
		(start 80.518254 -115.400582)
		(end 79.614776 -115.400582)
		(width 0.508)
		(layer "F.Cu")
		(net "P3V3_STBY")
	)
	(segment
		(start 12.205716 -215.25738)
		(end 13.094716 -214.36838)
		(width 0.508)
		(layer "F.Cu")
		(net "P3V3_STBY")
	)
	(segment
		(start 331.089 -142.113)
		(end 332.359 -143.383)
		(width 0.508)
		(layer "F.Cu")
		(net "P3V3_STBY")
	)
	(segment
		(start 22.619716 -204.90688)
		(end 22.048216 -204.90688)
		(width 0.508)
		(layer "F.Cu")
		(net "P3V3_STBY")
	)
	(segment
		(start 308.09438 -144.46504)
		(end 308.15788 -144.40154)
		(width 0.508)
		(layer "F.Cu")
		(net "P3V3_STBY")
	)
	(segment
		(start 201.4855 -219.6465)
		(end 200.16724 -219.6465)
		(width 0.381)
		(layer "F.Cu")
		(net "P3V3_STBY")
	)
	(segment
		(start 93.223588 -122.626882)
		(end 91.128342 -122.626882)
		(width 0.508)
		(layer "F.Cu")
		(net "P3V3_STBY")
	)
	(segment
		(start 196.977 -179.07)
		(end 197.993 -179.07)
		(width 0.508)
		(layer "F.Cu")
		(net "P3V3_STBY")
	)
	(segment
		(start 341.032592 -153.596848)
		(end 341.032592 -155.552648)
		(width 0.3048)
		(layer "F.Cu")
		(net "P3V3_STBY")
	)
	(segment
		(start 320.6242 -169.8117)
		(end 320.6242 -170.3578)
		(width 0.508)
		(layer "F.Cu")
		(net "P3V3_STBY")
	)
	(segment
		(start 179.2224 -146.2024)
		(end 179.451 -146.431)
		(width 0.508)
		(layer "F.Cu")
		(net "P3V3_STBY")
	)
	(segment
		(start 27.026616 -197.26148)
		(end 27.026616 -194.45478)
		(width 0.508)
		(layer "F.Cu")
		(net "P3V3_STBY")
	)
	(segment
		(start 295.413176 -171.564808)
		(end 295.855136 -171.564808)
		(width 0.3556)
		(layer "F.Cu")
		(net "P3V3_STBY")
	)
	(segment
		(start 238.493554 -113.03)
		(end 239.0648 -113.601246)
		(width 0.508)
		(layer "F.Cu")
		(net "P3V3_STBY")
	)
	(segment
		(start 218.58097 -68.6435)
		(end 218.58097 -66.675)
		(width 0.508)
		(layer "F.Cu")
		(net "P3V3_STBY")
	)
	(segment
		(start 333.366872 -233.544872)
		(end 333.883 -234.061)
		(width 0.508)
		(layer "F.Cu")
		(net "P3V3_STBY")
	)
	(segment
		(start 251.587 -136.271)
		(end 251.6505 -136.3345)
		(width 0.508)
		(layer "F.Cu")
		(net "P3V3_STBY")
	)
	(segment
		(start 41.048432 -126.873)
		(end 46.863 -126.873)
		(width 0.635)
		(layer "F.Cu")
		(net "P3V3_STBY")
	)
	(segment
		(start 261.039864 -231.449372)
		(end 261.039864 -232.355136)
		(width 0.508)
		(layer "F.Cu")
		(net "P3V3_STBY")
	)
	(segment
		(start 303.76876 -222.10776)
		(end 303.784 -222.123)
		(width 0.508)
		(layer "F.Cu")
		(net "P3V3_STBY")
	)
	(segment
		(start 24.025098 -174.481998)
		(end 24.207216 -174.29988)
		(width 0.2032)
		(layer "F.Cu")
		(net "P3V3_STBY")
	)
	(segment
		(start 245.080028 -94.36989)
		(end 245.077996 -94.367858)
		(width 0.508)
		(layer "F.Cu")
		(net "P3V3_STBY")
	)
	(segment
		(start 183.9595 -224.155)
		(end 182.245 -224.155)
		(width 0.508)
		(layer "F.Cu")
		(net "P3V3_STBY")
	)
	(segment
		(start 279.645872 -215.273636)
		(end 279.424384 -215.273636)
		(width 0.508)
		(layer "F.Cu")
		(net "P3V3_STBY")
	)
	(segment
		(start 279.781 -117.221)
		(end 279.781 -116.2685)
		(width 0.508)
		(layer "F.Cu")
		(net "P3V3_STBY")
	)
	(segment
		(start 181.356 -220.345)
		(end 181.356 -221.2975)
		(width 0.508)
		(layer "F.Cu")
		(net "P3V3_STBY")
	)
	(segment
		(start 219.075 -121.595642)
		(end 219.075 -123.444)
		(width 0.508)
		(layer "F.Cu")
		(net "P3V3_STBY")
	)
	(segment
		(start 185.855864 -38.616636)
		(end 185.855864 -39.751)
		(width 0.6096)
		(layer "F.Cu")
		(net "P3V3_STBY")
	)
	(segment
		(start 15.825216 -199.06488)
		(end 17.349216 -197.54088)
		(width 0.508)
		(layer "F.Cu")
		(net "P3V3_STBY")
	)
	(segment
		(start 305.363372 -205.177136)
		(end 305.363372 -206.065628)
		(width 0.508)
		(layer "F.Cu")
		(net "P3V3_STBY")
	)
	(segment
		(start 306.451 -193.2305)
		(end 306.451 -192.278)
		(width 0.508)
		(layer "F.Cu")
		(net "P3V3_STBY")
	)
	(segment
		(start 38.9128 -170.2943)
		(end 38.989 -170.3705)
		(width 0.508)
		(layer "F.Cu")
		(net "P3V3_STBY")
	)
	(segment
		(start 182.32374 -221.09176)
		(end 183.1975 -221.09176)
		(width 0.381)
		(layer "F.Cu")
		(net "P3V3_STBY")
	)
	(segment
		(start 40.64 -118.237)
		(end 40.5892 -118.1862)
		(width 0.508)
		(layer "F.Cu")
		(net "P3V3_STBY")
	)
	(segment
		(start 11.49858 -236.475016)
		(end 11.49858 -234.184952)
		(width 0.3556)
		(layer "F.Cu")
		(net "P3V3_STBY")
	)
	(segment
		(start 178.816 -225.6155)
		(end 178.816 -226.695)
		(width 0.508)
		(layer "F.Cu")
		(net "P3V3_STBY")
	)
	(segment
		(start 99.949 -221.0435)
		(end 99.314 -220.4085)
		(width 0.508)
		(layer "F.Cu")
		(net "P3V3_STBY")
	)
	(segment
		(start 106.54157 -74.8284)
		(end 106.54157 -74.422)
		(width 0.508)
		(layer "F.Cu")
		(net "P3V3_STBY")
	)
	(segment
		(start 15.185898 -175.746156)
		(end 15.185898 -176.602898)
		(width 0.2032)
		(layer "F.Cu")
		(net "P3V3_STBY")
	)
	(segment
		(start 345.786202 -156.454602)
		(end 345.4908 -156.1592)
		(width 0.508)
		(layer "F.Cu")
		(net "P3V3_STBY")
	)
	(segment
		(start 302.8315 -222.377)
		(end 303.53 -222.377)
		(width 0.508)
		(layer "F.Cu")
		(net "P3V3_STBY")
	)
	(segment
		(start 288.439606 -176.63541)
		(end 288.83483 -176.240186)
		(width 0.3556)
		(layer "F.Cu")
		(net "P3V3_STBY")
	)
	(segment
		(start 332.45298 -157.838648)
		(end 331.836522 -157.22219)
		(width 0.508)
		(layer "F.Cu")
		(net "P3V3_STBY")
	)
	(segment
		(start 15.063216 -213.41588)
		(end 14.428216 -214.05088)
		(width 0.508)
		(layer "F.Cu")
		(net "P3V3_STBY")
	)
	(segment
		(start 343.532714 -153.685748)
		(end 343.532714 -153.869644)
		(width 0.3048)
		(layer "F.Cu")
		(net "P3V3_STBY")
	)
	(segment
		(start 181.483 -224.917)
		(end 181.483 -226.314)
		(width 0.508)
		(layer "F.Cu")
		(net "P3V3_STBY")
	)
	(segment
		(start 193.802 -116.6495)
		(end 193.2305 -116.6495)
		(width 0.508)
		(layer "F.Cu")
		(net "P3V3_STBY")
	)
	(segment
		(start 306.2605 -191.262)
		(end 306.2605 -192.0875)
		(width 0.508)
		(layer "F.Cu")
		(net "P3V3_STBY")
	)
	(segment
		(start 203.6445 -217.424)
		(end 203.62926 -217.43924)
		(width 0.381)
		(layer "F.Cu")
		(net "P3V3_STBY")
	)
	(segment
		(start 204.5335 -216.154)
		(end 205.867 -216.154)
		(width 0.508)
		(layer "F.Cu")
		(net "P3V3_STBY")
	)
	(segment
		(start 264.814304 -178.054)
		(end 264.51814 -177.757836)
		(width 0.3556)
		(layer "F.Cu")
		(net "P3V3_STBY")
	)
	(segment
		(start 332.006702 -221.097856)
		(end 332.096872 -221.188026)
		(width 0.3048)
		(layer "F.Cu")
		(net "P3V3_STBY")
	)
	(segment
		(start 306.6415 -222.5675)
		(end 307.07076 -222.13824)
		(width 0.508)
		(layer "F.Cu")
		(net "P3V3_STBY")
	)
	(segment
		(start 296.672 -99.1235)
		(end 297.942 -99.1235)
		(width 0.508)
		(layer "F.Cu")
		(net "P3V3_STBY")
	)
	(segment
		(start 350.0628 -84.0232)
		(end 350.0628 -83.027774)
		(width 0.508)
		(layer "F.Cu")
		(net "P3V3_STBY")
	)
	(segment
		(start 171.365164 -20.828508)
		(end 171.365164 -22.045676)
		(width 0.6096)
		(layer "F.Cu")
		(net "P3V3_STBY")
	)
	(segment
		(start 330.399136 -209.858864)
		(end 331.161136 -209.096864)
		(width 0.635)
		(layer "F.Cu")
		(net "P3V3_STBY")
	)
	(segment
		(start 322.4276 -212.1154)
		(end 322.453 -212.09)
		(width 0.508)
		(layer "F.Cu")
		(net "P3V3_STBY")
	)
	(segment
		(start 318.4525 -172.72)
		(end 319.5193 -172.72)
		(width 0.508)
		(layer "F.Cu")
		(net "P3V3_STBY")
	)
	(segment
		(start 25.858216 -236.84738)
		(end 25.858216 -236.14888)
		(width 0.508)
		(layer "F.Cu")
		(net "P3V3_STBY")
	)
	(segment
		(start 297.634914 -173.84014)
		(end 297.129454 -173.33468)
		(width 0.3048)
		(layer "F.Cu")
		(net "P3V3_STBY")
	)
	(segment
		(start 302.768 -193.294)
		(end 302.777652 -193.303652)
		(width 0.508)
		(layer "F.Cu")
		(net "P3V3_STBY")
	)
	(segment
		(start 272.0467 -188.849)
		(end 272.288 -188.849)
		(width 0.508)
		(layer "F.Cu")
		(net "P3V3_STBY")
	)
	(segment
		(start 140.45057 -83.0961)
		(end 140.45057 -81.6864)
		(width 0.508)
		(layer "F.Cu")
		(net "P3V3_STBY")
	)
	(segment
		(start 345.97086 -156.454602)
		(end 345.786202 -156.454602)
		(width 0.508)
		(layer "F.Cu")
		(net "P3V3_STBY")
	)
	(segment
		(start 297.129454 -173.33468)
		(end 297.129454 -173.279054)
		(width 0.3048)
		(layer "F.Cu")
		(net "P3V3_STBY")
	)
	(segment
		(start 292.63086 -171.927774)
		(end 292.63086 -171.96054)
		(width 0.3556)
		(layer "F.Cu")
		(net "P3V3_STBY")
	)
	(segment
		(start 305.77282 -146.51736)
		(end 305.77282 -144.82318)
		(width 0.508)
		(layer "F.Cu")
		(net "P3V3_STBY")
	)
	(segment
		(start 40.0685 -168.2115)
		(end 40.0685 -169.291)
		(width 0.508)
		(layer "F.Cu")
		(net "P3V3_STBY")
	)
	(segment
		(start 221.615 -161.671)
		(end 221.488 -161.544)
		(width 0.508)
		(layer "F.Cu")
		(net "P3V3_STBY")
	)
	(segment
		(start 38.7985 -214.376)
		(end 38.7985 -213.4235)
		(width 0.508)
		(layer "F.Cu")
		(net "P3V3_STBY")
	)
	(segment
		(start 221.107 -112.776)
		(end 219.9005 -113.9825)
		(width 0.508)
		(layer "F.Cu")
		(net "P3V3_STBY")
	)
	(segment
		(start 257.556 -124.841)
		(end 257.556 -123.698)
		(width 0.508)
		(layer "F.Cu")
		(net "P3V3_STBY")
	)
	(segment
		(start 87.3125 -223.139)
		(end 86.106 -223.139)
		(width 0.4572)
		(layer "F.Cu")
		(net "P3V3_STBY")
	)
	(segment
		(start 278.765 -202.565)
		(end 278.765 -201.3585)
		(width 0.508)
		(layer "F.Cu")
		(net "P3V3_STBY")
	)
	(segment
		(start 188.087 -20.1295)
		(end 188.087 -19.05)
		(width 0.508)
		(layer "F.Cu")
		(net "P3V3_STBY")
	)
	(segment
		(start 336.3595 -77.851)
		(end 333.977488 -77.851)
		(width 0.508)
		(layer "F.Cu")
		(net "P3V3_STBY")
	)
	(segment
		(start 194.818 -120.7135)
		(end 194.818 -122.239278)
		(width 0.508)
		(layer "F.Cu")
		(net "P3V3_STBY")
	)
	(segment
		(start 339.964522 -147.105624)
		(end 339.800946 -146.942048)
		(width 0.3048)
		(layer "F.Cu")
		(net "P3V3_STBY")
	)
	(segment
		(start 333.883 -10.9855)
		(end 332.867 -10.9855)
		(width 0.508)
		(layer "F.Cu")
		(net "P3V3_STBY")
	)
	(segment
		(start 332.2955 -217.17)
		(end 332.2955 -218.059)
		(width 0.508)
		(layer "F.Cu")
		(net "P3V3_STBY")
	)
	(segment
		(start 221.869 -171.7675)
		(end 222.8215 -171.7675)
		(width 0.508)
		(layer "F.Cu")
		(net "P3V3_STBY")
	)
	(segment
		(start 273.617182 -167.960548)
		(end 273.423634 -167.767)
		(width 0.3048)
		(layer "F.Cu")
		(net "P3V3_STBY")
	)
	(segment
		(start 350.033336 -82.99831)
		(end 350.033336 -81.435194)
		(width 0.508)
		(layer "F.Cu")
		(net "P3V3_STBY")
	)
	(segment
		(start 40.64 -118.237)
		(end 40.64 -118.364)
		(width 0.3048)
		(layer "F.Cu")
		(net "P3V3_STBY")
	)
	(segment
		(start 343.933018 -147.767548)
		(end 344.631518 -147.069048)
		(width 0.3048)
		(layer "F.Cu")
		(net "P3V3_STBY")
	)
	(segment
		(start 19.159728 -192.746376)
		(end 19.159728 -191.020446)
		(width 0.3048)
		(layer "F.Cu")
		(net "P3V3_STBY")
	)
	(segment
		(start 219.049346 -120.746012)
		(end 219.049346 -121.569988)
		(width 0.508)
		(layer "F.Cu")
		(net "P3V3_STBY")
	)
	(via
		(at 272.639536 -183.485536)
		(size 0.5588)
		(drill 0.3048)
		(layers "F.Cu" "B.Cu")
		(net "P3V3_STBY")
	)
	(via
		(at 140.60297 -81.534)
		(size 0.5588)
		(drill 0.3048)
		(layers "F.Cu" "B.Cu")
		(net "P3V3_STBY")
	)
	(via
		(at 185.609992 -25.273)
		(size 0.7112)
		(drill 0.4064)
		(layers "F.Cu" "B.Cu")
		(net "P3V3_STBY")
	)
	(via
		(at 251.587 -136.271)
		(size 0.5588)
		(drill 0.3048)
		(layers "F.Cu" "B.Cu")
		(net "P3V3_STBY")
	)
	(via
		(at 182.934864 -20.863052)
		(size 0.5588)
		(drill 0.3048)
		(layers "F.Cu" "B.Cu")
		(net "P3V3_STBY")
	)
	(via
		(at 14.936216 -177.72888)
		(size 0.508)
		(drill 0.254)
		(layers "F.Cu" "B.Cu")
		(net "P3V3_STBY")
	)
	(via
		(at 11.303 -216.281)
		(size 0.5588)
		(drill 0.3048)
		(layers "F.Cu" "B.Cu")
		(net "P3V3_STBY")
	)
	(via
		(at 188.155072 -194.051936)
		(size 0.5588)
		(drill 0.3048)
		(layers "F.Cu" "B.Cu")
		(net "P3V3_STBY")
	)
	(via
		(at 337.185 -93.472)
		(size 0.7112)
		(drill 0.4064)
		(layers "F.Cu" "B.Cu")
		(net "P3V3_STBY")
	)
	(via
		(at 162.941 -114.173)
		(size 0.5588)
		(drill 0.3048)
		(layers "F.Cu" "B.Cu")
		(net "P3V3_STBY")
	)
	(via
		(at 303.784 -222.123)
		(size 0.5588)
		(drill 0.3048)
		(layers "F.Cu" "B.Cu")
		(net "P3V3_STBY")
	)
	(via
		(at 320.929 -139.7)
		(size 0.5588)
		(drill 0.3048)
		(layers "F.Cu" "B.Cu")
		(net "P3V3_STBY")
	)
	(via
		(at 278.257 -206.248)
		(size 0.5588)
		(drill 0.3048)
		(layers "F.Cu" "B.Cu")
		(net "P3V3_STBY")
	)
	(via
		(at 79.444342 -134.589012)
		(size 0.5588)
		(drill 0.3048)
		(layers "F.Cu" "B.Cu")
		(net "P3V3_STBY")
	)
	(via
		(at 221.107 -112.776)
		(size 0.5588)
		(drill 0.3048)
		(layers "F.Cu" "B.Cu")
		(net "P3V3_STBY")
	)
	(via
		(at 272.894806 -175.55337)
		(size 0.5588)
		(drill 0.3048)
		(layers "F.Cu" "B.Cu")
		(net "P3V3_STBY")
	)
	(via
		(at 264.51814 -177.757836)
		(size 0.508)
		(drill 0.254)
		(layers "F.Cu" "B.Cu")
		(net "P3V3_STBY")
	)
	(via
		(at 92.00134 -222.5548)
		(size 0.5588)
		(drill 0.3048)
		(layers "F.Cu" "B.Cu")
		(net "P3V3_STBY")
	)
	(via
		(at 272.904204 -174.56277)
		(size 0.5588)
		(drill 0.3048)
		(layers "F.Cu" "B.Cu")
		(net "P3V3_STBY")
	)
	(via
		(at 308.991 -180.37175)
		(size 0.7112)
		(drill 0.4064)
		(layers "F.Cu" "B.Cu")
		(net "P3V3_STBY")
	)
	(via
		(at 40.0685 -168.2115)
		(size 0.5588)
		(drill 0.3048)
		(layers "F.Cu" "B.Cu")
		(net "P3V3_STBY")
	)
	(via
		(at 256.921 -164.592)
		(size 0.7112)
		(drill 0.4064)
		(layers "F.Cu" "B.Cu")
		(net "P3V3_STBY")
	)
	(via
		(at 225.5393 -91.37142)
		(size 0.5588)
		(drill 0.3048)
		(layers "F.Cu" "B.Cu")
		(net "P3V3_STBY")
	)
	(via
		(at 329.311 -211.018628)
		(size 0.5588)
		(drill 0.3048)
		(layers "F.Cu" "B.Cu")
		(net "P3V3_STBY")
	)
	(via
		(at 181.639972 -197.138036)
		(size 0.5588)
		(drill 0.3048)
		(layers "F.Cu" "B.Cu")
		(net "P3V3_STBY")
	)
	(via
		(at 80.19415 -139.64666)
		(size 0.5588)
		(drill 0.3048)
		(layers "F.Cu" "B.Cu")
		(net "P3V3_STBY")
	)
	(via
		(at 336.423 -86.614)
		(size 0.7112)
		(drill 0.4064)
		(layers "F.Cu" "B.Cu")
		(net "P3V3_STBY")
	)
	(via
		(at 264.51814 -176.630076)
		(size 0.508)
		(drill 0.254)
		(layers "F.Cu" "B.Cu")
		(net "P3V3_STBY")
	)
	(via
		(at 337.312 -164.846)
		(size 0.5588)
		(drill 0.3048)
		(layers "F.Cu" "B.Cu")
		(net "P3V3_STBY")
	)
	(via
		(at 88.192102 -138.8618)
		(size 0.5588)
		(drill 0.3048)
		(layers "F.Cu" "B.Cu")
		(net "P3V3_STBY")
	)
	(via
		(at 321.945 -198.882)
		(size 0.5588)
		(drill 0.3048)
		(layers "F.Cu" "B.Cu")
		(net "P3V3_STBY")
	)
	(via
		(at 173.786038 -18.974562)
		(size 0.5588)
		(drill 0.3048)
		(layers "F.Cu" "B.Cu")
		(net "P3V3_STBY")
	)
	(via
		(at 76.04633 -114.08664)
		(size 0.5588)
		(drill 0.3048)
		(layers "F.Cu" "B.Cu")
		(net "P3V3_STBY")
	)
	(via
		(at 178.1556 -224.5106)
		(size 0.7112)
		(drill 0.3556)
		(layers "F.Cu" "B.Cu")
		(net "P3V3_STBY")
	)
	(via
		(at 255.913128 -229.226872)
		(size 0.5588)
		(drill 0.3048)
		(layers "F.Cu" "B.Cu")
		(net "P3V3_STBY")
	)
	(via
		(at 187.96 -27.821636)
		(size 0.7112)
		(drill 0.4064)
		(layers "F.Cu" "B.Cu")
		(net "P3V3_STBY")
	)
	(via
		(at 288.439606 -173.444916)
		(size 0.508)
		(drill 0.254)
		(layers "F.Cu" "B.Cu")
		(net "P3V3_STBY")
	)
	(via
		(at 308.253892 -177.587656)
		(size 0.5588)
		(drill 0.3048)
		(layers "F.Cu" "B.Cu")
		(net "P3V3_STBY")
	)
	(via
		(at 172.330872 -204.542136)
		(size 0.5588)
		(drill 0.3048)
		(layers "F.Cu" "B.Cu")
		(net "P3V3_STBY")
	)
	(via
		(at 339.170518 -146.154648)
		(size 0.5588)
		(drill 0.3048)
		(layers "F.Cu" "B.Cu")
		(net "P3V3_STBY")
	)
	(via
		(at 187.9346 -193.04)
		(size 0.7112)
		(drill 0.4064)
		(layers "F.Cu" "B.Cu")
		(net "P3V3_STBY")
	)
	(via
		(at 342.921336 -75.311)
		(size 0.5588)
		(drill 0.3048)
		(layers "F.Cu" "B.Cu")
		(net "P3V3_STBY")
	)
	(via
		(at 307.594 -215.265)
		(size 0.5588)
		(drill 0.3048)
		(layers "F.Cu" "B.Cu")
		(net "P3V3_STBY")
	)
	(via
		(at 178.264312 -32.9057)
		(size 0.7112)
		(drill 0.4064)
		(layers "F.Cu" "B.Cu")
		(net "P3V3_STBY")
	)
	(via
		(at 317.373 -194.437)
		(size 0.5588)
		(drill 0.3048)
		(layers "F.Cu" "B.Cu")
		(net "P3V3_STBY")
	)
	(via
		(at 33.02 -169.291)
		(size 0.5588)
		(drill 0.3048)
		(layers "F.Cu" "B.Cu")
		(net "P3V3_STBY")
	)
	(via
		(at 106.54157 -74.422)
		(size 0.5588)
		(drill 0.3048)
		(layers "F.Cu" "B.Cu")
		(net "P3V3_STBY")
	)
	(via
		(at 337.557872 -172.639736)
		(size 0.5588)
		(drill 0.3048)
		(layers "F.Cu" "B.Cu")
		(net "P3V3_STBY")
	)
	(via
		(at 306.451 -192.278)
		(size 0.5588)
		(drill 0.3048)
		(layers "F.Cu" "B.Cu")
		(net "P3V3_STBY")
	)
	(via
		(at 288.439606 -176.63541)
		(size 0.508)
		(drill 0.254)
		(layers "F.Cu" "B.Cu")
		(net "P3V3_STBY")
	)
	(via
		(at 14.936216 -180.39588)
		(size 0.5588)
		(drill 0.3048)
		(layers "F.Cu" "B.Cu")
		(net "P3V3_STBY")
	)
	(via
		(at 288.5694 -73.3806)
		(size 0.5588)
		(drill 0.3048)
		(layers "F.Cu" "B.Cu")
		(net "P3V3_STBY")
	)
	(via
		(at 270.016224 -173.114716)
		(size 0.508)
		(drill 0.254)
		(layers "F.Cu" "B.Cu")
		(net "P3V3_STBY")
	)
	(via
		(at 196.342 -235.458)
		(size 0.7112)
		(drill 0.4064)
		(layers "F.Cu" "B.Cu")
		(net "P3V3_STBY")
	)
	(via
		(at 310.769 -202.819)
		(size 0.5588)
		(drill 0.3048)
		(layers "F.Cu" "B.Cu")
		(net "P3V3_STBY")
	)
	(via
		(at 199.340216 -171.019216)
		(size 0.5588)
		(drill 0.3048)
		(layers "F.Cu" "B.Cu")
		(net "P3V3_STBY")
	)
	(via
		(at 340.233 -77.597)
		(size 0.5588)
		(drill 0.3048)
		(layers "F.Cu" "B.Cu")
		(net "P3V3_STBY")
	)
	(via
		(at 325.442072 -168.09212)
		(size 0.5588)
		(drill 0.3048)
		(layers "F.Cu" "B.Cu")
		(net "P3V3_STBY")
	)
	(via
		(at 312.166 -184.531)
		(size 0.5588)
		(drill 0.3048)
		(layers "F.Cu" "B.Cu")
		(net "P3V3_STBY")
	)
	(via
		(at 111.7092 -72.1614)
		(size 0.5588)
		(drill 0.3048)
		(layers "F.Cu" "B.Cu")
		(net "P3V3_STBY")
	)
	(via
		(at 236.347 -136.271)
		(size 0.7112)
		(drill 0.4064)
		(layers "F.Cu" "B.Cu")
		(net "P3V3_STBY")
	)
	(via
		(at 86.106 -223.139)
		(size 0.508)
		(drill 0.254)
		(layers "F.Cu" "B.Cu")
		(net "P3V3_STBY")
	)
	(via
		(at 332.994 -172.030136)
		(size 0.5588)
		(drill 0.3048)
		(layers "F.Cu" "B.Cu")
		(net "P3V3_STBY")
	)
	(via
		(at 339.852 -86.6394)
		(size 0.7112)
		(drill 0.4064)
		(layers "F.Cu" "B.Cu")
		(net "P3V3_STBY")
	)
	(via
		(at 286.639 -58.166)
		(size 0.7112)
		(drill 0.4064)
		(layers "F.Cu" "B.Cu")
		(net "P3V3_STBY")
	)
	(via
		(at 312.674 -195.199)
		(size 0.5588)
		(drill 0.3048)
		(layers "F.Cu" "B.Cu")
		(net "P3V3_STBY")
	)
	(via
		(at 163.2712 -110.131098)
		(size 0.5588)
		(drill 0.3048)
		(layers "F.Cu" "B.Cu")
		(net "P3V3_STBY")
	)
	(via
		(at 203.6445 -220.345)
		(size 0.5588)
		(drill 0.3048)
		(layers "F.Cu" "B.Cu")
		(net "P3V3_STBY")
	)
	(via
		(at 306.13096 -144.46504)
		(size 0.5588)
		(drill 0.3048)
		(layers "F.Cu" "B.Cu")
		(net "P3V3_STBY")
	)
	(via
		(at 215.011 -180.34)
		(size 0.5588)
		(drill 0.3048)
		(layers "F.Cu" "B.Cu")
		(net "P3V3_STBY")
	)
	(via
		(at 331.831442 -154.473656)
		(size 0.508)
		(drill 0.254)
		(layers "F.Cu" "B.Cu")
		(net "P3V3_STBY")
	)
	(via
		(at 195.834 -175.133)
		(size 0.5588)
		(drill 0.3048)
		(layers "F.Cu" "B.Cu")
		(net "P3V3_STBY")
	)
	(via
		(at 183.007 -218.44)
		(size 0.5588)
		(drill 0.3048)
		(layers "F.Cu" "B.Cu")
		(net "P3V3_STBY")
	)
	(via
		(at 333.756 -195.961)
		(size 0.7112)
		(drill 0.4064)
		(layers "F.Cu" "B.Cu")
		(net "P3V3_STBY")
	)
	(via
		(at 181.982364 -16.628364)
		(size 0.5588)
		(drill 0.3048)
		(layers "F.Cu" "B.Cu")
		(net "P3V3_STBY")
	)
	(via
		(at 306.959 -52.578)
		(size 0.7112)
		(drill 0.4064)
		(layers "F.Cu" "B.Cu")
		(net "P3V3_STBY")
	)
	(via
		(at 296.291 -56.388)
		(size 0.7112)
		(drill 0.4064)
		(layers "F.Cu" "B.Cu")
		(net "P3V3_STBY")
	)
	(via
		(at 282.321 -182.499)
		(size 0.5588)
		(drill 0.3048)
		(layers "F.Cu" "B.Cu")
		(net "P3V3_STBY")
	)
	(via
		(at 303.76368 -191.4398)
		(size 0.7112)
		(drill 0.4064)
		(layers "F.Cu" "B.Cu")
		(net "P3V3_STBY")
	)
	(via
		(at 272.796 -167.767)
		(size 0.508)
		(drill 0.254)
		(layers "F.Cu" "B.Cu")
		(net "P3V3_STBY")
	)
	(via
		(at 326.26046 -180.577744)
		(size 0.5588)
		(drill 0.3048)
		(layers "F.Cu" "B.Cu")
		(net "P3V3_STBY")
	)
	(via
		(at 332.359 -195.961)
		(size 0.7112)
		(drill 0.4064)
		(layers "F.Cu" "B.Cu")
		(net "P3V3_STBY")
	)
	(via
		(at 272.796 -173.482)
		(size 0.5588)
		(drill 0.3048)
		(layers "F.Cu" "B.Cu")
		(net "P3V3_STBY")
	)
	(via
		(at 338.709 -87.757)
		(size 0.7112)
		(drill 0.4064)
		(layers "F.Cu" "B.Cu")
		(net "P3V3_STBY")
	)
	(via
		(at 300.43501 -178.230784)
		(size 0.508)
		(drill 0.254)
		(layers "F.Cu" "B.Cu")
		(net "P3V3_STBY")
	)
	(via
		(at 300.430184 -179.835302)
		(size 0.508)
		(drill 0.254)
		(layers "F.Cu" "B.Cu")
		(net "P3V3_STBY")
	)
	(via
		(at 208.5975 -214.8205)
		(size 0.5588)
		(drill 0.3048)
		(layers "F.Cu" "B.Cu")
		(net "P3V3_STBY")
	)
	(via
		(at 203.708 -183.896)
		(size 0.5588)
		(drill 0.3048)
		(layers "F.Cu" "B.Cu")
		(net "P3V3_STBY")
	)
	(via
		(at 278.765 -202.565)
		(size 0.7112)
		(drill 0.4064)
		(layers "F.Cu" "B.Cu")
		(net "P3V3_STBY")
	)
	(via
		(at 341.032592 -155.552648)
		(size 0.5588)
		(drill 0.3048)
		(layers "F.Cu" "B.Cu")
		(net "P3V3_STBY")
	)
	(via
		(at 185.039 -122.555)
		(size 0.5588)
		(drill 0.3048)
		(layers "F.Cu" "B.Cu")
		(net "P3V3_STBY")
	)
	(via
		(at 298.069 -107.315)
		(size 0.5588)
		(drill 0.3048)
		(layers "F.Cu" "B.Cu")
		(net "P3V3_STBY")
	)
	(via
		(at 185.990992 -35.56)
		(size 0.7112)
		(drill 0.4064)
		(layers "F.Cu" "B.Cu")
		(net "P3V3_STBY")
	)
	(via
		(at 303.784 -215.265)
		(size 0.5588)
		(drill 0.3048)
		(layers "F.Cu" "B.Cu")
		(net "P3V3_STBY")
	)
	(via
		(at 233.27868 -114.07902)
		(size 0.5588)
		(drill 0.3048)
		(layers "F.Cu" "B.Cu")
		(net "P3V3_STBY")
	)
	(via
		(at 328.295 -102.108)
		(size 0.5588)
		(drill 0.3048)
		(layers "F.Cu" "B.Cu")
		(net "P3V3_STBY")
	)
	(via
		(at 344.297 -160.274)
		(size 0.7112)
		(drill 0.4064)
		(layers "F.Cu" "B.Cu")
		(net "P3V3_STBY")
	)
	(via
		(at 272.288 -188.849)
		(size 0.5588)
		(drill 0.3048)
		(layers "F.Cu" "B.Cu")
		(net "P3V3_STBY")
	)
	(via
		(at 279.781 -117.221)
		(size 0.7112)
		(drill 0.4064)
		(layers "F.Cu" "B.Cu")
		(net "P3V3_STBY")
	)
	(via
		(at 321.31 -164.465)
		(size 0.5588)
		(drill 0.3048)
		(layers "F.Cu" "B.Cu")
		(net "P3V3_STBY")
	)
	(via
		(at 245.11 -92.583)
		(size 0.5588)
		(drill 0.3048)
		(layers "F.Cu" "B.Cu")
		(net "P3V3_STBY")
	)
	(via
		(at 338.6074 -14.8844)
		(size 0.5588)
		(drill 0.3048)
		(layers "F.Cu" "B.Cu")
		(net "P3V3_STBY")
	)
	(via
		(at 321.31 -167.894)
		(size 0.5588)
		(drill 0.3048)
		(layers "F.Cu" "B.Cu")
		(net "P3V3_STBY")
	)
	(via
		(at 309.118 -114.935)
		(size 0.5588)
		(drill 0.3048)
		(layers "F.Cu" "B.Cu")
		(net "P3V3_STBY")
	)
	(via
		(at 86.106 -224.917)
		(size 0.508)
		(drill 0.254)
		(layers "F.Cu" "B.Cu")
		(net "P3V3_STBY")
	)
	(via
		(at 80.645 -25.654)
		(size 0.5588)
		(drill 0.3048)
		(layers "F.Cu" "B.Cu")
		(net "P3V3_STBY")
	)
	(via
		(at 89.916 -243.84)
		(size 0.5588)
		(drill 0.3048)
		(layers "F.Cu" "B.Cu")
		(net "P3V3_STBY")
	)
	(via
		(at 20.066 -212.471)
		(size 0.5588)
		(drill 0.3048)
		(layers "F.Cu" "B.Cu")
		(net "P3V3_STBY")
	)
	(via
		(at 218.58097 -66.675)
		(size 0.5588)
		(drill 0.3048)
		(layers "F.Cu" "B.Cu")
		(net "P3V3_STBY")
	)
	(via
		(at 208.534 -224.4598)
		(size 0.7112)
		(drill 0.3556)
		(layers "F.Cu" "B.Cu")
		(net "P3V3_STBY")
	)
	(via
		(at 186.377072 -203.386436)
		(size 0.5588)
		(drill 0.3048)
		(layers "F.Cu" "B.Cu")
		(net "P3V3_STBY")
	)
	(via
		(at 343.408 -21.717)
		(size 0.5588)
		(drill 0.3048)
		(layers "F.Cu" "B.Cu")
		(net "P3V3_STBY")
	)
	(via
		(at 94.107 -131.572)
		(size 0.508)
		(drill 0.254)
		(layers "F.Cu" "B.Cu")
		(net "P3V3_STBY")
	)
	(via
		(at 19.627088 -183.897016)
		(size 0.5588)
		(drill 0.3048)
		(layers "F.Cu" "B.Cu")
		(net "P3V3_STBY")
	)
	(via
		(at 192.659 -116.078)
		(size 0.5588)
		(drill 0.3048)
		(layers "F.Cu" "B.Cu")
		(net "P3V3_STBY")
	)
	(via
		(at 297.434 -56.388)
		(size 0.7112)
		(drill 0.4064)
		(layers "F.Cu" "B.Cu")
		(net "P3V3_STBY")
	)
	(via
		(at 217.43797 -66.675)
		(size 0.5588)
		(drill 0.3048)
		(layers "F.Cu" "B.Cu")
		(net "P3V3_STBY")
	)
	(via
		(at 305.816 -52.324)
		(size 0.7112)
		(drill 0.4064)
		(layers "F.Cu" "B.Cu")
		(net "P3V3_STBY")
	)
	(via
		(at 302.26 -177.673)
		(size 0.508)
		(drill 0.254)
		(layers "F.Cu" "B.Cu")
		(net "P3V3_STBY")
	)
	(via
		(at 319.786 -172.4533)
		(size 0.5588)
		(drill 0.3048)
		(layers "F.Cu" "B.Cu")
		(net "P3V3_STBY")
	)
	(via
		(at 288.036 -58.166)
		(size 0.7112)
		(drill 0.4064)
		(layers "F.Cu" "B.Cu")
		(net "P3V3_STBY")
	)
	(via
		(at 312.050938 -197.727062)
		(size 0.5588)
		(drill 0.3048)
		(layers "F.Cu" "B.Cu")
		(net "P3V3_STBY")
	)
	(via
		(at 180.5305 -219.2655)
		(size 0.5588)
		(drill 0.3048)
		(layers "F.Cu" "B.Cu")
		(net "P3V3_STBY")
	)
	(via
		(at 264.51814 -178.872896)
		(size 0.5588)
		(drill 0.3048)
		(layers "F.Cu" "B.Cu")
		(net "P3V3_STBY")
	)
	(via
		(at 333.883 -234.061)
		(size 0.5588)
		(drill 0.3048)
		(layers "F.Cu" "B.Cu")
		(net "P3V3_STBY")
	)
	(via
		(at 20.651216 -224.65538)
		(size 0.5588)
		(drill 0.3048)
		(layers "F.Cu" "B.Cu")
		(net "P3V3_STBY")
	)
	(via
		(at 297.1292 -173.2788)
		(size 0.508)
		(drill 0.254)
		(layers "F.Cu" "B.Cu")
		(net "P3V3_STBY")
	)
	(via
		(at 186.944 -36.068)
		(size 0.7112)
		(drill 0.4064)
		(layers "F.Cu" "B.Cu")
		(net "P3V3_STBY")
	)
	(via
		(at 311.023 -192.405)
		(size 0.5588)
		(drill 0.3048)
		(layers "F.Cu" "B.Cu")
		(net "P3V3_STBY")
	)
	(via
		(at 338.709 -86.6394)
		(size 0.7112)
		(drill 0.4064)
		(layers "F.Cu" "B.Cu")
		(net "P3V3_STBY")
	)
	(via
		(at 344.805 -161.417)
		(size 0.7112)
		(drill 0.4064)
		(layers "F.Cu" "B.Cu")
		(net "P3V3_STBY")
	)
	(via
		(at 203.581 -145.542)
		(size 0.7112)
		(drill 0.4064)
		(layers "F.Cu" "B.Cu")
		(net "P3V3_STBY")
	)
	(via
		(at 218.059 -166.751)
		(size 0.7112)
		(drill 0.4064)
		(layers "F.Cu" "B.Cu")
		(net "P3V3_STBY")
	)
	(via
		(at 179.197 -146.2024)
		(size 0.5588)
		(drill 0.3048)
		(layers "F.Cu" "B.Cu")
		(net "P3V3_STBY")
	)
	(via
		(at 182.88 -215.646)
		(size 0.7112)
		(drill 0.4064)
		(layers "F.Cu" "B.Cu")
		(net "P3V3_STBY")
	)
	(via
		(at 320.6242 -170.3578)
		(size 0.5588)
		(drill 0.3048)
		(layers "F.Cu" "B.Cu")
		(net "P3V3_STBY")
	)
	(via
		(at 22.333712 -215.419178)
		(size 0.5588)
		(drill 0.3048)
		(layers "F.Cu" "B.Cu")
		(net "P3V3_STBY")
	)
	(via
		(at 94.5642 -233.362246)
		(size 0.5588)
		(drill 0.3048)
		(layers "F.Cu" "B.Cu")
		(net "P3V3_STBY")
	)
	(via
		(at 282.829 -209.423)
		(size 0.5588)
		(drill 0.3048)
		(layers "F.Cu" "B.Cu")
		(net "P3V3_STBY")
	)
	(via
		(at 331.836522 -157.22219)
		(size 0.508)
		(drill 0.254)
		(layers "F.Cu" "B.Cu")
		(net "P3V3_STBY")
	)
	(via
		(at 184.15 -48.006)
		(size 0.7112)
		(drill 0.4064)
		(layers "F.Cu" "B.Cu")
		(net "P3V3_STBY")
	)
	(via
		(at 273.685 -189.324996)
		(size 0.5588)
		(drill 0.3048)
		(layers "F.Cu" "B.Cu")
		(net "P3V3_STBY")
	)
	(via
		(at 182.236872 -205.939136)
		(size 0.5588)
		(drill 0.3048)
		(layers "F.Cu" "B.Cu")
		(net "P3V3_STBY")
	)
	(via
		(at 272.923 -176.467516)
		(size 0.5588)
		(drill 0.3048)
		(layers "F.Cu" "B.Cu")
		(net "P3V3_STBY")
	)
	(via
		(at 302.006 -107.061)
		(size 0.5588)
		(drill 0.3048)
		(layers "F.Cu" "B.Cu")
		(net "P3V3_STBY")
	)
	(via
		(at 339.852 -87.757)
		(size 0.7112)
		(drill 0.4064)
		(layers "F.Cu" "B.Cu")
		(net "P3V3_STBY")
	)
	(via
		(at 187.96 -172.974)
		(size 0.7112)
		(drill 0.4064)
		(layers "F.Cu" "B.Cu")
		(net "P3V3_STBY")
	)
	(via
		(at 345.4908 -156.1592)
		(size 0.5588)
		(drill 0.3048)
		(layers "F.Cu" "B.Cu")
		(net "P3V3_STBY")
	)
	(via
		(at 264.51814 -180.036216)
		(size 0.5588)
		(drill 0.3048)
		(layers "F.Cu" "B.Cu")
		(net "P3V3_STBY")
	)
	(via
		(at 186.944 -117.983)
		(size 0.5588)
		(drill 0.3048)
		(layers "F.Cu" "B.Cu")
		(net "P3V3_STBY")
	)
	(via
		(at 179.2224 -195.4022)
		(size 0.7112)
		(drill 0.3556)
		(layers "F.Cu" "B.Cu")
		(net "P3V3_STBY")
	)
	(via
		(at 223.012 -102.743)
		(size 0.5588)
		(drill 0.3048)
		(layers "F.Cu" "B.Cu")
		(net "P3V3_STBY")
	)
	(via
		(at 171.365164 -20.828508)
		(size 0.7112)
		(drill 0.4064)
		(layers "F.Cu" "B.Cu")
		(net "P3V3_STBY")
	)
	(via
		(at 296.672 -99.1235)
		(size 0.5588)
		(drill 0.3048)
		(layers "F.Cu" "B.Cu")
		(net "P3V3_STBY")
	)
	(via
		(at 331.47 -216.027)
		(size 0.5588)
		(drill 0.3048)
		(layers "F.Cu" "B.Cu")
		(net "P3V3_STBY")
	)
	(via
		(at 15.055088 -200.788016)
		(size 0.5588)
		(drill 0.3048)
		(layers "F.Cu" "B.Cu")
		(net "P3V3_STBY")
	)
	(via
		(at 98.425 -239.903)
		(size 0.7112)
		(drill 0.3556)
		(layers "F.Cu" "B.Cu")
		(net "P3V3_STBY")
	)
	(via
		(at 19.159728 -192.746376)
		(size 0.5588)
		(drill 0.3048)
		(layers "F.Cu" "B.Cu")
		(net "P3V3_STBY")
	)
	(via
		(at 337.185 -94.5896)
		(size 0.7112)
		(drill 0.4064)
		(layers "F.Cu" "B.Cu")
		(net "P3V3_STBY")
	)
	(via
		(at 211.72297 -66.548)
		(size 0.5588)
		(drill 0.3048)
		(layers "F.Cu" "B.Cu")
		(net "P3V3_STBY")
	)
	(via
		(at 2.032 -216.789)
		(size 0.5588)
		(drill 0.3048)
		(layers "F.Cu" "B.Cu")
		(net "P3V3_STBY")
	)
	(via
		(at 337.566 -87.757)
		(size 0.7112)
		(drill 0.4064)
		(layers "F.Cu" "B.Cu")
		(net "P3V3_STBY")
	)
	(via
		(at 244.729 -136.271)
		(size 0.7112)
		(drill 0.4064)
		(layers "F.Cu" "B.Cu")
		(net "P3V3_STBY")
	)
	(via
		(at 23.445216 -212.27288)
		(size 0.5588)
		(drill 0.3048)
		(layers "F.Cu" "B.Cu")
		(net "P3V3_STBY")
	)
	(via
		(at 346.9132 -77.8764)
		(size 0.7112)
		(drill 0.3556)
		(layers "F.Cu" "B.Cu")
		(net "P3V3_STBY")
	)
	(via
		(at 319.278 -8.382)
		(size 0.5588)
		(drill 0.3048)
		(layers "F.Cu" "B.Cu")
		(net "P3V3_STBY")
	)
	(via
		(at 272.9484 -179.761896)
		(size 0.5588)
		(drill 0.3048)
		(layers "F.Cu" "B.Cu")
		(net "P3V3_STBY")
	)
	(via
		(at 224.79 -111.4298)
		(size 0.5588)
		(drill 0.3048)
		(layers "F.Cu" "B.Cu")
		(net "P3V3_STBY")
	)
	(via
		(at 86.106 -227.076)
		(size 0.508)
		(drill 0.254)
		(layers "F.Cu" "B.Cu")
		(net "P3V3_STBY")
	)
	(via
		(at 256.921 -163.068)
		(size 0.7112)
		(drill 0.4064)
		(layers "F.Cu" "B.Cu")
		(net "P3V3_STBY")
	)
	(via
		(at 292.63086 -171.96054)
		(size 0.508)
		(drill 0.254)
		(layers "F.Cu" "B.Cu")
		(net "P3V3_STBY")
	)
	(via
		(at 32.512 -138.1887)
		(size 0.508)
		(drill 0.254)
		(layers "F.Cu" "B.Cu")
		(net "P3V3_STBY")
	)
	(via
		(at 345.44 -160.401)
		(size 0.7112)
		(drill 0.4064)
		(layers "F.Cu" "B.Cu")
		(net "P3V3_STBY")
	)
	(via
		(at 336.960718 -150.980648)
		(size 0.5588)
		(drill 0.3048)
		(layers "F.Cu" "B.Cu")
		(net "P3V3_STBY")
	)
	(via
		(at 298.03471 -176.630838)
		(size 0.508)
		(drill 0.254)
		(layers "F.Cu" "B.Cu")
		(net "P3V3_STBY")
	)
	(via
		(at 272.923 -169.037)
		(size 0.508)
		(drill 0.254)
		(layers "F.Cu" "B.Cu")
		(net "P3V3_STBY")
	)
	(via
		(at 189.738 -53.34)
		(size 0.5588)
		(drill 0.3048)
		(layers "F.Cu" "B.Cu")
		(net "P3V3_STBY")
	)
	(via
		(at 297.307 -117.094)
		(size 0.7112)
		(drill 0.4064)
		(layers "F.Cu" "B.Cu")
		(net "P3V3_STBY")
	)
	(via
		(at 272.542 -185.631836)
		(size 0.5588)
		(drill 0.3048)
		(layers "F.Cu" "B.Cu")
		(net "P3V3_STBY")
	)
	(via
		(at 340.835742 -87.597742)
		(size 0.5588)
		(drill 0.3048)
		(layers "F.Cu" "B.Cu")
		(net "P3V3_STBY")
	)
	(via
		(at 234.442 -13.081)
		(size 0.5588)
		(drill 0.3048)
		(layers "F.Cu" "B.Cu")
		(net "P3V3_STBY")
	)
	(via
		(at 219.71 -124.079)
		(size 0.508)
		(drill 0.254)
		(layers "F.Cu" "B.Cu")
		(net "P3V3_STBY")
	)
	(via
		(at 296.926 -101.092)
		(size 0.7112)
		(drill 0.4064)
		(layers "F.Cu" "B.Cu")
		(net "P3V3_STBY")
	)
	(via
		(at 87.757 -141.351)
		(size 0.5588)
		(drill 0.3048)
		(layers "F.Cu" "B.Cu")
		(net "P3V3_STBY")
	)
	(via
		(at 272.796 -171.958)
		(size 0.5588)
		(drill 0.3048)
		(layers "F.Cu" "B.Cu")
		(net "P3V3_STBY")
	)
	(via
		(at 178.816 -226.695)
		(size 0.5588)
		(drill 0.3048)
		(layers "F.Cu" "B.Cu")
		(net "P3V3_STBY")
	)
	(via
		(at 99.018852 -239.3442)
		(size 0.5588)
		(drill 0.3048)
		(layers "F.Cu" "B.Cu")
		(net "P3V3_STBY")
	)
	(via
		(at 185.855864 -39.751)
		(size 0.7112)
		(drill 0.4064)
		(layers "F.Cu" "B.Cu")
		(net "P3V3_STBY")
	)
	(via
		(at 219.075 -157.7975)
		(size 0.5588)
		(drill 0.3048)
		(layers "F.Cu" "B.Cu")
		(net "P3V3_STBY")
	)
	(via
		(at 269.9258 -170.8404)
		(size 0.508)
		(drill 0.254)
		(layers "F.Cu" "B.Cu")
		(net "P3V3_STBY")
	)
	(via
		(at 322.58 -201.676)
		(size 0.7112)
		(drill 0.3556)
		(layers "F.Cu" "B.Cu")
		(net "P3V3_STBY")
	)
	(via
		(at 307.07076 -222.13824)
		(size 0.5588)
		(drill 0.3048)
		(layers "F.Cu" "B.Cu")
		(net "P3V3_STBY")
	)
	(via
		(at 85.852 -239.268)
		(size 0.5588)
		(drill 0.3048)
		(layers "F.Cu" "B.Cu")
		(net "P3V3_STBY")
	)
	(via
		(at 264.7696 -173.863)
		(size 0.5588)
		(drill 0.3048)
		(layers "F.Cu" "B.Cu")
		(net "P3V3_STBY")
	)
	(via
		(at 182.753 -47.1424)
		(size 0.7112)
		(drill 0.4064)
		(layers "F.Cu" "B.Cu")
		(net "P3V3_STBY")
	)
	(via
		(at 321.31 -166.878)
		(size 0.5588)
		(drill 0.3048)
		(layers "F.Cu" "B.Cu")
		(net "P3V3_STBY")
	)
	(via
		(at 336.042 -93.472)
		(size 0.7112)
		(drill 0.4064)
		(layers "F.Cu" "B.Cu")
		(net "P3V3_STBY")
	)
	(via
		(at 338.328 -93.472)
		(size 0.7112)
		(drill 0.4064)
		(layers "F.Cu" "B.Cu")
		(net "P3V3_STBY")
	)
	(via
		(at 272.542 -184.516776)
		(size 0.5588)
		(drill 0.3048)
		(layers "F.Cu" "B.Cu")
		(net "P3V3_STBY")
	)
	(via
		(at 244.729 -123.952)
		(size 0.7112)
		(drill 0.4064)
		(layers "F.Cu" "B.Cu")
		(net "P3V3_STBY")
	)
	(via
		(at 191.643 -17.145)
		(size 0.5588)
		(drill 0.3048)
		(layers "F.Cu" "B.Cu")
		(net "P3V3_STBY")
	)
	(via
		(at 99.06 -240.411)
		(size 0.5588)
		(drill 0.3048)
		(layers "F.Cu" "B.Cu")
		(net "P3V3_STBY")
	)
	(via
		(at 287.64103 -181.44363)
		(size 0.508)
		(drill 0.254)
		(layers "F.Cu" "B.Cu")
		(net "P3V3_STBY")
	)
	(via
		(at 257.556 -123.698)
		(size 0.5588)
		(drill 0.3048)
		(layers "F.Cu" "B.Cu")
		(net "P3V3_STBY")
	)
	(via
		(at 343.793318 -159.388048)
		(size 0.5588)
		(drill 0.3048)
		(layers "F.Cu" "B.Cu")
		(net "P3V3_STBY")
	)
	(via
		(at 294.835072 -171.83989)
		(size 0.508)
		(drill 0.254)
		(layers "F.Cu" "B.Cu")
		(net "P3V3_STBY")
	)
	(via
		(at 181.356 -220.345)
		(size 0.5588)
		(drill 0.3048)
		(layers "F.Cu" "B.Cu")
		(net "P3V3_STBY")
	)
	(via
		(at 182.859172 -191.702436)
		(size 0.5588)
		(drill 0.3048)
		(layers "F.Cu" "B.Cu")
		(net "P3V3_STBY")
	)
	(via
		(at 99.314 -220.091)
		(size 0.5588)
		(drill 0.3048)
		(layers "F.Cu" "B.Cu")
		(net "P3V3_STBY")
	)
	(via
		(at 183.3626 -216.5985)
		(size 0.7112)
		(drill 0.4064)
		(layers "F.Cu" "B.Cu")
		(net "P3V3_STBY")
	)
	(via
		(at 180.2765 -148.6408)
		(size 0.5588)
		(drill 0.3048)
		(layers "F.Cu" "B.Cu")
		(net "P3V3_STBY")
	)
	(via
		(at 225.53676 -96.5708)
		(size 0.5588)
		(drill 0.3048)
		(layers "F.Cu" "B.Cu")
		(net "P3V3_STBY")
	)
	(via
		(at 188.087 -19.05)
		(size 0.5588)
		(drill 0.3048)
		(layers "F.Cu" "B.Cu")
		(net "P3V3_STBY")
	)
	(via
		(at 333.248 -164.029136)
		(size 0.5588)
		(drill 0.3048)
		(layers "F.Cu" "B.Cu")
		(net "P3V3_STBY")
	)
	(via
		(at 179.505864 -20.941792)
		(size 0.5588)
		(drill 0.3048)
		(layers "F.Cu" "B.Cu")
		(net "P3V3_STBY")
	)
	(via
		(at 336.042 -94.5896)
		(size 0.7112)
		(drill 0.4064)
		(layers "F.Cu" "B.Cu")
		(net "P3V3_STBY")
	)
	(via
		(at 188.087 -191.77)
		(size 0.7112)
		(drill 0.4064)
		(layers "F.Cu" "B.Cu")
		(net "P3V3_STBY")
	)
	(via
		(at 261.039864 -232.355136)
		(size 0.5588)
		(drill 0.3048)
		(layers "F.Cu" "B.Cu")
		(net "P3V3_STBY")
	)
	(via
		(at 102.743 -222.8342)
		(size 0.5588)
		(drill 0.3048)
		(layers "F.Cu" "B.Cu")
		(net "P3V3_STBY")
	)
	(via
		(at 287.6042 -73.3552)
		(size 0.5588)
		(drill 0.3048)
		(layers "F.Cu" "B.Cu")
		(net "P3V3_STBY")
	)
	(via
		(at 319.405 -161.417)
		(size 0.5588)
		(drill 0.3048)
		(layers "F.Cu" "B.Cu")
		(net "P3V3_STBY")
	)
	(via
		(at 302.777652 -193.416174)
		(size 0.5588)
		(drill 0.3048)
		(layers "F.Cu" "B.Cu")
		(net "P3V3_STBY")
	)
	(via
		(at 344.932 -159.004)
		(size 0.7112)
		(drill 0.4064)
		(layers "F.Cu" "B.Cu")
		(net "P3V3_STBY")
	)
	(via
		(at 214.757 -219.71)
		(size 0.5588)
		(drill 0.3048)
		(layers "F.Cu" "B.Cu")
		(net "P3V3_STBY")
	)
	(via
		(at 194.7545 -215.7095)
		(size 0.5588)
		(drill 0.3048)
		(layers "F.Cu" "B.Cu")
		(net "P3V3_STBY")
	)
	(via
		(at 346.612718 -150.599648)
		(size 0.5588)
		(drill 0.3048)
		(layers "F.Cu" "B.Cu")
		(net "P3V3_STBY")
	)
	(via
		(at 39.27475 -139.77366)
		(size 0.5588)
		(drill 0.3048)
		(layers "F.Cu" "B.Cu")
		(net "P3V3_STBY")
	)
	(via
		(at 305.816 -53.467)
		(size 0.7112)
		(drill 0.4064)
		(layers "F.Cu" "B.Cu")
		(net "P3V3_STBY")
	)
	(via
		(at 297.434 -100.076)
		(size 0.7112)
		(drill 0.4064)
		(layers "F.Cu" "B.Cu")
		(net "P3V3_STBY")
	)
	(via
		(at 209.677 -169.926)
		(size 0.7112)
		(drill 0.3556)
		(layers "F.Cu" "B.Cu")
		(net "P3V3_STBY")
	)
	(via
		(at 205.867 -216.154)
		(size 0.5588)
		(drill 0.3048)
		(layers "F.Cu" "B.Cu")
		(net "P3V3_STBY")
	)
	(via
		(at 331.978 -145.646648)
		(size 0.5588)
		(drill 0.3048)
		(layers "F.Cu" "B.Cu")
		(net "P3V3_STBY")
	)
	(via
		(at 322.453 -212.09)
		(size 0.5588)
		(drill 0.3048)
		(layers "F.Cu" "B.Cu")
		(net "P3V3_STBY")
	)
	(via
		(at 221.488 -161.544)
		(size 0.5588)
		(drill 0.3048)
		(layers "F.Cu" "B.Cu")
		(net "P3V3_STBY")
	)
	(via
		(at 293.116 -149.606)
		(size 0.5588)
		(drill 0.3048)
		(layers "F.Cu" "B.Cu")
		(net "P3V3_STBY")
	)
	(via
		(at 173.473872 -192.604136)
		(size 0.5588)
		(drill 0.3048)
		(layers "F.Cu" "B.Cu")
		(net "P3V3_STBY")
	)
	(via
		(at 268.405864 -57.023)
		(size 0.7112)
		(drill 0.4064)
		(layers "F.Cu" "B.Cu")
		(net "P3V3_STBY")
	)
	(via
		(at 199.39 -226.568)
		(size 0.5588)
		(drill 0.3048)
		(layers "F.Cu" "B.Cu")
		(net "P3V3_STBY")
	)
	(via
		(at 86.233 -243.84)
		(size 0.5588)
		(drill 0.3048)
		(layers "F.Cu" "B.Cu")
		(net "P3V3_STBY")
	)
	(via
		(at 171.893992 -13.208)
		(size 0.5588)
		(drill 0.3048)
		(layers "F.Cu" "B.Cu")
		(net "P3V3_STBY")
	)
	(via
		(at 337.566 -86.6394)
		(size 0.7112)
		(drill 0.4064)
		(layers "F.Cu" "B.Cu")
		(net "P3V3_STBY")
	)
	(via
		(at 109.347 -244.348)
		(size 0.5588)
		(drill 0.3048)
		(layers "F.Cu" "B.Cu")
		(net "P3V3_STBY")
	)
	(via
		(at 25.985216 -227.38588)
		(size 0.5588)
		(drill 0.3048)
		(layers "F.Cu" "B.Cu")
		(net "P3V3_STBY")
	)
	(via
		(at 196.723 -124.333)
		(size 0.5588)
		(drill 0.3048)
		(layers "F.Cu" "B.Cu")
		(net "P3V3_STBY")
	)
	(via
		(at 16.714216 -212.27288)
		(size 0.5588)
		(drill 0.3048)
		(layers "F.Cu" "B.Cu")
		(net "P3V3_STBY")
	)
	(via
		(at 271.804892 -194.183)
		(size 0.5588)
		(drill 0.3048)
		(layers "F.Cu" "B.Cu")
		(net "P3V3_STBY")
	)
	(via
		(at 298.704 -56.388)
		(size 0.7112)
		(drill 0.4064)
		(layers "F.Cu" "B.Cu")
		(net "P3V3_STBY")
	)
	(via
		(at 197.039992 -47.879)
		(size 0.5588)
		(drill 0.3048)
		(layers "F.Cu" "B.Cu")
		(net "P3V3_STBY")
	)
	(via
		(at 330.962 -195.961)
		(size 0.7112)
		(drill 0.4064)
		(layers "F.Cu" "B.Cu")
		(net "P3V3_STBY")
	)
	(via
		(at 272.669 -170.688)
		(size 0.5588)
		(drill 0.3048)
		(layers "F.Cu" "B.Cu")
		(net "P3V3_STBY")
	)
	(via
		(at 305.363372 -206.065628)
		(size 0.5588)
		(drill 0.3048)
		(layers "F.Cu" "B.Cu")
		(net "P3V3_STBY")
	)
	(via
		(at 332.232 -78.994)
		(size 0.5588)
		(drill 0.3048)
		(layers "F.Cu" "B.Cu")
		(net "P3V3_STBY")
	)
	(via
		(at 272.796 -178.689)
		(size 0.5588)
		(drill 0.3048)
		(layers "F.Cu" "B.Cu")
		(net "P3V3_STBY")
	)
	(via
		(at 317.2333 -195.453)
		(size 0.5588)
		(drill 0.3048)
		(layers "F.Cu" "B.Cu")
		(net "P3V3_STBY")
	)
	(via
		(at 194.945 -235.458)
		(size 0.7112)
		(drill 0.4064)
		(layers "F.Cu" "B.Cu")
		(net "P3V3_STBY")
	)
	(via
		(at 214.00897 -66.548)
		(size 0.5588)
		(drill 0.3048)
		(layers "F.Cu" "B.Cu")
		(net "P3V3_STBY")
	)
	(via
		(at 286.512 -73.279)
		(size 0.5588)
		(drill 0.3048)
		(layers "F.Cu" "B.Cu")
		(net "P3V3_STBY")
	)
	(via
		(at 293.23538 -171.034202)
		(size 0.508)
		(drill 0.254)
		(layers "F.Cu" "B.Cu")
		(net "P3V3_STBY")
	)
	(via
		(at 24.207216 -174.29988)
		(size 0.5588)
		(drill 0.3048)
		(layers "F.Cu" "B.Cu")
		(net "P3V3_STBY")
	)
	(via
		(at 272.869152 -181.745636)
		(size 0.5588)
		(drill 0.3048)
		(layers "F.Cu" "B.Cu")
		(net "P3V3_STBY")
	)
	(via
		(at 132.5118 -28.956)
		(size 0.5588)
		(drill 0.254)
		(layers "F.Cu" "B.Cu")
		(net "P3V3_STBY")
	)
	(via
		(at 295.647872 -179.832)
		(size 0.508)
		(drill 0.254)
		(layers "F.Cu" "B.Cu")
		(net "P3V3_STBY")
	)
	(via
		(at 40.64 -118.237)
		(size 0.5588)
		(drill 0.3048)
		(layers "F.Cu" "B.Cu")
		(net "P3V3_STBY")
	)
	(via
		(at 267.462 -57.912)
		(size 0.7112)
		(drill 0.4064)
		(layers "F.Cu" "B.Cu")
		(net "P3V3_STBY")
	)
	(via
		(at 308.229 -192.024)
		(size 0.5588)
		(drill 0.3048)
		(layers "F.Cu" "B.Cu")
		(net "P3V3_STBY")
	)
	(via
		(at 10.491216 -235.51388)
		(size 0.5588)
		(drill 0.3048)
		(layers "F.Cu" "B.Cu")
		(net "P3V3_STBY")
	)
	(via
		(at 330.835 -142.113)
		(size 0.5588)
		(drill 0.3048)
		(layers "F.Cu" "B.Cu")
		(net "P3V3_STBY")
	)
	(via
		(at 223.774 -180.34)
		(size 0.5588)
		(drill 0.3048)
		(layers "F.Cu" "B.Cu")
		(net "P3V3_STBY")
	)
	(via
		(at 188.6712 -44.0944)
		(size 0.7112)
		(drill 0.3556)
		(layers "F.Cu" "B.Cu")
		(net "P3V3_STBY")
	)
	(via
		(at 195.58 -173.101)
		(size 0.7112)
		(drill 0.4064)
		(layers "F.Cu" "B.Cu")
		(net "P3V3_STBY")
	)
	(via
		(at 143.14297 -84.582)
		(size 0.5588)
		(drill 0.3048)
		(layers "F.Cu" "B.Cu")
		(net "P3V3_STBY")
	)
	(via
		(at 332.105 -81.407)
		(size 0.5588)
		(drill 0.3048)
		(layers "F.Cu" "B.Cu")
		(net "P3V3_STBY")
	)
	(via
		(at 314.96 -53.200046)
		(size 0.5588)
		(drill 0.3048)
		(layers "F.Cu" "B.Cu")
		(net "P3V3_STBY")
	)
	(via
		(at 298.323 -102.616)
		(size 0.5588)
		(drill 0.3048)
		(layers "F.Cu" "B.Cu")
		(net "P3V3_STBY")
	)
	(via
		(at 32.843216 -202.87488)
		(size 0.5588)
		(drill 0.3048)
		(layers "F.Cu" "B.Cu")
		(net "P3V3_STBY")
	)
	(via
		(at 272.833592 -180.752496)
		(size 0.5588)
		(drill 0.3048)
		(layers "F.Cu" "B.Cu")
		(net "P3V3_STBY")
	)
	(via
		(at 264.51814 -175.436276)
		(size 0.508)
		(drill 0.254)
		(layers "F.Cu" "B.Cu")
		(net "P3V3_STBY")
	)
	(via
		(at 252.476 -163.4744)
		(size 0.7112)
		(drill 0.3556)
		(layers "F.Cu" "B.Cu")
		(net "P3V3_STBY")
	)
	(via
		(at 288.036 -155.829)
		(size 0.5588)
		(drill 0.3048)
		(layers "F.Cu" "B.Cu")
		(net "P3V3_STBY")
	)
	(via
		(at 181.872636 -13.707364)
		(size 0.5588)
		(drill 0.3048)
		(layers "F.Cu" "B.Cu")
		(net "P3V3_STBY")
	)
	(via
		(at 194.818 -214.63)
		(size 0.7112)
		(drill 0.4064)
		(layers "F.Cu" "B.Cu")
		(net "P3V3_STBY")
	)
	(via
		(at 295.021 -56.388)
		(size 0.7112)
		(drill 0.4064)
		(layers "F.Cu" "B.Cu")
		(net "P3V3_STBY")
	)
	(via
		(at 93.223588 -122.626882)
		(size 0.5588)
		(drill 0.3048)
		(layers "F.Cu" "B.Cu")
		(net "P3V3_STBY")
	)
	(via
		(at 19.508216 -180.39588)
		(size 0.5588)
		(drill 0.3048)
		(layers "F.Cu" "B.Cu")
		(net "P3V3_STBY")
	)
	(via
		(at 196.342 -234.061)
		(size 0.7112)
		(drill 0.4064)
		(layers "F.Cu" "B.Cu")
		(net "P3V3_STBY")
	)
	(via
		(at 331.931518 -150.472648)
		(size 0.5588)
		(drill 0.3048)
		(layers "F.Cu" "B.Cu")
		(net "P3V3_STBY")
	)
	(via
		(at 344.631518 -147.069048)
		(size 0.5588)
		(drill 0.3048)
		(layers "F.Cu" "B.Cu")
		(net "P3V3_STBY")
	)
	(via
		(at 338.328 -94.5896)
		(size 0.7112)
		(drill 0.4064)
		(layers "F.Cu" "B.Cu")
		(net "P3V3_STBY")
	)
	(via
		(at 268.478 -58.293)
		(size 0.7112)
		(drill 0.4064)
		(layers "F.Cu" "B.Cu")
		(net "P3V3_STBY")
	)
	(via
		(at 79.48295 -117.49024)
		(size 0.5588)
		(drill 0.3048)
		(layers "F.Cu" "B.Cu")
		(net "P3V3_STBY")
	)
	(via
		(at 32.424116 -74.537062)
		(size 0.5588)
		(drill 0.3048)
		(layers "F.Cu" "B.Cu")
		(net "P3V3_STBY")
	)
	(via
		(at 38.735 -213.36)
		(size 0.5588)
		(drill 0.3048)
		(layers "F.Cu" "B.Cu")
		(net "P3V3_STBY")
	)
	(via
		(at 276.606 -220.290136)
		(size 0.5588)
		(drill 0.3048)
		(layers "F.Cu" "B.Cu")
		(net "P3V3_STBY")
	)
	(via
		(at 195.58 -171.958)
		(size 0.7112)
		(drill 0.4064)
		(layers "F.Cu" "B.Cu")
		(net "P3V3_STBY")
	)
	(via
		(at 278.765 -215.646)
		(size 0.5588)
		(drill 0.3048)
		(layers "F.Cu" "B.Cu")
		(net "P3V3_STBY")
	)
	(via
		(at 286.131 -156.083)
		(size 0.508)
		(drill 0.254)
		(layers "F.Cu" "B.Cu")
		(net "P3V3_STBY")
	)
	(via
		(at 337.646518 -159.134048)
		(size 0.5588)
		(drill 0.3048)
		(layers "F.Cu" "B.Cu")
		(net "P3V3_STBY")
	)
	(via
		(at 305.816 -54.61)
		(size 0.7112)
		(drill 0.4064)
		(layers "F.Cu" "B.Cu")
		(net "P3V3_STBY")
	)
	(via
		(at 21.540216 -205.41488)
		(size 0.5588)
		(drill 0.3048)
		(layers "F.Cu" "B.Cu")
		(net "P3V3_STBY")
	)
	(via
		(at 350.393 -79.756)
		(size 0.5588)
		(drill 0.3048)
		(layers "F.Cu" "B.Cu")
		(net "P3V3_STBY")
	)
	(via
		(at 323.596 -222.25)
		(size 0.7112)
		(drill 0.3556)
		(layers "F.Cu" "B.Cu")
		(net "P3V3_STBY")
	)
	(via
		(at 24.3078 -235.2802)
		(size 0.5588)
		(drill 0.3048)
		(layers "F.Cu" "B.Cu")
		(net "P3V3_STBY")
	)
	(via
		(at 310.261 -160.782)
		(size 0.5588)
		(drill 0.3048)
		(layers "F.Cu" "B.Cu")
		(net "P3V3_STBY")
	)
	(via
		(at 312.050938 -196.226938)
		(size 0.5588)
		(drill 0.3048)
		(layers "F.Cu" "B.Cu")
		(net "P3V3_STBY")
	)
	(via
		(at 124.079 -29.0068)
		(size 0.5588)
		(drill 0.3048)
		(layers "F.Cu" "B.Cu")
		(net "P3V3_STBY")
	)
	(via
		(at 170.433492 -29.46654)
		(size 0.7112)
		(drill 0.4064)
		(layers "F.Cu" "B.Cu")
		(net "P3V3_STBY")
	)
	(via
		(at 178.541172 -198.814436)
		(size 0.5588)
		(drill 0.3048)
		(layers "F.Cu" "B.Cu")
		(net "P3V3_STBY")
	)
	(via
		(at 106.5784 -71.8566)
		(size 0.5588)
		(drill 0.3048)
		(layers "F.Cu" "B.Cu")
		(net "P3V3_STBY")
	)
	(via
		(at 196.342 -232.918)
		(size 0.7112)
		(drill 0.4064)
		(layers "F.Cu" "B.Cu")
		(net "P3V3_STBY")
	)
	(via
		(at 347.374718 -144.783048)
		(size 0.5588)
		(drill 0.3048)
		(layers "F.Cu" "B.Cu")
		(net "P3V3_STBY")
	)
	(via
		(at 331.724 -10.922)
		(size 0.5588)
		(drill 0.3048)
		(layers "F.Cu" "B.Cu")
		(net "P3V3_STBY")
	)
	(via
		(at 256.159 -135.4836)
		(size 0.5588)
		(drill 0.3048)
		(layers "F.Cu" "B.Cu")
		(net "P3V3_STBY")
	)
	(via
		(at 270.758412 -168.800272)
		(size 0.508)
		(drill 0.254)
		(layers "F.Cu" "B.Cu")
		(net "P3V3_STBY")
	)
	(via
		(at 307.975 -110.744)
		(size 0.5588)
		(drill 0.3048)
		(layers "F.Cu" "B.Cu")
		(net "P3V3_STBY")
	)
	(via
		(at 272.796 -177.673)
		(size 0.5588)
		(drill 0.3048)
		(layers "F.Cu" "B.Cu")
		(net "P3V3_STBY")
	)
	(via
		(at 197.993 -179.07)
		(size 0.5588)
		(drill 0.3048)
		(layers "F.Cu" "B.Cu")
		(net "P3V3_STBY")
	)
	(via
		(at 336.423 -87.7316)
		(size 0.7112)
		(drill 0.4064)
		(layers "F.Cu" "B.Cu")
		(net "P3V3_STBY")
	)
	(via
		(at 181.483 -226.314)
		(size 0.5588)
		(drill 0.3048)
		(layers "F.Cu" "B.Cu")
		(net "P3V3_STBY")
	)
	(via
		(at 180.648864 -20.930108)
		(size 0.5588)
		(drill 0.3048)
		(layers "F.Cu" "B.Cu")
		(net "P3V3_STBY")
	)
	(via
		(at 177.419 -33.655)
		(size 0.7112)
		(drill 0.4064)
		(layers "F.Cu" "B.Cu")
		(net "P3V3_STBY")
	)
	(segment
		(start 326.26046 -180.40096)
		(end 326.26046 -180.577744)
		(width 0.508)
		(layer "B.Cu")
		(net "P3V3_STBY")
	)
	(segment
		(start 92.456 -141.351)
		(end 94.10827 -139.69873)
		(width 1.016)
		(layer "B.Cu")
		(net "P3V3_STBY")
	)
	(segment
		(start 288.598864 -176.657)
		(end 288.577274 -176.63541)
		(width 0.381)
		(layer "B.Cu")
		(net "P3V3_STBY")
	)
	(segment
		(start 79.756 -24.765)
		(end 79.629 -24.765)
		(width 0.508)
		(layer "B.Cu")
		(net "P3V3_STBY")
	)
	(segment
		(start 88.46947 -138.584432)
		(end 88.46947 -137.795)
		(width 0.508)
		(layer "B.Cu")
		(net "P3V3_STBY")
	)
	(segment
		(start 320.3575 -169.6085)
		(end 320.6242 -169.8752)
		(width 0.508)
		(layer "B.Cu")
		(net "P3V3_STBY")
	)
	(segment
		(start 261.039864 -232.355136)
		(end 261.039864 -231.956864)
		(width 1.016)
		(layer "B.Cu")
		(net "P3V3_STBY")
	)
	(segment
		(start 295.647872 -179.125372)
		(end 295.647872 -179.832)
		(width 0.508)
		(layer "B.Cu")
		(net "P3V3_STBY")
	)
	(segment
		(start 351.663 -81.0895)
		(end 350.393 -81.0895)
		(width 0.508)
		(layer "B.Cu")
		(net "P3V3_STBY")
	)
	(segment
		(start 289.297872 -176.729136)
		(end 288.804858 -176.729136)
		(width 0.381)
		(layer "B.Cu")
		(net "P3V3_STBY")
	)
	(segment
		(start 15.388844 -175.260762)
		(end 15.388844 -176.149762)
		(width 0.508)
		(layer "B.Cu")
		(net "P3V3_STBY")
	)
	(segment
		(start 195.961 -124.333)
		(end 194.183 -122.555)
		(width 0.508)
		(layer "B.Cu")
		(net "P3V3_STBY")
	)
	(segment
		(start 88.46947 -137.795)
		(end 88.46947 -136.779)
		(width 0.508)
		(layer "B.Cu")
		(net "P3V3_STBY")
	)
	(segment
		(start 15.388844 -177.276252)
		(end 14.936216 -177.72888)
		(width 0.508)
		(layer "B.Cu")
		(net "P3V3_STBY")
	)
	(segment
		(start 306.13096 -144.46504)
		(end 304.54092 -142.875)
		(width 0.635)
		(layer "B.Cu")
		(net "P3V3_STBY")
	)
	(segment
		(start 297.235372 -176.602136)
		(end 298.006008 -176.602136)
		(width 0.6096)
		(layer "B.Cu")
		(net "P3V3_STBY")
	)
	(segment
		(start 113.124996 -71.374)
		(end 112.4966 -71.374)
		(width 0.508)
		(layer "B.Cu")
		(net "P3V3_STBY")
	)
	(segment
		(start 203.581 -145.542)
		(end 203.581 -136.652)
		(width 1.016)
		(layer "B.Cu")
		(net "P3V3_STBY")
	)
	(segment
		(start 79.48295 -134.550404)
		(end 79.444342 -134.589012)
		(width 0.635)
		(layer "B.Cu")
		(net "P3V3_STBY")
	)
	(segment
		(start 186.944 -117.983)
		(end 190.754 -117.983)
		(width 0.508)
		(layer "B.Cu")
		(net "P3V3_STBY")
	)
	(segment
		(start 138.44397 -75.88377)
		(end 135.5852 -73.025)
		(width 0.508)
		(layer "B.Cu")
		(net "P3V3_STBY")
	)
	(segment
		(start 143.046196 -88.9508)
		(end 143.44777 -88.549226)
		(width 0.508)
		(layer "B.Cu")
		(net "P3V3_STBY")
	)
	(segment
		(start 32.335216 -203.38288)
		(end 31.255716 -203.38288)
		(width 0.508)
		(layer "B.Cu")
		(net "P3V3_STBY")
	)
	(segment
		(start 185.039 -122.555)
		(end 185.039 -119.888)
		(width 0.508)
		(layer "B.Cu")
		(net "P3V3_STBY")
	)
	(segment
		(start 24.588216 -227.38588)
		(end 25.985216 -227.38588)
		(width 0.635)
		(layer "B.Cu")
		(net "P3V3_STBY")
	)
	(segment
		(start 20.651216 -224.65538)
		(end 20.714716 -224.71888)
		(width 0.635)
		(layer "B.Cu")
		(net "P3V3_STBY")
	)
	(segment
		(start 94.10827 -131.57073)
		(end 94.107 -131.572)
		(width 0.635)
		(layer "B.Cu")
		(net "P3V3_STBY")
	)
	(segment
		(start 24.3078 -235.2802)
		(end 24.524716 -235.063284)
		(width 0.635)
		(layer "B.Cu")
		(net "P3V3_STBY")
	)
	(segment
		(start 15.388844 -176.149762)
		(end 15.388844 -177.276252)
		(width 0.508)
		(layer "B.Cu")
		(net "P3V3_STBY")
	)
	(segment
		(start 18.928588 -192.515236)
		(end 19.159728 -192.746376)
		(width 0.508)
		(layer "B.Cu")
		(net "P3V3_STBY")
	)
	(segment
		(start 224.155 -102.743)
		(end 223.012 -102.743)
		(width 0.508)
		(layer "B.Cu")
		(net "P3V3_STBY")
	)
	(segment
		(start 24.096726 -176.33188)
		(end 24.151844 -176.276762)
		(width 0.508)
		(layer "B.Cu")
		(net "P3V3_STBY")
	)
	(segment
		(start 125.862588 -73.025)
		(end 125.227588 -73.66)
		(width 0.508)
		(layer "B.Cu")
		(net "P3V3_STBY")
	)
	(segment
		(start 32.843216 -202.87488)
		(end 32.335216 -203.38288)
		(width 0.508)
		(layer "B.Cu")
		(net "P3V3_STBY")
	)
	(segment
		(start 331.936598 -154.3685)
		(end 331.831442 -154.473656)
		(width 0.508)
		(layer "B.Cu")
		(net "P3V3_STBY")
	)
	(segment
		(start 94.10827 -131.57327)
		(end 94.107 -131.572)
		(width 1.016)
		(layer "B.Cu")
		(net "P3V3_STBY")
	)
	(segment
		(start 320.167 -161.9885)
		(end 319.9765 -161.9885)
		(width 0.508)
		(layer "B.Cu")
		(net "P3V3_STBY")
	)
	(segment
		(start 325.374 -180.1495)
		(end 326.009 -180.1495)
		(width 0.508)
		(layer "B.Cu")
		(net "P3V3_STBY")
	)
	(segment
		(start 290.0299 -173.9392)
		(end 289.885628 -173.794928)
		(width 0.508)
		(layer "B.Cu")
		(net "P3V3_STBY")
	)
	(segment
		(start 194.183 -122.555)
		(end 185.039 -122.555)
		(width 0.508)
		(layer "B.Cu")
		(net "P3V3_STBY")
	)
	(segment
		(start 139.45997 -79.883)
		(end 138.44397 -78.867)
		(width 0.508)
		(layer "B.Cu")
		(net "P3V3_STBY")
	)
	(segment
		(start 31.255716 -203.38288)
		(end 31.255716 -204.84338)
		(width 0.508)
		(layer "B.Cu")
		(net "P3V3_STBY")
	)
	(segment
		(start 292.354 -144.653)
		(end 292.354 -148.844)
		(width 0.635)
		(layer "B.Cu")
		(net "P3V3_STBY")
	)
	(segment
		(start 25.985216 -227.425758)
		(end 25.985216 -227.38588)
		(width 0.635)
		(layer "B.Cu")
		(net "P3V3_STBY")
	)
	(segment
		(start 79.444342 -134.589012)
		(end 79.444342 -138.896852)
		(width 0.508)
		(layer "B.Cu")
		(net "P3V3_STBY")
	)
	(segment
		(start 343.408 -21.717)
		(end 343.408 -17.653)
		(width 1.016)
		(layer "B.Cu")
		(net "P3V3_STBY")
	)
	(segment
		(start 112.4966 -71.374)
		(end 111.7092 -72.1614)
		(width 0.508)
		(layer "B.Cu")
		(net "P3V3_STBY")
	)
	(segment
		(start 14.936216 -180.39588)
		(end 14.936216 -177.72888)
		(width 0.508)
		(layer "B.Cu")
		(net "P3V3_STBY")
	)
	(segment
		(start 87.757 -141.351)
		(end 92.456 -141.351)
		(width 1.016)
		(layer "B.Cu")
		(net "P3V3_STBY")
	)
	(segment
		(start 140.27277 -88.9508)
		(end 143.046196 -88.9508)
		(width 0.508)
		(layer "B.Cu")
		(net "P3V3_STBY")
	)
	(segment
		(start 79.502 -24.638)
		(end 79.629 -24.765)
		(width 0.508)
		(layer "B.Cu")
		(net "P3V3_STBY")
	)
	(segment
		(start 225.53676 -96.5708)
		(end 225.538792 -96.572832)
		(width 0.508)
		(layer "B.Cu")
		(net "P3V3_STBY")
	)
	(segment
		(start 94.10827 -139.136882)
		(end 94.29877 -138.946382)
		(width 1.016)
		(layer "B.Cu")
		(net "P3V3_STBY")
	)
	(segment
		(start 110.16107 -71.8566)
		(end 106.5784 -71.8566)
		(width 0.508)
		(layer "B.Cu")
		(net "P3V3_STBY")
	)
	(segment
		(start 291.914072 -171.687236)
		(end 292.357556 -171.687236)
		(width 0.508)
		(layer "B.Cu")
		(net "P3V3_STBY")
	)
	(segment
		(start 303.1363 -177.42408)
		(end 302.88738 -177.673)
		(width 0.3556)
		(layer "B.Cu")
		(net "P3V3_STBY")
	)
	(segment
		(start 24.524716 -228.886258)
		(end 25.985216 -227.425758)
		(width 0.635)
		(layer "B.Cu")
		(net "P3V3_STBY")
	)
	(segment
		(start 293.23538 -171.050204)
		(end 293.23538 -171.034202)
		(width 0.3556)
		(layer "B.Cu")
		(net "P3V3_STBY")
	)
	(segment
		(start 94.29877 -138.167618)
		(end 94.10827 -137.977118)
		(width 1.016)
		(layer "B.Cu")
		(net "P3V3_STBY")
	)
	(segment
		(start 340.6394 -14.8844)
		(end 338.6074 -14.8844)
		(width 1.016)
		(layer "B.Cu")
		(net "P3V3_STBY")
	)
	(segment
		(start 115.824 -74.549)
		(end 113.52657 -72.25157)
		(width 0.508)
		(layer "B.Cu")
		(net "P3V3_STBY")
	)
	(segment
		(start 304.54092 -142.875)
		(end 294.132 -142.875)
		(width 0.635)
		(layer "B.Cu")
		(net "P3V3_STBY")
	)
	(segment
		(start 187.96 -156.3243)
		(end 180.2765 -148.6408)
		(width 1.016)
		(layer "B.Cu")
		(net "P3V3_STBY")
	)
	(segment
		(start 94.29877 -138.946382)
		(end 94.29877 -138.167618)
		(width 1.016)
		(layer "B.Cu")
		(net "P3V3_STBY")
	)
	(segment
		(start 110.50397 -72.1995)
		(end 110.16107 -71.8566)
		(width 0.508)
		(layer "B.Cu")
		(net "P3V3_STBY")
	)
	(segment
		(start 31.255716 -202.36688)
		(end 32.335216 -202.36688)
		(width 0.508)
		(layer "B.Cu")
		(net "P3V3_STBY")
	)
	(segment
		(start 79.444342 -138.896852)
		(end 80.19415 -139.64666)
		(width 0.508)
		(layer "B.Cu")
		(net "P3V3_STBY")
	)
	(segment
		(start 222.4532 -111.4298)
		(end 221.107 -112.776)
		(width 0.508)
		(layer "B.Cu")
		(net "P3V3_STBY")
	)
	(segment
		(start 163.3728 -113.2332)
		(end 162.941 -113.665)
		(width 0.508)
		(layer "B.Cu")
		(net "P3V3_STBY")
	)
	(segment
		(start 143.14297 -84.582)
		(end 143.14297 -83.561682)
		(width 0.508)
		(layer "B.Cu")
		(net "P3V3_STBY")
	)
	(segment
		(start 93.223588 -122.626882)
		(end 94.10827 -123.511564)
		(width 0.635)
		(layer "B.Cu")
		(net "P3V3_STBY")
	)
	(segment
		(start 163.2712 -110.131098)
		(end 163.3728 -110.232698)
		(width 0.508)
		(layer "B.Cu")
		(net "P3V3_STBY")
	)
	(segment
		(start 289.885628 -173.78934)
		(end 289.523424 -173.427136)
		(width 0.508)
		(layer "B.Cu")
		(net "P3V3_STBY")
	)
	(segment
		(start 292.357556 -171.687236)
		(end 292.63086 -171.96054)
		(width 0.508)
		(layer "B.Cu")
		(net "P3V3_STBY")
	)
	(segment
		(start 224.79 -111.4298)
		(end 222.4532 -111.4298)
		(width 0.508)
		(layer "B.Cu")
		(net "P3V3_STBY")
	)
	(segment
		(start 133.141466 -31.171388)
		(end 132.331714 -30.361636)
		(width 0.508)
		(layer "B.Cu")
		(net "P3V3_STBY")
	)
	(segment
		(start 133.141466 -31.623)
		(end 133.141466 -31.171388)
		(width 0.508)
		(layer "B.Cu")
		(net "P3V3_STBY")
	)
	(segment
		(start 294.132 -142.875)
		(end 292.354 -144.653)
		(width 0.635)
		(layer "B.Cu")
		(net "P3V3_STBY")
	)
	(segment
		(start 187.96 -161.163)
		(end 203.581 -145.542)
		(width 1.016)
		(layer "B.Cu")
		(net "P3V3_STBY")
	)
	(segment
		(start 125.227588 -73.66)
		(end 118.999 -73.66)
		(width 0.508)
		(layer "B.Cu")
		(net "P3V3_STBY")
	)
	(segment
		(start 298.006008 -176.602136)
		(end 298.03471 -176.630838)
		(width 0.6096)
		(layer "B.Cu")
		(net "P3V3_STBY")
	)
	(segment
		(start 186.744864 -27.821636)
		(end 187.96 -27.821636)
		(width 0.508)
		(layer "B.Cu")
		(net "P3V3_STBY")
	)
	(segment
		(start 299.6565 -178.1302)
		(end 299.66666 -178.14036)
		(width 0.4572)
		(layer "B.Cu")
		(net "P3V3_STBY")
	)
	(segment
		(start 139.33297 -88.011)
		(end 140.27277 -88.9508)
		(width 0.508)
		(layer "B.Cu")
		(net "P3V3_STBY")
	)
	(segment
		(start 234.93222 -115.73256)
		(end 233.27868 -114.07902)
		(width 1.016)
		(layer "B.Cu")
		(net "P3V3_STBY")
	)
	(segment
		(start 88.192102 -138.8618)
		(end 88.46947 -138.584432)
		(width 0.508)
		(layer "B.Cu")
		(net "P3V3_STBY")
	)
	(segment
		(start 187.96 -161.163)
		(end 187.96 -156.3243)
		(width 1.016)
		(layer "B.Cu")
		(net "P3V3_STBY")
	)
	(segment
		(start 79.44993 -117.49024)
		(end 76.04633 -114.08664)
		(width 0.635)
		(layer "B.Cu")
		(net "P3V3_STBY")
	)
	(segment
		(start 94.10827 -139.69873)
		(end 94.10827 -139.136882)
		(width 1.016)
		(layer "B.Cu")
		(net "P3V3_STBY")
	)
	(segment
		(start 350.393 -81.0895)
		(end 350.393 -79.756)
		(width 0.508)
		(layer "B.Cu")
		(net "P3V3_STBY")
	)
	(segment
		(start 307.594 -181.0512)
		(end 308.4068 -181.0512)
		(width 1.016)
		(layer "B.Cu")
		(net "P3V3_STBY")
	)
	(segment
		(start 79.48295 -117.49024)
		(end 79.48295 -134.550404)
		(width 0.635)
		(layer "B.Cu")
		(net "P3V3_STBY")
	)
	(segment
		(start 143.44777 -87.5538)
		(end 143.038322 -87.144352)
		(width 0.508)
		(layer "B.Cu")
		(net "P3V3_STBY")
	)
	(segment
		(start 309.118 -160.2105)
		(end 309.6895 -160.2105)
		(width 0.508)
		(layer "B.Cu")
		(net "P3V3_STBY")
	)
	(segment
		(start 143.038322 -87.144352)
		(end 143.038322 -84.686648)
		(width 0.508)
		(layer "B.Cu")
		(net "P3V3_STBY")
	)
	(segment
		(start 279.781 -117.221)
		(end 297.18 -117.221)
		(width 0.508)
		(layer "B.Cu")
		(net "P3V3_STBY")
	)
	(segment
		(start 106.5784 -72.02043)
		(end 106.5784 -71.8566)
		(width 0.508)
		(layer "B.Cu")
		(net "P3V3_STBY")
	)
	(segment
		(start 21.921216 -224.71888)
		(end 24.588216 -227.38588)
		(width 0.635)
		(layer "B.Cu")
		(net "P3V3_STBY")
	)
	(segment
		(start 308.991 -180.467)
		(end 308.991 -180.37175)
		(width 1.016)
		(layer "B.Cu")
		(net "P3V3_STBY")
	)
	(segment
		(start 289.885628 -173.794928)
		(end 289.885628 -173.78934)
		(width 0.508)
		(layer "B.Cu")
		(net "P3V3_STBY")
	)
	(segment
		(start 164.211 -114.8715)
		(end 163.6395 -114.8715)
		(width 0.508)
		(layer "B.Cu")
		(net "P3V3_STBY")
	)
	(segment
		(start 273.7485 -170.561)
		(end 272.796 -170.561)
		(width 0.508)
		(layer "B.Cu")
		(net "P3V3_STBY")
	)
	(segment
		(start 32.512 -138.1887)
		(end 37.68979 -138.1887)
		(width 0.508)
		(layer "B.Cu")
		(net "P3V3_STBY")
	)
	(segment
		(start 12.62888 -237.651544)
		(end 21.936456 -237.651544)
		(width 0.635)
		(layer "B.Cu")
		(net "P3V3_STBY")
	)
	(segment
		(start 294.8559 -171.860718)
		(end 294.835072 -171.83989)
		(width 0.3556)
		(layer "B.Cu")
		(net "P3V3_STBY")
	)
	(segment
		(start 140.423138 -81.534)
		(end 139.45997 -80.570832)
		(width 0.508)
		(layer "B.Cu")
		(net "P3V3_STBY")
	)
	(segment
		(start 19.508216 -180.39588)
		(end 19.690588 -180.213508)
		(width 0.508)
		(layer "B.Cu")
		(net "P3V3_STBY")
	)
	(segment
		(start 19.690588 -185.421016)
		(end 19.690588 -183.960516)
		(width 0.508)
		(layer "B.Cu")
		(net "P3V3_STBY")
	)
	(segment
		(start 308.4068 -181.0512)
		(end 308.991 -180.467)
		(width 1.016)
		(layer "B.Cu")
		(net "P3V3_STBY")
	)
	(segment
		(start 111.7092 -72.1614)
		(end 111.6711 -72.1995)
		(width 0.508)
		(layer "B.Cu")
		(net "P3V3_STBY")
	)
	(segment
		(start 225.538792 -96.572832)
		(end 225.538792 -101.359208)
		(width 0.508)
		(layer "B.Cu")
		(net "P3V3_STBY")
	)
	(segment
		(start 24.524716 -235.063284)
		(end 24.524716 -228.886258)
		(width 0.635)
		(layer "B.Cu")
		(net "P3V3_STBY")
	)
	(segment
		(start 24.151844 -174.355252)
		(end 24.151844 -175.387762)
		(width 0.508)
		(layer "B.Cu")
		(net "P3V3_STBY")
	)
	(segment
		(start 140.60297 -81.534)
		(end 140.423138 -81.534)
		(width 0.508)
		(layer "B.Cu")
		(net "P3V3_STBY")
	)
	(segment
		(start 79.248 -24.765)
		(end 79.629 -24.765)
		(width 0.508)
		(layer "B.Cu")
		(net "P3V3_STBY")
	)
	(segment
		(start 288.732722 -176.657)
		(end 288.598864 -176.657)
		(width 0.381)
		(layer "B.Cu")
		(net "P3V3_STBY")
	)
	(segment
		(start 163.6395 -114.8715)
		(end 162.941 -114.173)
		(width 0.508)
		(layer "B.Cu")
		(net "P3V3_STBY")
	)
	(segment
		(start 299.66666 -178.14036)
		(end 300.344586 -178.14036)
		(width 0.4572)
		(layer "B.Cu")
		(net "P3V3_STBY")
	)
	(segment
		(start 143.44777 -88.549226)
		(end 143.44777 -87.5538)
		(width 0.508)
		(layer "B.Cu")
		(net "P3V3_STBY")
	)
	(segment
		(start 78.5495 -25.019)
		(end 78.994 -25.019)
		(width 0.508)
		(layer "B.Cu")
		(net "P3V3_STBY")
	)
	(segment
		(start 78.994 -25.019)
		(end 79.248 -24.765)
		(width 0.508)
		(layer "B.Cu")
		(net "P3V3_STBY")
	)
	(segment
		(start 311.404 -183.515)
		(end 312.166 -184.277)
		(width 0.508)
		(layer "B.Cu")
		(net "P3V3_STBY")
	)
	(segment
		(start 184.543192 -26.3398)
		(end 185.609992 -25.273)
		(width 0.508)
		(layer "B.Cu")
		(net "P3V3_STBY")
	)
	(segment
		(start 293.883588 -172.015912)
		(end 293.883588 -171.698412)
		(width 0.3556)
		(layer "B.Cu")
		(net "P3V3_STBY")
	)
	(segment
		(start 272.796 -170.561)
		(end 272.669 -170.688)
		(width 0.508)
		(layer "B.Cu")
		(net "P3V3_STBY")
	)
	(segment
		(start 143.038322 -84.686648)
		(end 143.14297 -84.582)
		(width 0.508)
		(layer "B.Cu")
		(net "P3V3_STBY")
	)
	(segment
		(start 22.183852 -216.726008)
		(end 22.183852 -215.569038)
		(width 0.508)
		(layer "B.Cu")
		(net "P3V3_STBY")
	)
	(segment
		(start 19.690588 -183.960516)
		(end 19.627088 -183.897016)
		(width 0.508)
		(layer "B.Cu")
		(net "P3V3_STBY")
	)
	(segment
		(start 295.4655 -178.943)
		(end 295.647872 -179.125372)
		(width 0.508)
		(layer "B.Cu")
		(net "P3V3_STBY")
	)
	(segment
		(start 79.48295 -117.49024)
		(end 79.44993 -117.49024)
		(width 0.635)
		(layer "B.Cu")
		(net "P3V3_STBY")
	)
	(segment
		(start 173.786038 -18.974562)
		(end 173.736 -18.924524)
		(width 0.635)
		(layer "B.Cu")
		(net "P3V3_STBY")
	)
	(segment
		(start 288.577274 -176.63541)
		(end 288.439606 -176.63541)
		(width 0.381)
		(layer "B.Cu")
		(net "P3V3_STBY")
	)
	(segment
		(start 21.936456 -237.651544)
		(end 24.3078 -235.2802)
		(width 0.635)
		(layer "B.Cu")
		(net "P3V3_STBY")
	)
	(segment
		(start 142.582138 -83.00085)
		(end 142.06982 -83.00085)
		(width 0.508)
		(layer "B.Cu")
		(net "P3V3_STBY")
	)
	(segment
		(start 135.5852 -73.025)
		(end 125.862588 -73.025)
		(width 0.508)
		(layer "B.Cu")
		(net "P3V3_STBY")
	)
	(segment
		(start 292.354 -148.844)
		(end 293.116 -149.606)
		(width 0.635)
		(layer "B.Cu")
		(net "P3V3_STBY")
	)
	(segment
		(start 342.921336 -72.242172)
		(end 342.921336 -75.311)
		(width 0.508)
		(layer "B.Cu")
		(net "P3V3_STBY")
	)
	(segment
		(start 288.457386 -173.427136)
		(end 288.439606 -173.444916)
		(width 0.508)
		(layer "B.Cu")
		(net "P3V3_STBY")
	)
	(segment
		(start 224.79 -111.4298)
		(end 230.62946 -111.4298)
		(width 0.508)
		(layer "B.Cu")
		(net "P3V3_STBY")
	)
	(segment
		(start 297.1292 -173.3677)
		(end 297.1292 -173.2788)
		(width 0.6096)
		(layer "B.Cu")
		(net "P3V3_STBY")
	)
	(segment
		(start 19.690588 -180.213508)
		(end 19.690588 -180.099208)
		(width 0.508)
		(layer "B.Cu")
		(net "P3V3_STBY")
	)
	(segment
		(start 23.826216 -212.27288)
		(end 23.445216 -212.27288)
		(width 0.508)
		(layer "B.Cu")
		(net "P3V3_STBY")
	)
	(segment
		(start 319.9765 -161.9885)
		(end 319.405 -161.417)
		(width 0.508)
		(layer "B.Cu")
		(net "P3V3_STBY")
	)
	(segment
		(start 162.941 -113.665)
		(end 162.941 -114.173)
		(width 0.508)
		(layer "B.Cu")
		(net "P3V3_STBY")
	)
	(segment
		(start 236.0041 -91.37142)
		(end 236.83468 -92.202)
		(width 0.508)
		(layer "B.Cu")
		(net "P3V3_STBY")
	)
	(segment
		(start 106.7562 -72.19823)
		(end 106.5784 -72.02043)
		(width 0.508)
		(layer "B.Cu")
		(net "P3V3_STBY")
	)
	(segment
		(start 143.14297 -83.561682)
		(end 142.582138 -83.00085)
		(width 0.508)
		(layer "B.Cu")
		(net "P3V3_STBY")
	)
	(segment
		(start 343.408 -17.653)
		(end 340.6394 -14.8844)
		(width 1.016)
		(layer "B.Cu")
		(net "P3V3_STBY")
	)
	(segment
		(start 333.375 -154.3685)
		(end 331.936598 -154.3685)
		(width 0.508)
		(layer "B.Cu")
		(net "P3V3_STBY")
	)
	(segment
		(start 196.723 -124.333)
		(end 195.961 -124.333)
		(width 0.508)
		(layer "B.Cu")
		(net "P3V3_STBY")
	)
	(segment
		(start 94.10827 -123.511564)
		(end 94.10827 -131.57073)
		(width 0.635)
		(layer "B.Cu")
		(net "P3V3_STBY")
	)
	(segment
		(start 142.06982 -83.00085)
		(end 140.60297 -81.534)
		(width 0.508)
		(layer "B.Cu")
		(net "P3V3_STBY")
	)
	(segment
		(start 22.333712 -215.419178)
		(end 23.445216 -214.307674)
		(width 0.635)
		(layer "B.Cu")
		(net "P3V3_STBY")
	)
	(segment
		(start 23.457916 -176.33188)
		(end 24.096726 -176.33188)
		(width 0.508)
		(layer "B.Cu")
		(net "P3V3_STBY")
	)
	(segment
		(start 139.33297 -87.6935)
		(end 139.33297 -88.011)
		(width 0.508)
		(layer "B.Cu")
		(net "P3V3_STBY")
	)
	(segment
		(start 106.7562 -74.20737)
		(end 106.7562 -72.19823)
		(width 0.508)
		(layer "B.Cu")
		(net "P3V3_STBY")
	)
	(segment
		(start 288.804858 -176.729136)
		(end 288.732722 -176.657)
		(width 0.381)
		(layer "B.Cu")
		(net "P3V3_STBY")
	)
	(segment
		(start 297.2435 -173.482)
		(end 297.1292 -173.3677)
		(width 0.6096)
		(layer "B.Cu")
		(net "P3V3_STBY")
	)
	(segment
		(start 33.02 -169.418)
		(end 28.13812 -174.29988)
		(width 0.508)
		(layer "B.Cu")
		(net "P3V3_STBY")
	)
	(segment
		(start 19.508216 -180.39588)
		(end 14.936216 -180.39588)
		(width 0.508)
		(layer "B.Cu")
		(net "P3V3_STBY")
	)
	(segment
		(start 298.069 -107.315)
		(end 301.752 -107.315)
		(width 0.508)
		(layer "B.Cu")
		(net "P3V3_STBY")
	)
	(segment
		(start 18.928588 -191.136016)
		(end 18.928588 -192.515236)
		(width 0.508)
		(layer "B.Cu")
		(net "P3V3_STBY")
	)
	(segment
		(start 196.723 -129.794)
		(end 196.723 -124.333)
		(width 1.016)
		(layer "B.Cu")
		(net "P3V3_STBY")
	)
	(segment
		(start 31.255716 -204.84338)
		(end 23.826216 -212.27288)
		(width 0.508)
		(layer "B.Cu")
		(net "P3V3_STBY")
	)
	(segment
		(start 20.714716 -224.71888)
		(end 21.921216 -224.71888)
		(width 0.635)
		(layer "B.Cu")
		(net "P3V3_STBY")
	)
	(segment
		(start 187.96 -172.974)
		(end 187.96 -161.163)
		(width 1.016)
		(layer "B.Cu")
		(net "P3V3_STBY")
	)
	(segment
		(start 132.331714 -29.136086)
		(end 132.5118 -28.956)
		(width 0.508)
		(layer "B.Cu")
		(net "P3V3_STBY")
	)
	(segment
		(start 203.581 -136.652)
		(end 196.723 -129.794)
		(width 1.016)
		(layer "B.Cu")
		(net "P3V3_STBY")
	)
	(segment
		(start 79.502 -23.5585)
		(end 79.502 -24.638)
		(width 0.508)
		(layer "B.Cu")
		(net "P3V3_STBY")
	)
	(segment
		(start 294.8559 -172.5422)
		(end 294.8559 -171.860718)
		(width 0.3556)
		(layer "B.Cu")
		(net "P3V3_STBY")
	)
	(segment
		(start 163.3728 -110.232698)
		(end 163.3728 -113.2332)
		(width 0.508)
		(layer "B.Cu")
		(net "P3V3_STBY")
	)
	(segment
		(start 309.6895 -160.2105)
		(end 310.261 -160.782)
		(width 0.508)
		(layer "B.Cu")
		(net "P3V3_STBY")
	)
	(segment
		(start 184.543192 -27.305)
		(end 184.543192 -26.3398)
		(width 0.508)
		(layer "B.Cu")
		(net "P3V3_STBY")
	)
	(segment
		(start 244.729 -92.202)
		(end 245.11 -92.583)
		(width 0.508)
		(layer "B.Cu")
		(net "P3V3_STBY")
	)
	(segment
		(start 138.44397 -78.867)
		(end 138.44397 -75.88377)
		(width 0.508)
		(layer "B.Cu")
		(net "P3V3_STBY")
	)
	(segment
		(start 320.3575 -169.545)
		(end 320.3575 -169.6085)
		(width 0.508)
		(layer "B.Cu")
		(net "P3V3_STBY")
	)
	(segment
		(start 94.10827 -137.977118)
		(end 94.10827 -131.57327)
		(width 1.016)
		(layer "B.Cu")
		(net "P3V3_STBY")
	)
	(segment
		(start 225.5393 -91.37142)
		(end 236.0041 -91.37142)
		(width 0.508)
		(layer "B.Cu")
		(net "P3V3_STBY")
	)
	(segment
		(start 19.690588 -180.099208)
		(end 23.457916 -176.33188)
		(width 0.508)
		(layer "B.Cu")
		(net "P3V3_STBY")
	)
	(segment
		(start 261.039864 -231.956864)
		(end 258.309872 -229.226872)
		(width 1.016)
		(layer "B.Cu")
		(net "P3V3_STBY")
	)
	(segment
		(start 180.2765 -148.6408)
		(end 179.197 -147.5613)
		(width 1.016)
		(layer "B.Cu")
		(net "P3V3_STBY")
	)
	(segment
		(start 289.523424 -173.427136)
		(end 288.457386 -173.427136)
		(width 0.508)
		(layer "B.Cu")
		(net "P3V3_STBY")
	)
	(segment
		(start 179.569364 -33.854136)
		(end 179.569364 -32.965136)
		(width 0.6096)
		(layer "B.Cu")
		(net "P3V3_STBY")
	)
	(segment
		(start 270.793972 -173.114716)
		(end 270.016224 -173.114716)
		(width 0.3556)
		(layer "B.Cu")
		(net "P3V3_STBY")
	)
	(segment
		(start 40.0685 -168.2115)
		(end 38.989 -169.291)
		(width 0.635)
		(layer "B.Cu")
		(net "P3V3_STBY")
	)
	(segment
		(start 293.878 -172.0215)
		(end 293.883588 -172.015912)
		(width 0.3556)
		(layer "B.Cu")
		(net "P3V3_STBY")
	)
	(segment
		(start 312.166 -184.277)
		(end 312.166 -184.531)
		(width 0.508)
		(layer "B.Cu")
		(net "P3V3_STBY")
	)
	(segment
		(start 230.62946 -111.4298)
		(end 233.27868 -114.07902)
		(width 0.508)
		(layer "B.Cu")
		(net "P3V3_STBY")
	)
	(segment
		(start 311.3405 -183.515)
		(end 311.404 -183.515)
		(width 0.508)
		(layer "B.Cu")
		(net "P3V3_STBY")
	)
	(segment
		(start 106.54157 -74.422)
		(end 106.7562 -74.20737)
		(width 0.508)
		(layer "B.Cu")
		(net "P3V3_STBY")
	)
	(segment
		(start 236.347 -136.271)
		(end 234.93222 -134.85622)
		(width 1.016)
		(layer "B.Cu")
		(net "P3V3_STBY")
	)
	(segment
		(start 113.52657 -71.775574)
		(end 113.124996 -71.374)
		(width 0.508)
		(layer "B.Cu")
		(net "P3V3_STBY")
	)
	(segment
		(start 19.508216 -183.778144)
		(end 19.627088 -183.897016)
		(width 0.508)
		(layer "B.Cu")
		(net "P3V3_STBY")
	)
	(segment
		(start 293.883588 -171.698412)
		(end 293.23538 -171.050204)
		(width 0.3556)
		(layer "B.Cu")
		(net "P3V3_STBY")
	)
	(segment
		(start 301.752 -107.315)
		(end 302.006 -107.061)
		(width 0.508)
		(layer "B.Cu")
		(net "P3V3_STBY")
	)
	(segment
		(start 236.83468 -92.202)
		(end 244.729 -92.202)
		(width 0.508)
		(layer "B.Cu")
		(net "P3V3_STBY")
	)
	(segment
		(start 326.009 -180.1495)
		(end 326.26046 -180.40096)
		(width 0.508)
		(layer "B.Cu")
		(net "P3V3_STBY")
	)
	(segment
		(start 300.344586 -178.14036)
		(end 300.43501 -178.230784)
		(width 0.4572)
		(layer "B.Cu")
		(net "P3V3_STBY")
	)
	(segment
		(start 302.88738 -177.673)
		(end 302.26 -177.673)
		(width 0.3556)
		(layer "B.Cu")
		(net "P3V3_STBY")
	)
	(segment
		(start 320.6242 -169.8752)
		(end 320.6242 -170.3578)
		(width 0.508)
		(layer "B.Cu")
		(net "P3V3_STBY")
	)
	(segment
		(start 113.52657 -72.25157)
		(end 113.52657 -71.775574)
		(width 0.508)
		(layer "B.Cu")
		(net "P3V3_STBY")
	)
	(segment
		(start 139.45997 -80.570832)
		(end 139.45997 -79.883)
		(width 0.508)
		(layer "B.Cu")
		(net "P3V3_STBY")
	)
	(segment
		(start 38.989 -169.291)
		(end 33.02 -169.291)
		(width 0.635)
		(layer "B.Cu")
		(net "P3V3_STBY")
	)
	(segment
		(start 37.68979 -138.1887)
		(end 39.27475 -139.77366)
		(width 0.508)
		(layer "B.Cu")
		(net "P3V3_STBY")
	)
	(segment
		(start 173.736 -17.018)
		(end 171.893992 -15.175992)
		(width 0.635)
		(layer "B.Cu")
		(net "P3V3_STBY")
	)
	(segment
		(start 22.183852 -215.569038)
		(end 22.333712 -215.419178)
		(width 0.508)
		(layer "B.Cu")
		(net "P3V3_STBY")
	)
	(segment
		(start 185.855864 -27.821636)
		(end 186.744864 -27.821636)
		(width 0.508)
		(layer "B.Cu")
		(net "P3V3_STBY")
	)
	(segment
		(start 331.851 -163.8935)
		(end 333.112364 -163.8935)
		(width 0.508)
		(layer "B.Cu")
		(net "P3V3_STBY")
	)
	(segment
		(start 333.112364 -163.8935)
		(end 333.248 -164.029136)
		(width 0.508)
		(layer "B.Cu")
		(net "P3V3_STBY")
	)
	(segment
		(start 234.93222 -134.85622)
		(end 234.93222 -115.73256)
		(width 1.016)
		(layer "B.Cu")
		(net "P3V3_STBY")
	)
	(segment
		(start 297.2435 -174.117)
		(end 297.2435 -173.482)
		(width 0.6096)
		(layer "B.Cu")
		(net "P3V3_STBY")
	)
	(segment
		(start 24.151844 -175.387762)
		(end 24.151844 -176.276762)
		(width 0.508)
		(layer "B.Cu")
		(net "P3V3_STBY")
	)
	(segment
		(start 225.538792 -101.359208)
		(end 224.155 -102.743)
		(width 0.508)
		(layer "B.Cu")
		(net "P3V3_STBY")
	)
	(segment
		(start 297.18 -117.221)
		(end 297.307 -117.094)
		(width 0.508)
		(layer "B.Cu")
		(net "P3V3_STBY")
	)
	(segment
		(start 19.508216 -180.39588)
		(end 19.508216 -183.778144)
		(width 0.508)
		(layer "B.Cu")
		(net "P3V3_STBY")
	)
	(segment
		(start 10.491216 -235.51388)
		(end 12.62888 -237.651544)
		(width 0.635)
		(layer "B.Cu")
		(net "P3V3_STBY")
	)
	(segment
		(start 185.039 -119.888)
		(end 186.944 -117.983)
		(width 0.508)
		(layer "B.Cu")
		(net "P3V3_STBY")
	)
	(segment
		(start 80.645 -25.654)
		(end 79.756 -24.765)
		(width 0.508)
		(layer "B.Cu")
		(net "P3V3_STBY")
	)
	(segment
		(start 328.295 -103.0605)
		(end 328.295 -102.108)
		(width 0.508)
		(layer "B.Cu")
		(net "P3V3_STBY")
	)
	(segment
		(start 23.445216 -214.307674)
		(end 23.445216 -212.27288)
		(width 0.635)
		(layer "B.Cu")
		(net "P3V3_STBY")
	)
	(segment
		(start 179.197 -147.5613)
		(end 179.197 -146.2024)
		(width 1.016)
		(layer "B.Cu")
		(net "P3V3_STBY")
	)
	(segment
		(start 24.207216 -174.29988)
		(end 24.151844 -174.355252)
		(width 0.508)
		(layer "B.Cu")
		(net "P3V3_STBY")
	)
	(segment
		(start 273.177 -171.577)
		(end 272.796 -171.958)
		(width 0.508)
		(layer "B.Cu")
		(net "P3V3_STBY")
	)
	(segment
		(start 190.754 -117.983)
		(end 192.659 -116.078)
		(width 0.508)
		(layer "B.Cu")
		(net "P3V3_STBY")
	)
	(segment
		(start 258.309872 -229.226872)
		(end 255.913128 -229.226872)
		(width 1.016)
		(layer "B.Cu")
		(net "P3V3_STBY")
	)
	(segment
		(start 32.335216 -202.36688)
		(end 32.843216 -202.87488)
		(width 0.508)
		(layer "B.Cu")
		(net "P3V3_STBY")
	)
	(segment
		(start 118.999 -73.66)
		(end 118.11 -74.549)
		(width 0.508)
		(layer "B.Cu")
		(net "P3V3_STBY")
	)
	(segment
		(start 273.7485 -171.577)
		(end 273.177 -171.577)
		(width 0.508)
		(layer "B.Cu")
		(net "P3V3_STBY")
	)
	(segment
		(start 111.6711 -72.1995)
		(end 110.50397 -72.1995)
		(width 0.508)
		(layer "B.Cu")
		(net "P3V3_STBY")
	)
	(segment
		(start 33.02 -169.291)
		(end 33.02 -169.418)
		(width 0.508)
		(layer "B.Cu")
		(net "P3V3_STBY")
	)
	(segment
		(start 132.331714 -30.361636)
		(end 132.331714 -29.136086)
		(width 0.508)
		(layer "B.Cu")
		(net "P3V3_STBY")
	)
	(segment
		(start 173.736 -18.924524)
		(end 173.736 -17.018)
		(width 0.635)
		(layer "B.Cu")
		(net "P3V3_STBY")
	)
	(segment
		(start 171.893992 -15.175992)
		(end 171.893992 -13.208)
		(width 0.635)
		(layer "B.Cu")
		(net "P3V3_STBY")
	)
	(segment
		(start 28.13812 -174.29988)
		(end 24.207216 -174.29988)
		(width 0.508)
		(layer "B.Cu")
		(net "P3V3_STBY")
	)
	(segment
		(start 118.11 -74.549)
		(end 115.824 -74.549)
		(width 0.508)
		(layer "B.Cu")
		(net "P3V3_STBY")
	)
	(segment
		(start 15.220696 -213.7664)
		(end 14.2494 -213.7664)
		(width 0.508)
		(layer "In2.Cu")
		(net "P3V3_STBY")
	)
	(segment
		(start 251.587 -136.271)
		(end 244.729 -136.271)
		(width 1.016)
		(layer "In2.Cu")
		(net "P3V3_STBY")
	)
	(segment
		(start 338.6074 -14.8844)
		(end 337.2104 -14.8844)
		(width 0.508)
		(layer "In2.Cu")
		(net "P3V3_STBY")
	)
	(segment
		(start 321.056 -10.16)
		(end 330.962 -10.16)
		(width 0.508)
		(layer "In2.Cu")
		(net "P3V3_STBY")
	)
	(segment
		(start 218.567 -124.333)
		(end 196.723 -124.333)
		(width 0.508)
		(layer "In2.Cu")
		(net "P3V3_STBY")
	)
	(segment
		(start 29.424376 -141.318234)
		(end 29.424376 -157.567376)
		(width 0.635)
		(layer "In2.Cu")
		(net "P3V3_STBY")
	)
	(segment
		(start 337.2104 -14.8844)
		(end 333.248 -10.922)
		(width 0.508)
		(layer "In2.Cu")
		(net "P3V3_STBY")
	)
	(segment
		(start 255.73736 -135.509)
		(end 254.97536 -136.271)
		(width 1.016)
		(layer "In2.Cu")
		(net "P3V3_STBY")
	)
	(segment
		(start 303.53 -109.855)
		(end 307.086 -109.855)
		(width 0.508)
		(layer "In2.Cu")
		(net "P3V3_STBY")
	)
	(segment
		(start 124.079 -29.0068)
		(end 124.1298 -28.956)
		(width 0.508)
		(layer "In2.Cu")
		(net "P3V3_STBY")
	)
	(segment
		(start 162.941 -114.173)
		(end 162.9918 -114.1222)
		(width 0.508)
		(layer "In2.Cu")
		(net "P3V3_STBY")
	)
	(segment
		(start 331.978 -143.256)
		(end 331.978 -145.646648)
		(width 0.508)
		(layer "In2.Cu")
		(net "P3V3_STBY")
	)
	(segment
		(start 11.303 -216.281)
		(end 10.668 -215.646)
		(width 0.508)
		(layer "In2.Cu")
		(net "P3V3_STBY")
	)
	(segment
		(start 275.209 -182.499)
		(end 274.222464 -183.485536)
		(width 0.508)
		(layer "In2.Cu")
		(net "P3V3_STBY")
	)
	(segment
		(start 330.962 -10.16)
		(end 331.724 -10.922)
		(width 0.508)
		(layer "In2.Cu")
		(net "P3V3_STBY")
	)
	(segment
		(start 256.1336 -135.509)
		(end 255.73736 -135.509)
		(width 1.016)
		(layer "In2.Cu")
		(net "P3V3_STBY")
	)
	(segment
		(start 282.321 -182.499)
		(end 275.209 -182.499)
		(width 0.508)
		(layer "In2.Cu")
		(net "P3V3_STBY")
	)
	(segment
		(start 44.327318 -139.77366)
		(end 48.914558 -144.3609)
		(width 0.635)
		(layer "In2.Cu")
		(net "P3V3_STBY")
	)
	(segment
		(start 30.016196 -80.473804)
		(end 32.258 -78.232)
		(width 0.508)
		(layer "In2.Cu")
		(net "P3V3_STBY")
	)
	(segment
		(start 29.424376 -157.567376)
		(end 40.0685 -168.2115)
		(width 0.635)
		(layer "In2.Cu")
		(net "P3V3_STBY")
	)
	(segment
		(start 162.9918 -114.1222)
		(end 190.7032 -114.1222)
		(width 0.508)
		(layer "In2.Cu")
		(net "P3V3_STBY")
	)
	(segment
		(start 39.06266 -139.77366)
		(end 39.27475 -139.77366)
		(width 0.508)
		(layer "In2.Cu")
		(net "P3V3_STBY")
	)
	(segment
		(start 32.258 -74.703178)
		(end 32.424116 -74.537062)
		(width 0.508)
		(layer "In2.Cu")
		(net "P3V3_STBY")
	)
	(segment
		(start 308.102 -111.506)
		(end 308.102 -113.919)
		(width 0.508)
		(layer "In2.Cu")
		(net "P3V3_STBY")
	)
	(segment
		(start 38.227 -212.852)
		(end 24.024336 -212.852)
		(width 0.508)
		(layer "In2.Cu")
		(net "P3V3_STBY")
	)
	(segment
		(start 218.821 -124.079)
		(end 218.567 -124.333)
		(width 0.508)
		(layer "In2.Cu")
		(net "P3V3_STBY")
	)
	(segment
		(start 32.258 -78.232)
		(end 32.258 -74.703178)
		(width 0.508)
		(layer "In2.Cu")
		(net "P3V3_STBY")
	)
	(segment
		(start 32.512 -138.1887)
		(end 31.773114 -138.927586)
		(width 0.635)
		(layer "In2.Cu")
		(net "P3V3_STBY")
	)
	(segment
		(start 256.159 -135.4836)
		(end 256.1336 -135.509)
		(width 1.016)
		(layer "In2.Cu")
		(net "P3V3_STBY")
	)
	(segment
		(start 48.914558 -144.3609)
		(end 71.5391 -144.3609)
		(width 0.635)
		(layer "In2.Cu")
		(net "P3V3_STBY")
	)
	(segment
		(start 178.17592 -148.6662)
		(end 178.15052 -148.6408)
		(width 1.016)
		(layer "In2.Cu")
		(net "P3V3_STBY")
	)
	(segment
		(start 31.773114 -138.969496)
		(end 29.424376 -141.318234)
		(width 0.635)
		(layer "In2.Cu")
		(net "P3V3_STBY")
	)
	(segment
		(start 246.761 -122.809)
		(end 256.286 -122.809)
		(width 1.016)
		(layer "In2.Cu")
		(net "P3V3_STBY")
	)
	(segment
		(start 180.24348 -148.6408)
		(end 180.21808 -148.6662)
		(width 1.016)
		(layer "In2.Cu")
		(net "P3V3_STBY")
	)
	(segment
		(start 38.735 -213.36)
		(end 38.227 -212.852)
		(width 0.508)
		(layer "In2.Cu")
		(net "P3V3_STBY")
	)
	(segment
		(start 80.19415 -139.64666)
		(end 82.87766 -139.64666)
		(width 0.635)
		(layer "In2.Cu")
		(net "P3V3_STBY")
	)
	(segment
		(start 145.2118 -41.656)
		(end 150.495 -41.656)
		(width 0.508)
		(layer "In2.Cu")
		(net "P3V3_STBY")
	)
	(segment
		(start 180.2765 -148.6408)
		(end 180.24348 -148.6408)
		(width 1.016)
		(layer "In2.Cu")
		(net "P3V3_STBY")
	)
	(segment
		(start 132.5118 -28.956)
		(end 145.2118 -41.656)
		(width 0.508)
		(layer "In2.Cu")
		(net "P3V3_STBY")
	)
	(segment
		(start 307.975 -110.744)
		(end 307.975 -111.379)
		(width 0.508)
		(layer "In2.Cu")
		(net "P3V3_STBY")
	)
	(segment
		(start 31.773114 -138.927586)
		(end 31.773114 -138.969496)
		(width 0.635)
		(layer "In2.Cu")
		(net "P3V3_STBY")
	)
	(segment
		(start 244.729 -123.952)
		(end 245.618 -123.952)
		(width 1.016)
		(layer "In2.Cu")
		(net "P3V3_STBY")
	)
	(segment
		(start 32.512 -102.616)
		(end 30.016196 -100.120196)
		(width 0.508)
		(layer "In2.Cu")
		(net "P3V3_STBY")
	)
	(segment
		(start 112.098582 -148.6408)
		(end 95.029782 -131.572)
		(width 1.016)
		(layer "In2.Cu")
		(net "P3V3_STBY")
	)
	(segment
		(start 178.15052 -148.6408)
		(end 112.098582 -148.6408)
		(width 1.016)
		(layer "In2.Cu")
		(net "P3V3_STBY")
	)
	(segment
		(start 76.25334 -139.64666)
		(end 80.19415 -139.64666)
		(width 0.635)
		(layer "In2.Cu")
		(net "P3V3_STBY")
	)
	(segment
		(start 274.222464 -183.485536)
		(end 272.639536 -183.485536)
		(width 0.508)
		(layer "In2.Cu")
		(net "P3V3_STBY")
	)
	(segment
		(start 3.175 -215.646)
		(end 2.032 -216.789)
		(width 0.508)
		(layer "In2.Cu")
		(net "P3V3_STBY")
	)
	(segment
		(start 81.89849 -141.351)
		(end 80.19415 -139.64666)
		(width 0.635)
		(layer "In2.Cu")
		(net "P3V3_STBY")
	)
	(segment
		(start 83.2993 -140.0683)
		(end 86.985602 -140.0683)
		(width 0.635)
		(layer "In2.Cu")
		(net "P3V3_STBY")
	)
	(segment
		(start 30.016196 -100.120196)
		(end 30.016196 -80.473804)
		(width 0.508)
		(layer "In2.Cu")
		(net "P3V3_STBY")
	)
	(segment
		(start 150.495 -41.656)
		(end 155.9814 -47.1424)
		(width 0.508)
		(layer "In2.Cu")
		(net "P3V3_STBY")
	)
	(segment
		(start 302.006 -107.061)
		(end 302.006 -108.331)
		(width 0.508)
		(layer "In2.Cu")
		(net "P3V3_STBY")
	)
	(segment
		(start 245.618 -123.952)
		(end 246.761 -122.809)
		(width 1.016)
		(layer "In2.Cu")
		(net "P3V3_STBY")
	)
	(segment
		(start 82.87766 -139.64666)
		(end 83.2993 -140.0683)
		(width 0.635)
		(layer "In2.Cu")
		(net "P3V3_STBY")
	)
	(segment
		(start 10.668 -215.646)
		(end 3.175 -215.646)
		(width 0.508)
		(layer "In2.Cu")
		(net "P3V3_STBY")
	)
	(segment
		(start 95.029782 -131.572)
		(end 94.107 -131.572)
		(width 1.016)
		(layer "In2.Cu")
		(net "P3V3_STBY")
	)
	(segment
		(start 190.7032 -114.1222)
		(end 192.659 -116.078)
		(width 0.508)
		(layer "In2.Cu")
		(net "P3V3_STBY")
	)
	(segment
		(start 244.729 -136.271)
		(end 236.347 -136.271)
		(width 1.016)
		(layer "In2.Cu")
		(net "P3V3_STBY")
	)
	(segment
		(start 124.1298 -28.956)
		(end 132.5118 -28.956)
		(width 0.508)
		(layer "In2.Cu")
		(net "P3V3_STBY")
	)
	(segment
		(start 308.102 -113.919)
		(end 309.118 -114.935)
		(width 0.508)
		(layer "In2.Cu")
		(net "P3V3_STBY")
	)
	(segment
		(start 330.835 -142.113)
		(end 331.978 -143.256)
		(width 0.508)
		(layer "In2.Cu")
		(net "P3V3_STBY")
	)
	(segment
		(start 14.2494 -213.7664)
		(end 11.7348 -216.281)
		(width 0.508)
		(layer "In2.Cu")
		(net "P3V3_STBY")
	)
	(segment
		(start 86.985602 -140.0683)
		(end 88.192102 -138.8618)
		(width 0.635)
		(layer "In2.Cu")
		(net "P3V3_STBY")
	)
	(segment
		(start 37.846 -121.031)
		(end 37.846 -138.557)
		(width 0.508)
		(layer "In2.Cu")
		(net "P3V3_STBY")
	)
	(segment
		(start 302.006 -108.331)
		(end 303.53 -109.855)
		(width 0.508)
		(layer "In2.Cu")
		(net "P3V3_STBY")
	)
	(segment
		(start 180.21808 -148.6662)
		(end 178.17592 -148.6662)
		(width 1.016)
		(layer "In2.Cu")
		(net "P3V3_STBY")
	)
	(segment
		(start 32.512 -138.1887)
		(end 32.512 -102.616)
		(width 0.508)
		(layer "In2.Cu")
		(net "P3V3_STBY")
	)
	(segment
		(start 24.024336 -212.852)
		(end 23.445216 -212.27288)
		(width 0.508)
		(layer "In2.Cu")
		(net "P3V3_STBY")
	)
	(segment
		(start 39.27475 -139.77366)
		(end 44.327318 -139.77366)
		(width 0.635)
		(layer "In2.Cu")
		(net "P3V3_STBY")
	)
	(segment
		(start 307.975 -111.379)
		(end 308.102 -111.506)
		(width 0.508)
		(layer "In2.Cu")
		(net "P3V3_STBY")
	)
	(segment
		(start 87.757 -141.351)
		(end 81.89849 -141.351)
		(width 0.635)
		(layer "In2.Cu")
		(net "P3V3_STBY")
	)
	(segment
		(start 11.7348 -216.281)
		(end 11.303 -216.281)
		(width 0.508)
		(layer "In2.Cu")
		(net "P3V3_STBY")
	)
	(segment
		(start 254.97536 -136.271)
		(end 251.587 -136.271)
		(width 1.016)
		(layer "In2.Cu")
		(net "P3V3_STBY")
	)
	(segment
		(start 16.714216 -212.27288)
		(end 15.220696 -213.7664)
		(width 0.508)
		(layer "In2.Cu")
		(net "P3V3_STBY")
	)
	(segment
		(start 333.248 -10.922)
		(end 331.724 -10.922)
		(width 0.508)
		(layer "In2.Cu")
		(net "P3V3_STBY")
	)
	(segment
		(start 40.64 -118.237)
		(end 37.846 -121.031)
		(width 0.508)
		(layer "In2.Cu")
		(net "P3V3_STBY")
	)
	(segment
		(start 307.086 -109.855)
		(end 307.975 -110.744)
		(width 0.508)
		(layer "In2.Cu")
		(net "P3V3_STBY")
	)
	(segment
		(start 319.278 -8.382)
		(end 321.056 -10.16)
		(width 0.508)
		(layer "In2.Cu")
		(net "P3V3_STBY")
	)
	(segment
		(start 71.5391 -144.3609)
		(end 76.25334 -139.64666)
		(width 0.635)
		(layer "In2.Cu")
		(net "P3V3_STBY")
	)
	(segment
		(start 155.9814 -47.1424)
		(end 182.753 -47.1424)
		(width 0.508)
		(layer "In2.Cu")
		(net "P3V3_STBY")
	)
	(segment
		(start 37.846 -138.557)
		(end 39.06266 -139.77366)
		(width 0.508)
		(layer "In2.Cu")
		(net "P3V3_STBY")
	)
	(segment
		(start 256.286 -122.809)
		(end 257.175 -123.698)
		(width 1.016)
		(layer "In2.Cu")
		(net "P3V3_STBY")
	)
	(segment
		(start 219.71 -124.079)
		(end 218.821 -124.079)
		(width 0.508)
		(layer "In2.Cu")
		(net "P3V3_STBY")
	)
	(segment
		(start 257.175 -123.698)
		(end 257.556 -123.698)
		(width 1.016)
		(layer "In2.Cu")
		(net "P3V3_STBY")
	)
	(segment
		(start 19.159728 -190.207392)
		(end 19.159728 -192.746376)
		(width 0.508)
		(layer "In5.Cu")
		(net "P3V3_STBY")
	)
	(segment
		(start 307.594 -221.615)
		(end 307.594 -215.265)
		(width 0.508)
		(layer "In5.Cu")
		(net "P3V3_STBY")
	)
	(segment
		(start 15.055088 -200.788016)
		(end 13.869416 -201.973688)
		(width 0.508)
		(layer "In5.Cu")
		(net "P3V3_STBY")
	)
	(segment
		(start 13.869416 -201.973688)
		(end 13.869416 -208.56956)
		(width 0.508)
		(layer "In5.Cu")
		(net "P3V3_STBY")
	)
	(segment
		(start 161.036 -93.410278)
		(end 160.462722 -92.837)
		(width 0.508)
		(layer "In5.Cu")
		(net "P3V3_STBY")
	)
	(segment
		(start 16.714216 -212.316568)
		(end 16.714216 -212.27288)
		(width 0.635)
		(layer "In5.Cu")
		(net "P3V3_STBY")
	)
	(segment
		(start 160.462722 -92.837)
		(end 149.067774 -92.837)
		(width 0.508)
		(layer "In5.Cu")
		(net "P3V3_STBY")
	)
	(segment
		(start 23.445216 -212.27288)
		(end 22.604984 -213.113112)
		(width 0.635)
		(layer "In5.Cu")
		(net "P3V3_STBY")
	)
	(segment
		(start 163.2712 -96.276922)
		(end 161.036 -94.041722)
		(width 0.508)
		(layer "In5.Cu")
		(net "P3V3_STBY")
	)
	(segment
		(start 108.35894 -23.84806)
		(end 105.395776 -26.811224)
		(width 0.508)
		(layer "In5.Cu")
		(net "P3V3_STBY")
	)
	(segment
		(start 22.333712 -215.419178)
		(end 22.333712 -219.861384)
		(width 0.635)
		(layer "In5.Cu")
		(net "P3V3_STBY")
	)
	(segment
		(start 81.661 -26.67)
		(end 80.645 -25.654)
		(width 0.508)
		(layer "In5.Cu")
		(net "P3V3_STBY")
	)
	(segment
		(start 20.651216 -221.54388)
		(end 20.651216 -224.65538)
		(width 0.635)
		(layer "In5.Cu")
		(net "P3V3_STBY")
	)
	(segment
		(start 307.07076 -222.13824)
		(end 307.594 -221.615)
		(width 0.508)
		(layer "In5.Cu")
		(net "P3V3_STBY")
	)
	(segment
		(start 16.714216 -211.41436)
		(end 16.714216 -212.27288)
		(width 0.508)
		(layer "In5.Cu")
		(net "P3V3_STBY")
	)
	(segment
		(start 15.055088 -200.788016)
		(end 16.125952 -200.788016)
		(width 0.508)
		(layer "In5.Cu")
		(net "P3V3_STBY")
	)
	(segment
		(start 18.473928 -185.050176)
		(end 18.473928 -189.521592)
		(width 0.508)
		(layer "In5.Cu")
		(net "P3V3_STBY")
	)
	(segment
		(start 105.395776 -26.811224)
		(end 88.660224 -26.811224)
		(width 0.508)
		(layer "In5.Cu")
		(net "P3V3_STBY")
	)
	(segment
		(start 22.604984 -213.113112)
		(end 20.708112 -213.113112)
		(width 0.635)
		(layer "In5.Cu")
		(net "P3V3_STBY")
	)
	(segment
		(start 303.79924 -222.13824)
		(end 303.784 -222.123)
		(width 0.508)
		(layer "In5.Cu")
		(net "P3V3_STBY")
	)
	(segment
		(start 143.168116 -86.937342)
		(end 143.002 -86.60511)
		(width 0.508)
		(layer "In5.Cu")
		(net "P3V3_STBY")
	)
	(segment
		(start 307.594 -215.265)
		(end 303.784 -215.265)
		(width 0.508)
		(layer "In5.Cu")
		(net "P3V3_STBY")
	)
	(segment
		(start 16.125952 -200.788016)
		(end 20.752816 -205.41488)
		(width 0.508)
		(layer "In5.Cu")
		(net "P3V3_STBY")
	)
	(segment
		(start 149.067774 -92.837)
		(end 143.168116 -86.937342)
		(width 0.508)
		(layer "In5.Cu")
		(net "P3V3_STBY")
	)
	(segment
		(start 124.079 -29.0068)
		(end 118.92026 -23.84806)
		(width 0.508)
		(layer "In5.Cu")
		(net "P3V3_STBY")
	)
	(segment
		(start 143.002 -84.72297)
		(end 143.14297 -84.582)
		(width 0.508)
		(layer "In5.Cu")
		(net "P3V3_STBY")
	)
	(segment
		(start 298.069 -102.87)
		(end 298.323 -102.616)
		(width 0.508)
		(layer "In5.Cu")
		(net "P3V3_STBY")
	)
	(segment
		(start 328.422 -139.7)
		(end 320.929 -139.7)
		(width 0.508)
		(layer "In5.Cu")
		(net "P3V3_STBY")
	)
	(segment
		(start 88.519 -26.67)
		(end 81.661 -26.67)
		(width 0.508)
		(layer "In5.Cu")
		(net "P3V3_STBY")
	)
	(segment
		(start 163.2712 -110.131098)
		(end 163.2712 -96.276922)
		(width 0.508)
		(layer "In5.Cu")
		(net "P3V3_STBY")
	)
	(segment
		(start 298.069 -116.332)
		(end 298.069 -107.315)
		(width 0.508)
		(layer "In5.Cu")
		(net "P3V3_STBY")
	)
	(segment
		(start 297.307 -117.094)
		(end 298.069 -116.332)
		(width 0.508)
		(layer "In5.Cu")
		(net "P3V3_STBY")
	)
	(segment
		(start 20.708112 -213.113112)
		(end 20.066 -212.471)
		(width 0.635)
		(layer "In5.Cu")
		(net "P3V3_STBY")
	)
	(segment
		(start 143.002 -86.60511)
		(end 143.002 -84.72297)
		(width 0.508)
		(layer "In5.Cu")
		(net "P3V3_STBY")
	)
	(segment
		(start 307.07076 -222.13824)
		(end 303.79924 -222.13824)
		(width 0.508)
		(layer "In5.Cu")
		(net "P3V3_STBY")
	)
	(segment
		(start 18.473928 -189.521592)
		(end 19.159728 -190.207392)
		(width 0.508)
		(layer "In5.Cu")
		(net "P3V3_STBY")
	)
	(segment
		(start 19.51482 -213.02218)
		(end 17.419828 -213.02218)
		(width 0.635)
		(layer "In5.Cu")
		(net "P3V3_STBY")
	)
	(segment
		(start 118.92026 -23.84806)
		(end 108.35894 -23.84806)
		(width 0.508)
		(layer "In5.Cu")
		(net "P3V3_STBY")
	)
	(segment
		(start 17.419828 -213.02218)
		(end 16.714216 -212.316568)
		(width 0.635)
		(layer "In5.Cu")
		(net "P3V3_STBY")
	)
	(segment
		(start 13.869416 -208.56956)
		(end 16.714216 -211.41436)
		(width 0.508)
		(layer "In5.Cu")
		(net "P3V3_STBY")
	)
	(segment
		(start 20.752816 -205.41488)
		(end 21.540216 -205.41488)
		(width 0.508)
		(layer "In5.Cu")
		(net "P3V3_STBY")
	)
	(segment
		(start 330.835 -142.113)
		(end 328.422 -139.7)
		(width 0.508)
		(layer "In5.Cu")
		(net "P3V3_STBY")
	)
	(segment
		(start 298.069 -107.315)
		(end 298.069 -102.87)
		(width 0.508)
		(layer "In5.Cu")
		(net "P3V3_STBY")
	)
	(segment
		(start 22.333712 -219.861384)
		(end 20.651216 -221.54388)
		(width 0.635)
		(layer "In5.Cu")
		(net "P3V3_STBY")
	)
	(segment
		(start 88.660224 -26.811224)
		(end 88.519 -26.67)
		(width 0.508)
		(layer "In5.Cu")
		(net "P3V3_STBY")
	)
	(segment
		(start 20.066 -212.471)
		(end 19.51482 -213.02218)
		(width 0.635)
		(layer "In5.Cu")
		(net "P3V3_STBY")
	)
	(segment
		(start 161.036 -94.041722)
		(end 161.036 -93.410278)
		(width 0.508)
		(layer "In5.Cu")
		(net "P3V3_STBY")
	)
	(segment
		(start 19.627088 -183.897016)
		(end 18.473928 -185.050176)
		(width 0.508)
		(layer "In5.Cu")
		(net "P3V3_STBY")
	)
	(segment
		(start 258.4196 -94.803214)
		(end 258.4196 -93.32468)
		(width 0.1143)
		(layer "F.Cu")
		(net "CLK_50M_RMII_PHY")
	)
	(segment
		(start 302.0314 -153.942288)
		(end 302.0314 -145.266664)
		(width 0.1143)
		(layer "F.Cu")
		(net "CLK_50M_RMII_PHY")
	)
	(segment
		(start 276.86 -147.32)
		(end 265.5443 -136.0043)
		(width 0.1143)
		(layer "F.Cu")
		(net "CLK_50M_RMII_PHY")
	)
	(segment
		(start 186.699652 -36.712652)
		(end 187.207652 -36.712652)
		(width 0.1143)
		(layer "F.Cu")
		(net "CLK_50M_RMII_PHY")
	)
	(segment
		(start 187.207652 -36.712652)
		(end 187.325 -36.83)
		(width 0.1143)
		(layer "F.Cu")
		(net "CLK_50M_RMII_PHY")
	)
	(segment
		(start 187.96 -39.37)
		(end 187.579 -38.989)
		(width 0.1143)
		(layer "F.Cu")
		(net "CLK_50M_RMII_PHY")
	)
	(segment
		(start 264.54735 -120.50903)
		(end 264.54735 -100.941378)
		(width 0.1143)
		(layer "F.Cu")
		(net "CLK_50M_RMII_PHY")
	)
	(segment
		(start 281.305 -147.32)
		(end 276.86 -147.32)
		(width 0.1143)
		(layer "F.Cu")
		(net "CLK_50M_RMII_PHY")
	)
	(segment
		(start 300.084236 -143.3195)
		(end 287.5153 -143.3195)
		(width 0.1143)
		(layer "F.Cu")
		(net "CLK_50M_RMII_PHY")
	)
	(segment
		(start 187.579 -38.01999)
		(end 187.578492 -38.019482)
		(width 0.1143)
		(layer "F.Cu")
		(net "CLK_50M_RMII_PHY")
	)
	(segment
		(start 287.5153 -143.3195)
		(end 285.9024 -144.9324)
		(width 0.1143)
		(layer "F.Cu")
		(net "CLK_50M_RMII_PHY")
	)
	(segment
		(start 265.5443 -136.0043)
		(end 265.5443 -121.50598)
		(width 0.1143)
		(layer "F.Cu")
		(net "CLK_50M_RMII_PHY")
	)
	(segment
		(start 204.46492 -39.37)
		(end 187.96 -39.37)
		(width 0.1143)
		(layer "F.Cu")
		(net "CLK_50M_RMII_PHY")
	)
	(segment
		(start 185.756804 -36.12515)
		(end 186.11215 -36.12515)
		(width 0.1143)
		(layer "F.Cu")
		(net "CLK_50M_RMII_PHY")
	)
	(segment
		(start 264.541 -100.935028)
		(end 264.541 -100.924614)
		(width 0.1143)
		(layer "F.Cu")
		(net "CLK_50M_RMII_PHY")
	)
	(segment
		(start 186.11215 -36.12515)
		(end 186.699652 -36.712652)
		(width 0.1143)
		(layer "F.Cu")
		(net "CLK_50M_RMII_PHY")
	)
	(segment
		(start 264.541 -100.924614)
		(end 258.4196 -94.803214)
		(width 0.1143)
		(layer "F.Cu")
		(net "CLK_50M_RMII_PHY")
	)
	(segment
		(start 185.065924 -35.43427)
		(end 185.756804 -36.12515)
		(width 0.1143)
		(layer "F.Cu")
		(net "CLK_50M_RMII_PHY")
	)
	(segment
		(start 187.579 -38.989)
		(end 187.579 -38.01999)
		(width 0.1143)
		(layer "F.Cu")
		(net "CLK_50M_RMII_PHY")
	)
	(segment
		(start 264.54735 -100.941378)
		(end 264.541 -100.935028)
		(width 0.1143)
		(layer "F.Cu")
		(net "CLK_50M_RMII_PHY")
	)
	(segment
		(start 299.703236 -154.856688)
		(end 301.117 -154.856688)
		(width 0.1143)
		(layer "F.Cu")
		(net "CLK_50M_RMII_PHY")
	)
	(segment
		(start 187.578492 -38.019482)
		(end 187.578492 -37.083492)
		(width 0.1143)
		(layer "F.Cu")
		(net "CLK_50M_RMII_PHY")
	)
	(segment
		(start 187.578492 -37.083492)
		(end 187.325 -36.83)
		(width 0.1143)
		(layer "F.Cu")
		(net "CLK_50M_RMII_PHY")
	)
	(segment
		(start 301.117 -154.856688)
		(end 302.0314 -153.942288)
		(width 0.1143)
		(layer "F.Cu")
		(net "CLK_50M_RMII_PHY")
	)
	(segment
		(start 185.065924 -34.235136)
		(end 185.065924 -35.43427)
		(width 0.1143)
		(layer "F.Cu")
		(net "CLK_50M_RMII_PHY")
	)
	(segment
		(start 302.0314 -145.266664)
		(end 300.084236 -143.3195)
		(width 0.1143)
		(layer "F.Cu")
		(net "CLK_50M_RMII_PHY")
	)
	(segment
		(start 265.5443 -121.50598)
		(end 264.54735 -120.50903)
		(width 0.1143)
		(layer "F.Cu")
		(net "CLK_50M_RMII_PHY")
	)
	(segment
		(start 258.4196 -93.32468)
		(end 204.46492 -39.37)
		(width 0.1143)
		(layer "F.Cu")
		(net "CLK_50M_RMII_PHY")
	)
	(via
		(at 285.9024 -144.9324)
		(size 0.5588)
		(drill 0.3048)
		(layers "F.Cu" "B.Cu")
		(net "CLK_50M_RMII_PHY")
	)
	(via
		(at 281.305 -147.32)
		(size 0.5588)
		(drill 0.3048)
		(layers "F.Cu" "B.Cu")
		(net "CLK_50M_RMII_PHY")
	)
	(via
		(at 187.325 -36.83)
		(size 0.7112)
		(drill 0.3556)
		(layers "F.Cu" "B.Cu")
		(net "CLK_50M_RMII_PHY")
	)
	(segment
		(start 281.305 -147.32)
		(end 283.6926 -144.9324)
		(width 0.127)
		(layer "In5.Cu")
		(net "CLK_50M_RMII_PHY")
	)
	(segment
		(start 283.6926 -144.9324)
		(end 285.9024 -144.9324)
		(width 0.127)
		(layer "In5.Cu")
		(net "CLK_50M_RMII_PHY")
	)
	(segment
		(start 30.874716 -222.418656)
		(end 30.874716 -227.38588)
		(width 0.1143)
		(layer "F.Cu")
		(net "SAS_HDD_PWR6")
	)
	(segment
		(start 30.874716 -227.38588)
		(end 30.8864 -227.397564)
		(width 0.1143)
		(layer "F.Cu")
		(net "SAS_HDD_PWR6")
	)
	(segment
		(start 27.15514 -218.69908)
		(end 30.874716 -222.418656)
		(width 0.1143)
		(layer "F.Cu")
		(net "SAS_HDD_PWR6")
	)
	(segment
		(start 24.283162 -216.714578)
		(end 24.283162 -218.190826)
		(width 0.1143)
		(layer "F.Cu")
		(net "SAS_HDD_PWR6")
	)
	(segment
		(start 30.874716 -227.409248)
		(end 30.8864 -227.397564)
		(width 0.1143)
		(layer "F.Cu")
		(net "SAS_HDD_PWR6")
	)
	(segment
		(start 24.283162 -218.190826)
		(end 24.791416 -218.69908)
		(width 0.1143)
		(layer "F.Cu")
		(net "SAS_HDD_PWR6")
	)
	(segment
		(start 24.791416 -218.69908)
		(end 27.15514 -218.69908)
		(width 0.1143)
		(layer "F.Cu")
		(net "SAS_HDD_PWR6")
	)
	(segment
		(start 30.874716 -228.96068)
		(end 30.874716 -227.409248)
		(width 0.1143)
		(layer "F.Cu")
		(net "SAS_HDD_PWR6")
	)
	(via
		(at 30.8864 -227.397564)
		(size 0.5588)
		(drill 0.3048)
		(layers "F.Cu" "B.Cu")
		(net "SAS_HDD_PWR6")
	)
	(via
		(at 31.217616 -230.58628)
		(size 0.7112)
		(drill 0.3556)
		(layers "F.Cu" "B.Cu")
		(net "SAS_HDD_PWR6")
	)
	(segment
		(start 31.446216 -230.81488)
		(end 31.217616 -230.58628)
		(width 0.1143)
		(layer "B.Cu")
		(net "SAS_HDD_PWR6")
	)
	(segment
		(start 31.446216 -231.89438)
		(end 31.446216 -230.81488)
		(width 0.1143)
		(layer "B.Cu")
		(net "SAS_HDD_PWR6")
	)
	(segment
		(start 30.874716 -230.24338)
		(end 31.217616 -230.58628)
		(width 0.1143)
		(layer "B.Cu")
		(net "SAS_HDD_PWR6")
	)
	(segment
		(start 30.8864 -227.397564)
		(end 30.874716 -227.409248)
		(width 0.1143)
		(layer "B.Cu")
		(net "SAS_HDD_PWR6")
	)
	(segment
		(start 30.874716 -227.409248)
		(end 30.874716 -230.24338)
		(width 0.1143)
		(layer "B.Cu")
		(net "SAS_HDD_PWR6")
	)
	(segment
		(start 179.039774 -29.42336)
		(end 178.117246 -29.42336)
		(width 0.1397)
		(layer "F.Cu")
		(net "BCM5221_TX_C_DN")
	)
	(segment
		(start 174.110396 -26.295096)
		(end 174.179992 -26.2255)
		(width 0.1397)
		(layer "F.Cu")
		(net "BCM5221_TX_C_DN")
	)
	(segment
		(start 173.120304 -26.295096)
		(end 174.110396 -26.295096)
		(width 0.1397)
		(layer "F.Cu")
		(net "BCM5221_TX_C_DN")
	)
	(segment
		(start 177.553112 -29.18968)
		(end 177.184812 -28.82138)
		(width 0.1397)
		(layer "F.Cu")
		(net "BCM5221_TX_C_DN")
	)
	(segment
		(start 176.044098 -25.831546)
		(end 174.789592 -25.831546)
		(width 0.1397)
		(layer "F.Cu")
		(net "BCM5221_TX_C_DN")
	)
	(segment
		(start 174.037244 -27.405076)
		(end 174.037244 -29.200856)
		(width 0.1397)
		(layer "F.Cu")
		(net "BCM5221_TX_C_DN")
	)
	(segment
		(start 176.817782 -26.41981)
		(end 176.360582 -25.96261)
		(width 0.1397)
		(layer "F.Cu")
		(net "BCM5221_TX_C_DN")
	)
	(segment
		(start 176.935892 -28.220416)
		(end 176.935892 -26.705052)
		(width 0.1397)
		(layer "F.Cu")
		(net "BCM5221_TX_C_DN")
	)
	(segment
		(start 174.075344 -27.250136)
		(end 174.075344 -27.366976)
		(width 0.1397)
		(layer "F.Cu")
		(net "BCM5221_TX_C_DN")
	)
	(segment
		(start 174.179992 -26.225246)
		(end 174.179992 -26.2255)
		(width 0.1397)
		(layer "F.Cu")
		(net "BCM5221_TX_C_DN")
	)
	(segment
		(start 179.18811 -29.519118)
		(end 179.129436 -29.460444)
		(width 0.1397)
		(layer "F.Cu")
		(net "BCM5221_TX_C_DN")
	)
	(segment
		(start 174.421292 -25.983946)
		(end 174.179992 -26.225246)
		(width 0.1397)
		(layer "F.Cu")
		(net "BCM5221_TX_C_DN")
	)
	(segment
		(start 174.075344 -27.366976)
		(end 174.037244 -27.405076)
		(width 0.1397)
		(layer "F.Cu")
		(net "BCM5221_TX_C_DN")
	)
	(segment
		(start 179.886864 -29.556202)
		(end 179.277772 -29.556202)
		(width 0.1397)
		(layer "F.Cu")
		(net "BCM5221_TX_C_DN")
	)
	(segment
		(start 173.120304 -26.295096)
		(end 174.075344 -27.250136)
		(width 0.1397)
		(layer "F.Cu")
		(net "BCM5221_TX_C_DN")
	)
	(arc
		(start 176.360582 -25.96261)
		(mid 176.215378 -25.865588)
		(end 176.044098 -25.831546)
		(width 0.1397)
		(layer "F.Cu")
		(net "BCM5221_TX_C_DN")
	)
	(arc
		(start 177.184812 -28.82138)
		(mid 177.000632 -28.545641)
		(end 176.935892 -28.220416)
		(width 0.1397)
		(layer "F.Cu")
		(net "BCM5221_TX_C_DN")
	)
	(arc
		(start 176.935892 -26.705052)
		(mid 176.905189 -26.550696)
		(end 176.817782 -26.41981)
		(width 0.1397)
		(layer "F.Cu")
		(net "BCM5221_TX_C_DN")
	)
	(arc
		(start 179.277772 -29.556202)
		(mid 179.229254 -29.546569)
		(end 179.18811 -29.519118)
		(width 0.1397)
		(layer "F.Cu")
		(net "BCM5221_TX_C_DN")
	)
	(arc
		(start 178.117246 -29.42336)
		(mid 177.811975 -29.362562)
		(end 177.553112 -29.18968)
		(width 0.1397)
		(layer "F.Cu")
		(net "BCM5221_TX_C_DN")
	)
	(arc
		(start 179.129436 -29.460444)
		(mid 179.088285 -29.433011)
		(end 179.039774 -29.42336)
		(width 0.1397)
		(layer "F.Cu")
		(net "BCM5221_TX_C_DN")
	)
	(arc
		(start 174.789592 -25.831546)
		(mid 174.590275 -25.871099)
		(end 174.421292 -25.983946)
		(width 0.1397)
		(layer "F.Cu")
		(net "BCM5221_TX_C_DN")
	)
	(segment
		(start 290.062158 -185.088784)
		(end 290.062158 -186.340242)
		(width 0.1143)
		(layer "F.Cu")
		(net "MEMBA_1")
	)
	(segment
		(start 289.473894 -187.621418)
		(end 289.473894 -187.782962)
		(width 0.1143)
		(layer "F.Cu")
		(net "MEMBA_1")
	)
	(segment
		(start 288.790888 -188.502798)
		(end 288.790888 -188.664342)
		(width 0.1143)
		(layer "F.Cu")
		(net "MEMBA_1")
	)
	(segment
		(start 290.062158 -186.340242)
		(end 289.20821 -187.19419)
		(width 0.1143)
		(layer "F.Cu")
		(net "MEMBA_1")
	)
	(segment
		(start 287.29813 -196.93509)
		(end 287.29813 -196.66331)
		(width 0.1143)
		(layer "F.Cu")
		(net "MEMBA_1")
	)
	(segment
		(start 289.20821 -187.19419)
		(end 289.20821 -187.355734)
		(width 0.1143)
		(layer "F.Cu")
		(net "MEMBA_1")
	)
	(segment
		(start 288.884868 -187.679076)
		(end 288.723324 -187.679076)
		(width 0.1143)
		(layer "F.Cu")
		(net "MEMBA_1")
	)
	(segment
		(start 288.426144 -188.1378)
		(end 288.790888 -188.502798)
		(width 0.1143)
		(layer "F.Cu")
		(net "MEMBA_1")
	)
	(segment
		(start 286.997394 -189.6364)
		(end 286.674814 -189.6364)
		(width 0.1143)
		(layer "F.Cu")
		(net "MEMBA_1")
	)
	(segment
		(start 287.294574 -189.107826)
		(end 286.997394 -189.405006)
		(width 0.1143)
		(layer "F.Cu")
		(net "MEMBA_1")
	)
	(segment
		(start 286.674814 -189.6364)
		(end 286.426402 -189.884812)
		(width 0.1143)
		(layer "F.Cu")
		(net "MEMBA_1")
	)
	(segment
		(start 288.102802 -188.461142)
		(end 287.941258 -188.461142)
		(width 0.1143)
		(layer "F.Cu")
		(net "MEMBA_1")
	)
	(segment
		(start 289.20821 -187.355734)
		(end 289.473894 -187.621418)
		(width 0.1143)
		(layer "F.Cu")
		(net "MEMBA_1")
	)
	(segment
		(start 288.144204 -189.149482)
		(end 288.144204 -189.311026)
		(width 0.1143)
		(layer "F.Cu")
		(net "MEMBA_1")
	)
	(segment
		(start 289.473894 -187.782962)
		(end 289.312096 -187.94476)
		(width 0.1143)
		(layer "F.Cu")
		(net "MEMBA_1")
	)
	(segment
		(start 288.426144 -187.976256)
		(end 288.426144 -188.1378)
		(width 0.1143)
		(layer "F.Cu")
		(net "MEMBA_1")
	)
	(segment
		(start 286.93618 -196.30136)
		(end 286.93618 -195.334636)
		(width 0.1143)
		(layer "F.Cu")
		(net "MEMBA_1")
	)
	(segment
		(start 287.820862 -189.472824)
		(end 287.456118 -189.107826)
		(width 0.1143)
		(layer "F.Cu")
		(net "MEMBA_1")
	)
	(segment
		(start 287.77946 -188.62294)
		(end 287.77946 -188.784484)
		(width 0.1143)
		(layer "F.Cu")
		(net "MEMBA_1")
	)
	(segment
		(start 290.898326 -183.77662)
		(end 290.898326 -184.252616)
		(width 0.1143)
		(layer "F.Cu")
		(net "MEMBA_1")
	)
	(segment
		(start 288.467546 -188.82614)
		(end 288.102802 -188.461142)
		(width 0.1143)
		(layer "F.Cu")
		(net "MEMBA_1")
	)
	(segment
		(start 286.997394 -189.405006)
		(end 286.997394 -189.6364)
		(width 0.1143)
		(layer "F.Cu")
		(net "MEMBA_1")
	)
	(segment
		(start 288.723324 -187.679076)
		(end 288.426144 -187.976256)
		(width 0.1143)
		(layer "F.Cu")
		(net "MEMBA_1")
	)
	(segment
		(start 289.150552 -187.94476)
		(end 288.884868 -187.679076)
		(width 0.1143)
		(layer "F.Cu")
		(net "MEMBA_1")
	)
	(segment
		(start 291.234876 -183.44007)
		(end 290.898326 -183.77662)
		(width 0.1143)
		(layer "F.Cu")
		(net "MEMBA_1")
	)
	(segment
		(start 289.312096 -187.94476)
		(end 289.150552 -187.94476)
		(width 0.1143)
		(layer "F.Cu")
		(net "MEMBA_1")
	)
	(segment
		(start 288.62909 -188.82614)
		(end 288.467546 -188.82614)
		(width 0.1143)
		(layer "F.Cu")
		(net "MEMBA_1")
	)
	(segment
		(start 285.9786 -194.377056)
		(end 285.9786 -194.1068)
		(width 0.1143)
		(layer "F.Cu")
		(net "MEMBA_1")
	)
	(segment
		(start 287.982406 -189.472824)
		(end 287.820862 -189.472824)
		(width 0.1143)
		(layer "F.Cu")
		(net "MEMBA_1")
	)
	(segment
		(start 287.456118 -189.107826)
		(end 287.294574 -189.107826)
		(width 0.1143)
		(layer "F.Cu")
		(net "MEMBA_1")
	)
	(segment
		(start 286.426402 -189.884812)
		(end 285.744412 -189.884812)
		(width 0.1143)
		(layer "F.Cu")
		(net "MEMBA_1")
	)
	(segment
		(start 287.77946 -188.784484)
		(end 288.144204 -189.149482)
		(width 0.1143)
		(layer "F.Cu")
		(net "MEMBA_1")
	)
	(segment
		(start 287.941258 -188.461142)
		(end 287.77946 -188.62294)
		(width 0.1143)
		(layer "F.Cu")
		(net "MEMBA_1")
	)
	(segment
		(start 290.898326 -184.252616)
		(end 290.062158 -185.088784)
		(width 0.1143)
		(layer "F.Cu")
		(net "MEMBA_1")
	)
	(segment
		(start 288.144204 -189.311026)
		(end 287.982406 -189.472824)
		(width 0.1143)
		(layer "F.Cu")
		(net "MEMBA_1")
	)
	(segment
		(start 286.93618 -195.334636)
		(end 285.9786 -194.377056)
		(width 0.1143)
		(layer "F.Cu")
		(net "MEMBA_1")
	)
	(segment
		(start 287.29813 -196.66331)
		(end 286.93618 -196.30136)
		(width 0.1143)
		(layer "F.Cu")
		(net "MEMBA_1")
	)
	(segment
		(start 288.790888 -188.664342)
		(end 288.62909 -188.82614)
		(width 0.1143)
		(layer "F.Cu")
		(net "MEMBA_1")
	)
	(via
		(at 285.9786 -194.1068)
		(size 0.508)
		(drill 0.254)
		(layers "F.Cu" "B.Cu")
		(net "MEMBA_1")
	)
	(via
		(at 286.997394 -189.6364)
		(size 0.7112)
		(drill 0.3556)
		(layers "F.Cu" "B.Cu")
		(net "MEMBA_1")
	)
	(via
		(at 285.744412 -189.884812)
		(size 0.508)
		(drill 0.254)
		(layers "F.Cu" "B.Cu")
		(net "MEMBA_1")
	)
	(segment
		(start 285.744412 -189.884812)
		(end 285.744412 -190.208408)
		(width 0.1143)
		(layer "B.Cu")
		(net "MEMBA_1")
	)
	(segment
		(start 285.68269 -193.08699)
		(end 285.56839 -193.20129)
		(width 0.1143)
		(layer "B.Cu")
		(net "MEMBA_1")
	)
	(segment
		(start 285.68269 -192.62979)
		(end 285.7246 -192.62979)
		(width 0.1143)
		(layer "B.Cu")
		(net "MEMBA_1")
	)
	(segment
		(start 285.8389 -192.97269)
		(end 285.7246 -193.08699)
		(width 0.1143)
		(layer "B.Cu")
		(net "MEMBA_1")
	)
	(segment
		(start 285.56839 -192.51549)
		(end 285.68269 -192.62979)
		(width 0.1143)
		(layer "B.Cu")
		(net "MEMBA_1")
	)
	(segment
		(start 285.8389 -192.74409)
		(end 285.8389 -192.97269)
		(width 0.1143)
		(layer "B.Cu")
		(net "MEMBA_1")
	)
	(segment
		(start 285.56839 -193.20129)
		(end 285.56839 -193.62039)
		(width 0.1143)
		(layer "B.Cu")
		(net "MEMBA_1")
	)
	(segment
		(start 285.7246 -192.62979)
		(end 285.8389 -192.74409)
		(width 0.1143)
		(layer "B.Cu")
		(net "MEMBA_1")
	)
	(segment
		(start 285.9786 -194.0306)
		(end 285.9786 -194.1068)
		(width 0.1143)
		(layer "B.Cu")
		(net "MEMBA_1")
	)
	(segment
		(start 285.7246 -193.08699)
		(end 285.68269 -193.08699)
		(width 0.1143)
		(layer "B.Cu")
		(net "MEMBA_1")
	)
	(segment
		(start 285.56839 -190.38443)
		(end 285.56839 -192.51549)
		(width 0.1143)
		(layer "B.Cu")
		(net "MEMBA_1")
	)
	(segment
		(start 285.744412 -190.208408)
		(end 285.56839 -190.38443)
		(width 0.1143)
		(layer "B.Cu")
		(net "MEMBA_1")
	)
	(segment
		(start 285.56839 -193.62039)
		(end 285.9786 -194.0306)
		(width 0.1143)
		(layer "B.Cu")
		(net "MEMBA_1")
	)
	(segment
		(start 14.67358 -233.35742)
		(end 14.67358 -234.184952)
		(width 0.1143)
		(layer "F.Cu")
		(net "SAS_HDD_PWR13_PCIE")
	)
	(segment
		(start 19.043142 -232.502202)
		(end 15.528798 -232.502202)
		(width 0.1143)
		(layer "F.Cu")
		(net "SAS_HDD_PWR13_PCIE")
	)
	(segment
		(start 31.999936 -256.25044)
		(end 31.999936 -249.679714)
		(width 0.1143)
		(layer "F.Cu")
		(net "SAS_HDD_PWR13_PCIE")
	)
	(segment
		(start 14.67358 -236.902244)
		(end 14.67358 -234.184952)
		(width 0.1143)
		(layer "F.Cu")
		(net "SAS_HDD_PWR13_PCIE")
	)
	(segment
		(start 19.9136 -237.593378)
		(end 19.9136 -233.37266)
		(width 0.1143)
		(layer "F.Cu")
		(net "SAS_HDD_PWR13_PCIE")
	)
	(segment
		(start 15.528798 -232.502202)
		(end 14.67358 -233.35742)
		(width 0.1143)
		(layer "F.Cu")
		(net "SAS_HDD_PWR13_PCIE")
	)
	(segment
		(start 31.999936 -249.679714)
		(end 19.9136 -237.593378)
		(width 0.1143)
		(layer "F.Cu")
		(net "SAS_HDD_PWR13_PCIE")
	)
	(segment
		(start 19.9136 -233.37266)
		(end 19.043142 -232.502202)
		(width 0.1143)
		(layer "F.Cu")
		(net "SAS_HDD_PWR13_PCIE")
	)
	(via
		(at 14.67358 -235.33608)
		(size 0.7112)
		(drill 0.3556)
		(layers "F.Cu" "B.Cu")
		(net "SAS_HDD_PWR13_PCIE")
	)
	(via
		(at 14.67358 -236.902244)
		(size 0.5588)
		(drill 0.3048)
		(layers "F.Cu" "B.Cu")
		(net "SAS_HDD_PWR13_PCIE")
	)
	(segment
		(start 14.67358 -236.902244)
		(end 14.67358 -235.33608)
		(width 0.1143)
		(layer "B.Cu")
		(net "SAS_HDD_PWR13_PCIE")
	)
	(segment
		(start 14.67358 -232.457752)
		(end 14.67358 -235.33608)
		(width 0.1143)
		(layer "B.Cu")
		(net "SAS_HDD_PWR13_PCIE")
	)
	(segment
		(start 14.48308 -232.267252)
		(end 14.67358 -232.457752)
		(width 0.1143)
		(layer "B.Cu")
		(net "SAS_HDD_PWR13_PCIE")
	)
	(segment
		(start 91.565222 -252.622812)
		(end 90.874596 -251.932186)
		(width 0.1143)
		(layer "F.Cu")
		(net "FAN_PWM_PCIE")
	)
	(segment
		(start 83.57997 -141.2875)
		(end 83.57997 -144.653)
		(width 0.1143)
		(layer "F.Cu")
		(net "FAN_PWM_PCIE")
	)
	(segment
		(start 86.331552 -148.942552)
		(end 86.331552 -155.419552)
		(width 0.1143)
		(layer "F.Cu")
		(net "FAN_PWM_PCIE")
	)
	(segment
		(start 311.531 -182.499)
		(end 312.166 -181.864)
		(width 0.1143)
		(layer "F.Cu")
		(net "FAN_PWM_PCIE")
	)
	(segment
		(start 86.331552 -164.465)
		(end 86.995 -165.128448)
		(width 0.1143)
		(layer "F.Cu")
		(net "FAN_PWM_PCIE")
	)
	(segment
		(start 90.874596 -248.454418)
		(end 91.223338 -248.105676)
		(width 0.1143)
		(layer "F.Cu")
		(net "FAN_PWM_PCIE")
	)
	(segment
		(start 311.3405 -182.499)
		(end 311.531 -182.499)
		(width 0.1143)
		(layer "F.Cu")
		(net "FAN_PWM_PCIE")
	)
	(segment
		(start 91.565222 -253.091188)
		(end 91.565222 -252.622812)
		(width 0.1143)
		(layer "F.Cu")
		(net "FAN_PWM_PCIE")
	)
	(segment
		(start 86.331552 -155.419552)
		(end 86.331552 -164.465)
		(width 0.1143)
		(layer "F.Cu")
		(net "FAN_PWM_PCIE")
	)
	(segment
		(start 91.223338 -248.105676)
		(end 91.244928 -248.053352)
		(width 0.1143)
		(layer "F.Cu")
		(net "FAN_PWM_PCIE")
	)
	(segment
		(start 90.874596 -251.932186)
		(end 90.874596 -248.454418)
		(width 0.1143)
		(layer "F.Cu")
		(net "FAN_PWM_PCIE")
	)
	(segment
		(start 91.000072 -256.25044)
		(end 91.000072 -253.656338)
		(width 0.1143)
		(layer "F.Cu")
		(net "FAN_PWM_PCIE")
	)
	(segment
		(start 91.244928 -248.053352)
		(end 91.270582 -247.991884)
		(width 0.1143)
		(layer "F.Cu")
		(net "FAN_PWM_PCIE")
	)
	(segment
		(start 91.270582 -247.991884)
		(end 91.694 -247.568466)
		(width 0.1143)
		(layer "F.Cu")
		(net "FAN_PWM_PCIE")
	)
	(segment
		(start 91.000072 -253.656338)
		(end 91.565222 -253.091188)
		(width 0.1143)
		(layer "F.Cu")
		(net "FAN_PWM_PCIE")
	)
	(segment
		(start 91.694 -247.568466)
		(end 91.694 -247.396)
		(width 0.1143)
		(layer "F.Cu")
		(net "FAN_PWM_PCIE")
	)
	(segment
		(start 86.995 -165.128448)
		(end 86.995 -165.862)
		(width 0.1143)
		(layer "F.Cu")
		(net "FAN_PWM_PCIE")
	)
	(via
		(at 267.335 -196.4309)
		(size 0.5588)
		(drill 0.3048)
		(layers "F.Cu" "B.Cu")
		(net "FAN_PWM_PCIE")
	)
	(via
		(at 91.694 -247.396)
		(size 0.5588)
		(drill 0.3048)
		(layers "F.Cu" "B.Cu")
		(net "FAN_PWM_PCIE")
	)
	(via
		(at 86.331552 -148.942552)
		(size 0.5588)
		(drill 0.3048)
		(layers "F.Cu" "B.Cu")
		(net "FAN_PWM_PCIE")
	)
	(via
		(at 83.57997 -144.653)
		(size 0.5588)
		(drill 0.3048)
		(layers "F.Cu" "B.Cu")
		(net "FAN_PWM_PCIE")
	)
	(via
		(at 86.995 -165.862)
		(size 0.5588)
		(drill 0.3048)
		(layers "F.Cu" "B.Cu")
		(net "FAN_PWM_PCIE")
	)
	(via
		(at 86.331552 -155.419552)
		(size 0.7112)
		(drill 0.3556)
		(layers "F.Cu" "B.Cu")
		(net "FAN_PWM_PCIE")
	)
	(via
		(at 312.166 -181.864)
		(size 0.5588)
		(drill 0.3048)
		(layers "F.Cu" "B.Cu")
		(net "FAN_PWM_PCIE")
	)
	(via
		(at 70.6247 -243.459)
		(size 0.5588)
		(drill 0.3048)
		(layers "F.Cu" "B.Cu")
		(net "FAN_PWM_PCIE")
	)
	(via
		(at 267.589 -157.607)
		(size 0.5588)
		(drill 0.3048)
		(layers "F.Cu" "B.Cu")
		(net "FAN_PWM_PCIE")
	)
	(segment
		(start 70.8914 -242.225068)
		(end 70.751446 -242.365022)
		(width 0.1143)
		(layer "B.Cu")
		(net "FAN_PWM_PCIE")
	)
	(segment
		(start 70.8914 -220.253814)
		(end 70.8914 -242.225068)
		(width 0.1143)
		(layer "B.Cu")
		(net "FAN_PWM_PCIE")
	)
	(segment
		(start 86.995 -165.862)
		(end 82.63255 -170.22445)
		(width 0.1143)
		(layer "B.Cu")
		(net "FAN_PWM_PCIE")
	)
	(segment
		(start 82.63255 -208.512918)
		(end 71.137018 -220.00845)
		(width 0.1143)
		(layer "B.Cu")
		(net "FAN_PWM_PCIE")
	)
	(segment
		(start 71.136764 -220.00845)
		(end 70.8914 -220.253814)
		(width 0.1143)
		(layer "B.Cu")
		(net "FAN_PWM_PCIE")
	)
	(segment
		(start 70.751446 -243.332254)
		(end 70.6247 -243.459)
		(width 0.1143)
		(layer "B.Cu")
		(net "FAN_PWM_PCIE")
	)
	(segment
		(start 70.751446 -242.365022)
		(end 70.751446 -243.332254)
		(width 0.1143)
		(layer "B.Cu")
		(net "FAN_PWM_PCIE")
	)
	(segment
		(start 71.137018 -220.00845)
		(end 71.136764 -220.00845)
		(width 0.1143)
		(layer "B.Cu")
		(net "FAN_PWM_PCIE")
	)
	(segment
		(start 82.63255 -170.22445)
		(end 82.63255 -208.512918)
		(width 0.1143)
		(layer "B.Cu")
		(net "FAN_PWM_PCIE")
	)
	(segment
		(start 173.038262 -162.052)
		(end 191.184784 -162.052)
		(width 0.127)
		(layer "In2.Cu")
		(net "FAN_PWM_PCIE")
	)
	(segment
		(start 193.851784 -159.385)
		(end 226.9744 -159.385)
		(width 0.127)
		(layer "In2.Cu")
		(net "FAN_PWM_PCIE")
	)
	(segment
		(start 300.159166 -188.087)
		(end 304.988468 -188.087)
		(width 0.127)
		(layer "In2.Cu")
		(net "FAN_PWM_PCIE")
	)
	(segment
		(start 70.6247 -243.459)
		(end 70.739 -243.459)
		(width 0.127)
		(layer "In2.Cu")
		(net "FAN_PWM_PCIE")
	)
	(segment
		(start 270.221202 -199.7583)
		(end 278.970232 -199.7583)
		(width 0.127)
		(layer "In2.Cu")
		(net "FAN_PWM_PCIE")
	)
	(segment
		(start 191.184784 -162.052)
		(end 193.851784 -159.385)
		(width 0.127)
		(layer "In2.Cu")
		(net "FAN_PWM_PCIE")
	)
	(segment
		(start 278.970232 -199.7583)
		(end 285.815532 -192.913)
		(width 0.127)
		(layer "In2.Cu")
		(net "FAN_PWM_PCIE")
	)
	(segment
		(start 295.333166 -192.913)
		(end 300.159166 -188.087)
		(width 0.127)
		(layer "In2.Cu")
		(net "FAN_PWM_PCIE")
	)
	(segment
		(start 93.187012 -148.970492)
		(end 106.01452 -161.798)
		(width 0.127)
		(layer "In2.Cu")
		(net "FAN_PWM_PCIE")
	)
	(segment
		(start 267.335 -196.4309)
		(end 268.5415 -197.6374)
		(width 0.127)
		(layer "In2.Cu")
		(net "FAN_PWM_PCIE")
	)
	(segment
		(start 268.5415 -197.6374)
		(end 268.5415 -198.078598)
		(width 0.127)
		(layer "In2.Cu")
		(net "FAN_PWM_PCIE")
	)
	(segment
		(start 171.326302 -162.814)
		(end 171.453556 -162.686746)
		(width 0.127)
		(layer "In2.Cu")
		(net "FAN_PWM_PCIE")
	)
	(segment
		(start 72.263 -244.983)
		(end 74.422 -244.983)
		(width 0.127)
		(layer "In2.Cu")
		(net "FAN_PWM_PCIE")
	)
	(segment
		(start 70.739 -243.459)
		(end 72.263 -244.983)
		(width 0.127)
		(layer "In2.Cu")
		(net "FAN_PWM_PCIE")
	)
	(segment
		(start 106.014774 -161.798)
		(end 106.129328 -161.9123)
		(width 0.127)
		(layer "In2.Cu")
		(net "FAN_PWM_PCIE")
	)
	(segment
		(start 304.988468 -188.087)
		(end 310.830468 -182.245)
		(width 0.127)
		(layer "In2.Cu")
		(net "FAN_PWM_PCIE")
	)
	(segment
		(start 154.134312 -161.9123)
		(end 155.036012 -162.814)
		(width 0.127)
		(layer "In2.Cu")
		(net "FAN_PWM_PCIE")
	)
	(segment
		(start 74.422 -244.983)
		(end 76.835 -247.396)
		(width 0.127)
		(layer "In2.Cu")
		(net "FAN_PWM_PCIE")
	)
	(segment
		(start 310.830468 -182.245)
		(end 311.785 -182.245)
		(width 0.127)
		(layer "In2.Cu")
		(net "FAN_PWM_PCIE")
	)
	(segment
		(start 106.129328 -161.9123)
		(end 154.134312 -161.9123)
		(width 0.127)
		(layer "In2.Cu")
		(net "FAN_PWM_PCIE")
	)
	(segment
		(start 172.478192 -161.975546)
		(end 172.961808 -161.975546)
		(width 0.127)
		(layer "In2.Cu")
		(net "FAN_PWM_PCIE")
	)
	(segment
		(start 285.815532 -192.913)
		(end 295.333166 -192.913)
		(width 0.127)
		(layer "In2.Cu")
		(net "FAN_PWM_PCIE")
	)
	(segment
		(start 106.01452 -161.798)
		(end 106.014774 -161.798)
		(width 0.127)
		(layer "In2.Cu")
		(net "FAN_PWM_PCIE")
	)
	(segment
		(start 226.9744 -159.385)
		(end 229.1334 -157.226)
		(width 0.127)
		(layer "In2.Cu")
		(net "FAN_PWM_PCIE")
	)
	(segment
		(start 93.141038 -148.970492)
		(end 93.187012 -148.970492)
		(width 0.127)
		(layer "In2.Cu")
		(net "FAN_PWM_PCIE")
	)
	(segment
		(start 268.5415 -198.078598)
		(end 270.221202 -199.7583)
		(width 0.127)
		(layer "In2.Cu")
		(net "FAN_PWM_PCIE")
	)
	(segment
		(start 93.113098 -148.942552)
		(end 93.141038 -148.970492)
		(width 0.127)
		(layer "In2.Cu")
		(net "FAN_PWM_PCIE")
	)
	(segment
		(start 171.766992 -162.686746)
		(end 172.478192 -161.975546)
		(width 0.127)
		(layer "In2.Cu")
		(net "FAN_PWM_PCIE")
	)
	(segment
		(start 311.785 -182.245)
		(end 312.166 -181.864)
		(width 0.127)
		(layer "In2.Cu")
		(net "FAN_PWM_PCIE")
	)
	(segment
		(start 245.1735 -157.6705)
		(end 267.5255 -157.6705)
		(width 0.127)
		(layer "In2.Cu")
		(net "FAN_PWM_PCIE")
	)
	(segment
		(start 155.036012 -162.814)
		(end 171.326302 -162.814)
		(width 0.127)
		(layer "In2.Cu")
		(net "FAN_PWM_PCIE")
	)
	(segment
		(start 267.5255 -157.6705)
		(end 267.589 -157.607)
		(width 0.127)
		(layer "In2.Cu")
		(net "FAN_PWM_PCIE")
	)
	(segment
		(start 86.331552 -148.942552)
		(end 93.113098 -148.942552)
		(width 0.127)
		(layer "In2.Cu")
		(net "FAN_PWM_PCIE")
	)
	(segment
		(start 172.961808 -161.975546)
		(end 173.038262 -162.052)
		(width 0.127)
		(layer "In2.Cu")
		(net "FAN_PWM_PCIE")
	)
	(segment
		(start 171.453556 -162.686746)
		(end 171.766992 -162.686746)
		(width 0.127)
		(layer "In2.Cu")
		(net "FAN_PWM_PCIE")
	)
	(segment
		(start 76.835 -247.396)
		(end 91.694 -247.396)
		(width 0.127)
		(layer "In2.Cu")
		(net "FAN_PWM_PCIE")
	)
	(segment
		(start 229.1334 -157.226)
		(end 244.729 -157.226)
		(width 0.127)
		(layer "In2.Cu")
		(net "FAN_PWM_PCIE")
	)
	(segment
		(start 244.729 -157.226)
		(end 245.1735 -157.6705)
		(width 0.127)
		(layer "In2.Cu")
		(net "FAN_PWM_PCIE")
	)
	(segment
		(start 267.589 -157.607)
		(end 266.192 -159.004)
		(width 0.127)
		(layer "In5.Cu")
		(net "FAN_PWM_PCIE")
	)
	(segment
		(start 265.8999 -194.9958)
		(end 267.335 -196.4309)
		(width 0.127)
		(layer "In5.Cu")
		(net "FAN_PWM_PCIE")
	)
	(segment
		(start 86.331552 -148.942552)
		(end 86.331552 -147.404582)
		(width 0.127)
		(layer "In5.Cu")
		(net "FAN_PWM_PCIE")
	)
	(segment
		(start 266.192 -165.481)
		(end 265.8999 -165.7731)
		(width 0.127)
		(layer "In5.Cu")
		(net "FAN_PWM_PCIE")
	)
	(segment
		(start 266.192 -159.004)
		(end 266.192 -165.481)
		(width 0.127)
		(layer "In5.Cu")
		(net "FAN_PWM_PCIE")
	)
	(segment
		(start 265.8999 -165.7731)
		(end 265.8999 -194.9958)
		(width 0.127)
		(layer "In5.Cu")
		(net "FAN_PWM_PCIE")
	)
	(segment
		(start 86.331552 -147.404582)
		(end 83.57997 -144.653)
		(width 0.127)
		(layer "In5.Cu")
		(net "FAN_PWM_PCIE")
	)
	(segment
		(start 173.183804 -25.215596)
		(end 174.059088 -25.215596)
		(width 0.1397)
		(layer "F.Cu")
		(net "BCM5221_TX_C_DP")
	)
	(segment
		(start 174.072804 -24.113236)
		(end 174.743364 -23.442676)
		(width 0.1397)
		(layer "F.Cu")
		(net "BCM5221_TX_C_DP")
	)
	(segment
		(start 177.278792 -26.705052)
		(end 177.278792 -28.220162)
		(width 0.1397)
		(layer "F.Cu")
		(net "BCM5221_TX_C_DP")
	)
	(segment
		(start 174.059088 -25.215596)
		(end 174.179992 -25.3365)
		(width 0.1397)
		(layer "F.Cu")
		(net "BCM5221_TX_C_DP")
	)
	(segment
		(start 173.120304 -25.152096)
		(end 174.072804 -24.199596)
		(width 0.1397)
		(layer "F.Cu")
		(net "BCM5221_TX_C_DP")
	)
	(segment
		(start 178.1175 -29.08046)
		(end 179.032408 -29.08046)
		(width 0.1397)
		(layer "F.Cu")
		(net "BCM5221_TX_C_DP")
	)
	(segment
		(start 179.091336 -29.056076)
		(end 179.886864 -29.056076)
		(width 0.1397)
		(layer "F.Cu")
		(net "BCM5221_TX_C_DP")
	)
	(segment
		(start 176.603152 -25.72004)
		(end 177.060352 -26.17724)
		(width 0.1397)
		(layer "F.Cu")
		(net "BCM5221_TX_C_DP")
	)
	(segment
		(start 174.743364 -23.442676)
		(end 174.743364 -22.490176)
		(width 0.1397)
		(layer "F.Cu")
		(net "BCM5221_TX_C_DP")
	)
	(segment
		(start 174.547276 -25.488646)
		(end 176.044098 -25.488646)
		(width 0.1397)
		(layer "F.Cu")
		(net "BCM5221_TX_C_DP")
	)
	(segment
		(start 174.072804 -24.199596)
		(end 174.072804 -24.113236)
		(width 0.1397)
		(layer "F.Cu")
		(net "BCM5221_TX_C_DP")
	)
	(segment
		(start 177.427382 -28.57881)
		(end 177.795682 -28.94711)
		(width 0.1397)
		(layer "F.Cu")
		(net "BCM5221_TX_C_DP")
	)
	(segment
		(start 173.120304 -25.152096)
		(end 173.183804 -25.215596)
		(width 0.1397)
		(layer "F.Cu")
		(net "BCM5221_TX_C_DP")
	)
	(arc
		(start 176.044098 -25.488646)
		(mid 176.346643 -25.548732)
		(end 176.603152 -25.72004)
		(width 0.1397)
		(layer "F.Cu")
		(net "BCM5221_TX_C_DP")
	)
	(arc
		(start 177.278792 -28.220162)
		(mid 177.317403 -28.414274)
		(end 177.427382 -28.57881)
		(width 0.1397)
		(layer "F.Cu")
		(net "BCM5221_TX_C_DP")
	)
	(arc
		(start 177.060352 -26.17724)
		(mid 177.222077 -26.419417)
		(end 177.278792 -26.705052)
		(width 0.1397)
		(layer "F.Cu")
		(net "BCM5221_TX_C_DP")
	)
	(arc
		(start 174.179992 -25.3365)
		(mid 174.348503 -25.449096)
		(end 174.547276 -25.488646)
		(width 0.1397)
		(layer "F.Cu")
		(net "BCM5221_TX_C_DP")
	)
	(arc
		(start 179.032408 -29.08046)
		(mid 179.059444 -29.062395)
		(end 179.091336 -29.056076)
		(width 0.1397)
		(layer "F.Cu")
		(net "BCM5221_TX_C_DP")
	)
	(arc
		(start 177.795682 -28.94711)
		(mid 177.943333 -29.045767)
		(end 178.1175 -29.08046)
		(width 0.1397)
		(layer "F.Cu")
		(net "BCM5221_TX_C_DP")
	)
	(segment
		(start 23.632922 -225.978466)
		(end 23.632922 -224.33788)
		(width 0.1143)
		(layer "F.Cu")
		(net "SAS_HDD_PWR14")
	)
	(segment
		(start 22.102572 -227.508816)
		(end 23.632922 -225.978466)
		(width 0.1143)
		(layer "F.Cu")
		(net "SAS_HDD_PWR14")
	)
	(segment
		(start 15.06728 -227.508816)
		(end 22.102572 -227.508816)
		(width 0.1143)
		(layer "F.Cu")
		(net "SAS_HDD_PWR14")
	)
	(segment
		(start 14.67358 -229.790244)
		(end 14.67358 -228.952552)
		(width 0.1143)
		(layer "F.Cu")
		(net "SAS_HDD_PWR14")
	)
	(segment
		(start 15.444216 -230.56088)
		(end 14.67358 -229.790244)
		(width 0.1143)
		(layer "F.Cu")
		(net "SAS_HDD_PWR14")
	)
	(segment
		(start 23.632922 -224.33788)
		(end 23.632922 -222.325438)
		(width 0.1143)
		(layer "F.Cu")
		(net "SAS_HDD_PWR14")
	)
	(segment
		(start 14.67358 -227.902516)
		(end 15.06728 -227.508816)
		(width 0.1143)
		(layer "F.Cu")
		(net "SAS_HDD_PWR14")
	)
	(segment
		(start 14.67358 -228.952552)
		(end 14.67358 -227.902516)
		(width 0.1143)
		(layer "F.Cu")
		(net "SAS_HDD_PWR14")
	)
	(via
		(at 23.632922 -224.33788)
		(size 0.7112)
		(drill 0.3556)
		(layers "F.Cu" "B.Cu")
		(net "SAS_HDD_PWR14")
	)
	(via
		(at 15.444216 -230.56088)
		(size 0.5588)
		(drill 0.3048)
		(layers "F.Cu" "B.Cu")
		(net "SAS_HDD_PWR14")
	)
	(segment
		(start 15.62608 -231.378252)
		(end 15.444216 -231.196388)
		(width 0.1143)
		(layer "B.Cu")
		(net "SAS_HDD_PWR14")
	)
	(segment
		(start 15.444216 -231.196388)
		(end 15.444216 -230.56088)
		(width 0.1143)
		(layer "B.Cu")
		(net "SAS_HDD_PWR14")
	)
	(segment
		(start 179.759864 -33.663128)
		(end 179.759864 -33.556194)
		(width 0.127)
		(layer "F.Cu")
		(net "NC_PHY_ENGY_DET")
	)
	(segment
		(start 178.552856 -34.870136)
		(end 179.759864 -33.663128)
		(width 0.127)
		(layer "F.Cu")
		(net "NC_PHY_ENGY_DET")
	)
	(segment
		(start 177.727864 -34.870136)
		(end 178.552856 -34.870136)
		(width 0.127)
		(layer "F.Cu")
		(net "NC_PHY_ENGY_DET")
	)
	(segment
		(start 294.009318 -200.935082)
		(end 294.1066 -200.8378)
		(width 0.1143)
		(layer "F.Cu")
		(net "MEMDQ_7")
	)
	(segment
		(start 294.0558 -183.02859)
		(end 294.041322 -183.043068)
		(width 0.1143)
		(layer "F.Cu")
		(net "MEMDQ_7")
	)
	(segment
		(start 294.1066 -200.8378)
		(end 294.1066 -200.128378)
		(width 0.1143)
		(layer "F.Cu")
		(net "MEMDQ_7")
	)
	(segment
		(start 294.1066 -200.128378)
		(end 294.155368 -200.07961)
		(width 0.1143)
		(layer "F.Cu")
		(net "MEMDQ_7")
	)
	(segment
		(start 293.698168 -200.935082)
		(end 294.009318 -200.935082)
		(width 0.1143)
		(layer "F.Cu")
		(net "MEMDQ_7")
	)
	(segment
		(start 294.0558 -183.019192)
		(end 294.0558 -183.02859)
		(width 0.1143)
		(layer "F.Cu")
		(net "MEMDQ_7")
	)
	(segment
		(start 294.434768 -182.640224)
		(end 294.0558 -183.019192)
		(width 0.1143)
		(layer "F.Cu")
		(net "MEMDQ_7")
	)
	(via
		(at 294.041322 -183.043068)
		(size 0.508)
		(drill 0.254)
		(layers "F.Cu" "B.Cu")
		(net "MEMDQ_7")
	)
	(via
		(at 294.091614 -199.32015)
		(size 0.7112)
		(drill 0.3556)
		(layers "F.Cu" "B.Cu")
		(net "MEMDQ_7")
	)
	(via
		(at 294.155368 -200.07961)
		(size 0.508)
		(drill 0.254)
		(layers "F.Cu" "B.Cu")
		(net "MEMDQ_7")
	)
	(segment
		(start 294.155368 -199.383904)
		(end 294.091614 -199.32015)
		(width 0.1143)
		(layer "B.Cu")
		(net "MEMDQ_7")
	)
	(segment
		(start 294.155368 -200.07961)
		(end 294.155368 -199.383904)
		(width 0.1143)
		(layer "B.Cu")
		(net "MEMDQ_7")
	)
	(segment
		(start 294.201088 -197.304152)
		(end 294.543734 -196.961506)
		(width 0.127)
		(layer "In5.Cu")
		(net "MEMDQ_7")
	)
	(segment
		(start 294.168322 -185.013346)
		(end 294.6908 -185.013346)
		(width 0.127)
		(layer "In5.Cu")
		(net "MEMDQ_7")
	)
	(segment
		(start 294.155368 -200.07961)
		(end 294.155368 -199.473058)
		(width 0.127)
		(layer "In5.Cu")
		(net "MEMDQ_7")
	)
	(segment
		(start 293.70528 -194.326764)
		(end 293.70528 -193.384424)
		(width 0.127)
		(layer "In5.Cu")
		(net "MEMDQ_7")
	)
	(segment
		(start 294.5257 -186.635136)
		(end 294.5257 -185.878724)
		(width 0.127)
		(layer "In5.Cu")
		(net "MEMDQ_7")
	)
	(segment
		(start 294.8178 -184.886346)
		(end 294.8178 -184.632346)
		(width 0.127)
		(layer "In5.Cu")
		(net "MEMDQ_7")
	)
	(segment
		(start 294.041322 -185.140346)
		(end 294.168322 -185.013346)
		(width 0.127)
		(layer "In5.Cu")
		(net "MEMDQ_7")
	)
	(segment
		(start 293.7129 -194.334384)
		(end 293.70528 -194.326764)
		(width 0.127)
		(layer "In5.Cu")
		(net "MEMDQ_7")
	)
	(segment
		(start 294.543734 -196.961506)
		(end 294.543734 -196.150484)
		(width 0.127)
		(layer "In5.Cu")
		(net "MEMDQ_7")
	)
	(segment
		(start 294.041322 -185.394346)
		(end 294.041322 -185.140346)
		(width 0.127)
		(layer "In5.Cu")
		(net "MEMDQ_7")
	)
	(segment
		(start 293.2684 -189.652402)
		(end 294.8305 -188.090302)
		(width 0.127)
		(layer "In5.Cu")
		(net "MEMDQ_7")
	)
	(segment
		(start 294.8178 -184.632346)
		(end 294.6908 -184.505346)
		(width 0.127)
		(layer "In5.Cu")
		(net "MEMDQ_7")
	)
	(segment
		(start 294.6908 -184.505346)
		(end 294.168322 -184.505346)
		(width 0.127)
		(layer "In5.Cu")
		(net "MEMDQ_7")
	)
	(segment
		(start 294.155368 -199.473058)
		(end 294.201088 -199.427338)
		(width 0.127)
		(layer "In5.Cu")
		(net "MEMDQ_7")
	)
	(segment
		(start 294.168322 -184.505346)
		(end 294.041322 -184.378346)
		(width 0.127)
		(layer "In5.Cu")
		(net "MEMDQ_7")
	)
	(segment
		(start 294.6908 -185.013346)
		(end 294.8178 -184.886346)
		(width 0.127)
		(layer "In5.Cu")
		(net "MEMDQ_7")
	)
	(segment
		(start 293.70528 -193.384424)
		(end 293.2684 -192.947544)
		(width 0.127)
		(layer "In5.Cu")
		(net "MEMDQ_7")
	)
	(segment
		(start 294.201088 -199.427338)
		(end 294.201088 -197.304152)
		(width 0.127)
		(layer "In5.Cu")
		(net "MEMDQ_7")
	)
	(segment
		(start 294.8305 -188.090302)
		(end 294.8305 -186.939936)
		(width 0.127)
		(layer "In5.Cu")
		(net "MEMDQ_7")
	)
	(segment
		(start 294.041322 -184.378346)
		(end 294.041322 -183.043068)
		(width 0.127)
		(layer "In5.Cu")
		(net "MEMDQ_7")
	)
	(segment
		(start 294.5257 -185.878724)
		(end 294.041322 -185.394346)
		(width 0.127)
		(layer "In5.Cu")
		(net "MEMDQ_7")
	)
	(segment
		(start 293.7129 -195.68795)
		(end 293.7129 -194.334384)
		(width 0.127)
		(layer "In5.Cu")
		(net "MEMDQ_7")
	)
	(segment
		(start 293.97325 -195.9483)
		(end 293.7129 -195.68795)
		(width 0.127)
		(layer "In5.Cu")
		(net "MEMDQ_7")
	)
	(segment
		(start 294.8305 -186.939936)
		(end 294.5257 -186.635136)
		(width 0.127)
		(layer "In5.Cu")
		(net "MEMDQ_7")
	)
	(segment
		(start 294.34155 -195.9483)
		(end 293.97325 -195.9483)
		(width 0.127)
		(layer "In5.Cu")
		(net "MEMDQ_7")
	)
	(segment
		(start 293.2684 -192.947544)
		(end 293.2684 -189.652402)
		(width 0.127)
		(layer "In5.Cu")
		(net "MEMDQ_7")
	)
	(segment
		(start 294.543734 -196.150484)
		(end 294.34155 -195.9483)
		(width 0.127)
		(layer "In5.Cu")
		(net "MEMDQ_7")
	)
	(segment
		(start 35.788092 -246.352568)
		(end 41.000426 -251.564902)
		(width 0.1143)
		(layer "F.Cu")
		(net "SAS_HDD_PWR6_PCIE")
	)
	(segment
		(start 41.000426 -251.564902)
		(end 41.000426 -256.25044)
		(width 0.1143)
		(layer "F.Cu")
		(net "SAS_HDD_PWR6_PCIE")
	)
	(segment
		(start 31.509716 -233.39933)
		(end 32.626046 -232.283)
		(width 0.1143)
		(layer "F.Cu")
		(net "SAS_HDD_PWR6_PCIE")
	)
	(segment
		(start 35.788092 -234.035092)
		(end 35.788092 -246.352568)
		(width 0.1143)
		(layer "F.Cu")
		(net "SAS_HDD_PWR6_PCIE")
	)
	(segment
		(start 31.509716 -236.847634)
		(end 31.509716 -234.19308)
		(width 0.1143)
		(layer "F.Cu")
		(net "SAS_HDD_PWR6_PCIE")
	)
	(segment
		(start 34.036 -232.283)
		(end 35.788092 -234.035092)
		(width 0.1143)
		(layer "F.Cu")
		(net "SAS_HDD_PWR6_PCIE")
	)
	(segment
		(start 32.626046 -232.283)
		(end 34.036 -232.283)
		(width 0.1143)
		(layer "F.Cu")
		(net "SAS_HDD_PWR6_PCIE")
	)
	(segment
		(start 31.509716 -234.19308)
		(end 31.509716 -233.39933)
		(width 0.1143)
		(layer "F.Cu")
		(net "SAS_HDD_PWR6_PCIE")
	)
	(segment
		(start 31.520892 -236.85881)
		(end 31.509716 -236.847634)
		(width 0.1143)
		(layer "F.Cu")
		(net "SAS_HDD_PWR6_PCIE")
	)
	(via
		(at 31.520892 -236.85881)
		(size 0.5588)
		(drill 0.3048)
		(layers "F.Cu" "B.Cu")
		(net "SAS_HDD_PWR6_PCIE")
	)
	(via
		(at 31.446216 -235.13288)
		(size 0.7112)
		(drill 0.3556)
		(layers "F.Cu" "B.Cu")
		(net "SAS_HDD_PWR6_PCIE")
	)
	(segment
		(start 31.446216 -235.13288)
		(end 31.446216 -236.784134)
		(width 0.1143)
		(layer "B.Cu")
		(net "SAS_HDD_PWR6_PCIE")
	)
	(segment
		(start 31.446216 -236.784134)
		(end 31.520892 -236.85881)
		(width 0.1143)
		(layer "B.Cu")
		(net "SAS_HDD_PWR6_PCIE")
	)
	(segment
		(start 31.446216 -232.78338)
		(end 31.446216 -235.13288)
		(width 0.1143)
		(layer "B.Cu")
		(net "SAS_HDD_PWR6_PCIE")
	)
	(segment
		(start 182.06593 -34.235136)
		(end 182.06593 -36.056062)
		(width 0.127)
		(layer "F.Cu")
		(net "PHY_AD3")
	)
	(segment
		(start 182.06593 -36.056062)
		(end 181.799992 -36.322)
		(width 0.127)
		(layer "F.Cu")
		(net "PHY_AD3")
	)
	(segment
		(start 181.283864 -36.838128)
		(end 181.799992 -36.322)
		(width 0.127)
		(layer "F.Cu")
		(net "PHY_AD3")
	)
	(segment
		(start 181.283864 -37.727636)
		(end 181.283864 -36.838128)
		(width 0.127)
		(layer "F.Cu")
		(net "PHY_AD3")
	)
	(via
		(at 181.799992 -36.322)
		(size 0.7112)
		(drill 0.3556)
		(layers "F.Cu" "B.Cu")
		(net "PHY_AD3")
	)
	(segment
		(start 288.097976 -200.935082)
		(end 288.097976 -200.320656)
		(width 0.1143)
		(layer "F.Cu")
		(net "MEMBA_2")
	)
	(segment
		(start 290.574222 -182.303674)
		(end 290.089082 -182.303674)
		(width 0.1143)
		(layer "F.Cu")
		(net "MEMBA_2")
	)
	(segment
		(start 288.07283 -200.29551)
		(end 288.07283 -200.2663)
		(width 0.1143)
		(layer "F.Cu")
		(net "MEMBA_2")
	)
	(segment
		(start 290.910772 -182.640224)
		(end 290.574222 -182.303674)
		(width 0.1143)
		(layer "F.Cu")
		(net "MEMBA_2")
	)
	(segment
		(start 290.089082 -182.303674)
		(end 290.03498 -182.249572)
		(width 0.1143)
		(layer "F.Cu")
		(net "MEMBA_2")
	)
	(segment
		(start 288.097976 -200.320656)
		(end 288.07283 -200.29551)
		(width 0.1143)
		(layer "F.Cu")
		(net "MEMBA_2")
	)
	(segment
		(start 291.234876 -182.640224)
		(end 290.910772 -182.640224)
		(width 0.1143)
		(layer "F.Cu")
		(net "MEMBA_2")
	)
	(via
		(at 290.03498 -182.249572)
		(size 0.508)
		(drill 0.254)
		(layers "F.Cu" "B.Cu")
		(net "MEMBA_2")
	)
	(via
		(at 289.708844 -184.2262)
		(size 0.7112)
		(drill 0.3556)
		(layers "F.Cu" "B.Cu")
		(net "MEMBA_2")
	)
	(via
		(at 288.07283 -200.2663)
		(size 0.508)
		(drill 0.254)
		(layers "F.Cu" "B.Cu")
		(net "MEMBA_2")
	)
	(segment
		(start 289.637216 -182.599584)
		(end 289.987228 -182.249572)
		(width 0.1016)
		(layer "B.Cu")
		(net "MEMBA_2")
	)
	(segment
		(start 289.6108 -188.26988)
		(end 289.6108 -187.02401)
		(width 0.1143)
		(layer "B.Cu")
		(net "MEMBA_2")
	)
	(segment
		(start 289.4076 -194.344036)
		(end 289.6235 -194.128136)
		(width 0.1143)
		(layer "B.Cu")
		(net "MEMBA_2")
	)
	(segment
		(start 289.708844 -183.435244)
		(end 289.637216 -183.363616)
		(width 0.1143)
		(layer "B.Cu")
		(net "MEMBA_2")
	)
	(segment
		(start 288.07283 -200.2663)
		(end 288.07283 -199.923146)
		(width 0.1143)
		(layer "B.Cu")
		(net "MEMBA_2")
	)
	(segment
		(start 289.4076 -195.754752)
		(end 289.4076 -194.344036)
		(width 0.1143)
		(layer "B.Cu")
		(net "MEMBA_2")
	)
	(segment
		(start 289.708844 -186.925966)
		(end 289.708844 -184.2262)
		(width 0.1143)
		(layer "B.Cu")
		(net "MEMBA_2")
	)
	(segment
		(start 288.165794 -198.148956)
		(end 288.3916 -197.92315)
		(width 0.1143)
		(layer "B.Cu")
		(net "MEMBA_2")
	)
	(segment
		(start 288.35985 -199.626474)
		(end 288.35985 -199.063102)
		(width 0.1143)
		(layer "B.Cu")
		(net "MEMBA_2")
	)
	(segment
		(start 288.3916 -196.770752)
		(end 289.4076 -195.754752)
		(width 0.1143)
		(layer "B.Cu")
		(net "MEMBA_2")
	)
	(segment
		(start 290.10737 -193.411856)
		(end 290.10737 -189.113922)
		(width 0.1143)
		(layer "B.Cu")
		(net "MEMBA_2")
	)
	(segment
		(start 289.708844 -184.2262)
		(end 289.708844 -183.435244)
		(width 0.1143)
		(layer "B.Cu")
		(net "MEMBA_2")
	)
	(segment
		(start 290.107624 -189.113668)
		(end 290.107624 -188.766704)
		(width 0.1143)
		(layer "B.Cu")
		(net "MEMBA_2")
	)
	(segment
		(start 289.6108 -187.02401)
		(end 289.708844 -186.925966)
		(width 0.1143)
		(layer "B.Cu")
		(net "MEMBA_2")
	)
	(segment
		(start 288.20237 -199.783954)
		(end 288.35985 -199.626474)
		(width 0.1143)
		(layer "B.Cu")
		(net "MEMBA_2")
	)
	(segment
		(start 288.07283 -199.923146)
		(end 288.20237 -199.793606)
		(width 0.1143)
		(layer "B.Cu")
		(net "MEMBA_2")
	)
	(segment
		(start 289.987228 -182.249572)
		(end 290.03498 -182.249572)
		(width 0.1016)
		(layer "B.Cu")
		(net "MEMBA_2")
	)
	(segment
		(start 289.96386 -193.558668)
		(end 289.96386 -193.555366)
		(width 0.1143)
		(layer "B.Cu")
		(net "MEMBA_2")
	)
	(segment
		(start 290.107624 -188.766704)
		(end 289.6108 -188.26988)
		(width 0.1143)
		(layer "B.Cu")
		(net "MEMBA_2")
	)
	(segment
		(start 290.10737 -189.113922)
		(end 290.107624 -189.113668)
		(width 0.1143)
		(layer "B.Cu")
		(net "MEMBA_2")
	)
	(segment
		(start 289.793426 -193.732912)
		(end 289.793426 -193.729102)
		(width 0.1143)
		(layer "B.Cu")
		(net "MEMBA_2")
	)
	(segment
		(start 289.793426 -193.729102)
		(end 289.96386 -193.558668)
		(width 0.1143)
		(layer "B.Cu")
		(net "MEMBA_2")
	)
	(segment
		(start 288.20237 -199.793606)
		(end 288.20237 -199.783954)
		(width 0.1143)
		(layer "B.Cu")
		(net "MEMBA_2")
	)
	(segment
		(start 289.6235 -194.128136)
		(end 289.6235 -193.902838)
		(width 0.1143)
		(layer "B.Cu")
		(net "MEMBA_2")
	)
	(segment
		(start 288.3916 -197.92315)
		(end 288.3916 -196.770752)
		(width 0.1143)
		(layer "B.Cu")
		(net "MEMBA_2")
	)
	(segment
		(start 289.6235 -193.902838)
		(end 289.793426 -193.732912)
		(width 0.1143)
		(layer "B.Cu")
		(net "MEMBA_2")
	)
	(segment
		(start 289.96386 -193.555366)
		(end 290.10737 -193.411856)
		(width 0.1143)
		(layer "B.Cu")
		(net "MEMBA_2")
	)
	(segment
		(start 289.637216 -183.363616)
		(end 289.637216 -182.599584)
		(width 0.1016)
		(layer "B.Cu")
		(net "MEMBA_2")
	)
	(segment
		(start 288.165794 -198.869046)
		(end 288.165794 -198.148956)
		(width 0.1143)
		(layer "B.Cu")
		(net "MEMBA_2")
	)
	(segment
		(start 288.35985 -199.063102)
		(end 288.165794 -198.869046)
		(width 0.1143)
		(layer "B.Cu")
		(net "MEMBA_2")
	)
	(segment
		(start 19.083782 -218.706446)
		(end 21.286216 -220.90888)
		(width 0.1143)
		(layer "F.Cu")
		(net "SAS_HDD_PWR0")
	)
	(segment
		(start 27.064716 -226.39528)
		(end 27.064716 -227.51288)
		(width 0.1143)
		(layer "F.Cu")
		(net "SAS_HDD_PWR0")
	)
	(segment
		(start 27.598116 -222.26778)
		(end 27.598116 -225.86188)
		(width 0.1143)
		(layer "F.Cu")
		(net "SAS_HDD_PWR0")
	)
	(segment
		(start 27.064716 -227.51288)
		(end 27.064716 -228.96068)
		(width 0.1143)
		(layer "F.Cu")
		(net "SAS_HDD_PWR0")
	)
	(segment
		(start 21.286216 -220.90888)
		(end 26.239216 -220.90888)
		(width 0.1143)
		(layer "F.Cu")
		(net "SAS_HDD_PWR0")
	)
	(segment
		(start 26.239216 -220.90888)
		(end 27.598116 -222.26778)
		(width 0.1143)
		(layer "F.Cu")
		(net "SAS_HDD_PWR0")
	)
	(segment
		(start 27.598116 -225.86188)
		(end 27.064716 -226.39528)
		(width 0.1143)
		(layer "F.Cu")
		(net "SAS_HDD_PWR0")
	)
	(segment
		(start 19.083782 -216.714578)
		(end 19.083782 -218.706446)
		(width 0.1143)
		(layer "F.Cu")
		(net "SAS_HDD_PWR0")
	)
	(via
		(at 26.241248 -229.796848)
		(size 0.7112)
		(drill 0.3556)
		(layers "F.Cu" "B.Cu")
		(net "SAS_HDD_PWR0")
	)
	(via
		(at 27.064716 -227.51288)
		(size 0.5588)
		(drill 0.3048)
		(layers "F.Cu" "B.Cu")
		(net "SAS_HDD_PWR0")
	)
	(segment
		(start 25.350216 -230.68788)
		(end 26.241248 -229.796848)
		(width 0.1143)
		(layer "B.Cu")
		(net "SAS_HDD_PWR0")
	)
	(segment
		(start 27.064716 -228.97338)
		(end 26.241248 -229.796848)
		(width 0.1143)
		(layer "B.Cu")
		(net "SAS_HDD_PWR0")
	)
	(segment
		(start 25.350216 -231.89438)
		(end 25.350216 -230.68788)
		(width 0.1143)
		(layer "B.Cu")
		(net "SAS_HDD_PWR0")
	)
	(segment
		(start 27.064716 -227.51288)
		(end 27.064716 -228.97338)
		(width 0.1143)
		(layer "B.Cu")
		(net "SAS_HDD_PWR0")
	)
	(segment
		(start 290.668964 -188.061092)
		(end 290.668964 -188.222636)
		(width 0.1143)
		(layer "F.Cu")
		(net "MEMA_0")
	)
	(segment
		(start 291.139626 -184.352692)
		(end 290.481258 -185.01106)
		(width 0.1143)
		(layer "F.Cu")
		(net "MEMA_0")
	)
	(segment
		(start 291.139626 -184.33542)
		(end 291.139626 -184.352692)
		(width 0.1143)
		(layer "F.Cu")
		(net "MEMA_0")
	)
	(segment
		(start 290.668964 -188.222636)
		(end 290.507166 -188.384434)
		(width 0.1143)
		(layer "F.Cu")
		(net "MEMA_0")
	)
	(segment
		(start 287.17494 -200.360788)
		(end 287.17494 -200.36028)
		(width 0.1143)
		(layer "F.Cu")
		(net "MEMA_0")
	)
	(segment
		(start 290.481258 -186.479942)
		(end 290.309808 -186.651392)
		(width 0.1143)
		(layer "F.Cu")
		(net "MEMA_0")
	)
	(segment
		(start 289.6362 -189.2554)
		(end 289.5854 -189.3062)
		(width 0.1143)
		(layer "F.Cu")
		(net "MEMA_0")
	)
	(segment
		(start 290.345622 -188.384434)
		(end 289.986466 -188.025278)
		(width 0.1143)
		(layer "F.Cu")
		(net "MEMA_0")
	)
	(segment
		(start 291.234876 -184.24017)
		(end 291.139626 -184.33542)
		(width 0.1143)
		(layer "F.Cu")
		(net "MEMA_0")
	)
	(segment
		(start 290.481258 -185.01106)
		(end 290.481258 -186.479942)
		(width 0.1143)
		(layer "F.Cu")
		(net "MEMA_0")
	)
	(segment
		(start 290.507166 -188.384434)
		(end 290.345622 -188.384434)
		(width 0.1143)
		(layer "F.Cu")
		(net "MEMA_0")
	)
	(segment
		(start 290.02228 -188.707776)
		(end 290.02228 -188.86932)
		(width 0.1143)
		(layer "F.Cu")
		(net "MEMA_0")
	)
	(segment
		(start 289.663124 -188.187076)
		(end 289.663124 -188.34862)
		(width 0.1143)
		(layer "F.Cu")
		(net "MEMA_0")
	)
	(segment
		(start 289.663124 -188.34862)
		(end 290.02228 -188.707776)
		(width 0.1143)
		(layer "F.Cu")
		(net "MEMA_0")
	)
	(segment
		(start 290.02228 -188.86932)
		(end 289.6362 -189.2554)
		(width 0.1143)
		(layer "F.Cu")
		(net "MEMA_0")
	)
	(segment
		(start 287.29813 -200.935082)
		(end 287.29813 -200.483978)
		(width 0.1143)
		(layer "F.Cu")
		(net "MEMA_0")
	)
	(segment
		(start 290.309808 -186.651392)
		(end 290.309808 -187.701936)
		(width 0.1143)
		(layer "F.Cu")
		(net "MEMA_0")
	)
	(segment
		(start 290.309808 -187.701936)
		(end 290.668964 -188.061092)
		(width 0.1143)
		(layer "F.Cu")
		(net "MEMA_0")
	)
	(segment
		(start 287.29813 -200.483978)
		(end 287.17494 -200.360788)
		(width 0.1143)
		(layer "F.Cu")
		(net "MEMA_0")
	)
	(segment
		(start 289.824922 -188.025278)
		(end 289.663124 -188.187076)
		(width 0.1143)
		(layer "F.Cu")
		(net "MEMA_0")
	)
	(segment
		(start 289.5854 -189.3062)
		(end 288.80562 -189.3062)
		(width 0.1143)
		(layer "F.Cu")
		(net "MEMA_0")
	)
	(segment
		(start 289.986466 -188.025278)
		(end 289.824922 -188.025278)
		(width 0.1143)
		(layer "F.Cu")
		(net "MEMA_0")
	)
	(via
		(at 288.80562 -189.3062)
		(size 0.508)
		(drill 0.254)
		(layers "F.Cu" "B.Cu")
		(net "MEMA_0")
	)
	(via
		(at 287.17494 -200.36028)
		(size 0.508)
		(drill 0.254)
		(layers "F.Cu" "B.Cu")
		(net "MEMA_0")
	)
	(via
		(at 289.6362 -189.2554)
		(size 0.7112)
		(drill 0.3556)
		(layers "F.Cu" "B.Cu")
		(net "MEMA_0")
	)
	(segment
		(start 287.17494 -200.36028)
		(end 287.17494 -199.00138)
		(width 0.1143)
		(layer "B.Cu")
		(net "MEMA_0")
	)
	(segment
		(start 288.244026 -193.0908)
		(end 288.80562 -192.529206)
		(width 0.1143)
		(layer "B.Cu")
		(net "MEMA_0")
	)
	(segment
		(start 288.24428 -194.365372)
		(end 288.24428 -193.44132)
		(width 0.1143)
		(layer "B.Cu")
		(net "MEMA_0")
	)
	(segment
		(start 287.6677 -197.55358)
		(end 287.6677 -196.470524)
		(width 0.1143)
		(layer "B.Cu")
		(net "MEMA_0")
	)
	(segment
		(start 288.544 -194.665092)
		(end 288.24428 -194.365372)
		(width 0.1143)
		(layer "B.Cu")
		(net "MEMA_0")
	)
	(segment
		(start 286.87903 -198.34225)
		(end 287.6677 -197.55358)
		(width 0.1143)
		(layer "B.Cu")
		(net "MEMA_0")
	)
	(segment
		(start 287.17494 -199.00138)
		(end 286.87903 -198.70547)
		(width 0.1143)
		(layer "B.Cu")
		(net "MEMA_0")
	)
	(segment
		(start 287.6677 -196.470524)
		(end 288.544 -195.594224)
		(width 0.1143)
		(layer "B.Cu")
		(net "MEMA_0")
	)
	(segment
		(start 288.24428 -193.44132)
		(end 288.244026 -193.441066)
		(width 0.1143)
		(layer "B.Cu")
		(net "MEMA_0")
	)
	(segment
		(start 286.87903 -198.70547)
		(end 286.87903 -198.34225)
		(width 0.1143)
		(layer "B.Cu")
		(net "MEMA_0")
	)
	(segment
		(start 288.80562 -192.529206)
		(end 288.80562 -189.3062)
		(width 0.1143)
		(layer "B.Cu")
		(net "MEMA_0")
	)
	(segment
		(start 288.244026 -193.441066)
		(end 288.244026 -193.0908)
		(width 0.1143)
		(layer "B.Cu")
		(net "MEMA_0")
	)
	(segment
		(start 288.544 -195.594224)
		(end 288.544 -194.665092)
		(width 0.1143)
		(layer "B.Cu")
		(net "MEMA_0")
	)
	(segment
		(start 24.969216 -217.300556)
		(end 25.99944 -218.33078)
		(width 0.1143)
		(layer "F.Cu")
		(net "SAS_HDD_PWR7")
	)
	(segment
		(start 27.307794 -218.33078)
		(end 31.509716 -222.532702)
		(width 0.1143)
		(layer "F.Cu")
		(net "SAS_HDD_PWR7")
	)
	(segment
		(start 31.509716 -222.532702)
		(end 31.509716 -226.62388)
		(width 0.1143)
		(layer "F.Cu")
		(net "SAS_HDD_PWR7")
	)
	(segment
		(start 25.99944 -218.33078)
		(end 27.307794 -218.33078)
		(width 0.1143)
		(layer "F.Cu")
		(net "SAS_HDD_PWR7")
	)
	(segment
		(start 24.933402 -216.714578)
		(end 24.969216 -216.750392)
		(width 0.1143)
		(layer "F.Cu")
		(net "SAS_HDD_PWR7")
	)
	(segment
		(start 31.509716 -226.62388)
		(end 31.509716 -228.96068)
		(width 0.1143)
		(layer "F.Cu")
		(net "SAS_HDD_PWR7")
	)
	(segment
		(start 24.969216 -216.750392)
		(end 24.969216 -217.300556)
		(width 0.1143)
		(layer "F.Cu")
		(net "SAS_HDD_PWR7")
	)
	(via
		(at 31.509716 -228.07168)
		(size 0.7112)
		(drill 0.3556)
		(layers "F.Cu" "B.Cu")
		(net "SAS_HDD_PWR7")
	)
	(via
		(at 31.509716 -226.62388)
		(size 0.5588)
		(drill 0.3048)
		(layers "F.Cu" "B.Cu")
		(net "SAS_HDD_PWR7")
	)
	(segment
		(start 32.462216 -231.89438)
		(end 32.462216 -230.700834)
		(width 0.1143)
		(layer "B.Cu")
		(net "SAS_HDD_PWR7")
	)
	(segment
		(start 31.509716 -226.62388)
		(end 31.509716 -228.07168)
		(width 0.1143)
		(layer "B.Cu")
		(net "SAS_HDD_PWR7")
	)
	(segment
		(start 32.462216 -230.700834)
		(end 31.509716 -229.748334)
		(width 0.1143)
		(layer "B.Cu")
		(net "SAS_HDD_PWR7")
	)
	(segment
		(start 31.509716 -229.748334)
		(end 31.509716 -228.07168)
		(width 0.1143)
		(layer "B.Cu")
		(net "SAS_HDD_PWR7")
	)
	(segment
		(start 294.434768 -181.840632)
		(end 294.039798 -182.235602)
		(width 0.1143)
		(layer "F.Cu")
		(net "MEMDM_0")
	)
	(segment
		(start 293.698168 -198.475092)
		(end 292.989 -199.18426)
		(width 0.1143)
		(layer "F.Cu")
		(net "MEMDM_0")
	)
	(segment
		(start 294.434768 -181.840124)
		(end 294.434768 -181.840632)
		(width 0.1143)
		(layer "F.Cu")
		(net "MEMDM_0")
	)
	(segment
		(start 293.698168 -197.73519)
		(end 293.698168 -198.475092)
		(width 0.1143)
		(layer "F.Cu")
		(net "MEMDM_0")
	)
	(via
		(at 293.64432 -183.764428)
		(size 0.7112)
		(drill 0.3556)
		(layers "F.Cu" "B.Cu")
		(net "MEMDM_0")
	)
	(via
		(at 294.039798 -182.235602)
		(size 0.508)
		(drill 0.254)
		(layers "F.Cu" "B.Cu")
		(net "MEMDM_0")
	)
	(via
		(at 292.989 -199.18426)
		(size 0.5588)
		(drill 0.3048)
		(layers "F.Cu" "B.Cu")
		(net "MEMDM_0")
	)
	(segment
		(start 293.628572 -183.74868)
		(end 293.628572 -182.850028)
		(width 0.1143)
		(layer "B.Cu")
		(net "MEMDM_0")
	)
	(segment
		(start 293.64432 -183.764428)
		(end 293.628572 -183.74868)
		(width 0.1143)
		(layer "B.Cu")
		(net "MEMDM_0")
	)
	(segment
		(start 293.628572 -182.850028)
		(end 294.039798 -182.438802)
		(width 0.1143)
		(layer "B.Cu")
		(net "MEMDM_0")
	)
	(segment
		(start 294.039798 -182.438802)
		(end 294.039798 -182.235602)
		(width 0.1143)
		(layer "B.Cu")
		(net "MEMDM_0")
	)
	(segment
		(start 294.039798 -182.235602)
		(end 293.86022 -182.41518)
		(width 0.1016)
		(layer "In5.Cu")
		(net "MEMDM_0")
	)
	(segment
		(start 293.2303 -184.2897)
		(end 293.2303 -186.4995)
		(width 0.127)
		(layer "In5.Cu")
		(net "MEMDM_0")
	)
	(segment
		(start 292.13048 -194.03695)
		(end 292.13048 -194.69608)
		(width 0.127)
		(layer "In5.Cu")
		(net "MEMDM_0")
	)
	(segment
		(start 293.362126 -197.987158)
		(end 293.362126 -198.811134)
		(width 0.127)
		(layer "In5.Cu")
		(net "MEMDM_0")
	)
	(segment
		(start 293.53002 -183.98998)
		(end 293.2303 -184.2897)
		(width 0.127)
		(layer "In5.Cu")
		(net "MEMDM_0")
	)
	(segment
		(start 293.86022 -182.41518)
		(end 293.86022 -182.503318)
		(width 0.1016)
		(layer "In5.Cu")
		(net "MEMDM_0")
	)
	(segment
		(start 293.137336 -187.538106)
		(end 292.639242 -188.0362)
		(width 0.127)
		(layer "In5.Cu")
		(net "MEMDM_0")
	)
	(segment
		(start 291.6936 -188.0362)
		(end 291.43452 -188.29528)
		(width 0.127)
		(layer "In5.Cu")
		(net "MEMDM_0")
	)
	(segment
		(start 293.2303 -186.4995)
		(end 293.137336 -186.592464)
		(width 0.127)
		(layer "In5.Cu")
		(net "MEMDM_0")
	)
	(segment
		(start 291.43452 -188.29528)
		(end 291.43452 -193.34099)
		(width 0.127)
		(layer "In5.Cu")
		(net "MEMDM_0")
	)
	(segment
		(start 292.9001 -196.025008)
		(end 293.0144 -196.139308)
		(width 0.127)
		(layer "In5.Cu")
		(net "MEMDM_0")
	)
	(segment
		(start 293.0144 -197.639432)
		(end 293.362126 -197.987158)
		(width 0.127)
		(layer "In5.Cu")
		(net "MEMDM_0")
	)
	(segment
		(start 291.43452 -193.34099)
		(end 292.13048 -194.03695)
		(width 0.127)
		(layer "In5.Cu")
		(net "MEMDM_0")
	)
	(segment
		(start 293.362126 -198.811134)
		(end 292.989 -199.18426)
		(width 0.127)
		(layer "In5.Cu")
		(net "MEMDM_0")
	)
	(segment
		(start 292.639242 -188.0362)
		(end 291.6936 -188.0362)
		(width 0.127)
		(layer "In5.Cu")
		(net "MEMDM_0")
	)
	(segment
		(start 292.13048 -194.69608)
		(end 292.9001 -195.4657)
		(width 0.127)
		(layer "In5.Cu")
		(net "MEMDM_0")
	)
	(segment
		(start 293.137336 -186.592464)
		(end 293.137336 -187.538106)
		(width 0.127)
		(layer "In5.Cu")
		(net "MEMDM_0")
	)
	(segment
		(start 293.0144 -196.139308)
		(end 293.0144 -197.639432)
		(width 0.127)
		(layer "In5.Cu")
		(net "MEMDM_0")
	)
	(segment
		(start 292.9001 -195.4657)
		(end 292.9001 -196.025008)
		(width 0.127)
		(layer "In5.Cu")
		(net "MEMDM_0")
	)
	(segment
		(start 293.53002 -182.833518)
		(end 293.53002 -183.98998)
		(width 0.1016)
		(layer "In5.Cu")
		(net "MEMDM_0")
	)
	(segment
		(start 293.86022 -182.503318)
		(end 293.53002 -182.833518)
		(width 0.1016)
		(layer "In5.Cu")
		(net "MEMDM_0")
	)
	(segment
		(start 39.999666 -251.198888)
		(end 35.339274 -246.538496)
		(width 0.1143)
		(layer "F.Cu")
		(net "SAS_HDD_PWR7_PCIE")
	)
	(segment
		(start 35.339274 -234.22102)
		(end 33.782254 -232.664)
		(width 0.1143)
		(layer "F.Cu")
		(net "SAS_HDD_PWR7_PCIE")
	)
	(segment
		(start 35.339274 -246.538496)
		(end 35.339274 -234.22102)
		(width 0.1143)
		(layer "F.Cu")
		(net "SAS_HDD_PWR7_PCIE")
	)
	(segment
		(start 32.144716 -233.285284)
		(end 32.144716 -234.19308)
		(width 0.1143)
		(layer "F.Cu")
		(net "SAS_HDD_PWR7_PCIE")
	)
	(segment
		(start 39.999666 -256.25044)
		(end 39.999666 -251.198888)
		(width 0.1143)
		(layer "F.Cu")
		(net "SAS_HDD_PWR7_PCIE")
	)
	(segment
		(start 32.144716 -236.190028)
		(end 32.144716 -234.19308)
		(width 0.1143)
		(layer "F.Cu")
		(net "SAS_HDD_PWR7_PCIE")
	)
	(segment
		(start 32.766 -232.664)
		(end 32.144716 -233.285284)
		(width 0.1143)
		(layer "F.Cu")
		(net "SAS_HDD_PWR7_PCIE")
	)
	(segment
		(start 33.782254 -232.664)
		(end 32.766 -232.664)
		(width 0.1143)
		(layer "F.Cu")
		(net "SAS_HDD_PWR7_PCIE")
	)
	(via
		(at 32.462216 -233.81208)
		(size 0.7112)
		(drill 0.3556)
		(layers "F.Cu" "B.Cu")
		(net "SAS_HDD_PWR7_PCIE")
	)
	(via
		(at 32.144716 -236.190028)
		(size 0.5588)
		(drill 0.3048)
		(layers "F.Cu" "B.Cu")
		(net "SAS_HDD_PWR7_PCIE")
	)
	(segment
		(start 32.462216 -232.78338)
		(end 32.462216 -233.81208)
		(width 0.1143)
		(layer "B.Cu")
		(net "SAS_HDD_PWR7_PCIE")
	)
	(segment
		(start 32.462216 -233.81208)
		(end 32.462216 -235.872528)
		(width 0.1143)
		(layer "B.Cu")
		(net "SAS_HDD_PWR7_PCIE")
	)
	(segment
		(start 32.462216 -235.872528)
		(end 32.144716 -236.190028)
		(width 0.1143)
		(layer "B.Cu")
		(net "SAS_HDD_PWR7_PCIE")
	)
	(segment
		(start 295.298114 -198.313802)
		(end 295.324022 -198.33971)
		(width 0.1016)
		(layer "F.Cu")
		(net "MEMDQS_P1")
	)
	(segment
		(start 296.418 -183.823102)
		(end 296.418 -184.785)
		(width 0.1016)
		(layer "F.Cu")
		(net "MEMDQS_P1")
	)
	(segment
		(start 295.298114 -197.73519)
		(end 295.298114 -198.313802)
		(width 0.1016)
		(layer "F.Cu")
		(net "MEMDQS_P1")
	)
	(segment
		(start 296.034968 -183.44007)
		(end 296.418 -183.823102)
		(width 0.1016)
		(layer "F.Cu")
		(net "MEMDQS_P1")
	)
	(via
		(at 295.324022 -198.33971)
		(size 0.508)
		(drill 0.254)
		(layers "F.Cu" "B.Cu")
		(net "MEMDQS_P1")
	)
	(via
		(at 296.418 -184.785)
		(size 0.508)
		(drill 0.254)
		(layers "F.Cu" "B.Cu")
		(net "MEMDQS_P1")
	)
	(via
		(at 295.5544 -197.5866)
		(size 0.7112)
		(drill 0.3556)
		(layers "F.Cu" "B.Cu")
		(net "MEMDQS_P1")
	)
	(segment
		(start 295.324022 -197.711822)
		(end 295.324022 -198.33971)
		(width 0.1016)
		(layer "B.Cu")
		(net "MEMDQS_P1")
	)
	(segment
		(start 295.5544 -197.5866)
		(end 295.449244 -197.5866)
		(width 0.1016)
		(layer "B.Cu")
		(net "MEMDQS_P1")
	)
	(segment
		(start 295.449244 -197.5866)
		(end 295.324022 -197.711822)
		(width 0.1016)
		(layer "B.Cu")
		(net "MEMDQS_P1")
	)
	(segment
		(start 295.945306 -194.167506)
		(end 295.6306 -193.8528)
		(width 0.1016)
		(layer "In5.Cu")
		(net "MEMDQS_P1")
	)
	(segment
		(start 296.591228 -185.626756)
		(end 296.591228 -184.958228)
		(width 0.1016)
		(layer "In5.Cu")
		(net "MEMDQS_P1")
	)
	(segment
		(start 295.3258 -197.43801)
		(end 295.670478 -197.093332)
		(width 0.1016)
		(layer "In5.Cu")
		(net "MEMDQS_P1")
	)
	(segment
		(start 297.18 -194.599306)
		(end 296.7482 -194.167506)
		(width 0.1016)
		(layer "In5.Cu")
		(net "MEMDQS_P1")
	)
	(segment
		(start 296.591228 -184.958228)
		(end 296.418 -184.785)
		(width 0.1016)
		(layer "In5.Cu")
		(net "MEMDQS_P1")
	)
	(segment
		(start 296.799 -187.091574)
		(end 296.5958 -186.888374)
		(width 0.1016)
		(layer "In5.Cu")
		(net "MEMDQS_P1")
	)
	(segment
		(start 295.842182 -191.956182)
		(end 295.842182 -191.329818)
		(width 0.1016)
		(layer "In5.Cu")
		(net "MEMDQS_P1")
	)
	(segment
		(start 296.799 -190.916306)
		(end 296.799 -187.091574)
		(width 0.1016)
		(layer "In5.Cu")
		(net "MEMDQS_P1")
	)
	(segment
		(start 295.3258 -197.98411)
		(end 295.3258 -197.43801)
		(width 0.1016)
		(layer "In5.Cu")
		(net "MEMDQS_P1")
	)
	(segment
		(start 296.799 -192.389506)
		(end 296.6974 -192.287906)
		(width 0.1016)
		(layer "In5.Cu")
		(net "MEMDQS_P1")
	)
	(segment
		(start 296.7482 -194.167506)
		(end 295.945306 -194.167506)
		(width 0.1016)
		(layer "In5.Cu")
		(net "MEMDQS_P1")
	)
	(segment
		(start 295.6306 -193.1924)
		(end 295.925494 -192.897506)
		(width 0.1016)
		(layer "In5.Cu")
		(net "MEMDQS_P1")
	)
	(segment
		(start 297.18 -195.58381)
		(end 297.18 -194.599306)
		(width 0.1016)
		(layer "In5.Cu")
		(net "MEMDQS_P1")
	)
	(segment
		(start 296.412666 -196.351144)
		(end 297.18 -195.58381)
		(width 0.1016)
		(layer "In5.Cu")
		(net "MEMDQS_P1")
	)
	(segment
		(start 295.842182 -191.329818)
		(end 296.154094 -191.017906)
		(width 0.1016)
		(layer "In5.Cu")
		(net "MEMDQS_P1")
	)
	(segment
		(start 296.5958 -186.888374)
		(end 296.5958 -185.631328)
		(width 0.1016)
		(layer "In5.Cu")
		(net "MEMDQS_P1")
	)
	(segment
		(start 296.6974 -192.897506)
		(end 296.799 -192.795906)
		(width 0.1016)
		(layer "In5.Cu")
		(net "MEMDQS_P1")
	)
	(segment
		(start 296.5958 -185.631328)
		(end 296.591228 -185.626756)
		(width 0.1016)
		(layer "In5.Cu")
		(net "MEMDQS_P1")
	)
	(segment
		(start 295.977056 -196.351144)
		(end 296.412666 -196.351144)
		(width 0.1016)
		(layer "In5.Cu")
		(net "MEMDQS_P1")
	)
	(segment
		(start 295.6306 -193.8528)
		(end 295.6306 -193.1924)
		(width 0.1016)
		(layer "In5.Cu")
		(net "MEMDQS_P1")
	)
	(segment
		(start 295.925494 -192.897506)
		(end 296.6974 -192.897506)
		(width 0.1016)
		(layer "In5.Cu")
		(net "MEMDQS_P1")
	)
	(segment
		(start 296.6974 -191.017906)
		(end 296.799 -190.916306)
		(width 0.1016)
		(layer "In5.Cu")
		(net "MEMDQS_P1")
	)
	(segment
		(start 295.324022 -198.33971)
		(end 295.324022 -197.985888)
		(width 0.1016)
		(layer "In5.Cu")
		(net "MEMDQS_P1")
	)
	(segment
		(start 296.173906 -192.287906)
		(end 295.842182 -191.956182)
		(width 0.1016)
		(layer "In5.Cu")
		(net "MEMDQS_P1")
	)
	(segment
		(start 295.670478 -197.093332)
		(end 295.670478 -196.657722)
		(width 0.1016)
		(layer "In5.Cu")
		(net "MEMDQS_P1")
	)
	(segment
		(start 296.6974 -192.287906)
		(end 296.173906 -192.287906)
		(width 0.1016)
		(layer "In5.Cu")
		(net "MEMDQS_P1")
	)
	(segment
		(start 295.324022 -197.985888)
		(end 295.3258 -197.98411)
		(width 0.1016)
		(layer "In5.Cu")
		(net "MEMDQS_P1")
	)
	(segment
		(start 296.799 -192.795906)
		(end 296.799 -192.389506)
		(width 0.1016)
		(layer "In5.Cu")
		(net "MEMDQS_P1")
	)
	(segment
		(start 295.670478 -196.657722)
		(end 295.977056 -196.351144)
		(width 0.1016)
		(layer "In5.Cu")
		(net "MEMDQS_P1")
	)
	(segment
		(start 296.154094 -191.017906)
		(end 296.6974 -191.017906)
		(width 0.1016)
		(layer "In5.Cu")
		(net "MEMDQS_P1")
	)
	(segment
		(start 19.083782 -222.325438)
		(end 19.083782 -221.206314)
		(width 0.1143)
		(layer "F.Cu")
		(net "SAS_HDD_PWR9")
	)
	(segment
		(start 19.083782 -221.206314)
		(end 19.381216 -220.90888)
		(width 0.1143)
		(layer "F.Cu")
		(net "SAS_HDD_PWR9")
	)
	(segment
		(start 32.779716 -228.96068)
		(end 32.779716 -226.81438)
		(width 0.1143)
		(layer "F.Cu")
		(net "SAS_HDD_PWR9")
	)
	(segment
		(start 32.779716 -226.81438)
		(end 32.7914 -226.802696)
		(width 0.1143)
		(layer "F.Cu")
		(net "SAS_HDD_PWR9")
	)
	(via
		(at 24.105616 -220.90888)
		(size 0.7112)
		(drill 0.3556)
		(layers "F.Cu" "B.Cu")
		(net "SAS_HDD_PWR9")
	)
	(via
		(at 19.381216 -220.90888)
		(size 0.5588)
		(drill 0.3048)
		(layers "F.Cu" "B.Cu")
		(net "SAS_HDD_PWR9")
	)
	(via
		(at 32.7914 -226.802696)
		(size 0.5588)
		(drill 0.3048)
		(layers "F.Cu" "B.Cu")
		(net "SAS_HDD_PWR9")
	)
	(segment
		(start 24.105616 -220.90888)
		(end 27.007312 -220.90888)
		(width 0.1143)
		(layer "B.Cu")
		(net "SAS_HDD_PWR9")
	)
	(segment
		(start 34.494216 -231.06888)
		(end 32.970216 -229.54488)
		(width 0.1143)
		(layer "B.Cu")
		(net "SAS_HDD_PWR9")
	)
	(segment
		(start 22.364954 -220.90888)
		(end 24.105616 -220.90888)
		(width 0.1143)
		(layer "B.Cu")
		(net "SAS_HDD_PWR9")
	)
	(segment
		(start 21.883878 -220.90888)
		(end 21.890228 -220.90253)
		(width 0.1143)
		(layer "B.Cu")
		(net "SAS_HDD_PWR9")
	)
	(segment
		(start 22.358604 -220.90253)
		(end 22.364954 -220.90888)
		(width 0.1143)
		(layer "B.Cu")
		(net "SAS_HDD_PWR9")
	)
	(segment
		(start 32.7914 -226.692968)
		(end 32.7914 -226.802696)
		(width 0.1143)
		(layer "B.Cu")
		(net "SAS_HDD_PWR9")
	)
	(segment
		(start 32.970216 -229.54488)
		(end 32.970216 -226.981512)
		(width 0.1143)
		(layer "B.Cu")
		(net "SAS_HDD_PWR9")
	)
	(segment
		(start 27.007312 -220.90888)
		(end 32.7914 -226.692968)
		(width 0.1143)
		(layer "B.Cu")
		(net "SAS_HDD_PWR9")
	)
	(segment
		(start 34.494216 -231.89438)
		(end 34.494216 -231.06888)
		(width 0.1143)
		(layer "B.Cu")
		(net "SAS_HDD_PWR9")
	)
	(segment
		(start 21.890228 -220.90253)
		(end 22.358604 -220.90253)
		(width 0.1143)
		(layer "B.Cu")
		(net "SAS_HDD_PWR9")
	)
	(segment
		(start 19.381216 -220.90888)
		(end 21.883878 -220.90888)
		(width 0.1143)
		(layer "B.Cu")
		(net "SAS_HDD_PWR9")
	)
	(segment
		(start 32.970216 -226.981512)
		(end 32.7914 -226.802696)
		(width 0.1143)
		(layer "B.Cu")
		(net "SAS_HDD_PWR9")
	)
	(segment
		(start 287.288478 -201.735182)
		(end 286.892238 -201.338942)
		(width 0.1143)
		(layer "F.Cu")
		(net "MEMA_3")
	)
	(segment
		(start 289.234372 -183.040782)
		(end 289.22599 -183.040782)
		(width 0.1143)
		(layer "F.Cu")
		(net "MEMA_3")
	)
	(segment
		(start 289.63493 -182.640224)
		(end 289.234372 -183.040782)
		(width 0.1143)
		(layer "F.Cu")
		(net "MEMA_3")
	)
	(segment
		(start 287.29813 -201.735182)
		(end 287.288478 -201.735182)
		(width 0.1143)
		(layer "F.Cu")
		(net "MEMA_3")
	)
	(via
		(at 289.22599 -183.040782)
		(size 0.508)
		(drill 0.254)
		(layers "F.Cu" "B.Cu")
		(net "MEMA_3")
	)
	(via
		(at 289.2806 -193.4464)
		(size 0.7112)
		(drill 0.3556)
		(layers "F.Cu" "B.Cu")
		(net "MEMA_3")
	)
	(via
		(at 286.892238 -201.338942)
		(size 0.508)
		(drill 0.254)
		(layers "F.Cu" "B.Cu")
		(net "MEMA_3")
	)
	(segment
		(start 287.96107 -199.683878)
		(end 288.11855 -199.526398)
		(width 0.1143)
		(layer "B.Cu")
		(net "MEMA_3")
	)
	(segment
		(start 287.63468 -200.5965)
		(end 287.63468 -200.01992)
		(width 0.1143)
		(layer "B.Cu")
		(net "MEMA_3")
	)
	(segment
		(start 289.68827 -188.940186)
		(end 289.1917 -188.443616)
		(width 0.1143)
		(layer "B.Cu")
		(net "MEMA_3")
	)
	(segment
		(start 286.892238 -201.338942)
		(end 287.63468 -200.5965)
		(width 0.1143)
		(layer "B.Cu")
		(net "MEMA_3")
	)
	(segment
		(start 289.22599 -183.909716)
		(end 289.22599 -183.040782)
		(width 0.1143)
		(layer "B.Cu")
		(net "MEMA_3")
	)
	(segment
		(start 287.924494 -198.04888)
		(end 288.1503 -197.823074)
		(width 0.1143)
		(layer "B.Cu")
		(net "MEMA_3")
	)
	(segment
		(start 289.68827 -193.03873)
		(end 289.68827 -188.940186)
		(width 0.1143)
		(layer "B.Cu")
		(net "MEMA_3")
	)
	(segment
		(start 288.1503 -197.823074)
		(end 288.1503 -196.670676)
		(width 0.1143)
		(layer "B.Cu")
		(net "MEMA_3")
	)
	(segment
		(start 287.63468 -200.01992)
		(end 287.96107 -199.69353)
		(width 0.1143)
		(layer "B.Cu")
		(net "MEMA_3")
	)
	(segment
		(start 288.11855 -199.526398)
		(end 288.11855 -199.163178)
		(width 0.1143)
		(layer "B.Cu")
		(net "MEMA_3")
	)
	(segment
		(start 287.96107 -199.69353)
		(end 287.96107 -199.683878)
		(width 0.1143)
		(layer "B.Cu")
		(net "MEMA_3")
	)
	(segment
		(start 289.1028 -195.718176)
		(end 289.1028 -194.486784)
		(width 0.1143)
		(layer "B.Cu")
		(net "MEMA_3")
	)
	(segment
		(start 289.08248 -194.466464)
		(end 289.08248 -193.64452)
		(width 0.1143)
		(layer "B.Cu")
		(net "MEMA_3")
	)
	(segment
		(start 289.143694 -185.002678)
		(end 289.143694 -183.992012)
		(width 0.1143)
		(layer "B.Cu")
		(net "MEMA_3")
	)
	(segment
		(start 287.924494 -198.969122)
		(end 287.924494 -198.04888)
		(width 0.1143)
		(layer "B.Cu")
		(net "MEMA_3")
	)
	(segment
		(start 289.435794 -185.294778)
		(end 289.143694 -185.002678)
		(width 0.1143)
		(layer "B.Cu")
		(net "MEMA_3")
	)
	(segment
		(start 288.1503 -196.670676)
		(end 289.1028 -195.718176)
		(width 0.1143)
		(layer "B.Cu")
		(net "MEMA_3")
	)
	(segment
		(start 289.143694 -183.992012)
		(end 289.22599 -183.909716)
		(width 0.1143)
		(layer "B.Cu")
		(net "MEMA_3")
	)
	(segment
		(start 289.1028 -194.486784)
		(end 289.08248 -194.466464)
		(width 0.1143)
		(layer "B.Cu")
		(net "MEMA_3")
	)
	(segment
		(start 289.2806 -193.4464)
		(end 289.68827 -193.03873)
		(width 0.1143)
		(layer "B.Cu")
		(net "MEMA_3")
	)
	(segment
		(start 289.1917 -188.443616)
		(end 289.1917 -187.024264)
		(width 0.1143)
		(layer "B.Cu")
		(net "MEMA_3")
	)
	(segment
		(start 288.11855 -199.163178)
		(end 287.924494 -198.969122)
		(width 0.1143)
		(layer "B.Cu")
		(net "MEMA_3")
	)
	(segment
		(start 289.435794 -186.78017)
		(end 289.435794 -185.294778)
		(width 0.1143)
		(layer "B.Cu")
		(net "MEMA_3")
	)
	(segment
		(start 289.1917 -187.024264)
		(end 289.435794 -186.78017)
		(width 0.1143)
		(layer "B.Cu")
		(net "MEMA_3")
	)
	(segment
		(start 289.08248 -193.64452)
		(end 289.2806 -193.4464)
		(width 0.1143)
		(layer "B.Cu")
		(net "MEMA_3")
	)
	(segment
		(start 18.433542 -222.325438)
		(end 18.433542 -220.977206)
		(width 0.1143)
		(layer "F.Cu")
		(net "SAS_HDD_PWR8")
	)
	(segment
		(start 32.144716 -228.96068)
		(end 32.144716 -227.44938)
		(width 0.1143)
		(layer "F.Cu")
		(net "SAS_HDD_PWR8")
	)
	(segment
		(start 18.433542 -220.977206)
		(end 18.365216 -220.90888)
		(width 0.1143)
		(layer "F.Cu")
		(net "SAS_HDD_PWR8")
	)
	(via
		(at 22.124416 -221.46768)
		(size 0.7112)
		(drill 0.3556)
		(layers "F.Cu" "B.Cu")
		(net "SAS_HDD_PWR8")
	)
	(via
		(at 32.144716 -227.44938)
		(size 0.5588)
		(drill 0.3048)
		(layers "F.Cu" "B.Cu")
		(net "SAS_HDD_PWR8")
	)
	(via
		(at 18.365216 -220.90888)
		(size 0.5588)
		(drill 0.3048)
		(layers "F.Cu" "B.Cu")
		(net "SAS_HDD_PWR8")
	)
	(segment
		(start 32.144716 -226.567238)
		(end 32.144716 -227.44938)
		(width 0.1143)
		(layer "B.Cu")
		(net "SAS_HDD_PWR8")
	)
	(segment
		(start 33.478216 -231.19588)
		(end 32.144716 -229.86238)
		(width 0.1143)
		(layer "B.Cu")
		(net "SAS_HDD_PWR8")
	)
	(segment
		(start 22.124416 -221.46768)
		(end 22.130766 -221.47403)
		(width 0.1143)
		(layer "B.Cu")
		(net "SAS_HDD_PWR8")
	)
	(segment
		(start 22.130766 -221.47403)
		(end 27.051508 -221.47403)
		(width 0.1143)
		(layer "B.Cu")
		(net "SAS_HDD_PWR8")
	)
	(segment
		(start 27.051508 -221.47403)
		(end 32.144716 -226.567238)
		(width 0.1143)
		(layer "B.Cu")
		(net "SAS_HDD_PWR8")
	)
	(segment
		(start 18.924016 -221.46768)
		(end 22.124416 -221.46768)
		(width 0.1143)
		(layer "B.Cu")
		(net "SAS_HDD_PWR8")
	)
	(segment
		(start 18.365216 -220.90888)
		(end 18.924016 -221.46768)
		(width 0.1143)
		(layer "B.Cu")
		(net "SAS_HDD_PWR8")
	)
	(segment
		(start 32.144716 -229.86238)
		(end 32.144716 -227.44938)
		(width 0.1143)
		(layer "B.Cu")
		(net "SAS_HDD_PWR8")
	)
	(segment
		(start 33.478216 -231.89438)
		(end 33.478216 -231.19588)
		(width 0.1143)
		(layer "B.Cu")
		(net "SAS_HDD_PWR8")
	)
	(segment
		(start 27.966416 -226.48418)
		(end 27.699716 -226.75088)
		(width 0.1143)
		(layer "F.Cu")
		(net "SAS_HDD_PWR1")
	)
	(segment
		(start 19.732752 -216.714578)
		(end 19.732752 -218.834462)
		(width 0.1143)
		(layer "F.Cu")
		(net "SAS_HDD_PWR1")
	)
	(segment
		(start 19.732752 -218.834462)
		(end 21.43887 -220.54058)
		(width 0.1143)
		(layer "F.Cu")
		(net "SAS_HDD_PWR1")
	)
	(segment
		(start 27.699716 -226.75088)
		(end 27.699716 -228.96068)
		(width 0.1143)
		(layer "F.Cu")
		(net "SAS_HDD_PWR1")
	)
	(segment
		(start 27.966416 -222.115126)
		(end 27.966416 -226.48418)
		(width 0.1143)
		(layer "F.Cu")
		(net "SAS_HDD_PWR1")
	)
	(segment
		(start 26.39187 -220.54058)
		(end 27.966416 -222.115126)
		(width 0.1143)
		(layer "F.Cu")
		(net "SAS_HDD_PWR1")
	)
	(segment
		(start 21.43887 -220.54058)
		(end 26.39187 -220.54058)
		(width 0.1143)
		(layer "F.Cu")
		(net "SAS_HDD_PWR1")
	)
	(via
		(at 27.699716 -228.24948)
		(size 0.7112)
		(drill 0.3556)
		(layers "F.Cu" "B.Cu")
		(net "SAS_HDD_PWR1")
	)
	(via
		(at 27.699716 -226.75088)
		(size 0.5588)
		(drill 0.3048)
		(layers "F.Cu" "B.Cu")
		(net "SAS_HDD_PWR1")
	)
	(segment
		(start 27.699716 -228.24948)
		(end 27.699716 -226.75088)
		(width 0.1143)
		(layer "B.Cu")
		(net "SAS_HDD_PWR1")
	)
	(segment
		(start 27.699716 -229.35438)
		(end 27.699716 -228.24948)
		(width 0.1143)
		(layer "B.Cu")
		(net "SAS_HDD_PWR1")
	)
	(segment
		(start 26.366216 -231.89438)
		(end 26.366216 -230.68788)
		(width 0.1143)
		(layer "B.Cu")
		(net "SAS_HDD_PWR1")
	)
	(segment
		(start 26.366216 -230.68788)
		(end 27.699716 -229.35438)
		(width 0.1143)
		(layer "B.Cu")
		(net "SAS_HDD_PWR1")
	)
	(via
		(at 258.826 -19.939)
		(size 0.7112)
		(drill 0.3556)
		(layers "F.Cu" "B.Cu")
		(net "P5V_USB_BP1_F")
	)
	(via
		(at 258.191 -19.177)
		(size 0.7112)
		(drill 0.4064)
		(layers "F.Cu" "B.Cu")
		(net "P5V_USB_BP1_F")
	)
	(via
		(at 259.334 -19.177)
		(size 0.7112)
		(drill 0.4064)
		(layers "F.Cu" "B.Cu")
		(net "P5V_USB_BP1_F")
	)
	(segment
		(start 294.498014 -200.935082)
		(end 295.03243 -200.400666)
		(width 0.1143)
		(layer "F.Cu")
		(net "MEMDM_1")
	)
	(segment
		(start 295.03243 -200.400666)
		(end 295.03243 -200.366376)
		(width 0.1143)
		(layer "F.Cu")
		(net "MEMDM_1")
	)
	(segment
		(start 296.430192 -181.435248)
		(end 296.034968 -181.040024)
		(width 0.1143)
		(layer "F.Cu")
		(net "MEMDM_1")
	)
	(via
		(at 295.03243 -200.366376)
		(size 0.508)
		(drill 0.254)
		(layers "F.Cu" "B.Cu")
		(net "MEMDM_1")
	)
	(via
		(at 296.430192 -181.435248)
		(size 0.508)
		(drill 0.254)
		(layers "F.Cu" "B.Cu")
		(net "MEMDM_1")
	)
	(via
		(at 294.2844 -200.8886)
		(size 0.7112)
		(drill 0.3556)
		(layers "F.Cu" "B.Cu")
		(net "MEMDM_1")
	)
	(segment
		(start 295.03243 -200.366376)
		(end 294.806624 -200.366376)
		(width 0.1143)
		(layer "B.Cu")
		(net "MEMDM_1")
	)
	(segment
		(start 294.806624 -200.366376)
		(end 294.2844 -200.8886)
		(width 0.1143)
		(layer "B.Cu")
		(net "MEMDM_1")
	)
	(segment
		(start 295.741852 -200.4695)
		(end 295.638728 -200.366376)
		(width 0.127)
		(layer "In5.Cu")
		(net "MEMDM_1")
	)
	(segment
		(start 296.830496 -181.895496)
		(end 296.830496 -182.483506)
		(width 0.0889)
		(layer "In5.Cu")
		(net "MEMDM_1")
	)
	(segment
		(start 296.830496 -182.483506)
		(end 297.103292 -182.756302)
		(width 0.0889)
		(layer "In5.Cu")
		(net "MEMDM_1")
	)
	(segment
		(start 296.430192 -181.435248)
		(end 296.430192 -181.495192)
		(width 0.0889)
		(layer "In5.Cu")
		(net "MEMDM_1")
	)
	(segment
		(start 295.638728 -200.366376)
		(end 295.03243 -200.366376)
		(width 0.127)
		(layer "In5.Cu")
		(net "MEMDM_1")
	)
	(segment
		(start 300.1772 -186.40679)
		(end 300.1772 -186.715908)
		(width 0.127)
		(layer "In5.Cu")
		(net "MEMDM_1")
	)
	(segment
		(start 297.103292 -182.756302)
		(end 297.103292 -183.16956)
		(width 0.127)
		(layer "In5.Cu")
		(net "MEMDM_1")
	)
	(segment
		(start 300.1772 -186.715908)
		(end 300.355 -186.893708)
		(width 0.127)
		(layer "In5.Cu")
		(net "MEMDM_1")
	)
	(segment
		(start 300.355 -197.052692)
		(end 296.938192 -200.4695)
		(width 0.127)
		(layer "In5.Cu")
		(net "MEMDM_1")
	)
	(segment
		(start 299.9994 -186.065668)
		(end 299.9994 -186.22899)
		(width 0.127)
		(layer "In5.Cu")
		(net "MEMDM_1")
	)
	(segment
		(start 296.938192 -200.4695)
		(end 295.741852 -200.4695)
		(width 0.127)
		(layer "In5.Cu")
		(net "MEMDM_1")
	)
	(segment
		(start 299.9994 -186.22899)
		(end 300.1772 -186.40679)
		(width 0.127)
		(layer "In5.Cu")
		(net "MEMDM_1")
	)
	(segment
		(start 296.430192 -181.495192)
		(end 296.830496 -181.895496)
		(width 0.0889)
		(layer "In5.Cu")
		(net "MEMDM_1")
	)
	(segment
		(start 300.355 -186.893708)
		(end 300.355 -197.052692)
		(width 0.127)
		(layer "In5.Cu")
		(net "MEMDM_1")
	)
	(segment
		(start 297.103292 -183.16956)
		(end 299.9994 -186.065668)
		(width 0.127)
		(layer "In5.Cu")
		(net "MEMDM_1")
	)
	(segment
		(start 34.890456 -246.724424)
		(end 34.890456 -234.406948)
		(width 0.1143)
		(layer "F.Cu")
		(net "SAS_HDD_PWR8_PCIE")
	)
	(segment
		(start 33.528508 -233.045)
		(end 33.02 -233.045)
		(width 0.1143)
		(layer "F.Cu")
		(net "SAS_HDD_PWR8_PCIE")
	)
	(segment
		(start 34.890456 -234.406948)
		(end 33.528508 -233.045)
		(width 0.1143)
		(layer "F.Cu")
		(net "SAS_HDD_PWR8_PCIE")
	)
	(segment
		(start 33.02 -233.045)
		(end 32.779716 -233.285284)
		(width 0.1143)
		(layer "F.Cu")
		(net "SAS_HDD_PWR8_PCIE")
	)
	(segment
		(start 39.000176 -250.834144)
		(end 34.890456 -246.724424)
		(width 0.1143)
		(layer "F.Cu")
		(net "SAS_HDD_PWR8_PCIE")
	)
	(segment
		(start 32.779716 -233.285284)
		(end 32.779716 -234.19308)
		(width 0.1143)
		(layer "F.Cu")
		(net "SAS_HDD_PWR8_PCIE")
	)
	(segment
		(start 32.779716 -236.91088)
		(end 32.779716 -234.19308)
		(width 0.1143)
		(layer "F.Cu")
		(net "SAS_HDD_PWR8_PCIE")
	)
	(segment
		(start 39.000176 -256.25044)
		(end 39.000176 -250.834144)
		(width 0.1143)
		(layer "F.Cu")
		(net "SAS_HDD_PWR8_PCIE")
	)
	(via
		(at 32.779716 -236.91088)
		(size 0.5588)
		(drill 0.3048)
		(layers "F.Cu" "B.Cu")
		(net "SAS_HDD_PWR8_PCIE")
	)
	(via
		(at 33.376616 -235.08208)
		(size 0.7112)
		(drill 0.3556)
		(layers "F.Cu" "B.Cu")
		(net "SAS_HDD_PWR8_PCIE")
	)
	(segment
		(start 33.478216 -232.78338)
		(end 33.478216 -234.98048)
		(width 0.1143)
		(layer "B.Cu")
		(net "SAS_HDD_PWR8_PCIE")
	)
	(segment
		(start 32.925766 -236.76483)
		(end 32.779716 -236.91088)
		(width 0.1143)
		(layer "B.Cu")
		(net "SAS_HDD_PWR8_PCIE")
	)
	(segment
		(start 33.478216 -234.98048)
		(end 33.376616 -235.08208)
		(width 0.1143)
		(layer "B.Cu")
		(net "SAS_HDD_PWR8_PCIE")
	)
	(segment
		(start 32.925766 -235.53293)
		(end 32.925766 -236.76483)
		(width 0.1143)
		(layer "B.Cu")
		(net "SAS_HDD_PWR8_PCIE")
	)
	(segment
		(start 33.376616 -235.08208)
		(end 32.925766 -235.53293)
		(width 0.1143)
		(layer "B.Cu")
		(net "SAS_HDD_PWR8_PCIE")
	)
	(segment
		(start 267.457936 -10.989818)
		(end 268.499844 -10.989818)
		(width 0.508)
		(layer "F.Cu")
		(net "P5V_USB")
	)
	(segment
		(start 268.499844 -10.989818)
		(end 269.541752 -10.989818)
		(width 0.508)
		(layer "F.Cu")
		(net "P5V_USB")
	)
	(segment
		(start 268.499844 -10.989818)
		(end 268.499844 -12.031726)
		(width 0.508)
		(layer "F.Cu")
		(net "P5V_USB")
	)
	(via
		(at 261.112 -13.081)
		(size 0.7112)
		(drill 0.4064)
		(layers "F.Cu" "B.Cu")
		(net "P5V_USB")
	)
	(via
		(at 257.3528 -13.3604)
		(size 0.7112)
		(drill 0.3556)
		(layers "F.Cu" "B.Cu")
		(net "P5V_USB")
	)
	(via
		(at 262.763 -13.081)
		(size 0.7112)
		(drill 0.4064)
		(layers "F.Cu" "B.Cu")
		(net "P5V_USB")
	)
	(via
		(at 259.715 -13.081)
		(size 0.7112)
		(drill 0.4064)
		(layers "F.Cu" "B.Cu")
		(net "P5V_USB")
	)
	(segment
		(start 267.457936 -10.989818)
		(end 268.499844 -10.989818)
		(width 0.508)
		(layer "B.Cu")
		(net "P5V_USB")
	)
	(segment
		(start 268.499844 -10.989818)
		(end 268.499844 -12.031726)
		(width 0.508)
		(layer "B.Cu")
		(net "P5V_USB")
	)
	(segment
		(start 268.499844 -10.989818)
		(end 269.541752 -10.989818)
		(width 0.508)
		(layer "B.Cu")
		(net "P5V_USB")
	)
	(segment
		(start 286.49803 -200.935082)
		(end 286.48152 -200.918572)
		(width 0.1143)
		(layer "F.Cu")
		(net "MEMA_2")
	)
	(segment
		(start 290.434776 -181.028086)
		(end 290.00831 -180.60162)
		(width 0.1143)
		(layer "F.Cu")
		(net "MEMA_2")
	)
	(segment
		(start 290.434776 -181.040024)
		(end 290.434776 -181.028086)
		(width 0.1143)
		(layer "F.Cu")
		(net "MEMA_2")
	)
	(segment
		(start 286.48152 -200.918572)
		(end 286.48152 -200.547478)
		(width 0.1143)
		(layer "F.Cu")
		(net "MEMA_2")
	)
	(segment
		(start 286.48152 -200.547478)
		(end 286.29864 -200.364598)
		(width 0.1143)
		(layer "F.Cu")
		(net "MEMA_2")
	)
	(via
		(at 286.29864 -200.364598)
		(size 0.508)
		(drill 0.254)
		(layers "F.Cu" "B.Cu")
		(net "MEMA_2")
	)
	(via
		(at 290.00831 -180.60162)
		(size 0.508)
		(drill 0.254)
		(layers "F.Cu" "B.Cu")
		(net "MEMA_2")
	)
	(via
		(at 286.608012 -196.633084)
		(size 0.7112)
		(drill 0.3556)
		(layers "F.Cu" "B.Cu")
		(net "MEMA_2")
	)
	(segment
		(start 287.515046 -187.21197)
		(end 287.515046 -187.906406)
		(width 0.1143)
		(layer "B.Cu")
		(net "MEMA_2")
	)
	(segment
		(start 286.608012 -196.652388)
		(end 286.131 -197.1294)
		(width 0.1143)
		(layer "B.Cu")
		(net "MEMA_2")
	)
	(segment
		(start 287.514792 -187.90666)
		(end 287.514792 -188.384688)
		(width 0.1143)
		(layer "B.Cu")
		(net "MEMA_2")
	)
	(segment
		(start 286.93618 -196.32422)
		(end 286.627316 -196.633084)
		(width 0.1143)
		(layer "B.Cu")
		(net "MEMA_2")
	)
	(segment
		(start 286.608012 -196.633084)
		(end 286.608012 -196.652388)
		(width 0.1143)
		(layer "B.Cu")
		(net "MEMA_2")
	)
	(segment
		(start 286.258 -193.69024)
		(end 286.4612 -193.89344)
		(width 0.1143)
		(layer "B.Cu")
		(net "MEMA_2")
	)
	(segment
		(start 286.54629 -191.416432)
		(end 286.258 -191.704722)
		(width 0.1143)
		(layer "B.Cu")
		(net "MEMA_2")
	)
	(segment
		(start 286.49549 -199.845676)
		(end 286.49549 -200.167748)
		(width 0.1143)
		(layer "B.Cu")
		(net "MEMA_2")
	)
	(segment
		(start 286.93618 -195.39077)
		(end 286.93618 -196.32422)
		(width 0.1143)
		(layer "B.Cu")
		(net "MEMA_2")
	)
	(segment
		(start 290.00831 -180.60162)
		(end 289.81654 -180.79339)
		(width 0.1143)
		(layer "B.Cu")
		(net "MEMA_2")
	)
	(segment
		(start 286.54629 -191.184022)
		(end 286.54629 -191.416432)
		(width 0.1143)
		(layer "B.Cu")
		(net "MEMA_2")
	)
	(segment
		(start 287.191958 -190.538354)
		(end 286.54629 -191.184022)
		(width 0.1143)
		(layer "B.Cu")
		(net "MEMA_2")
	)
	(segment
		(start 287.613344 -183.63819)
		(end 287.613344 -186.92622)
		(width 0.1143)
		(layer "B.Cu")
		(net "MEMA_2")
	)
	(segment
		(start 288.544 -181.215284)
		(end 288.544 -181.666642)
		(width 0.1143)
		(layer "B.Cu")
		(net "MEMA_2")
	)
	(segment
		(start 287.515046 -187.906406)
		(end 287.514792 -187.90666)
		(width 0.1143)
		(layer "B.Cu")
		(net "MEMA_2")
	)
	(segment
		(start 287.5153 -187.024264)
		(end 287.5153 -187.211716)
		(width 0.1143)
		(layer "B.Cu")
		(net "MEMA_2")
	)
	(segment
		(start 286.4612 -193.89344)
		(end 286.4612 -194.91579)
		(width 0.1143)
		(layer "B.Cu")
		(net "MEMA_2")
	)
	(segment
		(start 287.5153 -187.211716)
		(end 287.515046 -187.21197)
		(width 0.1143)
		(layer "B.Cu")
		(net "MEMA_2")
	)
	(segment
		(start 289.81654 -180.79339)
		(end 288.965894 -180.79339)
		(width 0.1143)
		(layer "B.Cu")
		(net "MEMA_2")
	)
	(segment
		(start 286.4612 -194.91579)
		(end 286.93618 -195.39077)
		(width 0.1143)
		(layer "B.Cu")
		(net "MEMA_2")
	)
	(segment
		(start 286.131 -198.826374)
		(end 286.630618 -199.325992)
		(width 0.1143)
		(layer "B.Cu")
		(net "MEMA_2")
	)
	(segment
		(start 288.965894 -180.79339)
		(end 288.544 -181.215284)
		(width 0.1143)
		(layer "B.Cu")
		(net "MEMA_2")
	)
	(segment
		(start 286.258 -191.704722)
		(end 286.258 -193.69024)
		(width 0.1143)
		(layer "B.Cu")
		(net "MEMA_2")
	)
	(segment
		(start 286.627316 -196.633084)
		(end 286.608012 -196.633084)
		(width 0.1143)
		(layer "B.Cu")
		(net "MEMA_2")
	)
	(segment
		(start 287.514792 -188.384688)
		(end 287.191958 -188.70803)
		(width 0.1143)
		(layer "B.Cu")
		(net "MEMA_2")
	)
	(segment
		(start 286.131 -197.1294)
		(end 286.131 -198.826374)
		(width 0.1143)
		(layer "B.Cu")
		(net "MEMA_2")
	)
	(segment
		(start 286.49549 -200.167748)
		(end 286.29864 -200.364598)
		(width 0.1143)
		(layer "B.Cu")
		(net "MEMA_2")
	)
	(segment
		(start 287.191958 -188.70803)
		(end 287.191958 -190.538354)
		(width 0.1143)
		(layer "B.Cu")
		(net "MEMA_2")
	)
	(segment
		(start 286.630618 -199.710548)
		(end 286.49549 -199.845676)
		(width 0.1143)
		(layer "B.Cu")
		(net "MEMA_2")
	)
	(segment
		(start 287.613344 -186.92622)
		(end 287.5153 -187.024264)
		(width 0.1143)
		(layer "B.Cu")
		(net "MEMA_2")
	)
	(segment
		(start 288.08934 -182.121302)
		(end 288.08934 -183.162194)
		(width 0.1143)
		(layer "B.Cu")
		(net "MEMA_2")
	)
	(segment
		(start 288.08934 -183.162194)
		(end 287.613344 -183.63819)
		(width 0.1143)
		(layer "B.Cu")
		(net "MEMA_2")
	)
	(segment
		(start 286.630618 -199.325992)
		(end 286.630618 -199.710548)
		(width 0.1143)
		(layer "B.Cu")
		(net "MEMA_2")
	)
	(segment
		(start 288.544 -181.666642)
		(end 288.08934 -182.121302)
		(width 0.1143)
		(layer "B.Cu")
		(net "MEMA_2")
	)
	(segment
		(start 33.914588 -234.19308)
		(end 33.414716 -234.19308)
		(width 0.1143)
		(layer "F.Cu")
		(net "SAS_HDD_PWR9_PCIE")
	)
	(segment
		(start 37.999416 -250.595384)
		(end 34.351722 -246.94769)
		(width 0.1143)
		(layer "F.Cu")
		(net "SAS_HDD_PWR9_PCIE")
	)
	(segment
		(start 33.414716 -236.08538)
		(end 33.414716 -234.19308)
		(width 0.1143)
		(layer "F.Cu")
		(net "SAS_HDD_PWR9_PCIE")
	)
	(segment
		(start 34.351722 -246.94769)
		(end 34.351722 -234.630214)
		(width 0.1143)
		(layer "F.Cu")
		(net "SAS_HDD_PWR9_PCIE")
	)
	(segment
		(start 34.351722 -234.630214)
		(end 33.914588 -234.19308)
		(width 0.1143)
		(layer "F.Cu")
		(net "SAS_HDD_PWR9_PCIE")
	)
	(segment
		(start 37.999416 -256.25044)
		(end 37.999416 -250.595384)
		(width 0.1143)
		(layer "F.Cu")
		(net "SAS_HDD_PWR9_PCIE")
	)
	(via
		(at 33.414716 -236.08538)
		(size 0.5588)
		(drill 0.3048)
		(layers "F.Cu" "B.Cu")
		(net "SAS_HDD_PWR9_PCIE")
	)
	(via
		(at 34.494216 -233.68508)
		(size 0.7112)
		(drill 0.3556)
		(layers "F.Cu" "B.Cu")
		(net "SAS_HDD_PWR9_PCIE")
	)
	(segment
		(start 34.494216 -233.68508)
		(end 34.494216 -235.00588)
		(width 0.1143)
		(layer "B.Cu")
		(net "SAS_HDD_PWR9_PCIE")
	)
	(segment
		(start 34.494216 -235.00588)
		(end 33.414716 -236.08538)
		(width 0.1143)
		(layer "B.Cu")
		(net "SAS_HDD_PWR9_PCIE")
	)
	(segment
		(start 34.494216 -232.78338)
		(end 34.494216 -233.68508)
		(width 0.1143)
		(layer "B.Cu")
		(net "SAS_HDD_PWR9_PCIE")
	)
	(segment
		(start 41.999916 -251.929646)
		(end 41.999916 -256.25044)
		(width 0.1143)
		(layer "F.Cu")
		(net "SAS_HDD_PWR5_PCIE")
	)
	(segment
		(start 34.29 -231.902)
		(end 36.23691 -233.84891)
		(width 0.1143)
		(layer "F.Cu")
		(net "SAS_HDD_PWR5_PCIE")
	)
	(segment
		(start 32.385 -231.902)
		(end 34.29 -231.902)
		(width 0.1143)
		(layer "F.Cu")
		(net "SAS_HDD_PWR5_PCIE")
	)
	(segment
		(start 36.23691 -233.84891)
		(end 36.23691 -246.16664)
		(width 0.1143)
		(layer "F.Cu")
		(net "SAS_HDD_PWR5_PCIE")
	)
	(segment
		(start 30.874716 -233.412284)
		(end 32.385 -231.902)
		(width 0.1143)
		(layer "F.Cu")
		(net "SAS_HDD_PWR5_PCIE")
	)
	(segment
		(start 30.885892 -236.200696)
		(end 30.874716 -236.18952)
		(width 0.1143)
		(layer "F.Cu")
		(net "SAS_HDD_PWR5_PCIE")
	)
	(segment
		(start 30.874716 -234.19308)
		(end 30.874716 -233.412284)
		(width 0.1143)
		(layer "F.Cu")
		(net "SAS_HDD_PWR5_PCIE")
	)
	(segment
		(start 36.23691 -246.16664)
		(end 41.999916 -251.929646)
		(width 0.1143)
		(layer "F.Cu")
		(net "SAS_HDD_PWR5_PCIE")
	)
	(segment
		(start 30.874716 -236.18952)
		(end 30.874716 -234.19308)
		(width 0.1143)
		(layer "F.Cu")
		(net "SAS_HDD_PWR5_PCIE")
	)
	(via
		(at 30.430216 -233.76128)
		(size 0.7112)
		(drill 0.3556)
		(layers "F.Cu" "B.Cu")
		(net "SAS_HDD_PWR5_PCIE")
	)
	(via
		(at 30.885892 -236.200696)
		(size 0.5588)
		(drill 0.3048)
		(layers "F.Cu" "B.Cu")
		(net "SAS_HDD_PWR5_PCIE")
	)
	(segment
		(start 30.430216 -235.15828)
		(end 30.430216 -233.76128)
		(width 0.1143)
		(layer "B.Cu")
		(net "SAS_HDD_PWR5_PCIE")
	)
	(segment
		(start 30.885892 -236.200696)
		(end 30.885892 -235.613956)
		(width 0.1143)
		(layer "B.Cu")
		(net "SAS_HDD_PWR5_PCIE")
	)
	(segment
		(start 30.885892 -235.613956)
		(end 30.430216 -235.15828)
		(width 0.1143)
		(layer "B.Cu")
		(net "SAS_HDD_PWR5_PCIE")
	)
	(segment
		(start 30.430216 -233.76128)
		(end 30.430216 -232.78338)
		(width 0.1143)
		(layer "B.Cu")
		(net "SAS_HDD_PWR5_PCIE")
	)
	(segment
		(start 292.027102 -182.640224)
		(end 291.62629 -183.041036)
		(width 0.1143)
		(layer "F.Cu")
		(net "MEMWEN")
	)
	(segment
		(start 288.898076 -200.935082)
		(end 288.898076 -200.432162)
		(width 0.1143)
		(layer "F.Cu")
		(net "MEMWEN")
	)
	(segment
		(start 292.034976 -182.640224)
		(end 292.027102 -182.640224)
		(width 0.1143)
		(layer "F.Cu")
		(net "MEMWEN")
	)
	(segment
		(start 288.898076 -200.432162)
		(end 289.19043 -200.139808)
		(width 0.1143)
		(layer "F.Cu")
		(net "MEMWEN")
	)
	(via
		(at 291.62629 -183.041036)
		(size 0.508)
		(drill 0.254)
		(layers "F.Cu" "B.Cu")
		(net "MEMWEN")
	)
	(via
		(at 294.976296 -190.3857)
		(size 0.7112)
		(drill 0.3556)
		(layers "F.Cu" "B.Cu")
		(net "MEMWEN")
	)
	(via
		(at 289.19043 -200.139808)
		(size 0.508)
		(drill 0.254)
		(layers "F.Cu" "B.Cu")
		(net "MEMWEN")
	)
	(segment
		(start 294.29075 -193.26225)
		(end 293.670482 -193.882518)
		(width 0.1143)
		(layer "B.Cu")
		(net "MEMWEN")
	)
	(segment
		(start 291.352732 -198.53148)
		(end 290.93795 -198.946262)
		(width 0.1143)
		(layer "B.Cu")
		(net "MEMWEN")
	)
	(segment
		(start 292.059106 -197.824852)
		(end 291.352732 -198.53148)
		(width 0.1143)
		(layer "B.Cu")
		(net "MEMWEN")
	)
	(segment
		(start 293.670482 -193.882518)
		(end 293.670482 -193.979292)
		(width 0.1143)
		(layer "B.Cu")
		(net "MEMWEN")
	)
	(segment
		(start 294.235632 -191.617092)
		(end 294.29075 -191.67221)
		(width 0.1143)
		(layer "B.Cu")
		(net "MEMWEN")
	)
	(segment
		(start 290.93795 -198.946262)
		(end 290.93795 -199.092312)
		(width 0.1143)
		(layer "B.Cu")
		(net "MEMWEN")
	)
	(segment
		(start 295.20515 -186.323732)
		(end 295.20515 -186.792108)
		(width 0.1143)
		(layer "B.Cu")
		(net "MEMWEN")
	)
	(segment
		(start 291.62629 -183.041036)
		(end 291.676836 -183.041036)
		(width 0.1143)
		(layer "B.Cu")
		(net "MEMWEN")
	)
	(segment
		(start 291.676836 -183.041036)
		(end 293.9288 -185.293)
		(width 0.1143)
		(layer "B.Cu")
		(net "MEMWEN")
	)
	(segment
		(start 294.29075 -191.67221)
		(end 294.29075 -193.26225)
		(width 0.1143)
		(layer "B.Cu")
		(net "MEMWEN")
	)
	(segment
		(start 294.976296 -190.3857)
		(end 294.976296 -190.471044)
		(width 0.1143)
		(layer "B.Cu")
		(net "MEMWEN")
	)
	(segment
		(start 294.976296 -190.471044)
		(end 294.235632 -191.211708)
		(width 0.1143)
		(layer "B.Cu")
		(net "MEMWEN")
	)
	(segment
		(start 289.473386 -199.856852)
		(end 289.19043 -200.139808)
		(width 0.1143)
		(layer "B.Cu")
		(net "MEMWEN")
	)
	(segment
		(start 295.0464 -190.315596)
		(end 294.976296 -190.3857)
		(width 0.1143)
		(layer "B.Cu")
		(net "MEMWEN")
	)
	(segment
		(start 295.20515 -186.792108)
		(end 295.0464 -186.950858)
		(width 0.1143)
		(layer "B.Cu")
		(net "MEMWEN")
	)
	(segment
		(start 295.0464 -186.950858)
		(end 295.0464 -190.315596)
		(width 0.1143)
		(layer "B.Cu")
		(net "MEMWEN")
	)
	(segment
		(start 292.608 -195.808346)
		(end 292.059106 -196.357494)
		(width 0.1143)
		(layer "B.Cu")
		(net "MEMWEN")
	)
	(segment
		(start 290.93795 -199.092312)
		(end 290.17341 -199.856852)
		(width 0.1143)
		(layer "B.Cu")
		(net "MEMWEN")
	)
	(segment
		(start 293.670482 -193.979292)
		(end 292.608 -195.041774)
		(width 0.1143)
		(layer "B.Cu")
		(net "MEMWEN")
	)
	(segment
		(start 294.235632 -191.211708)
		(end 294.235632 -191.617092)
		(width 0.1143)
		(layer "B.Cu")
		(net "MEMWEN")
	)
	(segment
		(start 290.17341 -199.856852)
		(end 289.473386 -199.856852)
		(width 0.1143)
		(layer "B.Cu")
		(net "MEMWEN")
	)
	(segment
		(start 293.9288 -185.293)
		(end 294.174418 -185.293)
		(width 0.1143)
		(layer "B.Cu")
		(net "MEMWEN")
	)
	(segment
		(start 292.608 -195.041774)
		(end 292.608 -195.808346)
		(width 0.1143)
		(layer "B.Cu")
		(net "MEMWEN")
	)
	(segment
		(start 292.059106 -196.357494)
		(end 292.059106 -197.824852)
		(width 0.1143)
		(layer "B.Cu")
		(net "MEMWEN")
	)
	(segment
		(start 294.174418 -185.293)
		(end 295.20515 -186.323732)
		(width 0.1143)
		(layer "B.Cu")
		(net "MEMWEN")
	)
	(segment
		(start 46.999906 -256.25044)
		(end 46.999906 -253.755906)
		(width 0.1143)
		(layer "F.Cu")
		(net "SAS_HDD_PWR0_PCIE")
	)
	(segment
		(start 38.481 -232.918)
		(end 35.56 -229.997)
		(width 0.1143)
		(layer "F.Cu")
		(net "SAS_HDD_PWR0_PCIE")
	)
	(segment
		(start 31.242 -229.997)
		(end 27.699716 -233.539284)
		(width 0.1143)
		(layer "F.Cu")
		(net "SAS_HDD_PWR0_PCIE")
	)
	(segment
		(start 27.699716 -236.91088)
		(end 27.699716 -234.19308)
		(width 0.1143)
		(layer "F.Cu")
		(net "SAS_HDD_PWR0_PCIE")
	)
	(segment
		(start 27.699716 -233.539284)
		(end 27.699716 -234.19308)
		(width 0.1143)
		(layer "F.Cu")
		(net "SAS_HDD_PWR0_PCIE")
	)
	(segment
		(start 38.481 -245.237)
		(end 38.481 -232.918)
		(width 0.1143)
		(layer "F.Cu")
		(net "SAS_HDD_PWR0_PCIE")
	)
	(segment
		(start 46.999906 -253.755906)
		(end 38.481 -245.237)
		(width 0.1143)
		(layer "F.Cu")
		(net "SAS_HDD_PWR0_PCIE")
	)
	(segment
		(start 35.56 -229.997)
		(end 31.242 -229.997)
		(width 0.1143)
		(layer "F.Cu")
		(net "SAS_HDD_PWR0_PCIE")
	)
	(via
		(at 25.350216 -233.81208)
		(size 0.7112)
		(drill 0.3556)
		(layers "F.Cu" "B.Cu")
		(net "SAS_HDD_PWR0_PCIE")
	)
	(via
		(at 27.699716 -236.91088)
		(size 0.5588)
		(drill 0.3048)
		(layers "F.Cu" "B.Cu")
		(net "SAS_HDD_PWR0_PCIE")
	)
	(segment
		(start 25.350216 -232.78338)
		(end 25.350216 -233.81208)
		(width 0.1143)
		(layer "B.Cu")
		(net "SAS_HDD_PWR0_PCIE")
	)
	(segment
		(start 25.350216 -233.81208)
		(end 25.350216 -234.56138)
		(width 0.1143)
		(layer "B.Cu")
		(net "SAS_HDD_PWR0_PCIE")
	)
	(segment
		(start 25.350216 -234.56138)
		(end 27.699716 -236.91088)
		(width 0.1143)
		(layer "B.Cu")
		(net "SAS_HDD_PWR0_PCIE")
	)
	(segment
		(start 291.298122 -198.595488)
		(end 290.474908 -199.418702)
		(width 0.1143)
		(layer "F.Cu")
		(net "MEMDQ_0")
	)
	(segment
		(start 292.834822 -181.849522)
		(end 292.434772 -182.249572)
		(width 0.1143)
		(layer "F.Cu")
		(net "MEMDQ_0")
	)
	(segment
		(start 291.298122 -197.73519)
		(end 291.298122 -198.595488)
		(width 0.1143)
		(layer "F.Cu")
		(net "MEMDQ_0")
	)
	(segment
		(start 292.834822 -181.840124)
		(end 292.834822 -181.849522)
		(width 0.1143)
		(layer "F.Cu")
		(net "MEMDQ_0")
	)
	(segment
		(start 290.474908 -199.418702)
		(end 289.9918 -199.418702)
		(width 0.1143)
		(layer "F.Cu")
		(net "MEMDQ_0")
	)
	(via
		(at 292.788086 -182.896256)
		(size 0.7112)
		(drill 0.3556)
		(layers "F.Cu" "B.Cu")
		(net "MEMDQ_0")
	)
	(via
		(at 289.9918 -199.418702)
		(size 0.508)
		(drill 0.254)
		(layers "F.Cu" "B.Cu")
		(net "MEMDQ_0")
	)
	(via
		(at 292.434772 -182.249572)
		(size 0.508)
		(drill 0.254)
		(layers "F.Cu" "B.Cu")
		(net "MEMDQ_0")
	)
	(segment
		(start 292.788086 -182.896256)
		(end 292.434772 -182.542942)
		(width 0.1143)
		(layer "B.Cu")
		(net "MEMDQ_0")
	)
	(segment
		(start 292.434772 -182.542942)
		(end 292.434772 -182.249572)
		(width 0.1143)
		(layer "B.Cu")
		(net "MEMDQ_0")
	)
	(segment
		(start 289.27552 -185.34253)
		(end 289.27552 -189.501018)
		(width 0.127)
		(layer "In5.Cu")
		(net "MEMDQ_0")
	)
	(segment
		(start 291.933884 -183.326278)
		(end 291.800026 -183.460136)
		(width 0.127)
		(layer "In5.Cu")
		(net "MEMDQ_0")
	)
	(segment
		(start 288.97453 -197.035674)
		(end 288.851594 -197.15861)
		(width 0.127)
		(layer "In5.Cu")
		(net "MEMDQ_0")
	)
	(segment
		(start 288.97453 -189.802008)
		(end 288.97453 -197.035674)
		(width 0.127)
		(layer "In5.Cu")
		(net "MEMDQ_0")
	)
	(segment
		(start 289.27552 -189.501018)
		(end 288.97453 -189.802008)
		(width 0.127)
		(layer "In5.Cu")
		(net "MEMDQ_0")
	)
	(segment
		(start 291.452554 -183.460136)
		(end 291.446458 -183.45404)
		(width 0.127)
		(layer "In5.Cu")
		(net "MEMDQ_0")
	)
	(segment
		(start 289.2806 -198.938134)
		(end 289.761168 -199.418702)
		(width 0.127)
		(layer "In5.Cu")
		(net "MEMDQ_0")
	)
	(segment
		(start 291.16401 -183.45404)
		(end 289.27552 -185.34253)
		(width 0.127)
		(layer "In5.Cu")
		(net "MEMDQ_0")
	)
	(segment
		(start 292.434772 -182.926228)
		(end 292.034722 -183.326278)
		(width 0.1016)
		(layer "In5.Cu")
		(net "MEMDQ_0")
	)
	(segment
		(start 288.851594 -197.52691)
		(end 289.2806 -197.955916)
		(width 0.127)
		(layer "In5.Cu")
		(net "MEMDQ_0")
	)
	(segment
		(start 292.034722 -183.326278)
		(end 291.933884 -183.326278)
		(width 0.127)
		(layer "In5.Cu")
		(net "MEMDQ_0")
	)
	(segment
		(start 291.446458 -183.45404)
		(end 291.16401 -183.45404)
		(width 0.127)
		(layer "In5.Cu")
		(net "MEMDQ_0")
	)
	(segment
		(start 292.434772 -182.249572)
		(end 292.434772 -182.926228)
		(width 0.1016)
		(layer "In5.Cu")
		(net "MEMDQ_0")
	)
	(segment
		(start 291.800026 -183.460136)
		(end 291.452554 -183.460136)
		(width 0.127)
		(layer "In5.Cu")
		(net "MEMDQ_0")
	)
	(segment
		(start 289.2806 -197.955916)
		(end 289.2806 -198.938134)
		(width 0.127)
		(layer "In5.Cu")
		(net "MEMDQ_0")
	)
	(segment
		(start 288.851594 -197.15861)
		(end 288.851594 -197.52691)
		(width 0.127)
		(layer "In5.Cu")
		(net "MEMDQ_0")
	)
	(segment
		(start 289.761168 -199.418702)
		(end 289.9918 -199.418702)
		(width 0.127)
		(layer "In5.Cu")
		(net "MEMDQ_0")
	)
	(segment
		(start 18.248884 -180.442616)
		(end 18.248884 -183.496204)
		(width 0.1143)
		(layer "F.Cu")
		(net "SAS_HDD_PRE13")
	)
	(segment
		(start 20.861528 -174.856394)
		(end 20.861528 -177.829972)
		(width 0.1143)
		(layer "F.Cu")
		(net "SAS_HDD_PRE13")
	)
	(segment
		(start 20.861528 -177.829972)
		(end 18.248884 -180.442616)
		(width 0.1143)
		(layer "F.Cu")
		(net "SAS_HDD_PRE13")
	)
	(segment
		(start 18.484088 -185.384186)
		(end 18.484088 -183.731408)
		(width 0.1143)
		(layer "F.Cu")
		(net "SAS_HDD_PRE13")
	)
	(segment
		(start 18.484088 -183.731408)
		(end 18.248884 -183.496204)
		(width 0.1143)
		(layer "F.Cu")
		(net "SAS_HDD_PRE13")
	)
	(segment
		(start 18.385028 -175.746156)
		(end 18.378932 -175.74006)
		(width 0.1143)
		(layer "F.Cu")
		(net "SAS_HDD_PRE13")
	)
	(segment
		(start 18.378932 -174.578264)
		(end 18.89379 -174.063406)
		(width 0.1143)
		(layer "F.Cu")
		(net "SAS_HDD_PRE13")
	)
	(segment
		(start 18.509488 -185.409586)
		(end 18.484088 -185.384186)
		(width 0.1143)
		(layer "F.Cu")
		(net "SAS_HDD_PRE13")
	)
	(segment
		(start 20.06854 -174.063406)
		(end 20.861528 -174.856394)
		(width 0.1143)
		(layer "F.Cu")
		(net "SAS_HDD_PRE13")
	)
	(segment
		(start 18.378932 -175.74006)
		(end 18.378932 -174.578264)
		(width 0.1143)
		(layer "F.Cu")
		(net "SAS_HDD_PRE13")
	)
	(segment
		(start 18.89379 -174.063406)
		(end 20.06854 -174.063406)
		(width 0.1143)
		(layer "F.Cu")
		(net "SAS_HDD_PRE13")
	)
	(via
		(at 18.248884 -183.496204)
		(size 0.5588)
		(drill 0.3048)
		(layers "F.Cu" "B.Cu")
		(net "SAS_HDD_PRE13")
	)
	(via
		(at 18.248884 -184.546748)
		(size 0.7112)
		(drill 0.3556)
		(layers "F.Cu" "B.Cu")
		(net "SAS_HDD_PRE13")
	)
	(segment
		(start 3.068066 -201.958448)
		(end 18.248884 -186.77763)
		(width 0.1143)
		(layer "B.Cu")
		(net "SAS_HDD_PRE13")
	)
	(segment
		(start 31.999936 -249.677936)
		(end 27.948636 -245.626636)
		(width 0.1143)
		(layer "B.Cu")
		(net "SAS_HDD_PRE13")
	)
	(segment
		(start 10.498836 -245.626636)
		(end 3.068066 -238.195866)
		(width 0.1143)
		(layer "B.Cu")
		(net "SAS_HDD_PRE13")
	)
	(segment
		(start 18.248884 -184.546748)
		(end 18.248884 -183.496204)
		(width 0.1143)
		(layer "B.Cu")
		(net "SAS_HDD_PRE13")
	)
	(segment
		(start 27.948636 -245.626636)
		(end 10.498836 -245.626636)
		(width 0.1143)
		(layer "B.Cu")
		(net "SAS_HDD_PRE13")
	)
	(segment
		(start 31.999936 -256.50444)
		(end 31.999936 -249.677936)
		(width 0.1143)
		(layer "B.Cu")
		(net "SAS_HDD_PRE13")
	)
	(segment
		(start 3.068066 -238.195866)
		(end 3.068066 -201.958448)
		(width 0.1143)
		(layer "B.Cu")
		(net "SAS_HDD_PRE13")
	)
	(segment
		(start 18.248884 -186.77763)
		(end 18.248884 -184.546748)
		(width 0.1143)
		(layer "B.Cu")
		(net "SAS_HDD_PRE13")
	)
	(segment
		(start 161.676588 -23.739856)
		(end 162.274504 -23.739856)
		(width 0.127)
		(layer "F.Cu")
		(net "TP_LAN_7")
	)
	(segment
		(start 158.474918 -17.809972)
		(end 158.465012 -17.819878)
		(width 0.127)
		(layer "F.Cu")
		(net "TP_LAN_7")
	)
	(segment
		(start 158.465012 -17.819878)
		(end 158.465012 -20.52828)
		(width 0.127)
		(layer "F.Cu")
		(net "TP_LAN_7")
	)
	(segment
		(start 158.465012 -20.52828)
		(end 161.676588 -23.739856)
		(width 0.127)
		(layer "F.Cu")
		(net "TP_LAN_7")
	)
	(segment
		(start 283.451808 -174.609506)
		(end 283.324808 -174.482506)
		(width 0.1143)
		(layer "F.Cu")
		(net "BMC0_SMB1_CLK")
	)
	(segment
		(start 285.346902 -174.64024)
		(end 285.010352 -174.97679)
		(width 0.1143)
		(layer "F.Cu")
		(net "BMC0_SMB1_CLK")
	)
	(segment
		(start 274.7645 -171.704)
		(end 276.098 -171.704)
		(width 0.1143)
		(layer "F.Cu")
		(net "BMC0_SMB1_CLK")
	)
	(segment
		(start 285.634938 -174.64024)
		(end 285.346902 -174.64024)
		(width 0.1143)
		(layer "F.Cu")
		(net "BMC0_SMB1_CLK")
	)
	(segment
		(start 283.324808 -174.482506)
		(end 281.457908 -174.482506)
		(width 0.1143)
		(layer "F.Cu")
		(net "BMC0_SMB1_CLK")
	)
	(segment
		(start 281.457908 -174.482506)
		(end 278.67864 -171.704)
		(width 0.1143)
		(layer "F.Cu")
		(net "BMC0_SMB1_CLK")
	)
	(segment
		(start 284.411166 -174.97679)
		(end 284.043882 -174.609506)
		(width 0.1143)
		(layer "F.Cu")
		(net "BMC0_SMB1_CLK")
	)
	(segment
		(start 274.6375 -171.577)
		(end 274.7645 -171.704)
		(width 0.1143)
		(layer "F.Cu")
		(net "BMC0_SMB1_CLK")
	)
	(segment
		(start 285.010352 -174.97679)
		(end 284.411166 -174.97679)
		(width 0.1143)
		(layer "F.Cu")
		(net "BMC0_SMB1_CLK")
	)
	(segment
		(start 278.67864 -171.704)
		(end 276.098 -171.704)
		(width 0.1143)
		(layer "F.Cu")
		(net "BMC0_SMB1_CLK")
	)
	(segment
		(start 284.043882 -174.609506)
		(end 283.451808 -174.609506)
		(width 0.1143)
		(layer "F.Cu")
		(net "BMC0_SMB1_CLK")
	)
	(via
		(at 276.098 -171.704)
		(size 0.7112)
		(drill 0.3556)
		(layers "F.Cu" "B.Cu")
		(net "BMC0_SMB1_CLK")
	)
	(segment
		(start 107.53725 -245.39575)
		(end 107.53725 -242.94465)
		(width 0.1143)
		(layer "F.Cu")
		(net "SAS_FAULT_LED7")
	)
	(segment
		(start 105.77195 -240.51895)
		(end 105.6005 -240.3475)
		(width 0.1143)
		(layer "F.Cu")
		(net "SAS_FAULT_LED7")
	)
	(segment
		(start 103.632 -249.992642)
		(end 103.937308 -250.29795)
		(width 0.1143)
		(layer "F.Cu")
		(net "SAS_FAULT_LED7")
	)
	(segment
		(start 104.902 -249.809)
		(end 105.0544 -249.809)
		(width 0.1143)
		(layer "F.Cu")
		(net "SAS_FAULT_LED7")
	)
	(segment
		(start 103.632 -248.145046)
		(end 103.632 -249.992642)
		(width 0.1143)
		(layer "F.Cu")
		(net "SAS_FAULT_LED7")
	)
	(segment
		(start 98.617532 -244.094)
		(end 99.580954 -244.094)
		(width 0.1143)
		(layer "F.Cu")
		(net "SAS_FAULT_LED7")
	)
	(segment
		(start 105.77195 -241.17935)
		(end 105.77195 -240.51895)
		(width 0.1143)
		(layer "F.Cu")
		(net "SAS_FAULT_LED7")
	)
	(segment
		(start 99.441 -232.918)
		(end 98.552 -233.807)
		(width 0.1143)
		(layer "F.Cu")
		(net "SAS_FAULT_LED7")
	)
	(segment
		(start 103.4415 -231.521)
		(end 103.124 -231.521)
		(width 0.1143)
		(layer "F.Cu")
		(net "SAS_FAULT_LED7")
	)
	(segment
		(start 101.854 -232.41)
		(end 101.346 -232.918)
		(width 0.1143)
		(layer "F.Cu")
		(net "SAS_FAULT_LED7")
	)
	(segment
		(start 106.03865 -238.13135)
		(end 105.6005 -238.5695)
		(width 0.1143)
		(layer "F.Cu")
		(net "SAS_FAULT_LED7")
	)
	(segment
		(start 105.0544 -249.809)
		(end 105.0544 -249.6566)
		(width 0.1143)
		(layer "F.Cu")
		(net "SAS_FAULT_LED7")
	)
	(segment
		(start 105.918 -248.793)
		(end 105.918 -247.015)
		(width 0.1143)
		(layer "F.Cu")
		(net "SAS_FAULT_LED7")
	)
	(segment
		(start 103.937308 -250.29795)
		(end 104.41305 -250.29795)
		(width 0.1143)
		(layer "F.Cu")
		(net "SAS_FAULT_LED7")
	)
	(segment
		(start 105.918 -247.015)
		(end 107.53725 -245.39575)
		(width 0.1143)
		(layer "F.Cu")
		(net "SAS_FAULT_LED7")
	)
	(segment
		(start 101.346 -232.918)
		(end 99.441 -232.918)
		(width 0.1143)
		(layer "F.Cu")
		(net "SAS_FAULT_LED7")
	)
	(segment
		(start 95.58655 -241.063018)
		(end 98.617532 -244.094)
		(width 0.1143)
		(layer "F.Cu")
		(net "SAS_FAULT_LED7")
	)
	(segment
		(start 107.51185 -238.13135)
		(end 106.03865 -238.13135)
		(width 0.1143)
		(layer "F.Cu")
		(net "SAS_FAULT_LED7")
	)
	(segment
		(start 107.53725 -242.94465)
		(end 105.77195 -241.17935)
		(width 0.1143)
		(layer "F.Cu")
		(net "SAS_FAULT_LED7")
	)
	(segment
		(start 104.41305 -250.29795)
		(end 104.902 -249.809)
		(width 0.1143)
		(layer "F.Cu")
		(net "SAS_FAULT_LED7")
	)
	(segment
		(start 98.552 -233.807)
		(end 98.552 -235.03255)
		(width 0.1143)
		(layer "F.Cu")
		(net "SAS_FAULT_LED7")
	)
	(segment
		(start 105.0544 -249.6566)
		(end 105.918 -248.793)
		(width 0.1143)
		(layer "F.Cu")
		(net "SAS_FAULT_LED7")
	)
	(segment
		(start 108.5215 -239.141)
		(end 107.51185 -238.13135)
		(width 0.1143)
		(layer "F.Cu")
		(net "SAS_FAULT_LED7")
	)
	(segment
		(start 105.6005 -238.5695)
		(end 105.6005 -239.4712)
		(width 0.1143)
		(layer "F.Cu")
		(net "SAS_FAULT_LED7")
	)
	(segment
		(start 98.552 -235.03255)
		(end 95.58655 -237.998)
		(width 0.1143)
		(layer "F.Cu")
		(net "SAS_FAULT_LED7")
	)
	(segment
		(start 105.6005 -240.3475)
		(end 105.6005 -239.4712)
		(width 0.1143)
		(layer "F.Cu")
		(net "SAS_FAULT_LED7")
	)
	(segment
		(start 103.124 -231.521)
		(end 102.235 -232.41)
		(width 0.1143)
		(layer "F.Cu")
		(net "SAS_FAULT_LED7")
	)
	(segment
		(start 95.58655 -237.998)
		(end 95.58655 -241.063018)
		(width 0.1143)
		(layer "F.Cu")
		(net "SAS_FAULT_LED7")
	)
	(segment
		(start 102.235 -232.41)
		(end 101.854 -232.41)
		(width 0.1143)
		(layer "F.Cu")
		(net "SAS_FAULT_LED7")
	)
	(segment
		(start 99.580954 -244.094)
		(end 103.632 -248.145046)
		(width 0.1143)
		(layer "F.Cu")
		(net "SAS_FAULT_LED7")
	)
	(via
		(at 102.5906 -251.587)
		(size 0.7112)
		(drill 0.3556)
		(layers "F.Cu" "B.Cu")
		(net "SAS_FAULT_LED7")
	)
	(via
		(at 105.0544 -249.809)
		(size 0.5588)
		(drill 0.3048)
		(layers "F.Cu" "B.Cu")
		(net "SAS_FAULT_LED7")
	)
	(segment
		(start 102.8446 -251.333)
		(end 104.521 -251.333)
		(width 0.1143)
		(layer "B.Cu")
		(net "SAS_FAULT_LED7")
	)
	(segment
		(start 104.521 -251.333)
		(end 105.0544 -250.7996)
		(width 0.1143)
		(layer "B.Cu")
		(net "SAS_FAULT_LED7")
	)
	(segment
		(start 102.5906 -251.587)
		(end 102.108 -251.587)
		(width 0.1143)
		(layer "B.Cu")
		(net "SAS_FAULT_LED7")
	)
	(segment
		(start 101.000052 -252.694948)
		(end 101.000052 -256.50444)
		(width 0.1143)
		(layer "B.Cu")
		(net "SAS_FAULT_LED7")
	)
	(segment
		(start 102.5906 -251.587)
		(end 102.8446 -251.333)
		(width 0.1143)
		(layer "B.Cu")
		(net "SAS_FAULT_LED7")
	)
	(segment
		(start 105.0544 -250.7996)
		(end 105.0544 -249.809)
		(width 0.1143)
		(layer "B.Cu")
		(net "SAS_FAULT_LED7")
	)
	(segment
		(start 102.108 -251.587)
		(end 101.000052 -252.694948)
		(width 0.1143)
		(layer "B.Cu")
		(net "SAS_FAULT_LED7")
	)
	(segment
		(start 149.94001 -2.320036)
		(end 148.6662 -3.593846)
		(width 0.1778)
		(layer "F.Cu")
		(net "LED_MDI0_ACT")
	)
	(segment
		(start 168.7322 -15.5702)
		(end 169.291 -16.129)
		(width 0.1778)
		(layer "F.Cu")
		(net "LED_MDI0_ACT")
	)
	(segment
		(start 151.1808 -9.1186)
		(end 167.2082 -9.1186)
		(width 0.1778)
		(layer "F.Cu")
		(net "LED_MDI0_ACT")
	)
	(segment
		(start 169.291 -16.129)
		(end 170.369992 -16.129)
		(width 0.1778)
		(layer "F.Cu")
		(net "LED_MDI0_ACT")
	)
	(segment
		(start 148.6662 -3.593846)
		(end 148.6662 -6.604)
		(width 0.1778)
		(layer "F.Cu")
		(net "LED_MDI0_ACT")
	)
	(segment
		(start 148.6662 -6.604)
		(end 151.1808 -9.1186)
		(width 0.1778)
		(layer "F.Cu")
		(net "LED_MDI0_ACT")
	)
	(segment
		(start 167.2082 -9.1186)
		(end 168.7322 -10.6426)
		(width 0.1778)
		(layer "F.Cu")
		(net "LED_MDI0_ACT")
	)
	(segment
		(start 168.7322 -10.6426)
		(end 168.7322 -15.5702)
		(width 0.1778)
		(layer "F.Cu")
		(net "LED_MDI0_ACT")
	)
	(segment
		(start 21.110448 -193.22288)
		(end 21.110448 -191.020446)
		(width 0.1143)
		(layer "F.Cu")
		(net "SAS_HDD_PRE2")
	)
	(segment
		(start 30.589982 -174.182786)
		(end 29.365702 -172.958506)
		(width 0.1143)
		(layer "F.Cu")
		(net "SAS_HDD_PRE2")
	)
	(segment
		(start 26.055574 -175.71593)
		(end 26.025348 -175.746156)
		(width 0.1143)
		(layer "F.Cu")
		(net "SAS_HDD_PRE2")
	)
	(segment
		(start 30.805882 -182.158894)
		(end 30.805628 -182.15864)
		(width 0.1143)
		(layer "F.Cu")
		(net "SAS_HDD_PRE2")
	)
	(segment
		(start 29.365702 -172.958506)
		(end 27.483054 -172.958506)
		(width 0.1143)
		(layer "F.Cu")
		(net "SAS_HDD_PRE2")
	)
	(segment
		(start 30.590236 -174.182786)
		(end 30.589982 -174.182786)
		(width 0.1143)
		(layer "F.Cu")
		(net "SAS_HDD_PRE2")
	)
	(segment
		(start 21.110448 -189.94374)
		(end 21.806408 -189.24778)
		(width 0.1143)
		(layer "F.Cu")
		(net "SAS_HDD_PRE2")
	)
	(segment
		(start 30.805882 -182.769002)
		(end 30.805882 -182.158894)
		(width 0.1143)
		(layer "F.Cu")
		(net "SAS_HDD_PRE2")
	)
	(segment
		(start 30.805374 -182.769764)
		(end 30.805882 -182.769002)
		(width 0.1143)
		(layer "F.Cu")
		(net "SAS_HDD_PRE2")
	)
	(segment
		(start 21.110448 -191.020446)
		(end 21.110448 -189.94374)
		(width 0.1143)
		(layer "F.Cu")
		(net "SAS_HDD_PRE2")
	)
	(segment
		(start 30.805628 -182.15864)
		(end 30.805628 -174.398178)
		(width 0.1143)
		(layer "F.Cu")
		(net "SAS_HDD_PRE2")
	)
	(segment
		(start 21.806408 -189.24778)
		(end 24.327358 -189.24778)
		(width 0.1143)
		(layer "F.Cu")
		(net "SAS_HDD_PRE2")
	)
	(segment
		(start 26.055574 -174.385986)
		(end 26.055574 -175.71593)
		(width 0.1143)
		(layer "F.Cu")
		(net "SAS_HDD_PRE2")
	)
	(segment
		(start 30.805628 -174.398178)
		(end 30.590236 -174.182786)
		(width 0.1143)
		(layer "F.Cu")
		(net "SAS_HDD_PRE2")
	)
	(segment
		(start 27.483054 -172.958506)
		(end 26.055574 -174.385986)
		(width 0.1143)
		(layer "F.Cu")
		(net "SAS_HDD_PRE2")
	)
	(segment
		(start 24.327358 -189.24778)
		(end 30.805374 -182.769764)
		(width 0.1143)
		(layer "F.Cu")
		(net "SAS_HDD_PRE2")
	)
	(via
		(at 19.686016 -194.92468)
		(size 0.7112)
		(drill 0.3556)
		(layers "F.Cu" "B.Cu")
		(net "SAS_HDD_PRE2")
	)
	(via
		(at 21.110448 -193.22288)
		(size 0.5588)
		(drill 0.3048)
		(layers "F.Cu" "B.Cu")
		(net "SAS_HDD_PRE2")
	)
	(segment
		(start 19.175984 -194.93357)
		(end 19.677126 -194.93357)
		(width 0.1143)
		(layer "B.Cu")
		(net "SAS_HDD_PRE2")
	)
	(segment
		(start 20.362672 -194.92468)
		(end 21.110448 -194.176904)
		(width 0.1143)
		(layer "B.Cu")
		(net "SAS_HDD_PRE2")
	)
	(segment
		(start 44.999656 -256.50444)
		(end 44.999656 -253.79934)
		(width 0.1143)
		(layer "B.Cu")
		(net "SAS_HDD_PRE2")
	)
	(segment
		(start 44.999656 -253.79934)
		(end 32.289496 -241.08918)
		(width 0.1143)
		(layer "B.Cu")
		(net "SAS_HDD_PRE2")
	)
	(segment
		(start 21.110448 -194.176904)
		(end 21.110448 -193.22288)
		(width 0.1143)
		(layer "B.Cu")
		(net "SAS_HDD_PRE2")
	)
	(segment
		(start 19.677126 -194.93357)
		(end 19.686016 -194.92468)
		(width 0.1143)
		(layer "B.Cu")
		(net "SAS_HDD_PRE2")
	)
	(segment
		(start 11.691874 -241.08918)
		(end 7.119366 -236.516672)
		(width 0.1143)
		(layer "B.Cu")
		(net "SAS_HDD_PRE2")
	)
	(segment
		(start 7.119366 -236.516672)
		(end 7.119366 -206.990188)
		(width 0.1143)
		(layer "B.Cu")
		(net "SAS_HDD_PRE2")
	)
	(segment
		(start 7.119366 -206.990188)
		(end 19.175984 -194.93357)
		(width 0.1143)
		(layer "B.Cu")
		(net "SAS_HDD_PRE2")
	)
	(segment
		(start 19.686016 -194.92468)
		(end 20.362672 -194.92468)
		(width 0.1143)
		(layer "B.Cu")
		(net "SAS_HDD_PRE2")
	)
	(segment
		(start 32.289496 -241.08918)
		(end 11.691874 -241.08918)
		(width 0.1143)
		(layer "B.Cu")
		(net "SAS_HDD_PRE2")
	)
	(segment
		(start 164.15766 -23.241)
		(end 164.560504 -23.643844)
		(width 0.127)
		(layer "F.Cu")
		(net "TP_LAN_5")
	)
	(segment
		(start 160.655 -20.6883)
		(end 163.2077 -23.241)
		(width 0.127)
		(layer "F.Cu")
		(net "TP_LAN_5")
	)
	(segment
		(start 163.2077 -23.241)
		(end 164.15766 -23.241)
		(width 0.127)
		(layer "F.Cu")
		(net "TP_LAN_5")
	)
	(segment
		(start 160.504886 -17.809972)
		(end 160.655 -17.960086)
		(width 0.127)
		(layer "F.Cu")
		(net "TP_LAN_5")
	)
	(segment
		(start 160.655 -17.960086)
		(end 160.655 -20.6883)
		(width 0.127)
		(layer "F.Cu")
		(net "TP_LAN_5")
	)
	(segment
		(start 164.560504 -23.643844)
		(end 164.560504 -23.739856)
		(width 0.127)
		(layer "F.Cu")
		(net "TP_LAN_5")
	)
	(segment
		(start 285.698184 -197.222872)
		(end 285.2928 -197.628256)
		(width 0.1143)
		(layer "F.Cu")
		(net "MEMA_6")
	)
	(segment
		(start 289.223958 -185.901584)
		(end 286.497522 -188.62802)
		(width 0.1143)
		(layer "F.Cu")
		(net "MEMA_6")
	)
	(segment
		(start 285.747968 -188.906404)
		(end 285.341822 -188.906404)
		(width 0.1143)
		(layer "F.Cu")
		(net "MEMA_6")
	)
	(segment
		(start 289.223958 -185.126884)
		(end 289.223958 -185.901584)
		(width 0.1143)
		(layer "F.Cu")
		(net "MEMA_6")
	)
	(segment
		(start 289.97148 -184.379616)
		(end 289.223958 -185.126884)
		(width 0.1143)
		(layer "F.Cu")
		(net "MEMA_6")
	)
	(segment
		(start 285.698184 -196.93509)
		(end 285.698184 -197.222872)
		(width 0.1143)
		(layer "F.Cu")
		(net "MEMA_6")
	)
	(segment
		(start 290.434776 -183.764174)
		(end 289.97148 -184.22747)
		(width 0.1143)
		(layer "F.Cu")
		(net "MEMA_6")
	)
	(segment
		(start 290.434776 -183.44007)
		(end 290.434776 -183.764174)
		(width 0.1143)
		(layer "F.Cu")
		(net "MEMA_6")
	)
	(segment
		(start 289.97148 -184.22747)
		(end 289.97148 -184.379616)
		(width 0.1143)
		(layer "F.Cu")
		(net "MEMA_6")
	)
	(segment
		(start 286.026352 -188.62802)
		(end 285.747968 -188.906404)
		(width 0.1143)
		(layer "F.Cu")
		(net "MEMA_6")
	)
	(segment
		(start 286.497522 -188.62802)
		(end 286.026352 -188.62802)
		(width 0.1143)
		(layer "F.Cu")
		(net "MEMA_6")
	)
	(segment
		(start 285.2928 -197.628256)
		(end 285.2928 -199.1106)
		(width 0.1143)
		(layer "F.Cu")
		(net "MEMA_6")
	)
	(via
		(at 285.301182 -196.127878)
		(size 0.7112)
		(drill 0.3556)
		(layers "F.Cu" "B.Cu")
		(net "MEMA_6")
	)
	(via
		(at 285.2928 -199.1106)
		(size 0.5588)
		(drill 0.3048)
		(layers "F.Cu" "B.Cu")
		(net "MEMA_6")
	)
	(via
		(at 285.341822 -188.906404)
		(size 0.508)
		(drill 0.254)
		(layers "F.Cu" "B.Cu")
		(net "MEMA_6")
	)
	(segment
		(start 285.341822 -188.906404)
		(end 285.341822 -188.999114)
		(width 0.1143)
		(layer "B.Cu")
		(net "MEMA_6")
	)
	(segment
		(start 285.2928 -197.970902)
		(end 285.2928 -199.1106)
		(width 0.1143)
		(layer "B.Cu")
		(net "MEMA_6")
	)
	(segment
		(start 285.301182 -195.415662)
		(end 285.301182 -196.127878)
		(width 0.1143)
		(layer "B.Cu")
		(net "MEMA_6")
	)
	(segment
		(start 285.341822 -188.999114)
		(end 284.73019 -189.610746)
		(width 0.1143)
		(layer "B.Cu")
		(net "MEMA_6")
	)
	(segment
		(start 284.88005 -197.047612)
		(end 284.88005 -197.558152)
		(width 0.1143)
		(layer "B.Cu")
		(net "MEMA_6")
	)
	(segment
		(start 285.301182 -196.62648)
		(end 284.88005 -197.047612)
		(width 0.1143)
		(layer "B.Cu")
		(net "MEMA_6")
	)
	(segment
		(start 284.88005 -197.558152)
		(end 285.2928 -197.970902)
		(width 0.1143)
		(layer "B.Cu")
		(net "MEMA_6")
	)
	(segment
		(start 284.73019 -189.610746)
		(end 284.73019 -194.84467)
		(width 0.1143)
		(layer "B.Cu")
		(net "MEMA_6")
	)
	(segment
		(start 284.73019 -194.84467)
		(end 285.301182 -195.415662)
		(width 0.1143)
		(layer "B.Cu")
		(net "MEMA_6")
	)
	(segment
		(start 285.301182 -196.127878)
		(end 285.301182 -196.62648)
		(width 0.1143)
		(layer "B.Cu")
		(net "MEMA_6")
	)
	(segment
		(start 101.7905 -243.6495)
		(end 101.7905 -241.808)
		(width 0.1143)
		(layer "F.Cu")
		(net "SAS_FAULT_LED1")
	)
	(segment
		(start 106.172 -244.348)
		(end 102.489 -244.348)
		(width 0.1143)
		(layer "F.Cu")
		(net "SAS_FAULT_LED1")
	)
	(segment
		(start 101.7905 -241.808)
		(end 101.7905 -239.4712)
		(width 0.1143)
		(layer "F.Cu")
		(net "SAS_FAULT_LED1")
	)
	(segment
		(start 102.489 -244.348)
		(end 101.7905 -243.6495)
		(width 0.1143)
		(layer "F.Cu")
		(net "SAS_FAULT_LED1")
	)
	(segment
		(start 106.68 -244.856)
		(end 106.172 -244.348)
		(width 0.1143)
		(layer "F.Cu")
		(net "SAS_FAULT_LED1")
	)
	(via
		(at 101.7905 -241.808)
		(size 0.5588)
		(drill 0.3048)
		(layers "F.Cu" "B.Cu")
		(net "SAS_FAULT_LED1")
	)
	(via
		(at 106.68 -244.856)
		(size 0.5588)
		(drill 0.3048)
		(layers "F.Cu" "B.Cu")
		(net "SAS_FAULT_LED1")
	)
	(via
		(at 101.092 -241.173)
		(size 0.7112)
		(drill 0.3556)
		(layers "F.Cu" "B.Cu")
		(net "SAS_FAULT_LED1")
	)
	(segment
		(start 108.41355 -253.02845)
		(end 108.41355 -246.58955)
		(width 0.1143)
		(layer "B.Cu")
		(net "SAS_FAULT_LED1")
	)
	(segment
		(start 108.000292 -253.441708)
		(end 108.41355 -253.02845)
		(width 0.1143)
		(layer "B.Cu")
		(net "SAS_FAULT_LED1")
	)
	(segment
		(start 103.4415 -225.933)
		(end 104.14 -225.933)
		(width 0.1143)
		(layer "B.Cu")
		(net "SAS_FAULT_LED1")
	)
	(segment
		(start 100.838 -240.919)
		(end 101.092 -241.173)
		(width 0.1143)
		(layer "B.Cu")
		(net "SAS_FAULT_LED1")
	)
	(segment
		(start 108.000292 -256.50444)
		(end 108.000292 -253.441708)
		(width 0.1143)
		(layer "B.Cu")
		(net "SAS_FAULT_LED1")
	)
	(segment
		(start 101.727 -241.808)
		(end 101.092 -241.173)
		(width 0.1143)
		(layer "B.Cu")
		(net "SAS_FAULT_LED1")
	)
	(segment
		(start 108.41355 -246.58955)
		(end 106.68 -244.856)
		(width 0.1143)
		(layer "B.Cu")
		(net "SAS_FAULT_LED1")
	)
	(segment
		(start 100.838 -239.8395)
		(end 100.838 -240.919)
		(width 0.1143)
		(layer "B.Cu")
		(net "SAS_FAULT_LED1")
	)
	(segment
		(start 109.22 -231.013)
		(end 109.22 -237.998)
		(width 0.1143)
		(layer "B.Cu")
		(net "SAS_FAULT_LED1")
	)
	(segment
		(start 101.7905 -241.808)
		(end 101.727 -241.808)
		(width 0.1143)
		(layer "B.Cu")
		(net "SAS_FAULT_LED1")
	)
	(segment
		(start 109.543342 -241.992658)
		(end 106.68 -244.856)
		(width 0.1143)
		(layer "B.Cu")
		(net "SAS_FAULT_LED1")
	)
	(segment
		(start 109.543342 -238.321342)
		(end 109.543342 -241.992658)
		(width 0.1143)
		(layer "B.Cu")
		(net "SAS_FAULT_LED1")
	)
	(segment
		(start 109.22 -237.998)
		(end 109.543342 -238.321342)
		(width 0.1143)
		(layer "B.Cu")
		(net "SAS_FAULT_LED1")
	)
	(segment
		(start 104.14 -225.933)
		(end 109.22 -231.013)
		(width 0.1143)
		(layer "B.Cu")
		(net "SAS_FAULT_LED1")
	)
	(segment
		(start 159.500062 -20.349972)
		(end 159.668972 -20.349972)
		(width 0.127)
		(layer "F.Cu")
		(net "TP_LAN_6")
	)
	(segment
		(start 159.668972 -20.349972)
		(end 163.058856 -23.739856)
		(width 0.127)
		(layer "F.Cu")
		(net "TP_LAN_6")
	)
	(segment
		(start 163.058856 -23.739856)
		(end 163.417504 -23.739856)
		(width 0.127)
		(layer "F.Cu")
		(net "TP_LAN_6")
	)
	(segment
		(start 292.834822 -181.040024)
		(end 292.468046 -181.4068)
		(width 0.1143)
		(layer "F.Cu")
		(net "MEMDQ_1")
	)
	(segment
		(start 291.298122 -200.935082)
		(end 291.298122 -200.938638)
		(width 0.1143)
		(layer "F.Cu")
		(net "MEMDQ_1")
	)
	(segment
		(start 292.458902 -181.4068)
		(end 292.431978 -181.433724)
		(width 0.1143)
		(layer "F.Cu")
		(net "MEMDQ_1")
	)
	(segment
		(start 292.468046 -181.4068)
		(end 292.458902 -181.4068)
		(width 0.1143)
		(layer "F.Cu")
		(net "MEMDQ_1")
	)
	(segment
		(start 291.298122 -200.938638)
		(end 290.89858 -201.33818)
		(width 0.1143)
		(layer "F.Cu")
		(net "MEMDQ_1")
	)
	(via
		(at 290.89858 -201.33818)
		(size 0.508)
		(drill 0.254)
		(layers "F.Cu" "B.Cu")
		(net "MEMDQ_1")
	)
	(via
		(at 291.607494 -201.61631)
		(size 0.7112)
		(drill 0.3556)
		(layers "F.Cu" "B.Cu")
		(net "MEMDQ_1")
	)
	(via
		(at 292.431978 -181.433724)
		(size 0.508)
		(drill 0.254)
		(layers "F.Cu" "B.Cu")
		(net "MEMDQ_1")
	)
	(segment
		(start 291.607494 -201.61631)
		(end 291.329364 -201.33818)
		(width 0.1143)
		(layer "B.Cu")
		(net "MEMDQ_1")
	)
	(segment
		(start 291.329364 -201.33818)
		(end 290.89858 -201.33818)
		(width 0.1143)
		(layer "B.Cu")
		(net "MEMDQ_1")
	)
	(segment
		(start 288.54273 -189.708028)
		(end 288.33572 -189.501018)
		(width 0.127)
		(layer "In5.Cu")
		(net "MEMDQ_1")
	)
	(segment
		(start 290.89096 -183.36768)
		(end 290.89096 -182.39994)
		(width 0.127)
		(layer "In5.Cu")
		(net "MEMDQ_1")
	)
	(segment
		(start 288.159444 -198.848218)
		(end 288.159444 -198.479918)
		(width 0.127)
		(layer "In5.Cu")
		(net "MEMDQ_1")
	)
	(segment
		(start 292.05174 -181.8132)
		(end 292.431978 -181.433724)
		(width 0.127)
		(layer "In5.Cu")
		(net "MEMDQ_1")
	)
	(segment
		(start 290.067492 -199.8853)
		(end 289.80765 -199.8853)
		(width 0.127)
		(layer "In5.Cu")
		(net "MEMDQ_1")
	)
	(segment
		(start 288.33572 -185.92292)
		(end 290.89096 -183.36768)
		(width 0.127)
		(layer "In5.Cu")
		(net "MEMDQ_1")
	)
	(segment
		(start 288.33572 -189.501018)
		(end 288.33572 -185.92292)
		(width 0.127)
		(layer "In5.Cu")
		(net "MEMDQ_1")
	)
	(segment
		(start 288.904426 -199.5932)
		(end 288.159444 -198.848218)
		(width 0.127)
		(layer "In5.Cu")
		(net "MEMDQ_1")
	)
	(segment
		(start 290.89096 -182.39994)
		(end 291.4777 -181.8132)
		(width 0.127)
		(layer "In5.Cu")
		(net "MEMDQ_1")
	)
	(segment
		(start 290.54806 -200.365868)
		(end 290.067492 -199.8853)
		(width 0.127)
		(layer "In5.Cu")
		(net "MEMDQ_1")
	)
	(segment
		(start 290.89858 -201.33818)
		(end 290.54806 -200.98766)
		(width 0.127)
		(layer "In5.Cu")
		(net "MEMDQ_1")
	)
	(segment
		(start 288.159444 -198.479918)
		(end 288.54273 -198.096632)
		(width 0.127)
		(layer "In5.Cu")
		(net "MEMDQ_1")
	)
	(segment
		(start 289.51555 -199.5932)
		(end 288.904426 -199.5932)
		(width 0.127)
		(layer "In5.Cu")
		(net "MEMDQ_1")
	)
	(segment
		(start 289.80765 -199.8853)
		(end 289.51555 -199.5932)
		(width 0.127)
		(layer "In5.Cu")
		(net "MEMDQ_1")
	)
	(segment
		(start 290.54806 -200.98766)
		(end 290.54806 -200.365868)
		(width 0.127)
		(layer "In5.Cu")
		(net "MEMDQ_1")
	)
	(segment
		(start 291.4777 -181.8132)
		(end 292.05174 -181.8132)
		(width 0.127)
		(layer "In5.Cu")
		(net "MEMDQ_1")
	)
	(segment
		(start 288.54273 -198.096632)
		(end 288.54273 -189.708028)
		(width 0.127)
		(layer "In5.Cu")
		(net "MEMDQ_1")
	)
	(segment
		(start 26.747216 -185.786014)
		(end 26.747216 -185.78576)
		(width 0.1143)
		(layer "F.Cu")
		(net "SAS_HDD_PRE4")
	)
	(segment
		(start 30.069028 -174.70374)
		(end 29.060394 -173.695106)
		(width 0.1143)
		(layer "F.Cu")
		(net "SAS_HDD_PRE4")
	)
	(segment
		(start 18.509488 -192.316608)
		(end 18.509488 -191.020446)
		(width 0.1143)
		(layer "F.Cu")
		(net "SAS_HDD_PRE4")
	)
	(segment
		(start 27.788362 -173.695106)
		(end 26.824178 -174.65929)
		(width 0.1143)
		(layer "F.Cu")
		(net "SAS_HDD_PRE4")
	)
	(segment
		(start 26.747216 -185.78576)
		(end 30.069028 -182.463948)
		(width 0.1143)
		(layer "F.Cu")
		(net "SAS_HDD_PRE4")
	)
	(segment
		(start 18.509488 -191.020446)
		(end 18.509488 -190.470282)
		(width 0.1143)
		(layer "F.Cu")
		(net "SAS_HDD_PRE4")
	)
	(segment
		(start 18.905474 -190.074296)
		(end 20.468844 -188.51118)
		(width 0.1143)
		(layer "F.Cu")
		(net "SAS_HDD_PRE4")
	)
	(segment
		(start 18.509488 -190.470282)
		(end 18.905474 -190.074296)
		(width 0.1143)
		(layer "F.Cu")
		(net "SAS_HDD_PRE4")
	)
	(segment
		(start 18.117566 -192.70853)
		(end 18.509488 -192.316608)
		(width 0.1143)
		(layer "F.Cu")
		(net "SAS_HDD_PRE4")
	)
	(segment
		(start 17.465548 -194.116706)
		(end 18.117566 -193.464688)
		(width 0.1143)
		(layer "F.Cu")
		(net "SAS_HDD_PRE4")
	)
	(segment
		(start 30.069028 -182.463948)
		(end 30.069028 -174.70374)
		(width 0.1143)
		(layer "F.Cu")
		(net "SAS_HDD_PRE4")
	)
	(segment
		(start 26.824178 -174.65929)
		(end 26.824178 -175.746156)
		(width 0.1143)
		(layer "F.Cu")
		(net "SAS_HDD_PRE4")
	)
	(segment
		(start 29.060394 -173.695106)
		(end 27.788362 -173.695106)
		(width 0.1143)
		(layer "F.Cu")
		(net "SAS_HDD_PRE4")
	)
	(segment
		(start 20.468844 -188.51118)
		(end 24.02205 -188.51118)
		(width 0.1143)
		(layer "F.Cu")
		(net "SAS_HDD_PRE4")
	)
	(segment
		(start 18.117566 -193.464688)
		(end 18.117566 -192.70853)
		(width 0.1143)
		(layer "F.Cu")
		(net "SAS_HDD_PRE4")
	)
	(segment
		(start 24.02205 -188.51118)
		(end 26.747216 -185.786014)
		(width 0.1143)
		(layer "F.Cu")
		(net "SAS_HDD_PRE4")
	)
	(via
		(at 17.465548 -194.116706)
		(size 0.5588)
		(drill 0.3048)
		(layers "F.Cu" "B.Cu")
		(net "SAS_HDD_PRE4")
	)
	(via
		(at 7.699248 -204.594206)
		(size 0.7112)
		(drill 0.3556)
		(layers "F.Cu" "B.Cu")
		(net "SAS_HDD_PRE4")
	)
	(segment
		(start 6.382766 -236.82198)
		(end 6.382766 -205.910688)
		(width 0.1143)
		(layer "B.Cu")
		(net "SAS_HDD_PRE4")
	)
	(segment
		(start 6.382766 -205.910688)
		(end 7.699248 -204.594206)
		(width 0.1143)
		(layer "B.Cu")
		(net "SAS_HDD_PRE4")
	)
	(segment
		(start 17.465548 -194.827906)
		(end 7.699248 -204.594206)
		(width 0.1143)
		(layer "B.Cu")
		(net "SAS_HDD_PRE4")
	)
	(segment
		(start 11.495786 -241.935)
		(end 6.382766 -236.82198)
		(width 0.1143)
		(layer "B.Cu")
		(net "SAS_HDD_PRE4")
	)
	(segment
		(start 42.999406 -252.840998)
		(end 32.093408 -241.935)
		(width 0.1143)
		(layer "B.Cu")
		(net "SAS_HDD_PRE4")
	)
	(segment
		(start 17.465548 -194.116706)
		(end 17.465548 -194.827906)
		(width 0.1143)
		(layer "B.Cu")
		(net "SAS_HDD_PRE4")
	)
	(segment
		(start 32.093408 -241.935)
		(end 11.495786 -241.935)
		(width 0.1143)
		(layer "B.Cu")
		(net "SAS_HDD_PRE4")
	)
	(segment
		(start 42.999406 -256.50444)
		(end 42.999406 -252.840998)
		(width 0.1143)
		(layer "B.Cu")
		(net "SAS_HDD_PRE4")
	)
	(segment
		(start 170.369992 -10.25017)
		(end 170.369992 -14.351)
		(width 0.1778)
		(layer "F.Cu")
		(net "LED_MDI0_LINK")
	)
	(segment
		(start 164.979858 -4.860036)
		(end 170.369992 -10.25017)
		(width 0.1778)
		(layer "F.Cu")
		(net "LED_MDI0_LINK")
	)
	(segment
		(start 286.49803 -201.73315)
		(end 286.09544 -201.33056)
		(width 0.1143)
		(layer "F.Cu")
		(net "MEMA_5")
	)
	(segment
		(start 289.62985 -181.840124)
		(end 289.237166 -181.44744)
		(width 0.1143)
		(layer "F.Cu")
		(net "MEMA_5")
	)
	(segment
		(start 286.49803 -201.735182)
		(end 286.49803 -201.73315)
		(width 0.1143)
		(layer "F.Cu")
		(net "MEMA_5")
	)
	(segment
		(start 289.63493 -181.840124)
		(end 289.62985 -181.840124)
		(width 0.1143)
		(layer "F.Cu")
		(net "MEMA_5")
	)
	(via
		(at 288.036 -192.3669)
		(size 0.7112)
		(drill 0.3556)
		(layers "F.Cu" "B.Cu")
		(net "MEMA_5")
	)
	(via
		(at 286.09544 -201.33056)
		(size 0.508)
		(drill 0.254)
		(layers "F.Cu" "B.Cu")
		(net "MEMA_5")
	)
	(via
		(at 289.237166 -181.44744)
		(size 0.508)
		(drill 0.254)
		(layers "F.Cu" "B.Cu")
		(net "MEMA_5")
	)
	(segment
		(start 288.57194 -182.321454)
		(end 288.57194 -184.14746)
		(width 0.1143)
		(layer "B.Cu")
		(net "MEMA_5")
	)
	(segment
		(start 288.57194 -184.14746)
		(end 288.305494 -184.413906)
		(width 0.1143)
		(layer "B.Cu")
		(net "MEMA_5")
	)
	(segment
		(start 287.4264 -197.453504)
		(end 286.63773 -198.242174)
		(width 0.1143)
		(layer "B.Cu")
		(net "MEMA_5")
	)
	(segment
		(start 288.3535 -189.102492)
		(end 288.322258 -189.133734)
		(width 0.1143)
		(layer "B.Cu")
		(net "MEMA_5")
	)
	(segment
		(start 286.63773 -198.805546)
		(end 286.871918 -199.039734)
		(width 0.1143)
		(layer "B.Cu")
		(net "MEMA_5")
	)
	(segment
		(start 288.305494 -184.413906)
		(end 288.305494 -186.974988)
		(width 0.1143)
		(layer "B.Cu")
		(net "MEMA_5")
	)
	(segment
		(start 286.871918 -199.039734)
		(end 286.871918 -199.810624)
		(width 0.1143)
		(layer "B.Cu")
		(net "MEMA_5")
	)
	(segment
		(start 288.305494 -186.974988)
		(end 288.354008 -187.023502)
		(width 0.1143)
		(layer "B.Cu")
		(net "MEMA_5")
	)
	(segment
		(start 288.3535 -187.559188)
		(end 288.353246 -187.559442)
		(width 0.1143)
		(layer "B.Cu")
		(net "MEMA_5")
	)
	(segment
		(start 287.66008 -196.136768)
		(end 287.4264 -196.370448)
		(width 0.1143)
		(layer "B.Cu")
		(net "MEMA_5")
	)
	(segment
		(start 288.353246 -187.559442)
		(end 288.353246 -188.253878)
		(width 0.1143)
		(layer "B.Cu")
		(net "MEMA_5")
	)
	(segment
		(start 286.63773 -198.242174)
		(end 286.63773 -198.805546)
		(width 0.1143)
		(layer "B.Cu")
		(net "MEMA_5")
	)
	(segment
		(start 286.73679 -200.68921)
		(end 286.09544 -201.33056)
		(width 0.1143)
		(layer "B.Cu")
		(net "MEMA_5")
	)
	(segment
		(start 287.824926 -192.577974)
		(end 287.824926 -194.785234)
		(width 0.1143)
		(layer "B.Cu")
		(net "MEMA_5")
	)
	(segment
		(start 286.73679 -199.945752)
		(end 286.73679 -200.68921)
		(width 0.1143)
		(layer "B.Cu")
		(net "MEMA_5")
	)
	(segment
		(start 289.237166 -181.44744)
		(end 289.237166 -181.656228)
		(width 0.1143)
		(layer "B.Cu")
		(net "MEMA_5")
	)
	(segment
		(start 288.036 -192.3669)
		(end 287.824926 -192.577974)
		(width 0.1143)
		(layer "B.Cu")
		(net "MEMA_5")
	)
	(segment
		(start 288.353246 -188.253878)
		(end 288.3535 -188.254132)
		(width 0.1143)
		(layer "B.Cu")
		(net "MEMA_5")
	)
	(segment
		(start 288.322258 -192.080642)
		(end 288.036 -192.3669)
		(width 0.1143)
		(layer "B.Cu")
		(net "MEMA_5")
	)
	(segment
		(start 289.237166 -181.656228)
		(end 288.57194 -182.321454)
		(width 0.1143)
		(layer "B.Cu")
		(net "MEMA_5")
	)
	(segment
		(start 288.3535 -187.024264)
		(end 288.3535 -187.559188)
		(width 0.1143)
		(layer "B.Cu")
		(net "MEMA_5")
	)
	(segment
		(start 286.871918 -199.810624)
		(end 286.73679 -199.945752)
		(width 0.1143)
		(layer "B.Cu")
		(net "MEMA_5")
	)
	(segment
		(start 288.3535 -188.254132)
		(end 288.3535 -189.102492)
		(width 0.1143)
		(layer "B.Cu")
		(net "MEMA_5")
	)
	(segment
		(start 287.66008 -194.95008)
		(end 287.66008 -196.136768)
		(width 0.1143)
		(layer "B.Cu")
		(net "MEMA_5")
	)
	(segment
		(start 288.354008 -187.023502)
		(end 288.3535 -187.024264)
		(width 0.1143)
		(layer "B.Cu")
		(net "MEMA_5")
	)
	(segment
		(start 287.824926 -194.785234)
		(end 287.66008 -194.95008)
		(width 0.1143)
		(layer "B.Cu")
		(net "MEMA_5")
	)
	(segment
		(start 288.322258 -189.133734)
		(end 288.322258 -192.080642)
		(width 0.1143)
		(layer "B.Cu")
		(net "MEMA_5")
	)
	(segment
		(start 287.4264 -196.370448)
		(end 287.4264 -197.453504)
		(width 0.1143)
		(layer "B.Cu")
		(net "MEMA_5")
	)
	(segment
		(start 162.787076 -21.616924)
		(end 164.030152 -22.86)
		(width 0.127)
		(layer "F.Cu")
		(net "TP_LAN_4")
	)
	(segment
		(start 164.823648 -22.86)
		(end 165.703504 -23.739856)
		(width 0.127)
		(layer "F.Cu")
		(net "TP_LAN_4")
	)
	(segment
		(start 161.53003 -20.349972)
		(end 162.787076 -21.607018)
		(width 0.127)
		(layer "F.Cu")
		(net "TP_LAN_4")
	)
	(segment
		(start 162.787076 -21.607018)
		(end 162.787076 -21.616924)
		(width 0.127)
		(layer "F.Cu")
		(net "TP_LAN_4")
	)
	(segment
		(start 164.030152 -22.86)
		(end 164.823648 -22.86)
		(width 0.127)
		(layer "F.Cu")
		(net "TP_LAN_4")
	)
	(segment
		(start 287.966658 -185.463434)
		(end 286.347154 -187.082938)
		(width 0.1143)
		(layer "F.Cu")
		(net "MEMA_14")
	)
	(segment
		(start 288.612834 -184.462166)
		(end 288.612834 -184.484518)
		(width 0.1143)
		(layer "F.Cu")
		(net "MEMA_14")
	)
	(segment
		(start 285.01975 -197.856856)
		(end 285.01975 -198.70801)
		(width 0.1143)
		(layer "F.Cu")
		(net "MEMA_14")
	)
	(segment
		(start 288.83483 -184.24017)
		(end 288.612834 -184.462166)
		(width 0.1143)
		(layer "F.Cu")
		(net "MEMA_14")
	)
	(segment
		(start 286.272986 -187.082938)
		(end 286.22879 -187.127134)
		(width 0.1143)
		(layer "F.Cu")
		(net "MEMA_14")
	)
	(segment
		(start 287.966658 -185.130694)
		(end 287.966658 -185.463434)
		(width 0.1143)
		(layer "F.Cu")
		(net "MEMA_14")
	)
	(segment
		(start 284.898084 -197.73519)
		(end 285.01975 -197.856856)
		(width 0.1143)
		(layer "F.Cu")
		(net "MEMA_14")
	)
	(segment
		(start 284.69336 -199.0344)
		(end 283.6037 -199.0344)
		(width 0.1143)
		(layer "F.Cu")
		(net "MEMA_14")
	)
	(segment
		(start 286.347154 -187.082938)
		(end 286.272986 -187.082938)
		(width 0.1143)
		(layer "F.Cu")
		(net "MEMA_14")
	)
	(segment
		(start 288.612834 -184.484518)
		(end 287.966658 -185.130694)
		(width 0.1143)
		(layer "F.Cu")
		(net "MEMA_14")
	)
	(segment
		(start 285.01975 -198.70801)
		(end 284.69336 -199.0344)
		(width 0.1143)
		(layer "F.Cu")
		(net "MEMA_14")
	)
	(via
		(at 286.22879 -187.127134)
		(size 0.508)
		(drill 0.254)
		(layers "F.Cu" "B.Cu")
		(net "MEMA_14")
	)
	(via
		(at 283.4132 -194.6656)
		(size 0.7112)
		(drill 0.3556)
		(layers "F.Cu" "B.Cu")
		(net "MEMA_14")
	)
	(via
		(at 283.6037 -199.0344)
		(size 0.508)
		(drill 0.254)
		(layers "F.Cu" "B.Cu")
		(net "MEMA_14")
	)
	(segment
		(start 283.160724 -197.881748)
		(end 283.160724 -198.110348)
		(width 0.1143)
		(layer "B.Cu")
		(net "MEMA_14")
	)
	(segment
		(start 283.4132 -198.8439)
		(end 283.6037 -199.0344)
		(width 0.1143)
		(layer "B.Cu")
		(net "MEMA_14")
	)
	(segment
		(start 285.279846 -187.127134)
		(end 283.2862 -189.12078)
		(width 0.1143)
		(layer "B.Cu")
		(net "MEMA_14")
	)
	(segment
		(start 283.160724 -196.281548)
		(end 283.275024 -196.395848)
		(width 0.1143)
		(layer "B.Cu")
		(net "MEMA_14")
	)
	(segment
		(start 283.4132 -194.6656)
		(end 283.4132 -195.824348)
		(width 0.1143)
		(layer "B.Cu")
		(net "MEMA_14")
	)
	(segment
		(start 283.160724 -196.052948)
		(end 283.160724 -196.281548)
		(width 0.1143)
		(layer "B.Cu")
		(net "MEMA_14")
	)
	(segment
		(start 283.4132 -196.738748)
		(end 283.2989 -196.853048)
		(width 0.1143)
		(layer "B.Cu")
		(net "MEMA_14")
	)
	(segment
		(start 283.160724 -198.110348)
		(end 283.275024 -198.224648)
		(width 0.1143)
		(layer "B.Cu")
		(net "MEMA_14")
	)
	(segment
		(start 283.2862 -189.12078)
		(end 283.2862 -194.5386)
		(width 0.1143)
		(layer "B.Cu")
		(net "MEMA_14")
	)
	(segment
		(start 283.2989 -196.853048)
		(end 283.275024 -196.853048)
		(width 0.1143)
		(layer "B.Cu")
		(net "MEMA_14")
	)
	(segment
		(start 283.160724 -197.195948)
		(end 283.275024 -197.310248)
		(width 0.1143)
		(layer "B.Cu")
		(net "MEMA_14")
	)
	(segment
		(start 283.4132 -197.424548)
		(end 283.4132 -197.653148)
		(width 0.1143)
		(layer "B.Cu")
		(net "MEMA_14")
	)
	(segment
		(start 283.275024 -196.853048)
		(end 283.160724 -196.967348)
		(width 0.1143)
		(layer "B.Cu")
		(net "MEMA_14")
	)
	(segment
		(start 283.275024 -195.938648)
		(end 283.160724 -196.052948)
		(width 0.1143)
		(layer "B.Cu")
		(net "MEMA_14")
	)
	(segment
		(start 283.4132 -195.824348)
		(end 283.2989 -195.938648)
		(width 0.1143)
		(layer "B.Cu")
		(net "MEMA_14")
	)
	(segment
		(start 283.2989 -197.767448)
		(end 283.275024 -197.767448)
		(width 0.1143)
		(layer "B.Cu")
		(net "MEMA_14")
	)
	(segment
		(start 283.2989 -195.938648)
		(end 283.275024 -195.938648)
		(width 0.1143)
		(layer "B.Cu")
		(net "MEMA_14")
	)
	(segment
		(start 283.4132 -198.338948)
		(end 283.4132 -198.8439)
		(width 0.1143)
		(layer "B.Cu")
		(net "MEMA_14")
	)
	(segment
		(start 283.275024 -197.767448)
		(end 283.160724 -197.881748)
		(width 0.1143)
		(layer "B.Cu")
		(net "MEMA_14")
	)
	(segment
		(start 283.160724 -196.967348)
		(end 283.160724 -197.195948)
		(width 0.1143)
		(layer "B.Cu")
		(net "MEMA_14")
	)
	(segment
		(start 283.275024 -197.310248)
		(end 283.2989 -197.310248)
		(width 0.1143)
		(layer "B.Cu")
		(net "MEMA_14")
	)
	(segment
		(start 283.275024 -196.395848)
		(end 283.2989 -196.395848)
		(width 0.1143)
		(layer "B.Cu")
		(net "MEMA_14")
	)
	(segment
		(start 283.4132 -197.653148)
		(end 283.2989 -197.767448)
		(width 0.1143)
		(layer "B.Cu")
		(net "MEMA_14")
	)
	(segment
		(start 283.275024 -198.224648)
		(end 283.2989 -198.224648)
		(width 0.1143)
		(layer "B.Cu")
		(net "MEMA_14")
	)
	(segment
		(start 283.2989 -196.395848)
		(end 283.4132 -196.510148)
		(width 0.1143)
		(layer "B.Cu")
		(net "MEMA_14")
	)
	(segment
		(start 286.22879 -187.127134)
		(end 285.279846 -187.127134)
		(width 0.1143)
		(layer "B.Cu")
		(net "MEMA_14")
	)
	(segment
		(start 283.2989 -197.310248)
		(end 283.4132 -197.424548)
		(width 0.1143)
		(layer "B.Cu")
		(net "MEMA_14")
	)
	(segment
		(start 283.2989 -198.224648)
		(end 283.4132 -198.338948)
		(width 0.1143)
		(layer "B.Cu")
		(net "MEMA_14")
	)
	(segment
		(start 283.4132 -196.510148)
		(end 283.4132 -196.738748)
		(width 0.1143)
		(layer "B.Cu")
		(net "MEMA_14")
	)
	(segment
		(start 283.2862 -194.5386)
		(end 283.4132 -194.6656)
		(width 0.1143)
		(layer "B.Cu")
		(net "MEMA_14")
	)
	(segment
		(start 184.085992 -194.869816)
		(end 183.642 -194.869816)
		(width 0.1143)
		(layer "F.Cu")
		(net "SAS_I2C_C_BUF_SDA")
	)
	(segment
		(start 186.999372 -195.100448)
		(end 186.999372 -195.271136)
		(width 0.1143)
		(layer "F.Cu")
		(net "SAS_I2C_C_BUF_SDA")
	)
	(segment
		(start 186.110372 -194.051936)
		(end 184.903872 -194.051936)
		(width 0.1143)
		(layer "F.Cu")
		(net "SAS_I2C_C_BUF_SDA")
	)
	(segment
		(start 184.903872 -194.051936)
		(end 184.085992 -194.869816)
		(width 0.1143)
		(layer "F.Cu")
		(net "SAS_I2C_C_BUF_SDA")
	)
	(segment
		(start 186.110372 -194.051936)
		(end 186.110372 -194.211448)
		(width 0.1143)
		(layer "F.Cu")
		(net "SAS_I2C_C_BUF_SDA")
	)
	(segment
		(start 186.999372 -195.271136)
		(end 188.015372 -195.271136)
		(width 0.1143)
		(layer "F.Cu")
		(net "SAS_I2C_C_BUF_SDA")
	)
	(segment
		(start 181.639972 -194.869816)
		(end 183.642 -194.869816)
		(width 0.1143)
		(layer "F.Cu")
		(net "SAS_I2C_C_BUF_SDA")
	)
	(segment
		(start 186.110372 -194.211448)
		(end 186.999372 -195.100448)
		(width 0.1143)
		(layer "F.Cu")
		(net "SAS_I2C_C_BUF_SDA")
	)
	(via
		(at 183.642 -194.869816)
		(size 0.7112)
		(drill 0.3556)
		(layers "F.Cu" "B.Cu")
		(net "SAS_I2C_C_BUF_SDA")
	)
	(segment
		(start 31.173928 -182.88127)
		(end 31.174182 -182.880762)
		(width 0.1143)
		(layer "F.Cu")
		(net "SAS_HDD_PRE1")
	)
	(segment
		(start 25.656794 -174.263812)
		(end 25.656794 -175.71466)
		(width 0.1143)
		(layer "F.Cu")
		(net "SAS_HDD_PRE1")
	)
	(segment
		(start 31.173928 -182.005986)
		(end 31.173928 -174.245524)
		(width 0.1143)
		(layer "F.Cu")
		(net "SAS_HDD_PRE1")
	)
	(segment
		(start 25.656794 -175.71466)
		(end 25.625298 -175.746156)
		(width 0.1143)
		(layer "F.Cu")
		(net "SAS_HDD_PRE1")
	)
	(segment
		(start 27.3304 -172.590206)
		(end 25.656794 -174.263812)
		(width 0.1143)
		(layer "F.Cu")
		(net "SAS_HDD_PRE1")
	)
	(segment
		(start 31.174182 -182.880762)
		(end 31.174182 -182.00624)
		(width 0.1143)
		(layer "F.Cu")
		(net "SAS_HDD_PRE1")
	)
	(segment
		(start 31.09214 -183.003952)
		(end 31.173928 -182.92191)
		(width 0.1143)
		(layer "F.Cu")
		(net "SAS_HDD_PRE1")
	)
	(segment
		(start 21.760688 -193.930016)
		(end 21.760688 -191.020446)
		(width 0.1143)
		(layer "F.Cu")
		(net "SAS_HDD_PRE1")
	)
	(segment
		(start 31.174182 -182.00624)
		(end 31.173928 -182.005986)
		(width 0.1143)
		(layer "F.Cu")
		(net "SAS_HDD_PRE1")
	)
	(segment
		(start 30.74289 -173.814486)
		(end 30.742636 -173.814486)
		(width 0.1143)
		(layer "F.Cu")
		(net "SAS_HDD_PRE1")
	)
	(segment
		(start 29.213302 -172.589952)
		(end 29.213048 -172.590206)
		(width 0.1143)
		(layer "F.Cu")
		(net "SAS_HDD_PRE1")
	)
	(segment
		(start 24.480012 -189.61608)
		(end 31.09214 -183.003952)
		(width 0.1143)
		(layer "F.Cu")
		(net "SAS_HDD_PRE1")
	)
	(segment
		(start 31.173928 -174.245524)
		(end 30.74289 -173.814486)
		(width 0.1143)
		(layer "F.Cu")
		(net "SAS_HDD_PRE1")
	)
	(segment
		(start 21.760688 -191.020446)
		(end 21.760688 -189.986666)
		(width 0.1143)
		(layer "F.Cu")
		(net "SAS_HDD_PRE1")
	)
	(segment
		(start 31.173928 -182.92191)
		(end 31.173928 -182.88127)
		(width 0.1143)
		(layer "F.Cu")
		(net "SAS_HDD_PRE1")
	)
	(segment
		(start 22.131274 -189.61608)
		(end 24.480012 -189.61608)
		(width 0.1143)
		(layer "F.Cu")
		(net "SAS_HDD_PRE1")
	)
	(segment
		(start 21.760688 -189.986666)
		(end 22.131274 -189.61608)
		(width 0.1143)
		(layer "F.Cu")
		(net "SAS_HDD_PRE1")
	)
	(segment
		(start 29.213048 -172.590206)
		(end 27.3304 -172.590206)
		(width 0.1143)
		(layer "F.Cu")
		(net "SAS_HDD_PRE1")
	)
	(segment
		(start 29.518102 -172.589952)
		(end 29.213302 -172.589952)
		(width 0.1143)
		(layer "F.Cu")
		(net "SAS_HDD_PRE1")
	)
	(segment
		(start 30.742636 -173.814486)
		(end 29.518102 -172.589952)
		(width 0.1143)
		(layer "F.Cu")
		(net "SAS_HDD_PRE1")
	)
	(via
		(at 21.760688 -193.930016)
		(size 0.5588)
		(drill 0.3048)
		(layers "F.Cu" "B.Cu")
		(net "SAS_HDD_PRE1")
	)
	(via
		(at 11.037824 -204.04328)
		(size 0.7112)
		(drill 0.3556)
		(layers "F.Cu" "B.Cu")
		(net "SAS_HDD_PRE1")
	)
	(segment
		(start 46.000416 -253.983998)
		(end 32.528764 -240.512346)
		(width 0.1143)
		(layer "B.Cu")
		(net "SAS_HDD_PRE1")
	)
	(segment
		(start 46.000416 -256.50444)
		(end 46.000416 -253.983998)
		(width 0.1143)
		(layer "B.Cu")
		(net "SAS_HDD_PRE1")
	)
	(segment
		(start 13.361416 -201.269092)
		(end 19.131788 -195.49872)
		(width 0.1143)
		(layer "B.Cu")
		(net "SAS_HDD_PRE1")
	)
	(segment
		(start 21.599398 -194.091306)
		(end 21.760688 -193.930016)
		(width 0.1143)
		(layer "B.Cu")
		(net "SAS_HDD_PRE1")
	)
	(segment
		(start 21.599398 -194.208908)
		(end 21.599398 -194.091306)
		(width 0.1143)
		(layer "B.Cu")
		(net "SAS_HDD_PRE1")
	)
	(segment
		(start 11.037824 -204.04328)
		(end 13.361416 -201.719688)
		(width 0.1143)
		(layer "B.Cu")
		(net "SAS_HDD_PRE1")
	)
	(segment
		(start 32.528764 -240.512346)
		(end 13.134086 -240.512346)
		(width 0.1143)
		(layer "B.Cu")
		(net "SAS_HDD_PRE1")
	)
	(segment
		(start 7.487666 -234.865926)
		(end 7.487666 -207.593438)
		(width 0.1143)
		(layer "B.Cu")
		(net "SAS_HDD_PRE1")
	)
	(segment
		(start 13.361416 -201.719688)
		(end 13.361416 -201.269092)
		(width 0.1143)
		(layer "B.Cu")
		(net "SAS_HDD_PRE1")
	)
	(segment
		(start 7.487666 -207.593438)
		(end 11.037824 -204.04328)
		(width 0.1143)
		(layer "B.Cu")
		(net "SAS_HDD_PRE1")
	)
	(segment
		(start 13.134086 -240.512346)
		(end 7.487666 -234.865926)
		(width 0.1143)
		(layer "B.Cu")
		(net "SAS_HDD_PRE1")
	)
	(segment
		(start 20.309586 -195.49872)
		(end 21.599398 -194.208908)
		(width 0.1143)
		(layer "B.Cu")
		(net "SAS_HDD_PRE1")
	)
	(segment
		(start 19.131788 -195.49872)
		(end 20.309586 -195.49872)
		(width 0.1143)
		(layer "B.Cu")
		(net "SAS_HDD_PRE1")
	)
	(segment
		(start 292.085522 -186.670696)
		(end 292.602412 -186.670696)
		(width 0.1143)
		(layer "F.Cu")
		(net "MEMDQ_2")
	)
	(segment
		(start 292.898068 -196.93509)
		(end 292.898068 -196.937884)
		(width 0.1143)
		(layer "F.Cu")
		(net "MEMDQ_2")
	)
	(segment
		(start 292.602412 -186.670696)
		(end 293.059358 -187.127642)
		(width 0.1143)
		(layer "F.Cu")
		(net "MEMDQ_2")
	)
	(segment
		(start 293.18204 -187.00496)
		(end 293.059358 -187.127642)
		(width 0.1143)
		(layer "F.Cu")
		(net "MEMDQ_2")
	)
	(segment
		(start 293.634922 -185.137806)
		(end 293.18204 -185.590688)
		(width 0.1143)
		(layer "F.Cu")
		(net "MEMDQ_2")
	)
	(segment
		(start 292.898068 -196.937884)
		(end 292.497256 -197.338696)
		(width 0.1143)
		(layer "F.Cu")
		(net "MEMDQ_2")
	)
	(segment
		(start 293.634922 -184.24017)
		(end 293.634922 -185.137806)
		(width 0.1143)
		(layer "F.Cu")
		(net "MEMDQ_2")
	)
	(segment
		(start 293.18204 -185.590688)
		(end 293.18204 -187.00496)
		(width 0.1143)
		(layer "F.Cu")
		(net "MEMDQ_2")
	)
	(segment
		(start 291.96538 -186.550554)
		(end 292.085522 -186.670696)
		(width 0.1143)
		(layer "F.Cu")
		(net "MEMDQ_2")
	)
	(via
		(at 293.059358 -187.127642)
		(size 0.7112)
		(drill 0.3556)
		(layers "F.Cu" "B.Cu")
		(net "MEMDQ_2")
	)
	(via
		(at 292.497256 -197.338696)
		(size 0.508)
		(drill 0.254)
		(layers "F.Cu" "B.Cu")
		(net "MEMDQ_2")
	)
	(via
		(at 291.96538 -186.550554)
		(size 0.508)
		(drill 0.254)
		(layers "F.Cu" "B.Cu")
		(net "MEMDQ_2")
	)
	(segment
		(start 290.7538 -193.01206)
		(end 290.7538 -193.27114)
		(width 0.127)
		(layer "In5.Cu")
		(net "MEMDQ_2")
	)
	(segment
		(start 292.608 -195.833492)
		(end 292.481 -195.960492)
		(width 0.127)
		(layer "In5.Cu")
		(net "MEMDQ_2")
	)
	(segment
		(start 291.96538 -186.550554)
		(end 292.244526 -186.550554)
		(width 0.127)
		(layer "In5.Cu")
		(net "MEMDQ_2")
	)
	(segment
		(start 292.481 -195.452492)
		(end 292.608 -195.579492)
		(width 0.127)
		(layer "In5.Cu")
		(net "MEMDQ_2")
	)
	(segment
		(start 290.7538 -193.27114)
		(end 291.87648 -194.39382)
		(width 0.127)
		(layer "In5.Cu")
		(net "MEMDQ_2")
	)
	(segment
		(start 292.00348 -195.960492)
		(end 291.6682 -196.295772)
		(width 0.127)
		(layer "In5.Cu")
		(net "MEMDQ_2")
	)
	(segment
		(start 291.00272 -191.74714)
		(end 290.7538 -191.99606)
		(width 0.127)
		(layer "In5.Cu")
		(net "MEMDQ_2")
	)
	(segment
		(start 292.460172 -187.6044)
		(end 291.1602 -187.6044)
		(width 0.127)
		(layer "In5.Cu")
		(net "MEMDQ_2")
	)
	(segment
		(start 291.00272 -191.48806)
		(end 291.00272 -191.74714)
		(width 0.127)
		(layer "In5.Cu")
		(net "MEMDQ_2")
	)
	(segment
		(start 291.87648 -195.325492)
		(end 292.00348 -195.452492)
		(width 0.127)
		(layer "In5.Cu")
		(net "MEMDQ_2")
	)
	(segment
		(start 292.705536 -187.359036)
		(end 292.460172 -187.6044)
		(width 0.127)
		(layer "In5.Cu")
		(net "MEMDQ_2")
	)
	(segment
		(start 292.608 -195.579492)
		(end 292.608 -195.833492)
		(width 0.127)
		(layer "In5.Cu")
		(net "MEMDQ_2")
	)
	(segment
		(start 291.87648 -194.39382)
		(end 291.87648 -195.325492)
		(width 0.127)
		(layer "In5.Cu")
		(net "MEMDQ_2")
	)
	(segment
		(start 291.1602 -187.6044)
		(end 291.00272 -187.76188)
		(width 0.127)
		(layer "In5.Cu")
		(net "MEMDQ_2")
	)
	(segment
		(start 292.481 -195.960492)
		(end 292.00348 -195.960492)
		(width 0.127)
		(layer "In5.Cu")
		(net "MEMDQ_2")
	)
	(segment
		(start 291.6682 -197.0278)
		(end 291.979096 -197.338696)
		(width 0.127)
		(layer "In5.Cu")
		(net "MEMDQ_2")
	)
	(segment
		(start 292.00348 -195.452492)
		(end 292.481 -195.452492)
		(width 0.127)
		(layer "In5.Cu")
		(net "MEMDQ_2")
	)
	(segment
		(start 291.00272 -192.50406)
		(end 291.00272 -192.76314)
		(width 0.127)
		(layer "In5.Cu")
		(net "MEMDQ_2")
	)
	(segment
		(start 291.979096 -197.338696)
		(end 292.497256 -197.338696)
		(width 0.127)
		(layer "In5.Cu")
		(net "MEMDQ_2")
	)
	(segment
		(start 292.705536 -187.011564)
		(end 292.705536 -187.359036)
		(width 0.127)
		(layer "In5.Cu")
		(net "MEMDQ_2")
	)
	(segment
		(start 291.00272 -187.76188)
		(end 291.00272 -190.73114)
		(width 0.127)
		(layer "In5.Cu")
		(net "MEMDQ_2")
	)
	(segment
		(start 292.244526 -186.550554)
		(end 292.705536 -187.011564)
		(width 0.127)
		(layer "In5.Cu")
		(net "MEMDQ_2")
	)
	(segment
		(start 291.6682 -196.295772)
		(end 291.6682 -197.0278)
		(width 0.127)
		(layer "In5.Cu")
		(net "MEMDQ_2")
	)
	(segment
		(start 291.00272 -190.73114)
		(end 290.7538 -190.98006)
		(width 0.127)
		(layer "In5.Cu")
		(net "MEMDQ_2")
	)
	(segment
		(start 290.7538 -190.98006)
		(end 290.7538 -191.23914)
		(width 0.127)
		(layer "In5.Cu")
		(net "MEMDQ_2")
	)
	(segment
		(start 290.7538 -192.25514)
		(end 291.00272 -192.50406)
		(width 0.127)
		(layer "In5.Cu")
		(net "MEMDQ_2")
	)
	(segment
		(start 290.7538 -191.99606)
		(end 290.7538 -192.25514)
		(width 0.127)
		(layer "In5.Cu")
		(net "MEMDQ_2")
	)
	(segment
		(start 291.00272 -192.76314)
		(end 290.7538 -193.01206)
		(width 0.127)
		(layer "In5.Cu")
		(net "MEMDQ_2")
	)
	(segment
		(start 290.7538 -191.23914)
		(end 291.00272 -191.48806)
		(width 0.127)
		(layer "In5.Cu")
		(net "MEMDQ_2")
	)
	(segment
		(start 102.743 -250.698)
		(end 102.743 -248.412)
		(width 0.1143)
		(layer "F.Cu")
		(net "SAS_FAULT_LED11")
	)
	(segment
		(start 105.000552 -256.25044)
		(end 105.000552 -252.955552)
		(width 0.1143)
		(layer "F.Cu")
		(net "SAS_FAULT_LED11")
	)
	(segment
		(start 99.187 -244.856)
		(end 97.917 -244.856)
		(width 0.1143)
		(layer "F.Cu")
		(net "SAS_FAULT_LED11")
	)
	(segment
		(start 91.826842 -235.966)
		(end 93.98 -235.966)
		(width 0.1143)
		(layer "F.Cu")
		(net "SAS_FAULT_LED11")
	)
	(segment
		(start 86.995 -241.9985)
		(end 86.995 -242.062)
		(width 0.1143)
		(layer "F.Cu")
		(net "SAS_FAULT_LED11")
	)
	(segment
		(start 94.488 -236.22)
		(end 94.234 -236.22)
		(width 0.1143)
		(layer "F.Cu")
		(net "SAS_FAULT_LED11")
	)
	(segment
		(start 94.742 -236.474)
		(end 94.488 -236.22)
		(width 0.1143)
		(layer "F.Cu")
		(net "SAS_FAULT_LED11")
	)
	(segment
		(start 102.743 -248.412)
		(end 99.187 -244.856)
		(width 0.1143)
		(layer "F.Cu")
		(net "SAS_FAULT_LED11")
	)
	(segment
		(start 88.5825 -238.4425)
		(end 91.11615 -235.90885)
		(width 0.1143)
		(layer "F.Cu")
		(net "SAS_FAULT_LED11")
	)
	(segment
		(start 91.11615 -235.90885)
		(end 91.769692 -235.90885)
		(width 0.1143)
		(layer "F.Cu")
		(net "SAS_FAULT_LED11")
	)
	(segment
		(start 97.917 -244.856)
		(end 94.742 -241.681)
		(width 0.1143)
		(layer "F.Cu")
		(net "SAS_FAULT_LED11")
	)
	(segment
		(start 88.519 -240.538)
		(end 88.519 -239.4077)
		(width 0.1143)
		(layer "F.Cu")
		(net "SAS_FAULT_LED11")
	)
	(segment
		(start 88.519 -239.4077)
		(end 88.5825 -239.3442)
		(width 0.1143)
		(layer "F.Cu")
		(net "SAS_FAULT_LED11")
	)
	(segment
		(start 88.5825 -239.3442)
		(end 88.5825 -238.4425)
		(width 0.1143)
		(layer "F.Cu")
		(net "SAS_FAULT_LED11")
	)
	(segment
		(start 93.98 -235.966)
		(end 94.234 -236.22)
		(width 0.1143)
		(layer "F.Cu")
		(net "SAS_FAULT_LED11")
	)
	(segment
		(start 86.995 -242.062)
		(end 88.519 -240.538)
		(width 0.1143)
		(layer "F.Cu")
		(net "SAS_FAULT_LED11")
	)
	(segment
		(start 94.742 -241.681)
		(end 94.742 -236.474)
		(width 0.1143)
		(layer "F.Cu")
		(net "SAS_FAULT_LED11")
	)
	(segment
		(start 105.000552 -252.955552)
		(end 102.743 -250.698)
		(width 0.1143)
		(layer "F.Cu")
		(net "SAS_FAULT_LED11")
	)
	(segment
		(start 91.769692 -235.90885)
		(end 91.826842 -235.966)
		(width 0.1143)
		(layer "F.Cu")
		(net "SAS_FAULT_LED11")
	)
	(via
		(at 96.774 -233.553)
		(size 0.7112)
		(drill 0.3556)
		(layers "F.Cu" "B.Cu")
		(net "SAS_FAULT_LED11")
	)
	(via
		(at 94.234 -236.22)
		(size 0.5588)
		(drill 0.3048)
		(layers "F.Cu" "B.Cu")
		(net "SAS_FAULT_LED11")
	)
	(segment
		(start 94.234 -235.966)
		(end 94.234 -236.22)
		(width 0.1143)
		(layer "B.Cu")
		(net "SAS_FAULT_LED11")
	)
	(segment
		(start 95.377 -234.823)
		(end 94.234 -235.966)
		(width 0.1143)
		(layer "B.Cu")
		(net "SAS_FAULT_LED11")
	)
	(segment
		(start 98.044 -232.283)
		(end 96.774 -233.553)
		(width 0.1143)
		(layer "B.Cu")
		(net "SAS_FAULT_LED11")
	)
	(segment
		(start 95.504 -234.823)
		(end 95.377 -234.823)
		(width 0.1143)
		(layer "B.Cu")
		(net "SAS_FAULT_LED11")
	)
	(segment
		(start 97.3455 -228.981)
		(end 98.044 -229.6795)
		(width 0.1143)
		(layer "B.Cu")
		(net "SAS_FAULT_LED11")
	)
	(segment
		(start 98.044 -229.6795)
		(end 98.044 -232.283)
		(width 0.1143)
		(layer "B.Cu")
		(net "SAS_FAULT_LED11")
	)
	(segment
		(start 96.774 -233.553)
		(end 95.504 -234.823)
		(width 0.1143)
		(layer "B.Cu")
		(net "SAS_FAULT_LED11")
	)
	(segment
		(start 176.403 -197.993)
		(end 176.470564 -197.925436)
		(width 0.1143)
		(layer "F.Cu")
		(net "I2C_C_BUFF_EN")
	)
	(segment
		(start 177.499772 -197.887336)
		(end 177.499772 -196.170296)
		(width 0.1143)
		(layer "F.Cu")
		(net "I2C_C_BUFF_EN")
	)
	(segment
		(start 176.470564 -197.925436)
		(end 177.537872 -197.925436)
		(width 0.1143)
		(layer "F.Cu")
		(net "I2C_C_BUFF_EN")
	)
	(segment
		(start 177.537872 -197.925436)
		(end 177.499772 -197.887336)
		(width 0.1143)
		(layer "F.Cu")
		(net "I2C_C_BUFF_EN")
	)
	(via
		(at 176.403 -197.993)
		(size 0.7112)
		(drill 0.3556)
		(layers "F.Cu" "B.Cu")
		(net "I2C_C_BUFF_EN")
	)
	(segment
		(start 286.26308 -189.04712)
		(end 286.174434 -189.135766)
		(width 0.1143)
		(layer "F.Cu")
		(net "MEMA_4")
	)
	(segment
		(start 290.21278 -184.479692)
		(end 289.643058 -185.049414)
		(width 0.1143)
		(layer "F.Cu")
		(net "MEMA_4")
	)
	(segment
		(start 286.167068 -197.916292)
		(end 286.167068 -199.51827)
		(width 0.1143)
		(layer "F.Cu")
		(net "MEMA_4")
	)
	(segment
		(start 290.21278 -184.462166)
		(end 290.21278 -184.479692)
		(width 0.1143)
		(layer "F.Cu")
		(net "MEMA_4")
	)
	(segment
		(start 290.434776 -184.24017)
		(end 290.21278 -184.462166)
		(width 0.1143)
		(layer "F.Cu")
		(net "MEMA_4")
	)
	(segment
		(start 286.671258 -189.04712)
		(end 286.26308 -189.04712)
		(width 0.1143)
		(layer "F.Cu")
		(net "MEMA_4")
	)
	(segment
		(start 289.643058 -185.049414)
		(end 289.643058 -186.07532)
		(width 0.1143)
		(layer "F.Cu")
		(net "MEMA_4")
	)
	(segment
		(start 286.13608 -197.47738)
		(end 286.13608 -197.885304)
		(width 0.1143)
		(layer "F.Cu")
		(net "MEMA_4")
	)
	(segment
		(start 286.13608 -197.885304)
		(end 286.167068 -197.916292)
		(width 0.1143)
		(layer "F.Cu")
		(net "MEMA_4")
	)
	(segment
		(start 289.643058 -186.07532)
		(end 286.671258 -189.04712)
		(width 0.1143)
		(layer "F.Cu")
		(net "MEMA_4")
	)
	(segment
		(start 286.49803 -197.11543)
		(end 286.13608 -197.47738)
		(width 0.1143)
		(layer "F.Cu")
		(net "MEMA_4")
	)
	(segment
		(start 286.49803 -196.93509)
		(end 286.49803 -197.11543)
		(width 0.1143)
		(layer "F.Cu")
		(net "MEMA_4")
	)
	(via
		(at 286.174434 -189.135766)
		(size 0.508)
		(drill 0.254)
		(layers "F.Cu" "B.Cu")
		(net "MEMA_4")
	)
	(via
		(at 285.458408 -197.337172)
		(size 0.7112)
		(drill 0.3556)
		(layers "F.Cu" "B.Cu")
		(net "MEMA_4")
	)
	(via
		(at 286.167068 -199.51827)
		(size 0.5588)
		(drill 0.3048)
		(layers "F.Cu" "B.Cu")
		(net "MEMA_4")
	)
	(segment
		(start 285.14929 -194.02425)
		(end 286.05099 -194.92595)
		(width 0.1143)
		(layer "B.Cu")
		(net "MEMA_4")
	)
	(segment
		(start 285.877 -199.228202)
		(end 286.167068 -199.51827)
		(width 0.1143)
		(layer "B.Cu")
		(net "MEMA_4")
	)
	(segment
		(start 285.837884 -189.135766)
		(end 285.14929 -189.82436)
		(width 0.1143)
		(layer "B.Cu")
		(net "MEMA_4")
	)
	(segment
		(start 285.458408 -197.737984)
		(end 285.877 -198.156576)
		(width 0.1143)
		(layer "B.Cu")
		(net "MEMA_4")
	)
	(segment
		(start 286.05099 -194.92595)
		(end 286.05099 -196.29501)
		(width 0.1143)
		(layer "B.Cu")
		(net "MEMA_4")
	)
	(segment
		(start 285.877 -198.156576)
		(end 285.877 -199.228202)
		(width 0.1143)
		(layer "B.Cu")
		(net "MEMA_4")
	)
	(segment
		(start 285.458408 -197.337172)
		(end 285.458408 -197.737984)
		(width 0.1143)
		(layer "B.Cu")
		(net "MEMA_4")
	)
	(segment
		(start 286.174434 -189.135766)
		(end 285.837884 -189.135766)
		(width 0.1143)
		(layer "B.Cu")
		(net "MEMA_4")
	)
	(segment
		(start 285.458408 -196.887592)
		(end 285.458408 -197.337172)
		(width 0.1143)
		(layer "B.Cu")
		(net "MEMA_4")
	)
	(segment
		(start 286.05099 -196.29501)
		(end 285.458408 -196.887592)
		(width 0.1143)
		(layer "B.Cu")
		(net "MEMA_4")
	)
	(segment
		(start 285.14929 -189.82436)
		(end 285.14929 -194.02425)
		(width 0.1143)
		(layer "B.Cu")
		(net "MEMA_4")
	)
	(segment
		(start 102.362 -245.11)
		(end 101.1555 -243.9035)
		(width 0.1143)
		(layer "F.Cu")
		(net "SAS_FAULT_LED0")
	)
	(segment
		(start 105.41 -245.11)
		(end 102.362 -245.11)
		(width 0.1143)
		(layer "F.Cu")
		(net "SAS_FAULT_LED0")
	)
	(segment
		(start 101.1555 -242.57)
		(end 101.1555 -239.4712)
		(width 0.1143)
		(layer "F.Cu")
		(net "SAS_FAULT_LED0")
	)
	(segment
		(start 101.1555 -243.9035)
		(end 101.1555 -242.57)
		(width 0.1143)
		(layer "F.Cu")
		(net "SAS_FAULT_LED0")
	)
	(segment
		(start 105.664 -244.856)
		(end 105.41 -245.11)
		(width 0.1143)
		(layer "F.Cu")
		(net "SAS_FAULT_LED0")
	)
	(via
		(at 101.1555 -242.57)
		(size 0.5588)
		(drill 0.3048)
		(layers "F.Cu" "B.Cu")
		(net "SAS_FAULT_LED0")
	)
	(via
		(at 105.664 -244.856)
		(size 0.5588)
		(drill 0.3048)
		(layers "F.Cu" "B.Cu")
		(net "SAS_FAULT_LED0")
	)
	(via
		(at 99.822 -241.046)
		(size 0.7112)
		(drill 0.3556)
		(layers "F.Cu" "B.Cu")
		(net "SAS_FAULT_LED0")
	)
	(segment
		(start 109.175042 -238.588042)
		(end 109.175042 -241.765328)
		(width 0.1143)
		(layer "B.Cu")
		(net "SAS_FAULT_LED0")
	)
	(segment
		(start 107.38485 -246.57685)
		(end 105.664 -244.856)
		(width 0.1143)
		(layer "B.Cu")
		(net "SAS_FAULT_LED0")
	)
	(segment
		(start 106.84637 -244.094)
		(end 106.750358 -244.094)
		(width 0.1143)
		(layer "B.Cu")
		(net "SAS_FAULT_LED0")
	)
	(segment
		(start 109.175042 -241.765328)
		(end 106.84637 -244.094)
		(width 0.1143)
		(layer "B.Cu")
		(net "SAS_FAULT_LED0")
	)
	(segment
		(start 108.839 -232.156)
		(end 108.839 -238.252)
		(width 0.1143)
		(layer "B.Cu")
		(net "SAS_FAULT_LED0")
	)
	(segment
		(start 107.38485 -252.66015)
		(end 107.38485 -246.57685)
		(width 0.1143)
		(layer "B.Cu")
		(net "SAS_FAULT_LED0")
	)
	(segment
		(start 106.750358 -244.094)
		(end 105.988358 -244.856)
		(width 0.1143)
		(layer "B.Cu")
		(net "SAS_FAULT_LED0")
	)
	(segment
		(start 99.822 -241.046)
		(end 99.822 -241.2365)
		(width 0.1143)
		(layer "B.Cu")
		(net "SAS_FAULT_LED0")
	)
	(segment
		(start 108.839 -238.252)
		(end 109.175042 -238.588042)
		(width 0.1143)
		(layer "B.Cu")
		(net "SAS_FAULT_LED0")
	)
	(segment
		(start 106.999532 -256.50444)
		(end 106.999532 -253.045468)
		(width 0.1143)
		(layer "B.Cu")
		(net "SAS_FAULT_LED0")
	)
	(segment
		(start 103.632 -226.949)
		(end 108.839 -232.156)
		(width 0.1143)
		(layer "B.Cu")
		(net "SAS_FAULT_LED0")
	)
	(segment
		(start 105.988358 -244.856)
		(end 105.664 -244.856)
		(width 0.1143)
		(layer "B.Cu")
		(net "SAS_FAULT_LED0")
	)
	(segment
		(start 99.822 -239.8395)
		(end 99.822 -241.046)
		(width 0.1143)
		(layer "B.Cu")
		(net "SAS_FAULT_LED0")
	)
	(segment
		(start 106.999532 -253.045468)
		(end 107.38485 -252.66015)
		(width 0.1143)
		(layer "B.Cu")
		(net "SAS_FAULT_LED0")
	)
	(segment
		(start 103.4415 -226.949)
		(end 103.632 -226.949)
		(width 0.1143)
		(layer "B.Cu")
		(net "SAS_FAULT_LED0")
	)
	(segment
		(start 99.822 -241.2365)
		(end 101.1555 -242.57)
		(width 0.1143)
		(layer "B.Cu")
		(net "SAS_FAULT_LED0")
	)
	(segment
		(start 174.426372 -202.637136)
		(end 174.426372 -201.604372)
		(width 0.1143)
		(layer "F.Cu")
		(net "SAS_I2C_B_BUF_SCL")
	)
	(segment
		(start 174.482252 -203.886816)
		(end 176.991772 -203.886816)
		(width 0.1143)
		(layer "F.Cu")
		(net "SAS_I2C_B_BUF_SCL")
	)
	(segment
		(start 174.426372 -202.637136)
		(end 174.426372 -203.830936)
		(width 0.1143)
		(layer "F.Cu")
		(net "SAS_I2C_B_BUF_SCL")
	)
	(segment
		(start 174.426372 -203.830936)
		(end 174.482252 -203.886816)
		(width 0.1143)
		(layer "F.Cu")
		(net "SAS_I2C_B_BUF_SCL")
	)
	(via
		(at 174.426372 -201.604372)
		(size 0.7112)
		(drill 0.3556)
		(layers "F.Cu" "B.Cu")
		(net "SAS_I2C_B_BUF_SCL")
	)
	(segment
		(start 19.863562 -187.77458)
		(end 23.716742 -187.77458)
		(width 0.1143)
		(layer "F.Cu")
		(net "SAS_HDD_PRE6")
	)
	(segment
		(start 16.429482 -193.562224)
		(end 16.452088 -193.562224)
		(width 0.1143)
		(layer "F.Cu")
		(net "SAS_HDD_PRE6")
	)
	(segment
		(start 29.332428 -182.15864)
		(end 29.332428 -175.009048)
		(width 0.1143)
		(layer "F.Cu")
		(net "SAS_HDD_PRE6")
	)
	(segment
		(start 29.332428 -175.009048)
		(end 28.755086 -174.431706)
		(width 0.1143)
		(layer "F.Cu")
		(net "SAS_HDD_PRE6")
	)
	(segment
		(start 17.210278 -192.804034)
		(end 17.210278 -191.020446)
		(width 0.1143)
		(layer "F.Cu")
		(net "SAS_HDD_PRE6")
	)
	(segment
		(start 27.648916 -175.721518)
		(end 27.624278 -175.746156)
		(width 0.1143)
		(layer "F.Cu")
		(net "SAS_HDD_PRE6")
	)
	(segment
		(start 26.010362 -185.480706)
		(end 29.332428 -182.15864)
		(width 0.1143)
		(layer "F.Cu")
		(net "SAS_HDD_PRE6")
	)
	(segment
		(start 17.210278 -191.020446)
		(end 17.210278 -190.427864)
		(width 0.1143)
		(layer "F.Cu")
		(net "SAS_HDD_PRE6")
	)
	(segment
		(start 26.010362 -185.48096)
		(end 26.010362 -185.480706)
		(width 0.1143)
		(layer "F.Cu")
		(net "SAS_HDD_PRE6")
	)
	(segment
		(start 28.09367 -174.431706)
		(end 27.648916 -174.87646)
		(width 0.1143)
		(layer "F.Cu")
		(net "SAS_HDD_PRE6")
	)
	(segment
		(start 23.716742 -187.77458)
		(end 26.010362 -185.48096)
		(width 0.1143)
		(layer "F.Cu")
		(net "SAS_HDD_PRE6")
	)
	(segment
		(start 28.755086 -174.431706)
		(end 28.09367 -174.431706)
		(width 0.1143)
		(layer "F.Cu")
		(net "SAS_HDD_PRE6")
	)
	(segment
		(start 27.648916 -174.87646)
		(end 27.648916 -175.721518)
		(width 0.1143)
		(layer "F.Cu")
		(net "SAS_HDD_PRE6")
	)
	(segment
		(start 16.452088 -193.562224)
		(end 17.210278 -192.804034)
		(width 0.1143)
		(layer "F.Cu")
		(net "SAS_HDD_PRE6")
	)
	(segment
		(start 17.210278 -190.427864)
		(end 19.863562 -187.77458)
		(width 0.1143)
		(layer "F.Cu")
		(net "SAS_HDD_PRE6")
	)
	(via
		(at 10.211816 -200.36028)
		(size 0.7112)
		(drill 0.3556)
		(layers "F.Cu" "B.Cu")
		(net "SAS_HDD_PRE6")
	)
	(via
		(at 16.429482 -193.562224)
		(size 0.5588)
		(drill 0.3048)
		(layers "F.Cu" "B.Cu")
		(net "SAS_HDD_PRE6")
	)
	(segment
		(start 41.000426 -256.50444)
		(end 41.000426 -252.029468)
		(width 0.1143)
		(layer "B.Cu")
		(net "SAS_HDD_PRE6")
	)
	(segment
		(start 16.429482 -193.562224)
		(end 16.429482 -194.142614)
		(width 0.1143)
		(layer "B.Cu")
		(net "SAS_HDD_PRE6")
	)
	(segment
		(start 11.293348 -242.77447)
		(end 5.646166 -237.127288)
		(width 0.1143)
		(layer "B.Cu")
		(net "SAS_HDD_PRE6")
	)
	(segment
		(start 5.646166 -204.92593)
		(end 10.211816 -200.36028)
		(width 0.1143)
		(layer "B.Cu")
		(net "SAS_HDD_PRE6")
	)
	(segment
		(start 5.646166 -237.127288)
		(end 5.646166 -204.92593)
		(width 0.1143)
		(layer "B.Cu")
		(net "SAS_HDD_PRE6")
	)
	(segment
		(start 41.000426 -252.029468)
		(end 31.745428 -242.77447)
		(width 0.1143)
		(layer "B.Cu")
		(net "SAS_HDD_PRE6")
	)
	(segment
		(start 16.429482 -194.142614)
		(end 10.211816 -200.36028)
		(width 0.1143)
		(layer "B.Cu")
		(net "SAS_HDD_PRE6")
	)
	(segment
		(start 31.745428 -242.77447)
		(end 11.293348 -242.77447)
		(width 0.1143)
		(layer "B.Cu")
		(net "SAS_HDD_PRE6")
	)
	(segment
		(start 293.634922 -183.525922)
		(end 293.971472 -183.862472)
		(width 0.1143)
		(layer "F.Cu")
		(net "MEMDQ_3")
	)
	(segment
		(start 294.05072 -187.319666)
		(end 294.05072 -187.837572)
		(width 0.1143)
		(layer "F.Cu")
		(net "MEMDQ_3")
	)
	(segment
		(start 293.46525 -185.70575)
		(end 293.46525 -186.734196)
		(width 0.1143)
		(layer "F.Cu")
		(net "MEMDQ_3")
	)
	(segment
		(start 292.917626 -198.378318)
		(end 292.917626 -198.450962)
		(width 0.1143)
		(layer "F.Cu")
		(net "MEMDQ_3")
	)
	(segment
		(start 293.971472 -185.199528)
		(end 293.46525 -185.70575)
		(width 0.1143)
		(layer "F.Cu")
		(net "MEMDQ_3")
	)
	(segment
		(start 292.938708 -187.837572)
		(end 294.05072 -187.837572)
		(width 0.1143)
		(layer "F.Cu")
		(net "MEMDQ_3")
	)
	(segment
		(start 292.898068 -198.35876)
		(end 292.917626 -198.378318)
		(width 0.1143)
		(layer "F.Cu")
		(net "MEMDQ_3")
	)
	(segment
		(start 293.971472 -183.862472)
		(end 293.971472 -185.199528)
		(width 0.1143)
		(layer "F.Cu")
		(net "MEMDQ_3")
	)
	(segment
		(start 293.634922 -183.44007)
		(end 293.634922 -183.525922)
		(width 0.1143)
		(layer "F.Cu")
		(net "MEMDQ_3")
	)
	(segment
		(start 292.898068 -197.73519)
		(end 292.898068 -198.35876)
		(width 0.1143)
		(layer "F.Cu")
		(net "MEMDQ_3")
	)
	(segment
		(start 292.286436 -187.1853)
		(end 292.938708 -187.837572)
		(width 0.1143)
		(layer "F.Cu")
		(net "MEMDQ_3")
	)
	(segment
		(start 293.46525 -186.734196)
		(end 294.05072 -187.319666)
		(width 0.1143)
		(layer "F.Cu")
		(net "MEMDQ_3")
	)
	(via
		(at 294.05072 -187.837572)
		(size 0.7112)
		(drill 0.3556)
		(layers "F.Cu" "B.Cu")
		(net "MEMDQ_3")
	)
	(via
		(at 292.917626 -198.450962)
		(size 0.508)
		(drill 0.254)
		(layers "F.Cu" "B.Cu")
		(net "MEMDQ_3")
	)
	(via
		(at 292.286436 -187.1853)
		(size 0.508)
		(drill 0.254)
		(layers "F.Cu" "B.Cu")
		(net "MEMDQ_3")
	)
	(segment
		(start 291.07003 -196.8881)
		(end 291.34181 -197.15988)
		(width 0.127)
		(layer "In5.Cu")
		(net "MEMDQ_3")
	)
	(segment
		(start 291.34181 -197.15988)
		(end 291.34181 -198.175372)
		(width 0.127)
		(layer "In5.Cu")
		(net "MEMDQ_3")
	)
	(segment
		(start 291.07003 -196.14134)
		(end 291.07003 -196.8881)
		(width 0.127)
		(layer "In5.Cu")
		(net "MEMDQ_3")
	)
	(segment
		(start 290.322 -190.287148)
		(end 290.322 -193.94805)
		(width 0.127)
		(layer "In5.Cu")
		(net "MEMDQ_3")
	)
	(segment
		(start 290.57092 -187.38088)
		(end 290.57092 -190.038228)
		(width 0.127)
		(layer "In5.Cu")
		(net "MEMDQ_3")
	)
	(segment
		(start 291.6174 -198.450962)
		(end 292.917626 -198.450962)
		(width 0.127)
		(layer "In5.Cu")
		(net "MEMDQ_3")
	)
	(segment
		(start 290.57092 -190.038228)
		(end 290.322 -190.287148)
		(width 0.127)
		(layer "In5.Cu")
		(net "MEMDQ_3")
	)
	(segment
		(start 291.31895 -194.1957)
		(end 291.62248 -194.49923)
		(width 0.127)
		(layer "In5.Cu")
		(net "MEMDQ_3")
	)
	(segment
		(start 291.62248 -195.58889)
		(end 291.07003 -196.14134)
		(width 0.127)
		(layer "In5.Cu")
		(net "MEMDQ_3")
	)
	(segment
		(start 290.322 -193.94805)
		(end 290.56965 -194.1957)
		(width 0.127)
		(layer "In5.Cu")
		(net "MEMDQ_3")
	)
	(segment
		(start 292.286436 -187.1853)
		(end 290.7665 -187.1853)
		(width 0.127)
		(layer "In5.Cu")
		(net "MEMDQ_3")
	)
	(segment
		(start 291.62248 -194.49923)
		(end 291.62248 -195.58889)
		(width 0.127)
		(layer "In5.Cu")
		(net "MEMDQ_3")
	)
	(segment
		(start 290.7665 -187.1853)
		(end 290.57092 -187.38088)
		(width 0.127)
		(layer "In5.Cu")
		(net "MEMDQ_3")
	)
	(segment
		(start 290.56965 -194.1957)
		(end 291.31895 -194.1957)
		(width 0.127)
		(layer "In5.Cu")
		(net "MEMDQ_3")
	)
	(segment
		(start 291.34181 -198.175372)
		(end 291.6174 -198.450962)
		(width 0.127)
		(layer "In5.Cu")
		(net "MEMDQ_3")
	)
	(segment
		(start 21.598128 -183.59628)
		(end 21.110448 -184.08396)
		(width 0.1143)
		(layer "F.Cu")
		(net "SAS_HDD_PRE11")
	)
	(segment
		(start 20.617942 -186.716162)
		(end 20.389088 -186.716162)
		(width 0.1143)
		(layer "F.Cu")
		(net "SAS_HDD_PRE11")
	)
	(segment
		(start 18.588482 -173.326806)
		(end 20.373848 -173.326806)
		(width 0.1143)
		(layer "F.Cu")
		(net "SAS_HDD_PRE11")
	)
	(segment
		(start 21.110448 -185.409586)
		(end 21.110448 -186.223656)
		(width 0.1143)
		(layer "F.Cu")
		(net "SAS_HDD_PRE11")
	)
	(segment
		(start 21.110448 -184.08396)
		(end 21.110448 -185.409586)
		(width 0.1143)
		(layer "F.Cu")
		(net "SAS_HDD_PRE11")
	)
	(segment
		(start 21.598128 -174.551086)
		(end 21.598128 -183.59628)
		(width 0.1143)
		(layer "F.Cu")
		(net "SAS_HDD_PRE11")
	)
	(segment
		(start 20.373848 -173.326806)
		(end 21.598128 -174.551086)
		(width 0.1143)
		(layer "F.Cu")
		(net "SAS_HDD_PRE11")
	)
	(segment
		(start 17.584928 -175.746156)
		(end 17.584928 -174.330614)
		(width 0.1143)
		(layer "F.Cu")
		(net "SAS_HDD_PRE11")
	)
	(segment
		(start 21.110448 -186.223656)
		(end 20.617942 -186.716162)
		(width 0.1143)
		(layer "F.Cu")
		(net "SAS_HDD_PRE11")
	)
	(segment
		(start 17.584928 -174.330614)
		(end 17.612868 -174.30242)
		(width 0.1143)
		(layer "F.Cu")
		(net "SAS_HDD_PRE11")
	)
	(segment
		(start 17.612868 -174.30242)
		(end 18.588482 -173.326806)
		(width 0.1143)
		(layer "F.Cu")
		(net "SAS_HDD_PRE11")
	)
	(via
		(at 20.389088 -186.716162)
		(size 0.5588)
		(drill 0.3048)
		(layers "F.Cu" "B.Cu")
		(net "SAS_HDD_PRE11")
	)
	(via
		(at 19.735546 -187.58281)
		(size 0.7112)
		(drill 0.3556)
		(layers "F.Cu" "B.Cu")
		(net "SAS_HDD_PRE11")
	)
	(segment
		(start 33.445958 -253.746)
		(end 33.445958 -249.968004)
		(width 0.1143)
		(layer "B.Cu")
		(net "SAS_HDD_PRE11")
	)
	(segment
		(start 18.604484 -188.101732)
		(end 19.216624 -188.101732)
		(width 0.1143)
		(layer "B.Cu")
		(net "SAS_HDD_PRE11")
	)
	(segment
		(start 33.445958 -249.968004)
		(end 28.206954 -244.729)
		(width 0.1143)
		(layer "B.Cu")
		(net "SAS_HDD_PRE11")
	)
	(segment
		(start 19.735546 -187.58281)
		(end 20.389088 -186.929268)
		(width 0.1143)
		(layer "B.Cu")
		(net "SAS_HDD_PRE11")
	)
	(segment
		(start 20.389088 -186.929268)
		(end 20.389088 -186.716162)
		(width 0.1143)
		(layer "B.Cu")
		(net "SAS_HDD_PRE11")
	)
	(segment
		(start 28.206954 -244.729)
		(end 10.643108 -244.729)
		(width 0.1143)
		(layer "B.Cu")
		(net "SAS_HDD_PRE11")
	)
	(segment
		(start 3.804666 -237.890558)
		(end 3.804666 -202.90155)
		(width 0.1143)
		(layer "B.Cu")
		(net "SAS_HDD_PRE11")
	)
	(segment
		(start 10.643108 -244.729)
		(end 3.804666 -237.890558)
		(width 0.1143)
		(layer "B.Cu")
		(net "SAS_HDD_PRE11")
	)
	(segment
		(start 3.804666 -202.90155)
		(end 18.604484 -188.101732)
		(width 0.1143)
		(layer "B.Cu")
		(net "SAS_HDD_PRE11")
	)
	(segment
		(start 34.000186 -256.50444)
		(end 34.000186 -254.300228)
		(width 0.1143)
		(layer "B.Cu")
		(net "SAS_HDD_PRE11")
	)
	(segment
		(start 19.216624 -188.101732)
		(end 19.735546 -187.58281)
		(width 0.1143)
		(layer "B.Cu")
		(net "SAS_HDD_PRE11")
	)
	(segment
		(start 34.000186 -254.300228)
		(end 33.445958 -253.746)
		(width 0.1143)
		(layer "B.Cu")
		(net "SAS_HDD_PRE11")
	)
	(segment
		(start 184.332372 -202.560936)
		(end 184.306464 -202.586844)
		(width 0.1143)
		(layer "F.Cu")
		(net "I2C_B_BUF_READY")
	)
	(segment
		(start 181.131972 -203.236576)
		(end 182.335424 -203.236576)
		(width 0.1143)
		(layer "F.Cu")
		(net "I2C_B_BUF_READY")
	)
	(segment
		(start 183.028844 -202.586844)
		(end 183.007 -202.565)
		(width 0.1143)
		(layer "F.Cu")
		(net "I2C_B_BUF_READY")
	)
	(segment
		(start 184.306464 -202.586844)
		(end 183.028844 -202.586844)
		(width 0.1143)
		(layer "F.Cu")
		(net "I2C_B_BUF_READY")
	)
	(segment
		(start 182.335424 -203.236576)
		(end 183.007 -202.565)
		(width 0.1143)
		(layer "F.Cu")
		(net "I2C_B_BUF_READY")
	)
	(via
		(at 183.007 -202.565)
		(size 0.7112)
		(drill 0.3556)
		(layers "F.Cu" "B.Cu")
		(net "I2C_B_BUF_READY")
	)
	(segment
		(start 291.234876 -181.040024)
		(end 291.225224 -181.040024)
		(width 0.1143)
		(layer "F.Cu")
		(net "MEMODT")
	)
	(segment
		(start 289.319208 -202.15606)
		(end 289.31362 -202.15606)
		(width 0.1143)
		(layer "F.Cu")
		(net "MEMODT")
	)
	(segment
		(start 291.225224 -181.040024)
		(end 290.83 -180.6448)
		(width 0.1143)
		(layer "F.Cu")
		(net "MEMODT")
	)
	(segment
		(start 289.31362 -202.15606)
		(end 289.29838 -202.14082)
		(width 0.1143)
		(layer "F.Cu")
		(net "MEMODT")
	)
	(segment
		(start 289.698176 -202.535028)
		(end 289.319208 -202.15606)
		(width 0.1143)
		(layer "F.Cu")
		(net "MEMODT")
	)
	(via
		(at 289.29838 -202.14082)
		(size 0.508)
		(drill 0.254)
		(layers "F.Cu" "B.Cu")
		(net "MEMODT")
	)
	(via
		(at 288.5186 -201.295)
		(size 0.7112)
		(drill 0.3556)
		(layers "F.Cu" "B.Cu")
		(net "MEMODT")
	)
	(via
		(at 290.83 -180.6448)
		(size 0.508)
		(drill 0.254)
		(layers "F.Cu" "B.Cu")
		(net "MEMODT")
	)
	(segment
		(start 289.283394 -199.427084)
		(end 288.75228 -199.958198)
		(width 0.1143)
		(layer "B.Cu")
		(net "MEMODT")
	)
	(segment
		(start 292.11905 -185.676286)
		(end 291.55263 -186.242706)
		(width 0.1143)
		(layer "B.Cu")
		(net "MEMODT")
	)
	(segment
		(start 290.83 -180.6448)
		(end 290.83 -180.822854)
		(width 0.1143)
		(layer "B.Cu")
		(net "MEMODT")
	)
	(segment
		(start 288.75228 -201.06132)
		(end 288.5186 -201.295)
		(width 0.1143)
		(layer "B.Cu")
		(net "MEMODT")
	)
	(segment
		(start 288.5186 -201.295)
		(end 289.29838 -202.07478)
		(width 0.1143)
		(layer "B.Cu")
		(net "MEMODT")
	)
	(segment
		(start 290.957 -196.66458)
		(end 289.283394 -198.338186)
		(width 0.1143)
		(layer "B.Cu")
		(net "MEMODT")
	)
	(segment
		(start 289.283394 -198.338186)
		(end 289.283394 -199.427084)
		(width 0.1143)
		(layer "B.Cu")
		(net "MEMODT")
	)
	(segment
		(start 291.21354 -182.08625)
		(end 291.21354 -183.212232)
		(width 0.1143)
		(layer "B.Cu")
		(net "MEMODT")
	)
	(segment
		(start 291.9984 -193.89217)
		(end 291.61613 -194.27444)
		(width 0.1143)
		(layer "B.Cu")
		(net "MEMODT")
	)
	(segment
		(start 289.29838 -202.07478)
		(end 289.29838 -202.14082)
		(width 0.1143)
		(layer "B.Cu")
		(net "MEMODT")
	)
	(segment
		(start 288.75228 -199.958198)
		(end 288.75228 -201.06132)
		(width 0.1143)
		(layer "B.Cu")
		(net "MEMODT")
	)
	(segment
		(start 292.11905 -184.117742)
		(end 292.11905 -185.676286)
		(width 0.1143)
		(layer "B.Cu")
		(net "MEMODT")
	)
	(segment
		(start 290.957 -196.24548)
		(end 290.957 -196.66458)
		(width 0.1143)
		(layer "B.Cu")
		(net "MEMODT")
	)
	(segment
		(start 291.256212 -181.249066)
		(end 291.256212 -182.043578)
		(width 0.1143)
		(layer "B.Cu")
		(net "MEMODT")
	)
	(segment
		(start 291.55263 -186.242706)
		(end 291.55263 -187.43803)
		(width 0.1143)
		(layer "B.Cu")
		(net "MEMODT")
	)
	(segment
		(start 291.55263 -187.43803)
		(end 291.9984 -187.8838)
		(width 0.1143)
		(layer "B.Cu")
		(net "MEMODT")
	)
	(segment
		(start 291.256212 -182.043578)
		(end 291.21354 -182.08625)
		(width 0.1143)
		(layer "B.Cu")
		(net "MEMODT")
	)
	(segment
		(start 290.83 -180.822854)
		(end 291.256212 -181.249066)
		(width 0.1143)
		(layer "B.Cu")
		(net "MEMODT")
	)
	(segment
		(start 291.9984 -187.8838)
		(end 291.9984 -193.89217)
		(width 0.1143)
		(layer "B.Cu")
		(net "MEMODT")
	)
	(segment
		(start 291.61613 -195.58635)
		(end 290.957 -196.24548)
		(width 0.1143)
		(layer "B.Cu")
		(net "MEMODT")
	)
	(segment
		(start 291.21354 -183.212232)
		(end 292.11905 -184.117742)
		(width 0.1143)
		(layer "B.Cu")
		(net "MEMODT")
	)
	(segment
		(start 291.61613 -194.27444)
		(end 291.61613 -195.58635)
		(width 0.1143)
		(layer "B.Cu")
		(net "MEMODT")
	)
	(segment
		(start 184.149492 -203.886816)
		(end 183.261 -203.886816)
		(width 0.1143)
		(layer "F.Cu")
		(net "SAS_I2C_B_BUF_SDA")
	)
	(segment
		(start 184.332372 -204.796136)
		(end 184.332372 -203.703936)
		(width 0.1143)
		(layer "F.Cu")
		(net "SAS_I2C_B_BUF_SDA")
	)
	(segment
		(start 181.131972 -203.886816)
		(end 183.261 -203.886816)
		(width 0.1143)
		(layer "F.Cu")
		(net "SAS_I2C_B_BUF_SDA")
	)
	(segment
		(start 184.332372 -203.703936)
		(end 184.149492 -203.886816)
		(width 0.1143)
		(layer "F.Cu")
		(net "SAS_I2C_B_BUF_SDA")
	)
	(via
		(at 183.261 -203.886816)
		(size 0.7112)
		(drill 0.3556)
		(layers "F.Cu" "B.Cu")
		(net "SAS_I2C_B_BUF_SDA")
	)
	(segment
		(start 284.1879 -198.042022)
		(end 284.3022 -198.156322)
		(width 0.1143)
		(layer "F.Cu")
		(net "MEMA_8")
	)
	(segment
		(start 288.804858 -185.148982)
		(end 288.804858 -185.727848)
		(width 0.1143)
		(layer "F.Cu")
		(net "MEMA_8")
	)
	(segment
		(start 283.3878 -197.254622)
		(end 283.3878 -197.927722)
		(width 0.1143)
		(layer "F.Cu")
		(net "MEMA_8")
	)
	(segment
		(start 284.1879 -197.584822)
		(end 283.9593 -197.584822)
		(width 0.1143)
		(layer "F.Cu")
		(net "MEMA_8")
	)
	(segment
		(start 283.845 -197.470522)
		(end 283.845 -197.254622)
		(width 0.1143)
		(layer "F.Cu")
		(net "MEMA_8")
	)
	(segment
		(start 283.9593 -197.584822)
		(end 283.845 -197.470522)
		(width 0.1143)
		(layer "F.Cu")
		(net "MEMA_8")
	)
	(segment
		(start 289.63493 -184.24017)
		(end 289.63493 -184.31891)
		(width 0.1143)
		(layer "F.Cu")
		(net "MEMA_8")
	)
	(segment
		(start 284.4292 -196.93509)
		(end 284.3022 -197.06209)
		(width 0.1143)
		(layer "F.Cu")
		(net "MEMA_8")
	)
	(segment
		(start 289.63493 -184.31891)
		(end 288.804858 -185.148982)
		(width 0.1143)
		(layer "F.Cu")
		(net "MEMA_8")
	)
	(segment
		(start 284.3022 -197.470522)
		(end 284.1879 -197.584822)
		(width 0.1143)
		(layer "F.Cu")
		(net "MEMA_8")
	)
	(segment
		(start 283.3878 -197.927722)
		(end 283.5021 -198.042022)
		(width 0.1143)
		(layer "F.Cu")
		(net "MEMA_8")
	)
	(segment
		(start 288.804858 -185.727848)
		(end 286.522922 -188.009784)
		(width 0.1143)
		(layer "F.Cu")
		(net "MEMA_8")
	)
	(segment
		(start 283.5021 -197.140322)
		(end 283.3878 -197.254622)
		(width 0.1143)
		(layer "F.Cu")
		(net "MEMA_8")
	)
	(segment
		(start 283.5021 -198.042022)
		(end 284.1879 -198.042022)
		(width 0.1143)
		(layer "F.Cu")
		(net "MEMA_8")
	)
	(segment
		(start 284.3022 -198.247)
		(end 284.5816 -198.5264)
		(width 0.1143)
		(layer "F.Cu")
		(net "MEMA_8")
	)
	(segment
		(start 286.459168 -188.009784)
		(end 286.304482 -188.16447)
		(width 0.1143)
		(layer "F.Cu")
		(net "MEMA_8")
	)
	(segment
		(start 283.7307 -197.140322)
		(end 283.5021 -197.140322)
		(width 0.1143)
		(layer "F.Cu")
		(net "MEMA_8")
	)
	(segment
		(start 283.845 -197.254622)
		(end 283.7307 -197.140322)
		(width 0.1143)
		(layer "F.Cu")
		(net "MEMA_8")
	)
	(segment
		(start 284.3022 -197.06209)
		(end 284.3022 -197.470522)
		(width 0.1143)
		(layer "F.Cu")
		(net "MEMA_8")
	)
	(segment
		(start 286.522922 -188.009784)
		(end 286.459168 -188.009784)
		(width 0.1143)
		(layer "F.Cu")
		(net "MEMA_8")
	)
	(segment
		(start 284.3022 -198.156322)
		(end 284.3022 -198.247)
		(width 0.1143)
		(layer "F.Cu")
		(net "MEMA_8")
	)
	(segment
		(start 284.898084 -196.93509)
		(end 284.4292 -196.93509)
		(width 0.1143)
		(layer "F.Cu")
		(net "MEMA_8")
	)
	(via
		(at 286.304482 -188.16447)
		(size 0.508)
		(drill 0.254)
		(layers "F.Cu" "B.Cu")
		(net "MEMA_8")
	)
	(via
		(at 284.30093 -196.825362)
		(size 0.7112)
		(drill 0.3556)
		(layers "F.Cu" "B.Cu")
		(net "MEMA_8")
	)
	(via
		(at 284.5816 -198.5264)
		(size 0.508)
		(drill 0.254)
		(layers "F.Cu" "B.Cu")
		(net "MEMA_8")
	)
	(segment
		(start 285.336742 -188.25591)
		(end 286.06115 -188.25591)
		(width 0.1143)
		(layer "B.Cu")
		(net "MEMA_8")
	)
	(segment
		(start 284.5816 -198.5264)
		(end 284.5816 -197.8152)
		(width 0.1143)
		(layer "B.Cu")
		(net "MEMA_8")
	)
	(segment
		(start 286.06115 -188.25591)
		(end 286.15259 -188.16447)
		(width 0.1143)
		(layer "B.Cu")
		(net "MEMA_8")
	)
	(segment
		(start 284.1371 -192.71615)
		(end 284.3022 -192.55105)
		(width 0.1143)
		(layer "B.Cu")
		(net "MEMA_8")
	)
	(segment
		(start 284.3022 -192.25895)
		(end 284.1371 -192.09385)
		(width 0.1143)
		(layer "B.Cu")
		(net "MEMA_8")
	)
	(segment
		(start 284.3022 -190.72225)
		(end 284.3022 -190.43015)
		(width 0.1143)
		(layer "B.Cu")
		(net "MEMA_8")
	)
	(segment
		(start 284.3022 -192.55105)
		(end 284.3022 -192.25895)
		(width 0.1143)
		(layer "B.Cu")
		(net "MEMA_8")
	)
	(segment
		(start 284.03423 -195.413884)
		(end 284.14853 -195.299584)
		(width 0.1143)
		(layer "B.Cu")
		(net "MEMA_8")
	)
	(segment
		(start 284.3022 -189.80785)
		(end 284.3022 -189.290452)
		(width 0.1143)
		(layer "B.Cu")
		(net "MEMA_8")
	)
	(segment
		(start 284.1371 -190.26505)
		(end 284.1371 -189.97295)
		(width 0.1143)
		(layer "B.Cu")
		(net "MEMA_8")
	)
	(segment
		(start 284.3022 -195.185284)
		(end 284.3022 -194.08775)
		(width 0.1143)
		(layer "B.Cu")
		(net "MEMA_8")
	)
	(segment
		(start 284.3022 -191.34455)
		(end 284.1371 -191.17945)
		(width 0.1143)
		(layer "B.Cu")
		(net "MEMA_8")
	)
	(segment
		(start 284.30093 -196.825362)
		(end 284.3022 -196.824092)
		(width 0.1143)
		(layer "B.Cu")
		(net "MEMA_8")
	)
	(segment
		(start 284.1371 -192.09385)
		(end 284.1371 -191.80175)
		(width 0.1143)
		(layer "B.Cu")
		(net "MEMA_8")
	)
	(segment
		(start 284.3022 -194.08775)
		(end 284.1371 -193.92265)
		(width 0.1143)
		(layer "B.Cu")
		(net "MEMA_8")
	)
	(segment
		(start 284.1371 -193.63055)
		(end 284.3022 -193.46545)
		(width 0.1143)
		(layer "B.Cu")
		(net "MEMA_8")
	)
	(segment
		(start 284.3022 -193.17335)
		(end 284.1371 -193.00825)
		(width 0.1143)
		(layer "B.Cu")
		(net "MEMA_8")
	)
	(segment
		(start 284.14853 -195.756784)
		(end 284.03423 -195.642484)
		(width 0.1143)
		(layer "B.Cu")
		(net "MEMA_8")
	)
	(segment
		(start 284.5816 -197.8152)
		(end 284.3022 -197.5358)
		(width 0.1143)
		(layer "B.Cu")
		(net "MEMA_8")
	)
	(segment
		(start 286.15259 -188.16447)
		(end 286.304482 -188.16447)
		(width 0.1143)
		(layer "B.Cu")
		(net "MEMA_8")
	)
	(segment
		(start 284.3022 -193.46545)
		(end 284.3022 -193.17335)
		(width 0.1143)
		(layer "B.Cu")
		(net "MEMA_8")
	)
	(segment
		(start 284.3022 -197.5358)
		(end 284.3022 -196.826632)
		(width 0.1143)
		(layer "B.Cu")
		(net "MEMA_8")
	)
	(segment
		(start 284.3022 -191.63665)
		(end 284.3022 -191.34455)
		(width 0.1143)
		(layer "B.Cu")
		(net "MEMA_8")
	)
	(segment
		(start 284.3022 -196.824092)
		(end 284.3022 -195.871084)
		(width 0.1143)
		(layer "B.Cu")
		(net "MEMA_8")
	)
	(segment
		(start 284.1879 -195.299584)
		(end 284.3022 -195.185284)
		(width 0.1143)
		(layer "B.Cu")
		(net "MEMA_8")
	)
	(segment
		(start 284.3022 -195.871084)
		(end 284.1879 -195.756784)
		(width 0.1143)
		(layer "B.Cu")
		(net "MEMA_8")
	)
	(segment
		(start 284.1371 -193.92265)
		(end 284.1371 -193.63055)
		(width 0.1143)
		(layer "B.Cu")
		(net "MEMA_8")
	)
	(segment
		(start 284.1371 -191.17945)
		(end 284.1371 -190.88735)
		(width 0.1143)
		(layer "B.Cu")
		(net "MEMA_8")
	)
	(segment
		(start 284.1371 -191.80175)
		(end 284.3022 -191.63665)
		(width 0.1143)
		(layer "B.Cu")
		(net "MEMA_8")
	)
	(segment
		(start 284.1371 -190.88735)
		(end 284.3022 -190.72225)
		(width 0.1143)
		(layer "B.Cu")
		(net "MEMA_8")
	)
	(segment
		(start 284.03423 -195.642484)
		(end 284.03423 -195.413884)
		(width 0.1143)
		(layer "B.Cu")
		(net "MEMA_8")
	)
	(segment
		(start 284.3022 -189.290452)
		(end 285.336742 -188.25591)
		(width 0.1143)
		(layer "B.Cu")
		(net "MEMA_8")
	)
	(segment
		(start 284.1371 -189.97295)
		(end 284.3022 -189.80785)
		(width 0.1143)
		(layer "B.Cu")
		(net "MEMA_8")
	)
	(segment
		(start 284.1879 -195.756784)
		(end 284.14853 -195.756784)
		(width 0.1143)
		(layer "B.Cu")
		(net "MEMA_8")
	)
	(segment
		(start 284.14853 -195.299584)
		(end 284.1879 -195.299584)
		(width 0.1143)
		(layer "B.Cu")
		(net "MEMA_8")
	)
	(segment
		(start 284.1371 -193.00825)
		(end 284.1371 -192.71615)
		(width 0.1143)
		(layer "B.Cu")
		(net "MEMA_8")
	)
	(segment
		(start 284.3022 -196.826632)
		(end 284.30093 -196.825362)
		(width 0.1143)
		(layer "B.Cu")
		(net "MEMA_8")
	)
	(segment
		(start 284.3022 -190.43015)
		(end 284.1371 -190.26505)
		(width 0.1143)
		(layer "B.Cu")
		(net "MEMA_8")
	)
	(segment
		(start 18.13052 -172.221906)
		(end 21.077174 -172.221906)
		(width 0.1143)
		(layer "F.Cu")
		(net "SAS_HDD_PRE8")
	)
	(segment
		(start 23.059898 -174.20463)
		(end 23.059898 -185.409586)
		(width 0.1143)
		(layer "F.Cu")
		(net "SAS_HDD_PRE8")
	)
	(segment
		(start 16.386048 -175.746156)
		(end 16.386048 -173.966378)
		(width 0.1143)
		(layer "F.Cu")
		(net "SAS_HDD_PRE8")
	)
	(segment
		(start 16.386048 -173.966378)
		(end 18.13052 -172.221906)
		(width 0.1143)
		(layer "F.Cu")
		(net "SAS_HDD_PRE8")
	)
	(segment
		(start 23.059898 -185.409586)
		(end 23.059898 -186.379358)
		(width 0.1143)
		(layer "F.Cu")
		(net "SAS_HDD_PRE8")
	)
	(segment
		(start 23.3807 -186.70016)
		(end 23.46071 -186.70016)
		(width 0.1143)
		(layer "F.Cu")
		(net "SAS_HDD_PRE8")
	)
	(segment
		(start 21.077174 -172.221906)
		(end 23.059898 -174.20463)
		(width 0.1143)
		(layer "F.Cu")
		(net "SAS_HDD_PRE8")
	)
	(segment
		(start 23.059898 -186.379358)
		(end 23.3807 -186.70016)
		(width 0.1143)
		(layer "F.Cu")
		(net "SAS_HDD_PRE8")
	)
	(via
		(at 23.46071 -186.70016)
		(size 0.5588)
		(drill 0.3048)
		(layers "F.Cu" "B.Cu")
		(net "SAS_HDD_PRE8")
	)
	(via
		(at 22.022816 -188.14288)
		(size 0.7112)
		(drill 0.3556)
		(layers "F.Cu" "B.Cu")
		(net "SAS_HDD_PRE8")
	)
	(segment
		(start 20.68068 -189.485016)
		(end 22.022816 -188.14288)
		(width 0.1143)
		(layer "B.Cu")
		(net "SAS_HDD_PRE8")
	)
	(segment
		(start 4.909566 -204.03693)
		(end 15.342616 -193.60388)
		(width 0.1143)
		(layer "B.Cu")
		(net "SAS_HDD_PRE8")
	)
	(segment
		(start 39.000176 -256.50444)
		(end 39.000176 -251.979176)
		(width 0.1143)
		(layer "B.Cu")
		(net "SAS_HDD_PRE8")
	)
	(segment
		(start 15.342616 -193.60388)
		(end 15.342616 -193.204846)
		(width 0.1143)
		(layer "B.Cu")
		(net "SAS_HDD_PRE8")
	)
	(segment
		(start 15.342616 -193.204846)
		(end 19.062446 -189.485016)
		(width 0.1143)
		(layer "B.Cu")
		(net "SAS_HDD_PRE8")
	)
	(segment
		(start 23.46071 -186.704986)
		(end 22.022816 -188.14288)
		(width 0.1143)
		(layer "B.Cu")
		(net "SAS_HDD_PRE8")
	)
	(segment
		(start 4.909566 -237.432596)
		(end 4.909566 -204.03693)
		(width 0.1143)
		(layer "B.Cu")
		(net "SAS_HDD_PRE8")
	)
	(segment
		(start 39.000176 -251.979176)
		(end 30.5943 -243.5733)
		(width 0.1143)
		(layer "B.Cu")
		(net "SAS_HDD_PRE8")
	)
	(segment
		(start 19.062446 -189.485016)
		(end 20.68068 -189.485016)
		(width 0.1143)
		(layer "B.Cu")
		(net "SAS_HDD_PRE8")
	)
	(segment
		(start 23.46071 -186.70016)
		(end 23.46071 -186.704986)
		(width 0.1143)
		(layer "B.Cu")
		(net "SAS_HDD_PRE8")
	)
	(segment
		(start 11.05027 -243.5733)
		(end 4.909566 -237.432596)
		(width 0.1143)
		(layer "B.Cu")
		(net "SAS_HDD_PRE8")
	)
	(segment
		(start 30.5943 -243.5733)
		(end 11.05027 -243.5733)
		(width 0.1143)
		(layer "B.Cu")
		(net "SAS_HDD_PRE8")
	)
	(segment
		(start 298.43476 -170.640248)
		(end 298.831762 -170.243246)
		(width 0.1143)
		(layer "F.Cu")
		(net "PU_BMC0_SDA11")
	)
	(segment
		(start 298.831762 -170.243246)
		(end 298.831762 -170.235372)
		(width 0.1143)
		(layer "F.Cu")
		(net "PU_BMC0_SDA11")
	)
	(via
		(at 298.831762 -170.235372)
		(size 0.508)
		(drill 0.254)
		(layers "F.Cu" "B.Cu")
		(net "PU_BMC0_SDA11")
	)
	(via
		(at 302.514 -165.481)
		(size 0.7112)
		(drill 0.3556)
		(layers "F.Cu" "B.Cu")
		(net "PU_BMC0_SDA11")
	)
	(segment
		(start 298.431458 -169.930064)
		(end 298.736766 -170.235372)
		(width 0.0889)
		(layer "B.Cu")
		(net "PU_BMC0_SDA11")
	)
	(segment
		(start 298.642024 -169.044874)
		(end 298.431458 -169.25544)
		(width 0.0889)
		(layer "B.Cu")
		(net "PU_BMC0_SDA11")
	)
	(segment
		(start 299.127672 -168.994328)
		(end 299.087286 -169.034714)
		(width 0.0889)
		(layer "B.Cu")
		(net "PU_BMC0_SDA11")
	)
	(segment
		(start 309.118 -161.0995)
		(end 305.8795 -164.338)
		(width 0.1143)
		(layer "B.Cu")
		(net "PU_BMC0_SDA11")
	)
	(segment
		(start 298.431458 -169.25544)
		(end 298.431458 -169.281602)
		(width 0.0889)
		(layer "B.Cu")
		(net "PU_BMC0_SDA11")
	)
	(segment
		(start 298.686474 -169.034714)
		(end 298.676314 -169.044874)
		(width 0.0889)
		(layer "B.Cu")
		(net "PU_BMC0_SDA11")
	)
	(segment
		(start 302.514 -165.481)
		(end 302.514 -165.608)
		(width 0.1143)
		(layer "B.Cu")
		(net "PU_BMC0_SDA11")
	)
	(segment
		(start 303.657 -164.338)
		(end 302.514 -165.481)
		(width 0.1143)
		(layer "B.Cu")
		(net "PU_BMC0_SDA11")
	)
	(segment
		(start 298.430696 -169.282364)
		(end 298.430696 -169.631868)
		(width 0.0889)
		(layer "B.Cu")
		(net "PU_BMC0_SDA11")
	)
	(segment
		(start 302.514 -165.608)
		(end 299.127672 -168.994328)
		(width 0.1143)
		(layer "B.Cu")
		(net "PU_BMC0_SDA11")
	)
	(segment
		(start 298.676314 -169.044874)
		(end 298.642024 -169.044874)
		(width 0.0889)
		(layer "B.Cu")
		(net "PU_BMC0_SDA11")
	)
	(segment
		(start 299.087286 -169.034714)
		(end 298.686474 -169.034714)
		(width 0.0889)
		(layer "B.Cu")
		(net "PU_BMC0_SDA11")
	)
	(segment
		(start 298.431458 -169.281602)
		(end 298.430696 -169.282364)
		(width 0.0889)
		(layer "B.Cu")
		(net "PU_BMC0_SDA11")
	)
	(segment
		(start 305.8795 -164.338)
		(end 303.657 -164.338)
		(width 0.1143)
		(layer "B.Cu")
		(net "PU_BMC0_SDA11")
	)
	(segment
		(start 298.431458 -169.63263)
		(end 298.431458 -169.930064)
		(width 0.0889)
		(layer "B.Cu")
		(net "PU_BMC0_SDA11")
	)
	(segment
		(start 298.430696 -169.631868)
		(end 298.431458 -169.63263)
		(width 0.0889)
		(layer "B.Cu")
		(net "PU_BMC0_SDA11")
	)
	(segment
		(start 298.736766 -170.235372)
		(end 298.831762 -170.235372)
		(width 0.0889)
		(layer "B.Cu")
		(net "PU_BMC0_SDA11")
	)
	(segment
		(start 31.542482 -181.853586)
		(end 31.542228 -181.853332)
		(width 0.1143)
		(layer "F.Cu")
		(net "SAS_HDD_PRE0")
	)
	(segment
		(start 30.89529 -173.446186)
		(end 29.670756 -172.221652)
		(width 0.1143)
		(layer "F.Cu")
		(net "SAS_HDD_PRE0")
	)
	(segment
		(start 21.667216 -195.25488)
		(end 22.409658 -194.512438)
		(width 0.1143)
		(layer "F.Cu")
		(net "SAS_HDD_PRE0")
	)
	(segment
		(start 31.542228 -174.09287)
		(end 30.895544 -173.446186)
		(width 0.1143)
		(layer "F.Cu")
		(net "SAS_HDD_PRE0")
	)
	(segment
		(start 29.060648 -172.221652)
		(end 29.060394 -172.221906)
		(width 0.1143)
		(layer "F.Cu")
		(net "SAS_HDD_PRE0")
	)
	(segment
		(start 22.409658 -190.194438)
		(end 22.619716 -189.98438)
		(width 0.1143)
		(layer "F.Cu")
		(net "SAS_HDD_PRE0")
	)
	(segment
		(start 24.632666 -189.98438)
		(end 31.542228 -183.074818)
		(width 0.1143)
		(layer "F.Cu")
		(net "SAS_HDD_PRE0")
	)
	(segment
		(start 27.177492 -172.221906)
		(end 26.9621 -172.437298)
		(width 0.1143)
		(layer "F.Cu")
		(net "SAS_HDD_PRE0")
	)
	(segment
		(start 22.409658 -191.020446)
		(end 22.409658 -190.194438)
		(width 0.1143)
		(layer "F.Cu")
		(net "SAS_HDD_PRE0")
	)
	(segment
		(start 31.542228 -182.968392)
		(end 31.542482 -182.967884)
		(width 0.1143)
		(layer "F.Cu")
		(net "SAS_HDD_PRE0")
	)
	(segment
		(start 26.9621 -172.437552)
		(end 25.256744 -174.142908)
		(width 0.1143)
		(layer "F.Cu")
		(net "SAS_HDD_PRE0")
	)
	(segment
		(start 29.670756 -172.221652)
		(end 29.060648 -172.221652)
		(width 0.1143)
		(layer "F.Cu")
		(net "SAS_HDD_PRE0")
	)
	(segment
		(start 22.409658 -194.512438)
		(end 22.409658 -191.020446)
		(width 0.1143)
		(layer "F.Cu")
		(net "SAS_HDD_PRE0")
	)
	(segment
		(start 30.895544 -173.446186)
		(end 30.89529 -173.446186)
		(width 0.1143)
		(layer "F.Cu")
		(net "SAS_HDD_PRE0")
	)
	(segment
		(start 22.619716 -189.98438)
		(end 24.632666 -189.98438)
		(width 0.1143)
		(layer "F.Cu")
		(net "SAS_HDD_PRE0")
	)
	(segment
		(start 29.060394 -172.221906)
		(end 27.177492 -172.221906)
		(width 0.1143)
		(layer "F.Cu")
		(net "SAS_HDD_PRE0")
	)
	(segment
		(start 25.256744 -174.142908)
		(end 25.256744 -175.71466)
		(width 0.1143)
		(layer "F.Cu")
		(net "SAS_HDD_PRE0")
	)
	(segment
		(start 31.542228 -183.074818)
		(end 31.542228 -182.968392)
		(width 0.1143)
		(layer "F.Cu")
		(net "SAS_HDD_PRE0")
	)
	(segment
		(start 26.9621 -172.437298)
		(end 26.9621 -172.437552)
		(width 0.1143)
		(layer "F.Cu")
		(net "SAS_HDD_PRE0")
	)
	(segment
		(start 31.542228 -181.853332)
		(end 31.542228 -174.09287)
		(width 0.1143)
		(layer "F.Cu")
		(net "SAS_HDD_PRE0")
	)
	(segment
		(start 25.256744 -175.71466)
		(end 25.225248 -175.746156)
		(width 0.1143)
		(layer "F.Cu")
		(net "SAS_HDD_PRE0")
	)
	(segment
		(start 31.542482 -182.967884)
		(end 31.542482 -181.853586)
		(width 0.1143)
		(layer "F.Cu")
		(net "SAS_HDD_PRE0")
	)
	(via
		(at 9.373616 -206.50708)
		(size 0.7112)
		(drill 0.3556)
		(layers "F.Cu" "B.Cu")
		(net "SAS_HDD_PRE0")
	)
	(via
		(at 21.667216 -195.25488)
		(size 0.5588)
		(drill 0.3048)
		(layers "F.Cu" "B.Cu")
		(net "SAS_HDD_PRE0")
	)
	(segment
		(start 13.871956 -201.279506)
		(end 19.284442 -195.86702)
		(width 0.1143)
		(layer "B.Cu")
		(net "SAS_HDD_PRE0")
	)
	(segment
		(start 21.055076 -195.86702)
		(end 21.667216 -195.25488)
		(width 0.1143)
		(layer "B.Cu")
		(net "SAS_HDD_PRE0")
	)
	(segment
		(start 9.373616 -206.506826)
		(end 13.871956 -202.008486)
		(width 0.1143)
		(layer "B.Cu")
		(net "SAS_HDD_PRE0")
	)
	(segment
		(start 46.999906 -254.390906)
		(end 32.753046 -240.144046)
		(width 0.1143)
		(layer "B.Cu")
		(net "SAS_HDD_PRE0")
	)
	(segment
		(start 19.284442 -195.86702)
		(end 21.055076 -195.86702)
		(width 0.1143)
		(layer "B.Cu")
		(net "SAS_HDD_PRE0")
	)
	(segment
		(start 46.999906 -256.50444)
		(end 46.999906 -254.390906)
		(width 0.1143)
		(layer "B.Cu")
		(net "SAS_HDD_PRE0")
	)
	(segment
		(start 9.373616 -206.50708)
		(end 9.373616 -206.506826)
		(width 0.1143)
		(layer "B.Cu")
		(net "SAS_HDD_PRE0")
	)
	(segment
		(start 7.855966 -208.02473)
		(end 9.373616 -206.50708)
		(width 0.1143)
		(layer "B.Cu")
		(net "SAS_HDD_PRE0")
	)
	(segment
		(start 13.871956 -202.008486)
		(end 13.871956 -201.279506)
		(width 0.1143)
		(layer "B.Cu")
		(net "SAS_HDD_PRE0")
	)
	(segment
		(start 32.753046 -240.144046)
		(end 13.28674 -240.144046)
		(width 0.1143)
		(layer "B.Cu")
		(net "SAS_HDD_PRE0")
	)
	(segment
		(start 13.28674 -240.144046)
		(end 7.855966 -234.713272)
		(width 0.1143)
		(layer "B.Cu")
		(net "SAS_HDD_PRE0")
	)
	(segment
		(start 7.855966 -234.713272)
		(end 7.855966 -208.02473)
		(width 0.1143)
		(layer "B.Cu")
		(net "SAS_HDD_PRE0")
	)
	(segment
		(start 174.680372 -194.496436)
		(end 173.473872 -194.496436)
		(width 0.1143)
		(layer "F.Cu")
		(net "SAS_I2C_C_BUF_SCL")
	)
	(segment
		(start 175.053752 -194.869816)
		(end 174.743872 -194.559936)
		(width 0.1143)
		(layer "F.Cu")
		(net "SAS_I2C_C_BUF_SCL")
	)
	(segment
		(start 172.715936 -195.639436)
		(end 172.2755 -195.199)
		(width 0.1143)
		(layer "F.Cu")
		(net "SAS_I2C_C_BUF_SCL")
	)
	(segment
		(start 175.895 -194.869816)
		(end 175.053752 -194.869816)
		(width 0.1143)
		(layer "F.Cu")
		(net "SAS_I2C_C_BUF_SCL")
	)
	(segment
		(start 173.473872 -194.496436)
		(end 173.473872 -195.639436)
		(width 0.1143)
		(layer "F.Cu")
		(net "SAS_I2C_C_BUF_SCL")
	)
	(segment
		(start 174.743872 -194.559936)
		(end 174.680372 -194.496436)
		(width 0.1143)
		(layer "F.Cu")
		(net "SAS_I2C_C_BUF_SCL")
	)
	(segment
		(start 173.473872 -195.639436)
		(end 172.715936 -195.639436)
		(width 0.1143)
		(layer "F.Cu")
		(net "SAS_I2C_C_BUF_SCL")
	)
	(segment
		(start 175.895 -194.869816)
		(end 177.499772 -194.869816)
		(width 0.1143)
		(layer "F.Cu")
		(net "SAS_I2C_C_BUF_SCL")
	)
	(via
		(at 175.895 -194.869816)
		(size 0.7112)
		(drill 0.3556)
		(layers "F.Cu" "B.Cu")
		(net "SAS_I2C_C_BUF_SCL")
	)
	(segment
		(start 16.786098 -175.746156)
		(end 16.786098 -174.087282)
		(width 0.1143)
		(layer "F.Cu")
		(net "SAS_HDD_PRE9")
	)
	(segment
		(start 22.409658 -174.320708)
		(end 22.409658 -185.409586)
		(width 0.1143)
		(layer "F.Cu")
		(net "SAS_HDD_PRE9")
	)
	(segment
		(start 22.409658 -185.409586)
		(end 22.409658 -186.564016)
		(width 0.1143)
		(layer "F.Cu")
		(net "SAS_HDD_PRE9")
	)
	(segment
		(start 18.283174 -172.590206)
		(end 20.679156 -172.590206)
		(width 0.1143)
		(layer "F.Cu")
		(net "SAS_HDD_PRE9")
	)
	(segment
		(start 16.786098 -174.087282)
		(end 18.283174 -172.590206)
		(width 0.1143)
		(layer "F.Cu")
		(net "SAS_HDD_PRE9")
	)
	(segment
		(start 20.679156 -172.590206)
		(end 22.409658 -174.320708)
		(width 0.1143)
		(layer "F.Cu")
		(net "SAS_HDD_PRE9")
	)
	(segment
		(start 22.409658 -186.564016)
		(end 22.294088 -186.679586)
		(width 0.1143)
		(layer "F.Cu")
		(net "SAS_HDD_PRE9")
	)
	(segment
		(start 22.294088 -186.679586)
		(end 22.294088 -186.704986)
		(width 0.1143)
		(layer "F.Cu")
		(net "SAS_HDD_PRE9")
	)
	(via
		(at 22.294088 -186.704986)
		(size 0.5588)
		(drill 0.3048)
		(layers "F.Cu" "B.Cu")
		(net "SAS_HDD_PRE9")
	)
	(via
		(at 6.05028 -201.976228)
		(size 0.7112)
		(drill 0.3556)
		(layers "F.Cu" "B.Cu")
		(net "SAS_HDD_PRE9")
	)
	(segment
		(start 18.935192 -189.091316)
		(end 14.974316 -193.052192)
		(width 0.1143)
		(layer "B.Cu")
		(net "SAS_HDD_PRE9")
	)
	(segment
		(start 7.748778 -200.556114)
		(end 7.470394 -200.556114)
		(width 0.1143)
		(layer "B.Cu")
		(net "SAS_HDD_PRE9")
	)
	(segment
		(start 19.907758 -189.091316)
		(end 18.935192 -189.091316)
		(width 0.1143)
		(layer "B.Cu")
		(net "SAS_HDD_PRE9")
	)
	(segment
		(start 7.470394 -200.556114)
		(end 6.05028 -201.976228)
		(width 0.1143)
		(layer "B.Cu")
		(net "SAS_HDD_PRE9")
	)
	(segment
		(start 4.541266 -237.58525)
		(end 4.541266 -203.485242)
		(width 0.1143)
		(layer "B.Cu")
		(net "SAS_HDD_PRE9")
	)
	(segment
		(start 30.2006 -243.9416)
		(end 10.897616 -243.9416)
		(width 0.1143)
		(layer "B.Cu")
		(net "SAS_HDD_PRE9")
	)
	(segment
		(start 37.999416 -251.740416)
		(end 30.2006 -243.9416)
		(width 0.1143)
		(layer "B.Cu")
		(net "SAS_HDD_PRE9")
	)
	(segment
		(start 10.897616 -243.9416)
		(end 4.541266 -237.58525)
		(width 0.1143)
		(layer "B.Cu")
		(net "SAS_HDD_PRE9")
	)
	(segment
		(start 22.294088 -186.704986)
		(end 19.907758 -189.091316)
		(width 0.1143)
		(layer "B.Cu")
		(net "SAS_HDD_PRE9")
	)
	(segment
		(start 4.541266 -203.485242)
		(end 6.05028 -201.976228)
		(width 0.1143)
		(layer "B.Cu")
		(net "SAS_HDD_PRE9")
	)
	(segment
		(start 37.999416 -256.50444)
		(end 37.999416 -251.740416)
		(width 0.1143)
		(layer "B.Cu")
		(net "SAS_HDD_PRE9")
	)
	(segment
		(start 14.974316 -193.052192)
		(end 14.974316 -193.330576)
		(width 0.1143)
		(layer "B.Cu")
		(net "SAS_HDD_PRE9")
	)
	(segment
		(start 14.974316 -193.330576)
		(end 7.748778 -200.556114)
		(width 0.1143)
		(layer "B.Cu")
		(net "SAS_HDD_PRE9")
	)
	(segment
		(start 181.728872 -192.591436)
		(end 181.288436 -192.591436)
		(width 0.1143)
		(layer "F.Cu")
		(net "I2C_C_BUF_READY")
	)
	(segment
		(start 181.229 -192.532)
		(end 180.594 -192.532)
		(width 0.1143)
		(layer "F.Cu")
		(net "I2C_C_BUF_READY")
	)
	(segment
		(start 181.288436 -192.591436)
		(end 181.229 -192.532)
		(width 0.1143)
		(layer "F.Cu")
		(net "I2C_C_BUF_READY")
	)
	(segment
		(start 181.639972 -194.219576)
		(end 181.639972 -192.680336)
		(width 0.1143)
		(layer "F.Cu")
		(net "I2C_C_BUF_READY")
	)
	(segment
		(start 181.639972 -192.680336)
		(end 181.728872 -192.591436)
		(width 0.1143)
		(layer "F.Cu")
		(net "I2C_C_BUF_READY")
	)
	(via
		(at 180.594 -192.532)
		(size 0.7112)
		(drill 0.3556)
		(layers "F.Cu" "B.Cu")
		(net "I2C_C_BUF_READY")
	)
	(segment
		(start 296.491914 -167.582342)
		(end 296.834814 -167.925242)
		(width 0.127)
		(layer "F.Cu")
		(net "TP_GPIOH2")
	)
	(segment
		(start 296.491914 -165.6588)
		(end 296.491914 -167.582342)
		(width 0.127)
		(layer "F.Cu")
		(net "TP_GPIOH2")
	)
	(segment
		(start 300.482254 -160.436052)
		(end 296.926 -163.992306)
		(width 0.127)
		(layer "F.Cu")
		(net "TP_GPIOH2")
	)
	(segment
		(start 302.641 -160.274)
		(end 302.478948 -160.436052)
		(width 0.127)
		(layer "F.Cu")
		(net "TP_GPIOH2")
	)
	(segment
		(start 296.745914 -165.404546)
		(end 296.491914 -165.6588)
		(width 0.127)
		(layer "F.Cu")
		(net "TP_GPIOH2")
	)
	(segment
		(start 302.478948 -160.436052)
		(end 300.482254 -160.436052)
		(width 0.127)
		(layer "F.Cu")
		(net "TP_GPIOH2")
	)
	(segment
		(start 296.834814 -167.925242)
		(end 296.834814 -168.240202)
		(width 0.127)
		(layer "F.Cu")
		(net "TP_GPIOH2")
	)
	(segment
		(start 296.926 -165.22446)
		(end 296.745914 -165.404546)
		(width 0.127)
		(layer "F.Cu")
		(net "TP_GPIOH2")
	)
	(segment
		(start 296.926 -163.992306)
		(end 296.926 -165.22446)
		(width 0.127)
		(layer "F.Cu")
		(net "TP_GPIOH2")
	)
	(segment
		(start 103.0605 -241.808)
		(end 103.048816 -241.819684)
		(width 0.1143)
		(layer "F.Cu")
		(net "SAS_FAULT_LED3")
	)
	(segment
		(start 103.759 -243.078)
		(end 105.029 -243.078)
		(width 0.1143)
		(layer "F.Cu")
		(net "SAS_FAULT_LED3")
	)
	(segment
		(start 103.0605 -242.3795)
		(end 103.759 -243.078)
		(width 0.1143)
		(layer "F.Cu")
		(net "SAS_FAULT_LED3")
	)
	(segment
		(start 103.0605 -241.831368)
		(end 103.0605 -242.3795)
		(width 0.1143)
		(layer "F.Cu")
		(net "SAS_FAULT_LED3")
	)
	(segment
		(start 103.048816 -241.819684)
		(end 103.0605 -241.831368)
		(width 0.1143)
		(layer "F.Cu")
		(net "SAS_FAULT_LED3")
	)
	(segment
		(start 103.0605 -239.4712)
		(end 103.0605 -241.808)
		(width 0.1143)
		(layer "F.Cu")
		(net "SAS_FAULT_LED3")
	)
	(via
		(at 106.190034 -247.638824)
		(size 0.7112)
		(drill 0.3556)
		(layers "F.Cu" "B.Cu")
		(net "SAS_FAULT_LED3")
	)
	(via
		(at 105.029 -243.078)
		(size 0.5588)
		(drill 0.3048)
		(layers "F.Cu" "B.Cu")
		(net "SAS_FAULT_LED3")
	)
	(via
		(at 103.048816 -241.819684)
		(size 0.5588)
		(drill 0.3048)
		(layers "F.Cu" "B.Cu")
		(net "SAS_FAULT_LED3")
	)
	(segment
		(start 104.80675 -243.30025)
		(end 105.029 -243.078)
		(width 0.1143)
		(layer "B.Cu")
		(net "SAS_FAULT_LED3")
	)
	(segment
		(start 104.80675 -246.25554)
		(end 104.80675 -243.30025)
		(width 0.1143)
		(layer "B.Cu")
		(net "SAS_FAULT_LED3")
	)
	(segment
		(start 108.077 -234.340908)
		(end 108.077 -238.76)
		(width 0.1143)
		(layer "B.Cu")
		(net "SAS_FAULT_LED3")
	)
	(segment
		(start 105.000552 -256.50444)
		(end 105.000552 -253.647448)
		(width 0.1143)
		(layer "B.Cu")
		(net "SAS_FAULT_LED3")
	)
	(segment
		(start 105.283 -231.546908)
		(end 108.077 -234.340908)
		(width 0.1143)
		(layer "B.Cu")
		(net "SAS_FAULT_LED3")
	)
	(segment
		(start 105.283 -230.8225)
		(end 105.283 -231.546908)
		(width 0.1143)
		(layer "B.Cu")
		(net "SAS_FAULT_LED3")
	)
	(segment
		(start 108.077 -238.76)
		(end 108.438442 -239.121442)
		(width 0.1143)
		(layer "B.Cu")
		(net "SAS_FAULT_LED3")
	)
	(segment
		(start 108.438442 -241.46002)
		(end 106.820462 -243.078)
		(width 0.1143)
		(layer "B.Cu")
		(net "SAS_FAULT_LED3")
	)
	(segment
		(start 103.4415 -228.981)
		(end 105.283 -230.8225)
		(width 0.1143)
		(layer "B.Cu")
		(net "SAS_FAULT_LED3")
	)
	(segment
		(start 106.20121 -247.83796)
		(end 106.20121 -247.65)
		(width 0.1143)
		(layer "B.Cu")
		(net "SAS_FAULT_LED3")
	)
	(segment
		(start 106.820462 -243.078)
		(end 105.029 -243.078)
		(width 0.1143)
		(layer "B.Cu")
		(net "SAS_FAULT_LED3")
	)
	(segment
		(start 108.438442 -239.121442)
		(end 108.438442 -241.46002)
		(width 0.1143)
		(layer "B.Cu")
		(net "SAS_FAULT_LED3")
	)
	(segment
		(start 106.64825 -248.285)
		(end 106.20121 -247.83796)
		(width 0.1143)
		(layer "B.Cu")
		(net "SAS_FAULT_LED3")
	)
	(segment
		(start 105.000552 -253.647448)
		(end 106.64825 -251.99975)
		(width 0.1143)
		(layer "B.Cu")
		(net "SAS_FAULT_LED3")
	)
	(segment
		(start 106.20121 -247.65)
		(end 106.190034 -247.638824)
		(width 0.1143)
		(layer "B.Cu")
		(net "SAS_FAULT_LED3")
	)
	(segment
		(start 103.048816 -240.018316)
		(end 103.048816 -241.819684)
		(width 0.1143)
		(layer "B.Cu")
		(net "SAS_FAULT_LED3")
	)
	(segment
		(start 106.190034 -247.638824)
		(end 104.80675 -246.25554)
		(width 0.1143)
		(layer "B.Cu")
		(net "SAS_FAULT_LED3")
	)
	(segment
		(start 102.87 -239.8395)
		(end 103.048816 -240.018316)
		(width 0.1143)
		(layer "B.Cu")
		(net "SAS_FAULT_LED3")
	)
	(segment
		(start 106.64825 -251.99975)
		(end 106.64825 -248.285)
		(width 0.1143)
		(layer "B.Cu")
		(net "SAS_FAULT_LED3")
	)
	(segment
		(start 110.065566 -249.838972)
		(end 110.734348 -249.17019)
		(width 0.1016)
		(layer "F.Cu")
		(net "SAS_EXP_GF_TX_DN9")
	)
	(segment
		(start 109.328712 -254.07874)
		(end 109.328712 -251.618242)
		(width 0.1016)
		(layer "F.Cu")
		(net "SAS_EXP_GF_TX_DN9")
	)
	(segment
		(start 111.462312 -247.412764)
		(end 111.462312 -230.494332)
		(width 0.1016)
		(layer "F.Cu")
		(net "SAS_EXP_GF_TX_DN9")
	)
	(segment
		(start 109.101382 -254.18034)
		(end 109.227112 -254.18034)
		(width 0.1016)
		(layer "F.Cu")
		(net "SAS_EXP_GF_TX_DN9")
	)
	(segment
		(start 103.844852 -222.174054)
		(end 103.844852 -208.2292)
		(width 0.1016)
		(layer "F.Cu")
		(net "SAS_EXP_GF_TX_DN9")
	)
	(segment
		(start 112.40897 -114.634772)
		(end 112.40897 -114.5794)
		(width 0.1016)
		(layer "F.Cu")
		(net "SAS_EXP_GF_TX_DN9")
	)
	(segment
		(start 112.55502 -193.877438)
		(end 112.55502 -114.987324)
		(width 0.1016)
		(layer "F.Cu")
		(net "SAS_EXP_GF_TX_DN9")
	)
	(segment
		(start 111.208058 -229.880668)
		(end 104.087422 -222.760032)
		(width 0.1016)
		(layer "F.Cu")
		(net "SAS_EXP_GF_TX_DN9")
	)
	(segment
		(start 106.874564 -200.914508)
		(end 111.595662 -196.19341)
		(width 0.1016)
		(layer "F.Cu")
		(net "SAS_EXP_GF_TX_DN9")
	)
	(segment
		(start 108.999782 -256.25044)
		(end 108.999782 -254.28194)
		(width 0.1016)
		(layer "F.Cu")
		(net "SAS_EXP_GF_TX_DN9")
	)
	(arc
		(start 110.734348 -249.17019)
		(mid 111.27311 -248.363876)
		(end 111.462312 -247.412764)
		(width 0.1016)
		(layer "F.Cu")
		(net "SAS_EXP_GF_TX_DN9")
	)
	(arc
		(start 112.482122 -114.811302)
		(mid 112.428004 -114.730309)
		(end 112.40897 -114.634772)
		(width 0.1016)
		(layer "F.Cu")
		(net "SAS_EXP_GF_TX_DN9")
	)
	(arc
		(start 112.55502 -114.987324)
		(mid 112.536072 -114.892066)
		(end 112.482122 -114.811302)
		(width 0.1016)
		(layer "F.Cu")
		(net "SAS_EXP_GF_TX_DN9")
	)
	(arc
		(start 109.328712 -251.618242)
		(mid 109.520158 -250.655309)
		(end 110.065566 -249.838972)
		(width 0.1016)
		(layer "F.Cu")
		(net "SAS_EXP_GF_TX_DN9")
	)
	(arc
		(start 111.595662 -196.19341)
		(mid 112.305653 -195.130833)
		(end 112.55502 -193.877438)
		(width 0.1016)
		(layer "F.Cu")
		(net "SAS_EXP_GF_TX_DN9")
	)
	(arc
		(start 111.462312 -230.494332)
		(mid 111.396231 -230.162208)
		(end 111.208058 -229.880668)
		(width 0.1016)
		(layer "F.Cu")
		(net "SAS_EXP_GF_TX_DN9")
	)
	(arc
		(start 108.999782 -254.28194)
		(mid 109.02954 -254.210098)
		(end 109.101382 -254.18034)
		(width 0.1016)
		(layer "F.Cu")
		(net "SAS_EXP_GF_TX_DN9")
	)
	(arc
		(start 104.087422 -222.760032)
		(mid 103.907866 -222.491168)
		(end 103.844852 -222.174054)
		(width 0.1016)
		(layer "F.Cu")
		(net "SAS_EXP_GF_TX_DN9")
	)
	(arc
		(start 103.844852 -208.2292)
		(mid 104.63219 -204.270514)
		(end 106.874564 -200.914508)
		(width 0.1016)
		(layer "F.Cu")
		(net "SAS_EXP_GF_TX_DN9")
	)
	(arc
		(start 109.227112 -254.18034)
		(mid 109.298954 -254.150582)
		(end 109.328712 -254.07874)
		(width 0.1016)
		(layer "F.Cu")
		(net "SAS_EXP_GF_TX_DN9")
	)
	(segment
		(start 176.991772 -205.379828)
		(end 176.5046 -205.867)
		(width 0.1143)
		(layer "F.Cu")
		(net "I2C_B_BUFF_EN")
	)
	(segment
		(start 174.426372 -205.100936)
		(end 174.493936 -205.100936)
		(width 0.1143)
		(layer "F.Cu")
		(net "I2C_B_BUFF_EN")
	)
	(segment
		(start 176.5046 -205.867)
		(end 175.26 -205.867)
		(width 0.1143)
		(layer "F.Cu")
		(net "I2C_B_BUFF_EN")
	)
	(segment
		(start 176.991772 -205.187296)
		(end 176.991772 -205.379828)
		(width 0.1143)
		(layer "F.Cu")
		(net "I2C_B_BUFF_EN")
	)
	(segment
		(start 174.493936 -205.100936)
		(end 175.26 -205.867)
		(width 0.1143)
		(layer "F.Cu")
		(net "I2C_B_BUFF_EN")
	)
	(via
		(at 175.26 -205.867)
		(size 0.7112)
		(drill 0.3556)
		(layers "F.Cu" "B.Cu")
		(net "I2C_B_BUFF_EN")
	)
	(segment
		(start 276.733 -179.578)
		(end 276.733 -179.451)
		(width 0.1143)
		(layer "F.Cu")
		(net "ROMA1")
	)
	(segment
		(start 276.733 -179.451)
		(end 277.114 -179.07)
		(width 0.1143)
		(layer "F.Cu")
		(net "ROMA1")
	)
	(segment
		(start 277.283672 -178.900328)
		(end 277.114 -179.07)
		(width 0.1143)
		(layer "F.Cu")
		(net "ROMA1")
	)
	(segment
		(start 274.6375 -181.737)
		(end 274.797012 -181.513988)
		(width 0.1143)
		(layer "F.Cu")
		(net "ROMA1")
	)
	(segment
		(start 274.797012 -181.513988)
		(end 276.733 -179.578)
		(width 0.1143)
		(layer "F.Cu")
		(net "ROMA1")
	)
	(segment
		(start 283.460444 -178.976782)
		(end 283.38399 -178.900328)
		(width 0.1143)
		(layer "F.Cu")
		(net "ROMA1")
	)
	(segment
		(start 285.634938 -178.640232)
		(end 285.298388 -178.976782)
		(width 0.1143)
		(layer "F.Cu")
		(net "ROMA1")
	)
	(segment
		(start 285.298388 -178.976782)
		(end 283.460444 -178.976782)
		(width 0.1143)
		(layer "F.Cu")
		(net "ROMA1")
	)
	(segment
		(start 283.38399 -178.900328)
		(end 277.283672 -178.900328)
		(width 0.1143)
		(layer "F.Cu")
		(net "ROMA1")
	)
	(via
		(at 277.114 -179.07)
		(size 0.7112)
		(drill 0.3556)
		(layers "F.Cu" "B.Cu")
		(net "ROMA1")
	)
	(segment
		(start 107.124754 -238.52505)
		(end 106.40695 -238.52505)
		(width 0.1143)
		(layer "F.Cu")
		(net "SAS_FAULT_LED8")
	)
	(segment
		(start 106.40695 -238.52505)
		(end 106.2355 -238.6965)
		(width 0.1143)
		(layer "F.Cu")
		(net "SAS_FAULT_LED8")
	)
	(segment
		(start 106.299 -249.301)
		(end 106.299 -247.675908)
		(width 0.1143)
		(layer "F.Cu")
		(net "SAS_FAULT_LED8")
	)
	(segment
		(start 106.2355 -238.6965)
		(end 106.2355 -239.4712)
		(width 0.1143)
		(layer "F.Cu")
		(net "SAS_FAULT_LED8")
	)
	(segment
		(start 107.696 -239.096296)
		(end 107.124754 -238.52505)
		(width 0.1143)
		(layer "F.Cu")
		(net "SAS_FAULT_LED8")
	)
	(segment
		(start 107.90555 -242.52555)
		(end 106.299 -240.919)
		(width 0.1143)
		(layer "F.Cu")
		(net "SAS_FAULT_LED8")
	)
	(segment
		(start 107.90555 -246.069358)
		(end 107.90555 -242.52555)
		(width 0.1143)
		(layer "F.Cu")
		(net "SAS_FAULT_LED8")
	)
	(segment
		(start 104.775 -250.825)
		(end 106.299 -249.301)
		(width 0.1143)
		(layer "F.Cu")
		(net "SAS_FAULT_LED8")
	)
	(segment
		(start 106.299 -247.675908)
		(end 107.90555 -246.069358)
		(width 0.1143)
		(layer "F.Cu")
		(net "SAS_FAULT_LED8")
	)
	(segment
		(start 97.536 -234.2515)
		(end 97.536 -235.331)
		(width 0.1143)
		(layer "F.Cu")
		(net "SAS_FAULT_LED8")
	)
	(segment
		(start 106.2355 -239.4712)
		(end 106.2355 -240.8555)
		(width 0.1143)
		(layer "F.Cu")
		(net "SAS_FAULT_LED8")
	)
	(segment
		(start 106.2355 -240.8555)
		(end 106.299 -240.919)
		(width 0.1143)
		(layer "F.Cu")
		(net "SAS_FAULT_LED8")
	)
	(segment
		(start 108.077 -240.157)
		(end 107.696 -239.776)
		(width 0.1143)
		(layer "F.Cu")
		(net "SAS_FAULT_LED8")
	)
	(segment
		(start 104.267 -250.825)
		(end 104.775 -250.825)
		(width 0.1143)
		(layer "F.Cu")
		(net "SAS_FAULT_LED8")
	)
	(segment
		(start 108.5215 -240.157)
		(end 108.077 -240.157)
		(width 0.1143)
		(layer "F.Cu")
		(net "SAS_FAULT_LED8")
	)
	(segment
		(start 107.696 -239.776)
		(end 107.696 -239.096296)
		(width 0.1143)
		(layer "F.Cu")
		(net "SAS_FAULT_LED8")
	)
	(via
		(at 97.536 -235.331)
		(size 0.5588)
		(drill 0.3048)
		(layers "F.Cu" "B.Cu")
		(net "SAS_FAULT_LED8")
	)
	(via
		(at 106.299 -240.919)
		(size 0.5588)
		(drill 0.3048)
		(layers "F.Cu" "B.Cu")
		(net "SAS_FAULT_LED8")
	)
	(via
		(at 102.235 -235.585)
		(size 0.7112)
		(drill 0.3556)
		(layers "F.Cu" "B.Cu")
		(net "SAS_FAULT_LED8")
	)
	(via
		(at 104.267 -250.825)
		(size 0.5588)
		(drill 0.3048)
		(layers "F.Cu" "B.Cu")
		(net "SAS_FAULT_LED8")
	)
	(segment
		(start 103.760778 -235.585)
		(end 106.529378 -238.3536)
		(width 0.1143)
		(layer "B.Cu")
		(net "SAS_FAULT_LED8")
	)
	(segment
		(start 97.79 -235.585)
		(end 102.235 -235.585)
		(width 0.1143)
		(layer "B.Cu")
		(net "SAS_FAULT_LED8")
	)
	(segment
		(start 102.235 -235.585)
		(end 103.760778 -235.585)
		(width 0.1143)
		(layer "B.Cu")
		(net "SAS_FAULT_LED8")
	)
	(segment
		(start 100.711 -250.825)
		(end 104.267 -250.825)
		(width 0.1143)
		(layer "B.Cu")
		(net "SAS_FAULT_LED8")
	)
	(segment
		(start 100.000562 -256.50444)
		(end 100.000562 -251.535438)
		(width 0.1143)
		(layer "B.Cu")
		(net "SAS_FAULT_LED8")
	)
	(segment
		(start 97.536 -235.331)
		(end 97.79 -235.585)
		(width 0.1143)
		(layer "B.Cu")
		(net "SAS_FAULT_LED8")
	)
	(segment
		(start 106.529378 -240.688622)
		(end 106.299 -240.919)
		(width 0.1143)
		(layer "B.Cu")
		(net "SAS_FAULT_LED8")
	)
	(segment
		(start 106.529378 -238.3536)
		(end 106.529378 -240.688622)
		(width 0.1143)
		(layer "B.Cu")
		(net "SAS_FAULT_LED8")
	)
	(segment
		(start 100.000562 -251.535438)
		(end 100.711 -250.825)
		(width 0.1143)
		(layer "B.Cu")
		(net "SAS_FAULT_LED8")
	)
	(segment
		(start 83.463384 -188.47054)
		(end 83.678776 -188.254894)
		(width 0.1016)
		(layer "F.Cu")
		(net "SAS_EXP_GF_TX_DP13")
	)
	(segment
		(start 92.959936 -178.973988)
		(end 93.175328 -178.758342)
		(width 0.1016)
		(layer "F.Cu")
		(net "SAS_EXP_GF_TX_DP13")
	)
	(segment
		(start 78.11008 -193.486024)
		(end 81.850484 -189.74562)
		(width 0.1016)
		(layer "F.Cu")
		(net "SAS_EXP_GF_TX_DP13")
	)
	(segment
		(start 79.674466 -252.603)
		(end 79.674466 -252.274578)
		(width 0.1016)
		(layer "F.Cu")
		(net "SAS_EXP_GF_TX_DP13")
	)
	(segment
		(start 92.237814 -179.35829)
		(end 92.45346 -179.142644)
		(width 0.1016)
		(layer "F.Cu")
		(net "SAS_EXP_GF_TX_DP13")
	)
	(segment
		(start 82.741262 -188.854842)
		(end 82.956908 -188.639196)
		(width 0.1016)
		(layer "F.Cu")
		(net "SAS_EXP_GF_TX_DP13")
	)
	(segment
		(start 105.78592 -165.125146)
		(end 105.78592 -114.980974)
		(width 0.1016)
		(layer "F.Cu")
		(net "SAS_EXP_GF_TX_DP13")
	)
	(segment
		(start 79.674212 -252.603)
		(end 79.674466 -252.603)
		(width 0.1016)
		(layer "F.Cu")
		(net "SAS_EXP_GF_TX_DP13")
	)
	(segment
		(start 105.93197 -114.628422)
		(end 105.93197 -114.5794)
		(width 0.1016)
		(layer "F.Cu")
		(net "SAS_EXP_GF_TX_DP13")
	)
	(segment
		(start 79.999332 -256.25044)
		(end 79.999332 -254.677418)
		(width 0.1016)
		(layer "F.Cu")
		(net "SAS_EXP_GF_TX_DP13")
	)
	(segment
		(start 99.082098 -172.514006)
		(end 105.301796 -166.294308)
		(width 0.1016)
		(layer "F.Cu")
		(net "SAS_EXP_GF_TX_DP13")
	)
	(segment
		(start 94.450662 -177.145442)
		(end 98.19132 -173.404784)
		(width 0.1016)
		(layer "F.Cu")
		(net "SAS_EXP_GF_TX_DP13")
	)
	(segment
		(start 91.853512 -180.080412)
		(end 92.068904 -179.864766)
		(width 0.1016)
		(layer "F.Cu")
		(net "SAS_EXP_GF_TX_DP13")
	)
	(segment
		(start 79.674212 -253.892558)
		(end 79.674212 -252.603)
		(width 0.1016)
		(layer "F.Cu")
		(net "SAS_EXP_GF_TX_DP13")
	)
	(segment
		(start 98.697796 -173.235874)
		(end 98.913442 -173.020482)
		(width 0.1016)
		(layer "F.Cu")
		(net "SAS_EXP_GF_TX_DP13")
	)
	(segment
		(start 77.5589 -248.708164)
		(end 77.5589 -194.81673)
		(width 0.1016)
		(layer "F.Cu")
		(net "SAS_EXP_GF_TX_DP13")
	)
	(segment
		(start 82.35696 -189.576964)
		(end 82.572352 -189.361318)
		(width 0.1016)
		(layer "F.Cu")
		(net "SAS_EXP_GF_TX_DP13")
	)
	(segment
		(start 79.056738 -250.783344)
		(end 77.967078 -249.693684)
		(width 0.1016)
		(layer "F.Cu")
		(net "SAS_EXP_GF_TX_DP13")
	)
	(segment
		(start 83.847686 -187.748418)
		(end 84.063078 -187.533026)
		(width 0.1016)
		(layer "F.Cu")
		(net "SAS_EXP_GF_TX_DP13")
	)
	(segment
		(start 84.95411 -186.641994)
		(end 91.347036 -180.249068)
		(width 0.1016)
		(layer "F.Cu")
		(net "SAS_EXP_GF_TX_DP13")
	)
	(segment
		(start 94.066106 -177.867564)
		(end 94.281752 -177.651918)
		(width 0.1016)
		(layer "F.Cu")
		(net "SAS_EXP_GF_TX_DP13")
	)
	(segment
		(start 93.344238 -178.251866)
		(end 93.55963 -178.036474)
		(width 0.1016)
		(layer "F.Cu")
		(net "SAS_EXP_GF_TX_DP13")
	)
	(segment
		(start 84.569554 -187.364116)
		(end 84.7852 -187.148724)
		(width 0.1016)
		(layer "F.Cu")
		(net "SAS_EXP_GF_TX_DP13")
	)
	(arc
		(start 98.913442 -173.020482)
		(mid 98.986502 -172.904157)
		(end 98.99777 -172.767244)
		(width 0.1016)
		(layer "F.Cu")
		(net "SAS_EXP_GF_TX_DP13")
	)
	(arc
		(start 84.869528 -186.895232)
		(mid 84.880892 -186.758284)
		(end 84.95411 -186.641994)
		(width 0.1016)
		(layer "F.Cu")
		(net "SAS_EXP_GF_TX_DP13")
	)
	(arc
		(start 93.55963 -178.036474)
		(mid 93.675918 -177.963251)
		(end 93.812868 -177.951892)
		(width 0.1016)
		(layer "F.Cu")
		(net "SAS_EXP_GF_TX_DP13")
	)
	(arc
		(start 82.656934 -189.10808)
		(mid 82.668164 -188.971155)
		(end 82.741262 -188.854842)
		(width 0.1016)
		(layer "F.Cu")
		(net "SAS_EXP_GF_TX_DP13")
	)
	(arc
		(start 79.674466 -252.274578)
		(mid 79.513931 -251.467513)
		(end 79.056738 -250.783344)
		(width 0.1016)
		(layer "F.Cu")
		(net "SAS_EXP_GF_TX_DP13")
	)
	(arc
		(start 77.5589 -194.81673)
		(mid 77.70215 -194.096563)
		(end 78.11008 -193.486024)
		(width 0.1016)
		(layer "F.Cu")
		(net "SAS_EXP_GF_TX_DP13")
	)
	(arc
		(start 92.068904 -179.864766)
		(mid 92.142127 -179.748478)
		(end 92.153486 -179.611528)
		(width 0.1016)
		(layer "F.Cu")
		(net "SAS_EXP_GF_TX_DP13")
	)
	(arc
		(start 105.78592 -114.980974)
		(mid 105.804868 -114.885716)
		(end 105.858818 -114.804952)
		(width 0.1016)
		(layer "F.Cu")
		(net "SAS_EXP_GF_TX_DP13")
	)
	(arc
		(start 105.858818 -114.804952)
		(mid 105.912936 -114.723959)
		(end 105.93197 -114.628422)
		(width 0.1016)
		(layer "F.Cu")
		(net "SAS_EXP_GF_TX_DP13")
	)
	(arc
		(start 105.301796 -166.294308)
		(mid 105.660135 -165.757877)
		(end 105.78592 -165.125146)
		(width 0.1016)
		(layer "F.Cu")
		(net "SAS_EXP_GF_TX_DP13")
	)
	(arc
		(start 83.763104 -188.001656)
		(mid 83.774468 -187.864708)
		(end 83.847686 -187.748418)
		(width 0.1016)
		(layer "F.Cu")
		(net "SAS_EXP_GF_TX_DP13")
	)
	(arc
		(start 98.444558 -173.320456)
		(mid 98.581506 -173.309092)
		(end 98.697796 -173.235874)
		(width 0.1016)
		(layer "F.Cu")
		(net "SAS_EXP_GF_TX_DP13")
	)
	(arc
		(start 92.153486 -179.611528)
		(mid 92.164716 -179.474603)
		(end 92.237814 -179.35829)
		(width 0.1016)
		(layer "F.Cu")
		(net "SAS_EXP_GF_TX_DP13")
	)
	(arc
		(start 83.210146 -188.554868)
		(mid 83.347071 -188.543638)
		(end 83.463384 -188.47054)
		(width 0.1016)
		(layer "F.Cu")
		(net "SAS_EXP_GF_TX_DP13")
	)
	(arc
		(start 84.7852 -187.148724)
		(mid 84.8583 -187.03228)
		(end 84.869528 -186.895232)
		(width 0.1016)
		(layer "F.Cu")
		(net "SAS_EXP_GF_TX_DP13")
	)
	(arc
		(start 93.259656 -178.505104)
		(mid 93.27102 -178.368156)
		(end 93.344238 -178.251866)
		(width 0.1016)
		(layer "F.Cu")
		(net "SAS_EXP_GF_TX_DP13")
	)
	(arc
		(start 98.99777 -172.767244)
		(mid 99.009 -172.630319)
		(end 99.082098 -172.514006)
		(width 0.1016)
		(layer "F.Cu")
		(net "SAS_EXP_GF_TX_DP13")
	)
	(arc
		(start 94.281752 -177.651918)
		(mid 94.354812 -177.535593)
		(end 94.36608 -177.39868)
		(width 0.1016)
		(layer "F.Cu")
		(net "SAS_EXP_GF_TX_DP13")
	)
	(arc
		(start 92.706698 -179.058316)
		(mid 92.843623 -179.047086)
		(end 92.959936 -178.973988)
		(width 0.1016)
		(layer "F.Cu")
		(net "SAS_EXP_GF_TX_DP13")
	)
	(arc
		(start 79.999332 -254.677418)
		(mid 79.9654 -254.506829)
		(end 79.868776 -254.362204)
		(width 0.1016)
		(layer "F.Cu")
		(net "SAS_EXP_GF_TX_DP13")
	)
	(arc
		(start 93.812868 -177.951892)
		(mid 93.949793 -177.940662)
		(end 94.066106 -177.867564)
		(width 0.1016)
		(layer "F.Cu")
		(net "SAS_EXP_GF_TX_DP13")
	)
	(arc
		(start 83.678776 -188.254894)
		(mid 83.751836 -188.138569)
		(end 83.763104 -188.001656)
		(width 0.1016)
		(layer "F.Cu")
		(net "SAS_EXP_GF_TX_DP13")
	)
	(arc
		(start 84.063078 -187.533026)
		(mid 84.179366 -187.459803)
		(end 84.316316 -187.448444)
		(width 0.1016)
		(layer "F.Cu")
		(net "SAS_EXP_GF_TX_DP13")
	)
	(arc
		(start 82.956908 -188.639196)
		(mid 83.073233 -188.566136)
		(end 83.210146 -188.554868)
		(width 0.1016)
		(layer "F.Cu")
		(net "SAS_EXP_GF_TX_DP13")
	)
	(arc
		(start 94.36608 -177.39868)
		(mid 94.377444 -177.261732)
		(end 94.450662 -177.145442)
		(width 0.1016)
		(layer "F.Cu")
		(net "SAS_EXP_GF_TX_DP13")
	)
	(arc
		(start 82.103722 -189.661292)
		(mid 82.240647 -189.650062)
		(end 82.35696 -189.576964)
		(width 0.1016)
		(layer "F.Cu")
		(net "SAS_EXP_GF_TX_DP13")
	)
	(arc
		(start 79.868776 -254.362204)
		(mid 79.7248 -254.146729)
		(end 79.674212 -253.892558)
		(width 0.1016)
		(layer "F.Cu")
		(net "SAS_EXP_GF_TX_DP13")
	)
	(arc
		(start 77.967078 -249.693684)
		(mid 77.664954 -249.241524)
		(end 77.5589 -248.708164)
		(width 0.1016)
		(layer "F.Cu")
		(net "SAS_EXP_GF_TX_DP13")
	)
	(arc
		(start 92.45346 -179.142644)
		(mid 92.569785 -179.069584)
		(end 92.706698 -179.058316)
		(width 0.1016)
		(layer "F.Cu")
		(net "SAS_EXP_GF_TX_DP13")
	)
	(arc
		(start 82.572352 -189.361318)
		(mid 82.645575 -189.24503)
		(end 82.656934 -189.10808)
		(width 0.1016)
		(layer "F.Cu")
		(net "SAS_EXP_GF_TX_DP13")
	)
	(arc
		(start 91.600274 -180.16474)
		(mid 91.737199 -180.15351)
		(end 91.853512 -180.080412)
		(width 0.1016)
		(layer "F.Cu")
		(net "SAS_EXP_GF_TX_DP13")
	)
	(arc
		(start 84.316316 -187.448444)
		(mid 84.453241 -187.437214)
		(end 84.569554 -187.364116)
		(width 0.1016)
		(layer "F.Cu")
		(net "SAS_EXP_GF_TX_DP13")
	)
	(arc
		(start 81.850484 -189.74562)
		(mid 81.966809 -189.67256)
		(end 82.103722 -189.661292)
		(width 0.1016)
		(layer "F.Cu")
		(net "SAS_EXP_GF_TX_DP13")
	)
	(arc
		(start 91.347036 -180.249068)
		(mid 91.463361 -180.176008)
		(end 91.600274 -180.16474)
		(width 0.1016)
		(layer "F.Cu")
		(net "SAS_EXP_GF_TX_DP13")
	)
	(arc
		(start 93.175328 -178.758342)
		(mid 93.248388 -178.642017)
		(end 93.259656 -178.505104)
		(width 0.1016)
		(layer "F.Cu")
		(net "SAS_EXP_GF_TX_DP13")
	)
	(arc
		(start 98.19132 -173.404784)
		(mid 98.307645 -173.331724)
		(end 98.444558 -173.320456)
		(width 0.1016)
		(layer "F.Cu")
		(net "SAS_EXP_GF_TX_DP13")
	)
	(segment
		(start 108.3183 -242.0493)
		(end 107.22102 -240.95202)
		(width 0.1143)
		(layer "F.Cu")
		(net "SAS_FAULT_LED9")
	)
	(segment
		(start 106.999532 -256.25044)
		(end 106.999532 -248.727468)
		(width 0.1143)
		(layer "F.Cu")
		(net "SAS_FAULT_LED9")
	)
	(segment
		(start 106.8705 -240.6015)
		(end 107.20705 -240.93805)
		(width 0.1143)
		(layer "F.Cu")
		(net "SAS_FAULT_LED9")
	)
	(segment
		(start 95.377 -235.331)
		(end 95.631 -235.585)
		(width 0.1143)
		(layer "F.Cu")
		(net "SAS_FAULT_LED9")
	)
	(segment
		(start 106.8705 -239.4712)
		(end 106.8705 -240.6015)
		(width 0.1143)
		(layer "F.Cu")
		(net "SAS_FAULT_LED9")
	)
	(segment
		(start 108.3183 -247.4087)
		(end 108.3183 -242.0493)
		(width 0.1143)
		(layer "F.Cu")
		(net "SAS_FAULT_LED9")
	)
	(segment
		(start 107.20705 -240.946178)
		(end 107.212892 -240.95202)
		(width 0.1143)
		(layer "F.Cu")
		(net "SAS_FAULT_LED9")
	)
	(segment
		(start 96.52 -234.2515)
		(end 95.377 -234.2515)
		(width 0.1143)
		(layer "F.Cu")
		(net "SAS_FAULT_LED9")
	)
	(segment
		(start 95.631 -235.585)
		(end 95.758 -235.585)
		(width 0.1143)
		(layer "F.Cu")
		(net "SAS_FAULT_LED9")
	)
	(segment
		(start 107.20705 -240.93805)
		(end 107.20705 -240.946178)
		(width 0.1143)
		(layer "F.Cu")
		(net "SAS_FAULT_LED9")
	)
	(segment
		(start 106.999532 -248.727468)
		(end 108.3183 -247.4087)
		(width 0.1143)
		(layer "F.Cu")
		(net "SAS_FAULT_LED9")
	)
	(segment
		(start 107.22102 -240.95202)
		(end 107.212892 -240.95202)
		(width 0.1143)
		(layer "F.Cu")
		(net "SAS_FAULT_LED9")
	)
	(segment
		(start 95.377 -234.2515)
		(end 95.377 -235.331)
		(width 0.1143)
		(layer "F.Cu")
		(net "SAS_FAULT_LED9")
	)
	(via
		(at 107.212892 -240.95202)
		(size 0.5588)
		(drill 0.3048)
		(layers "F.Cu" "B.Cu")
		(net "SAS_FAULT_LED9")
	)
	(via
		(at 95.758 -235.585)
		(size 0.5588)
		(drill 0.3048)
		(layers "F.Cu" "B.Cu")
		(net "SAS_FAULT_LED9")
	)
	(via
		(at 99.71405 -234.84205)
		(size 0.7112)
		(drill 0.3556)
		(layers "F.Cu" "B.Cu")
		(net "SAS_FAULT_LED9")
	)
	(segment
		(start 103.538782 -234.84205)
		(end 99.71405 -234.84205)
		(width 0.1143)
		(layer "B.Cu")
		(net "SAS_FAULT_LED9")
	)
	(segment
		(start 97.11055 -234.84205)
		(end 96.3676 -235.585)
		(width 0.1143)
		(layer "B.Cu")
		(net "SAS_FAULT_LED9")
	)
	(segment
		(start 99.71405 -234.84205)
		(end 97.11055 -234.84205)
		(width 0.1143)
		(layer "B.Cu")
		(net "SAS_FAULT_LED9")
	)
	(segment
		(start 106.934 -239.522)
		(end 106.934 -238.237268)
		(width 0.1143)
		(layer "B.Cu")
		(net "SAS_FAULT_LED9")
	)
	(segment
		(start 107.212892 -240.95202)
		(end 107.212892 -239.800892)
		(width 0.1143)
		(layer "B.Cu")
		(net "SAS_FAULT_LED9")
	)
	(segment
		(start 106.934 -238.237268)
		(end 103.538782 -234.84205)
		(width 0.1143)
		(layer "B.Cu")
		(net "SAS_FAULT_LED9")
	)
	(segment
		(start 107.212892 -239.800892)
		(end 106.934 -239.522)
		(width 0.1143)
		(layer "B.Cu")
		(net "SAS_FAULT_LED9")
	)
	(segment
		(start 96.3676 -235.585)
		(end 95.758 -235.585)
		(width 0.1143)
		(layer "B.Cu")
		(net "SAS_FAULT_LED9")
	)
	(segment
		(start 109.349794 -102.350062)
		(end 108.849668 -102.850188)
		(width 0.1016)
		(layer "F.Cu")
		(net "SAS_GF_EXP_RX_DN13")
	)
	(via
		(at 108.849668 -102.850188)
		(size 0.508)
		(drill 0.254)
		(layers "F.Cu" "B.Cu")
		(net "SAS_GF_EXP_RX_DN13")
	)
	(segment
		(start 108.417868 -104.8385)
		(end 108.417868 -103.810816)
		(width 0.1016)
		(layer "B.Cu")
		(net "SAS_GF_EXP_RX_DN13")
	)
	(segment
		(start 88.5571 -211.353908)
		(end 88.5571 -175.637444)
		(width 0.1016)
		(layer "B.Cu")
		(net "SAS_GF_EXP_RX_DN13")
	)
	(segment
		(start 106.912664 -113.090198)
		(end 107.037124 -112.966246)
		(width 0.1016)
		(layer "B.Cu")
		(net "SAS_GF_EXP_RX_DN13")
	)
	(segment
		(start 108.849668 -103.075486)
		(end 108.849668 -102.850188)
		(width 0.1016)
		(layer "B.Cu")
		(net "SAS_GF_EXP_RX_DN13")
	)
	(segment
		(start 105.97007 -115.3668)
		(end 105.969816 -115.3668)
		(width 0.1016)
		(layer "B.Cu")
		(net "SAS_GF_EXP_RX_DN13")
	)
	(segment
		(start 80.978502 -256.45237)
		(end 80.978502 -254.270764)
		(width 0.1016)
		(layer "B.Cu")
		(net "SAS_GF_EXP_RX_DN13")
	)
	(segment
		(start 108.243624 -105.258362)
		(end 108.243878 -105.258108)
		(width 0.1016)
		(layer "B.Cu")
		(net "SAS_GF_EXP_RX_DN13")
	)
	(segment
		(start 80.935322 -251.40285)
		(end 80.691736 -251.159264)
		(width 0.1016)
		(layer "B.Cu")
		(net "SAS_GF_EXP_RX_DN13")
	)
	(segment
		(start 107.037124 -112.966246)
		(end 107.27817 -112.7252)
		(width 0.1016)
		(layer "B.Cu")
		(net "SAS_GF_EXP_RX_DN13")
	)
	(segment
		(start 105.97007 -154.784298)
		(end 105.97007 -115.3668)
		(width 0.1016)
		(layer "B.Cu")
		(net "SAS_GF_EXP_RX_DN13")
	)
	(segment
		(start 80.772 -220.091)
		(end 87.884 -212.979)
		(width 0.1016)
		(layer "B.Cu")
		(net "SAS_GF_EXP_RX_DN13")
	)
	(segment
		(start 108.070142 -110.813088)
		(end 108.070142 -105.677716)
		(width 0.1016)
		(layer "B.Cu")
		(net "SAS_GF_EXP_RX_DN13")
	)
	(segment
		(start 81.337912 -253.402846)
		(end 81.337912 -252.3744)
		(width 0.1016)
		(layer "B.Cu")
		(net "SAS_GF_EXP_RX_DN13")
	)
	(segment
		(start 89.325958 -173.781212)
		(end 104.30637 -158.8008)
		(width 0.1016)
		(layer "B.Cu")
		(net "SAS_GF_EXP_RX_DN13")
	)
	(segment
		(start 108.5723 -103.43769)
		(end 108.77296 -103.23703)
		(width 0.1016)
		(layer "B.Cu")
		(net "SAS_GF_EXP_RX_DN13")
	)
	(segment
		(start 80.3021 -250.21794)
		(end 80.3021 -221.225872)
		(width 0.1016)
		(layer "B.Cu")
		(net "SAS_GF_EXP_RX_DN13")
	)
	(arc
		(start 80.978502 -254.270764)
		(mid 81.025165 -254.035994)
		(end 81.15808 -253.836932)
		(width 0.1016)
		(layer "B.Cu")
		(net "SAS_GF_EXP_RX_DN13")
	)
	(arc
		(start 81.15808 -253.836932)
		(mid 81.291155 -253.637772)
		(end 81.337912 -253.402846)
		(width 0.1016)
		(layer "B.Cu")
		(net "SAS_GF_EXP_RX_DN13")
	)
	(arc
		(start 80.3021 -221.225872)
		(mid 80.424173 -220.611699)
		(end 80.772 -220.091)
		(width 0.1016)
		(layer "B.Cu")
		(net "SAS_GF_EXP_RX_DN13")
	)
	(arc
		(start 105.969816 -115.3668)
		(mid 106.214814 -114.13473)
		(end 106.912664 -113.090198)
		(width 0.1016)
		(layer "B.Cu")
		(net "SAS_GF_EXP_RX_DN13")
	)
	(arc
		(start 104.30637 -158.8008)
		(mid 105.537681 -156.958013)
		(end 105.97007 -154.784298)
		(width 0.1016)
		(layer "B.Cu")
		(net "SAS_GF_EXP_RX_DN13")
	)
	(arc
		(start 81.337912 -252.3744)
		(mid 81.233229 -251.848593)
		(end 80.935322 -251.40285)
		(width 0.1016)
		(layer "B.Cu")
		(net "SAS_GF_EXP_RX_DN13")
	)
	(arc
		(start 108.847382 -103.097584)
		(mid 108.849068 -103.086591)
		(end 108.849668 -103.075486)
		(width 0.1016)
		(layer "B.Cu")
		(net "SAS_GF_EXP_RX_DN13")
	)
	(arc
		(start 108.243878 -105.258108)
		(mid 108.372597 -105.065605)
		(end 108.417868 -104.8385)
		(width 0.1016)
		(layer "B.Cu")
		(net "SAS_GF_EXP_RX_DN13")
	)
	(arc
		(start 108.070142 -105.677716)
		(mid 108.115224 -105.450805)
		(end 108.243624 -105.258362)
		(width 0.1016)
		(layer "B.Cu")
		(net "SAS_GF_EXP_RX_DN13")
	)
	(arc
		(start 107.27817 -112.7252)
		(mid 107.864353 -111.847916)
		(end 108.070142 -110.813088)
		(width 0.1016)
		(layer "B.Cu")
		(net "SAS_GF_EXP_RX_DN13")
	)
	(arc
		(start 80.691736 -251.159264)
		(mid 80.403273 -250.727365)
		(end 80.3021 -250.21794)
		(width 0.1016)
		(layer "B.Cu")
		(net "SAS_GF_EXP_RX_DN13")
	)
	(arc
		(start 88.5571 -175.637444)
		(mid 88.756908 -174.632851)
		(end 89.325958 -173.781212)
		(width 0.1016)
		(layer "B.Cu")
		(net "SAS_GF_EXP_RX_DN13")
	)
	(arc
		(start 81.000092 -256.50444)
		(mid 80.984129 -256.48055)
		(end 80.978502 -256.45237)
		(width 0.1016)
		(layer "B.Cu")
		(net "SAS_GF_EXP_RX_DN13")
	)
	(arc
		(start 108.417868 -103.810816)
		(mid 108.457943 -103.608875)
		(end 108.5723 -103.43769)
		(width 0.1016)
		(layer "B.Cu")
		(net "SAS_GF_EXP_RX_DN13")
	)
	(arc
		(start 108.77296 -103.23703)
		(mid 108.82053 -103.172838)
		(end 108.847382 -103.097584)
		(width 0.1016)
		(layer "B.Cu")
		(net "SAS_GF_EXP_RX_DN13")
	)
	(arc
		(start 87.884 -212.979)
		(mid 88.382193 -212.233401)
		(end 88.5571 -211.353908)
		(width 0.1016)
		(layer "B.Cu")
		(net "SAS_GF_EXP_RX_DN13")
	)
	(segment
		(start 79.048102 -254.75946)
		(end 79.283052 -254.192786)
		(width 0.1016)
		(layer "F.Cu")
		(net "SAS_EXP_GF_TX_DN13")
	)
	(segment
		(start 77.86751 -193.243454)
		(end 105.059226 -166.051738)
		(width 0.1016)
		(layer "F.Cu")
		(net "SAS_EXP_GF_TX_DN13")
	)
	(segment
		(start 79.331312 -252.382274)
		(end 79.331566 -252.382274)
		(width 0.1016)
		(layer "F.Cu")
		(net "SAS_EXP_GF_TX_DN13")
	)
	(segment
		(start 77.216 -248.708164)
		(end 77.216 -194.81673)
		(width 0.1016)
		(layer "F.Cu")
		(net "SAS_EXP_GF_TX_DN13")
	)
	(segment
		(start 105.29697 -114.704622)
		(end 105.29697 -114.5794)
		(width 0.1016)
		(layer "F.Cu")
		(net "SAS_EXP_GF_TX_DN13")
	)
	(segment
		(start 105.44302 -165.125146)
		(end 105.44302 -115.057428)
		(width 0.1016)
		(layer "F.Cu")
		(net "SAS_EXP_GF_TX_DN13")
	)
	(segment
		(start 79.331566 -252.382274)
		(end 79.331566 -252.274832)
		(width 0.1016)
		(layer "F.Cu")
		(net "SAS_EXP_GF_TX_DN13")
	)
	(segment
		(start 78.814168 -251.025914)
		(end 77.724508 -249.936254)
		(width 0.1016)
		(layer "F.Cu")
		(net "SAS_EXP_GF_TX_DN13")
	)
	(segment
		(start 79.331312 -253.949962)
		(end 79.331312 -252.382274)
		(width 0.1016)
		(layer "F.Cu")
		(net "SAS_EXP_GF_TX_DN13")
	)
	(segment
		(start 78.999842 -256.25044)
		(end 78.999842 -255.002538)
		(width 0.1016)
		(layer "F.Cu")
		(net "SAS_EXP_GF_TX_DN13")
	)
	(arc
		(start 105.370122 -114.881152)
		(mid 105.316004 -114.800159)
		(end 105.29697 -114.704622)
		(width 0.1016)
		(layer "F.Cu")
		(net "SAS_EXP_GF_TX_DN13")
	)
	(arc
		(start 77.724508 -249.936254)
		(mid 77.348104 -249.372786)
		(end 77.216 -248.708164)
		(width 0.1016)
		(layer "F.Cu")
		(net "SAS_EXP_GF_TX_DN13")
	)
	(arc
		(start 77.216 -194.81673)
		(mid 77.385269 -193.965288)
		(end 77.86751 -193.243454)
		(width 0.1016)
		(layer "F.Cu")
		(net "SAS_EXP_GF_TX_DN13")
	)
	(arc
		(start 78.999842 -255.002538)
		(mid 79.011999 -254.878622)
		(end 79.048102 -254.75946)
		(width 0.1016)
		(layer "F.Cu")
		(net "SAS_EXP_GF_TX_DN13")
	)
	(arc
		(start 105.44302 -115.057428)
		(mid 105.424083 -114.962045)
		(end 105.370122 -114.881152)
		(width 0.1016)
		(layer "F.Cu")
		(net "SAS_EXP_GF_TX_DN13")
	)
	(arc
		(start 105.059226 -166.051738)
		(mid 105.343285 -165.626614)
		(end 105.44302 -165.125146)
		(width 0.1016)
		(layer "F.Cu")
		(net "SAS_EXP_GF_TX_DN13")
	)
	(arc
		(start 79.331566 -252.274832)
		(mid 79.197098 -251.598906)
		(end 78.814168 -251.025914)
		(width 0.1016)
		(layer "F.Cu")
		(net "SAS_EXP_GF_TX_DN13")
	)
	(arc
		(start 79.283052 -254.192786)
		(mid 79.319132 -254.073749)
		(end 79.331312 -253.949962)
		(width 0.1016)
		(layer "F.Cu")
		(net "SAS_EXP_GF_TX_DN13")
	)
	(segment
		(start 274.6375 -173.604936)
		(end 274.862036 -173.3804)
		(width 0.1143)
		(layer "F.Cu")
		(net "ROMA15")
	)
	(segment
		(start 284.236414 -175.48479)
		(end 284.23108 -175.479456)
		(width 0.1143)
		(layer "F.Cu")
		(net "ROMA15")
	)
	(segment
		(start 284.367478 -175.48479)
		(end 284.236414 -175.48479)
		(width 0.1143)
		(layer "F.Cu")
		(net "ROMA15")
	)
	(segment
		(start 285.634938 -175.440086)
		(end 285.346902 -175.440086)
		(width 0.1143)
		(layer "F.Cu")
		(net "ROMA15")
	)
	(segment
		(start 274.6375 -173.609)
		(end 274.6375 -173.604936)
		(width 0.1143)
		(layer "F.Cu")
		(net "ROMA15")
	)
	(segment
		(start 285.346902 -175.440086)
		(end 285.010352 -175.776636)
		(width 0.1143)
		(layer "F.Cu")
		(net "ROMA15")
	)
	(segment
		(start 285.010352 -175.776636)
		(end 284.659324 -175.776636)
		(width 0.1143)
		(layer "F.Cu")
		(net "ROMA15")
	)
	(segment
		(start 284.659324 -175.776636)
		(end 284.367478 -175.48479)
		(width 0.1143)
		(layer "F.Cu")
		(net "ROMA15")
	)
	(segment
		(start 281.10942 -175.479456)
		(end 279.020016 -173.390052)
		(width 0.1143)
		(layer "F.Cu")
		(net "ROMA15")
	)
	(segment
		(start 279.020016 -173.390052)
		(end 276.031452 -173.390052)
		(width 0.1143)
		(layer "F.Cu")
		(net "ROMA15")
	)
	(segment
		(start 276.031452 -173.390052)
		(end 276.0218 -173.3804)
		(width 0.1143)
		(layer "F.Cu")
		(net "ROMA15")
	)
	(segment
		(start 284.23108 -175.479456)
		(end 281.10942 -175.479456)
		(width 0.1143)
		(layer "F.Cu")
		(net "ROMA15")
	)
	(segment
		(start 274.862036 -173.3804)
		(end 276.0218 -173.3804)
		(width 0.1143)
		(layer "F.Cu")
		(net "ROMA15")
	)
	(via
		(at 276.0218 -173.3804)
		(size 0.7112)
		(drill 0.3556)
		(layers "F.Cu" "B.Cu")
		(net "ROMA15")
	)
	(segment
		(start 16.579088 -191.039496)
		(end 16.579088 -192.660016)
		(width 0.1143)
		(layer "F.Cu")
		(net "SAS_HDD_PRE7")
	)
	(segment
		(start 28.602432 -174.800006)
		(end 28.964128 -175.161702)
		(width 0.1143)
		(layer "F.Cu")
		(net "SAS_HDD_PRE7")
	)
	(segment
		(start 28.246324 -174.800006)
		(end 28.602432 -174.800006)
		(width 0.1143)
		(layer "F.Cu")
		(net "SAS_HDD_PRE7")
	)
	(segment
		(start 19.482816 -187.40628)
		(end 16.560038 -190.329058)
		(width 0.1143)
		(layer "F.Cu")
		(net "SAS_HDD_PRE7")
	)
	(segment
		(start 16.560038 -190.329058)
		(end 16.560038 -191.020446)
		(width 0.1143)
		(layer "F.Cu")
		(net "SAS_HDD_PRE7")
	)
	(segment
		(start 25.642062 -185.328306)
		(end 23.564088 -187.40628)
		(width 0.1143)
		(layer "F.Cu")
		(net "SAS_HDD_PRE7")
	)
	(segment
		(start 25.642062 -185.328052)
		(end 25.642062 -185.328306)
		(width 0.1143)
		(layer "F.Cu")
		(net "SAS_HDD_PRE7")
	)
	(segment
		(start 28.017216 -175.739044)
		(end 28.017216 -175.029114)
		(width 0.1143)
		(layer "F.Cu")
		(net "SAS_HDD_PRE7")
	)
	(segment
		(start 28.017216 -175.029114)
		(end 28.246324 -174.800006)
		(width 0.1143)
		(layer "F.Cu")
		(net "SAS_HDD_PRE7")
	)
	(segment
		(start 23.564088 -187.40628)
		(end 19.482816 -187.40628)
		(width 0.1143)
		(layer "F.Cu")
		(net "SAS_HDD_PRE7")
	)
	(segment
		(start 16.560038 -191.020446)
		(end 16.579088 -191.039496)
		(width 0.1143)
		(layer "F.Cu")
		(net "SAS_HDD_PRE7")
	)
	(segment
		(start 28.964128 -175.161702)
		(end 28.964128 -182.005986)
		(width 0.1143)
		(layer "F.Cu")
		(net "SAS_HDD_PRE7")
	)
	(segment
		(start 28.024328 -175.746156)
		(end 28.017216 -175.739044)
		(width 0.1143)
		(layer "F.Cu")
		(net "SAS_HDD_PRE7")
	)
	(segment
		(start 28.964128 -182.005986)
		(end 25.642062 -185.328052)
		(width 0.1143)
		(layer "F.Cu")
		(net "SAS_HDD_PRE7")
	)
	(via
		(at 11.761216 -197.99808)
		(size 0.7112)
		(drill 0.3556)
		(layers "F.Cu" "B.Cu")
		(net "SAS_HDD_PRE7")
	)
	(via
		(at 16.579088 -192.660016)
		(size 0.5588)
		(drill 0.3048)
		(layers "F.Cu" "B.Cu")
		(net "SAS_HDD_PRE7")
	)
	(segment
		(start 39.999666 -256.50444)
		(end 39.999666 -252.457712)
		(width 0.1143)
		(layer "B.Cu")
		(net "SAS_HDD_PRE7")
	)
	(segment
		(start 11.202924 -243.205)
		(end 5.277866 -237.279942)
		(width 0.1143)
		(layer "B.Cu")
		(net "SAS_HDD_PRE7")
	)
	(segment
		(start 39.999666 -252.457712)
		(end 30.746954 -243.205)
		(width 0.1143)
		(layer "B.Cu")
		(net "SAS_HDD_PRE7")
	)
	(segment
		(start 5.277866 -237.279942)
		(end 5.277866 -204.48143)
		(width 0.1143)
		(layer "B.Cu")
		(net "SAS_HDD_PRE7")
	)
	(segment
		(start 15.774416 -193.464688)
		(end 16.579088 -192.660016)
		(width 0.1143)
		(layer "B.Cu")
		(net "SAS_HDD_PRE7")
	)
	(segment
		(start 11.761216 -197.99808)
		(end 15.774416 -193.98488)
		(width 0.1143)
		(layer "B.Cu")
		(net "SAS_HDD_PRE7")
	)
	(segment
		(start 30.746954 -243.205)
		(end 11.202924 -243.205)
		(width 0.1143)
		(layer "B.Cu")
		(net "SAS_HDD_PRE7")
	)
	(segment
		(start 5.277866 -204.48143)
		(end 11.761216 -197.99808)
		(width 0.1143)
		(layer "B.Cu")
		(net "SAS_HDD_PRE7")
	)
	(segment
		(start 15.774416 -193.98488)
		(end 15.774416 -193.464688)
		(width 0.1143)
		(layer "B.Cu")
		(net "SAS_HDD_PRE7")
	)
	(segment
		(start 116.350034 -103.35006)
		(end 116.350034 -103.36149)
		(width 0.1016)
		(layer "F.Cu")
		(net "SAS_GF_EXP_RX_DP6")
	)
	(segment
		(start 116.350034 -103.36149)
		(end 115.880642 -103.830882)
		(width 0.1016)
		(layer "F.Cu")
		(net "SAS_GF_EXP_RX_DP6")
	)
	(via
		(at 115.880642 -103.830882)
		(size 0.508)
		(drill 0.254)
		(layers "F.Cu" "B.Cu")
		(net "SAS_GF_EXP_RX_DP6")
	)
	(segment
		(start 116.74729 -110.06836)
		(end 116.517928 -109.838744)
		(width 0.1016)
		(layer "B.Cu")
		(net "SAS_GF_EXP_RX_DP6")
	)
	(segment
		(start 124.708412 -236.3978)
		(end 129.382012 -231.7242)
		(width 0.1016)
		(layer "B.Cu")
		(net "SAS_GF_EXP_RX_DP6")
	)
	(segment
		(start 130.435858 -170.426888)
		(end 121.26087 -161.2519)
		(width 0.1016)
		(layer "B.Cu")
		(net "SAS_GF_EXP_RX_DP6")
	)
	(segment
		(start 123.999752 -256.50444)
		(end 123.999752 -254.704342)
		(width 0.1016)
		(layer "B.Cu")
		(net "SAS_GF_EXP_RX_DP6")
	)
	(segment
		(start 123.641612 -247.358408)
		(end 123.641612 -247.053608)
		(width 0.1016)
		(layer "B.Cu")
		(net "SAS_GF_EXP_RX_DP6")
	)
	(segment
		(start 115.888262 -105.616502)
		(end 115.56873 -105.29697)
		(width 0.1016)
		(layer "B.Cu")
		(net "SAS_GF_EXP_RX_DP6")
	)
	(segment
		(start 115.568476 -104.412034)
		(end 115.642644 -104.337866)
		(width 0.1016)
		(layer "B.Cu")
		(net "SAS_GF_EXP_RX_DP6")
	)
	(segment
		(start 130.974084 -215.39073)
		(end 130.974084 -215.08593)
		(width 0.1016)
		(layer "B.Cu")
		(net "SAS_GF_EXP_RX_DP6")
	)
	(segment
		(start 123.641612 -248.923048)
		(end 123.641612 -248.618248)
		(width 0.1016)
		(layer "B.Cu")
		(net "SAS_GF_EXP_RX_DP6")
	)
	(segment
		(start 123.880372 -249.705368)
		(end 123.880372 -249.400568)
		(width 0.1016)
		(layer "B.Cu")
		(net "SAS_GF_EXP_RX_DP6")
	)
	(segment
		(start 123.880372 -246.576088)
		(end 123.880372 -246.271288)
		(width 0.1016)
		(layer "B.Cu")
		(net "SAS_GF_EXP_RX_DP6")
	)
	(segment
		(start 118.81739 -112.13846)
		(end 116.74729 -110.06836)
		(width 0.1016)
		(layer "B.Cu")
		(net "SAS_GF_EXP_RX_DP6")
	)
	(segment
		(start 123.647962 -253.709678)
		(end 123.64212 -253.591314)
		(width 0.1016)
		(layer "B.Cu")
		(net "SAS_GF_EXP_RX_DP6")
	)
	(segment
		(start 131.212844 -216.17305)
		(end 131.212844 -215.86825)
		(width 0.1016)
		(layer "B.Cu")
		(net "SAS_GF_EXP_RX_DP6")
	)
	(segment
		(start 123.641612 -245.793768)
		(end 123.641612 -238.97336)
		(width 0.1016)
		(layer "B.Cu")
		(net "SAS_GF_EXP_RX_DP6")
	)
	(segment
		(start 123.641612 -253.576074)
		(end 123.641612 -251.747528)
		(width 0.1016)
		(layer "B.Cu")
		(net "SAS_GF_EXP_RX_DP6")
	)
	(segment
		(start 115.709192 -104.258618)
		(end 115.785646 -104.194864)
		(width 0.1016)
		(layer "B.Cu")
		(net "SAS_GF_EXP_RX_DP6")
	)
	(segment
		(start 123.641612 -250.487688)
		(end 123.641612 -250.182888)
		(width 0.1016)
		(layer "B.Cu")
		(net "SAS_GF_EXP_RX_DP6")
	)
	(segment
		(start 119.64797 -157.35808)
		(end 119.64797 -114.144044)
		(width 0.1016)
		(layer "B.Cu")
		(net "SAS_GF_EXP_RX_DP6")
	)
	(segment
		(start 123.937776 -254.430784)
		(end 123.709176 -253.95174)
		(width 0.1016)
		(layer "B.Cu")
		(net "SAS_GF_EXP_RX_DP6")
	)
	(segment
		(start 116.07419 -108.76788)
		(end 116.07419 -106.065574)
		(width 0.1016)
		(layer "B.Cu")
		(net "SAS_GF_EXP_RX_DP6")
	)
	(segment
		(start 115.880642 -103.965248)
		(end 115.880642 -103.830882)
		(width 0.1016)
		(layer "B.Cu")
		(net "SAS_GF_EXP_RX_DP6")
	)
	(segment
		(start 131.212844 -213.04377)
		(end 131.212844 -212.73897)
		(width 0.1016)
		(layer "B.Cu")
		(net "SAS_GF_EXP_RX_DP6")
	)
	(segment
		(start 123.880372 -251.270008)
		(end 123.880372 -250.965208)
		(width 0.1016)
		(layer "B.Cu")
		(net "SAS_GF_EXP_RX_DP6")
	)
	(segment
		(start 115.716812 -104.263698)
		(end 115.709192 -104.258618)
		(width 0.1016)
		(layer "B.Cu")
		(net "SAS_GF_EXP_RX_DP6")
	)
	(segment
		(start 130.974084 -213.82609)
		(end 130.974084 -213.52129)
		(width 0.1016)
		(layer "B.Cu")
		(net "SAS_GF_EXP_RX_DP6")
	)
	(segment
		(start 130.974084 -212.26145)
		(end 130.974084 -171.726352)
		(width 0.1016)
		(layer "B.Cu")
		(net "SAS_GF_EXP_RX_DP6")
	)
	(segment
		(start 130.974084 -227.880164)
		(end 130.974084 -216.65057)
		(width 0.1016)
		(layer "B.Cu")
		(net "SAS_GF_EXP_RX_DP6")
	)
	(segment
		(start 123.880372 -248.140728)
		(end 123.880372 -247.835928)
		(width 0.1016)
		(layer "B.Cu")
		(net "SAS_GF_EXP_RX_DP6")
	)
	(segment
		(start 131.212844 -214.60841)
		(end 131.212844 -214.30361)
		(width 0.1016)
		(layer "B.Cu")
		(net "SAS_GF_EXP_RX_DP6")
	)
	(arc
		(start 130.974084 -213.52129)
		(mid 131.004576 -213.387297)
		(end 131.093464 -213.28253)
		(width 0.1016)
		(layer "B.Cu")
		(net "SAS_GF_EXP_RX_DP6")
	)
	(arc
		(start 115.385342 -104.854248)
		(mid 115.432929 -104.614923)
		(end 115.568476 -104.412034)
		(width 0.1016)
		(layer "B.Cu")
		(net "SAS_GF_EXP_RX_DP6")
	)
	(arc
		(start 123.880372 -246.271288)
		(mid 123.84988 -246.137295)
		(end 123.760992 -246.032528)
		(width 0.1016)
		(layer "B.Cu")
		(net "SAS_GF_EXP_RX_DP6")
	)
	(arc
		(start 123.641612 -248.618248)
		(mid 123.672104 -248.484255)
		(end 123.760992 -248.379488)
		(width 0.1016)
		(layer "B.Cu")
		(net "SAS_GF_EXP_RX_DP6")
	)
	(arc
		(start 131.093464 -216.41181)
		(mid 131.182258 -216.306996)
		(end 131.212844 -216.17305)
		(width 0.1016)
		(layer "B.Cu")
		(net "SAS_GF_EXP_RX_DP6")
	)
	(arc
		(start 131.212844 -215.86825)
		(mid 131.182352 -215.734257)
		(end 131.093464 -215.62949)
		(width 0.1016)
		(layer "B.Cu")
		(net "SAS_GF_EXP_RX_DP6")
	)
	(arc
		(start 131.093464 -214.84717)
		(mid 131.182258 -214.742356)
		(end 131.212844 -214.60841)
		(width 0.1016)
		(layer "B.Cu")
		(net "SAS_GF_EXP_RX_DP6")
	)
	(arc
		(start 123.709176 -253.95174)
		(mid 123.666578 -253.833744)
		(end 123.647962 -253.709678)
		(width 0.1016)
		(layer "B.Cu")
		(net "SAS_GF_EXP_RX_DP6")
	)
	(arc
		(start 115.785646 -104.194864)
		(mid 115.855955 -104.0895)
		(end 115.880642 -103.965248)
		(width 0.1016)
		(layer "B.Cu")
		(net "SAS_GF_EXP_RX_DP6")
	)
	(arc
		(start 121.26087 -161.2519)
		(mid 120.067169 -159.4654)
		(end 119.64797 -157.35808)
		(width 0.1016)
		(layer "B.Cu")
		(net "SAS_GF_EXP_RX_DP6")
	)
	(arc
		(start 130.974084 -216.65057)
		(mid 131.004576 -216.516577)
		(end 131.093464 -216.41181)
		(width 0.1016)
		(layer "B.Cu")
		(net "SAS_GF_EXP_RX_DP6")
	)
	(arc
		(start 123.760992 -247.597168)
		(mid 123.672104 -247.492373)
		(end 123.641612 -247.358408)
		(width 0.1016)
		(layer "B.Cu")
		(net "SAS_GF_EXP_RX_DP6")
	)
	(arc
		(start 123.641612 -247.053608)
		(mid 123.672104 -246.919615)
		(end 123.760992 -246.814848)
		(width 0.1016)
		(layer "B.Cu")
		(net "SAS_GF_EXP_RX_DP6")
	)
	(arc
		(start 123.641612 -250.182888)
		(mid 123.672104 -250.048895)
		(end 123.760992 -249.944128)
		(width 0.1016)
		(layer "B.Cu")
		(net "SAS_GF_EXP_RX_DP6")
	)
	(arc
		(start 123.64212 -253.591314)
		(mid 123.641772 -253.583697)
		(end 123.641612 -253.576074)
		(width 0.1016)
		(layer "B.Cu")
		(net "SAS_GF_EXP_RX_DP6")
	)
	(arc
		(start 123.760992 -250.726448)
		(mid 123.672104 -250.621653)
		(end 123.641612 -250.487688)
		(width 0.1016)
		(layer "B.Cu")
		(net "SAS_GF_EXP_RX_DP6")
	)
	(arc
		(start 131.093464 -214.06485)
		(mid 131.00467 -213.960036)
		(end 130.974084 -213.82609)
		(width 0.1016)
		(layer "B.Cu")
		(net "SAS_GF_EXP_RX_DP6")
	)
	(arc
		(start 123.760992 -249.161808)
		(mid 123.672104 -249.057013)
		(end 123.641612 -248.923048)
		(width 0.1016)
		(layer "B.Cu")
		(net "SAS_GF_EXP_RX_DP6")
	)
	(arc
		(start 123.760992 -246.814848)
		(mid 123.84988 -246.710053)
		(end 123.880372 -246.576088)
		(width 0.1016)
		(layer "B.Cu")
		(net "SAS_GF_EXP_RX_DP6")
	)
	(arc
		(start 130.974084 -171.726352)
		(mid 130.834213 -171.023084)
		(end 130.435858 -170.426888)
		(width 0.1016)
		(layer "B.Cu")
		(net "SAS_GF_EXP_RX_DP6")
	)
	(arc
		(start 123.641612 -238.97336)
		(mid 123.91887 -237.579489)
		(end 124.708412 -236.3978)
		(width 0.1016)
		(layer "B.Cu")
		(net "SAS_GF_EXP_RX_DP6")
	)
	(arc
		(start 123.880372 -249.400568)
		(mid 123.84988 -249.266575)
		(end 123.760992 -249.161808)
		(width 0.1016)
		(layer "B.Cu")
		(net "SAS_GF_EXP_RX_DP6")
	)
	(arc
		(start 116.517928 -109.838744)
		(mid 116.189558 -109.347442)
		(end 116.07419 -108.76788)
		(width 0.1016)
		(layer "B.Cu")
		(net "SAS_GF_EXP_RX_DP6")
	)
	(arc
		(start 115.642644 -104.337866)
		(mid 115.681356 -104.30241)
		(end 115.716812 -104.263698)
		(width 0.1016)
		(layer "B.Cu")
		(net "SAS_GF_EXP_RX_DP6")
	)
	(arc
		(start 116.07419 -106.065574)
		(mid 116.025869 -105.822556)
		(end 115.888262 -105.616502)
		(width 0.1016)
		(layer "B.Cu")
		(net "SAS_GF_EXP_RX_DP6")
	)
	(arc
		(start 123.760992 -251.508768)
		(mid 123.84988 -251.403973)
		(end 123.880372 -251.270008)
		(width 0.1016)
		(layer "B.Cu")
		(net "SAS_GF_EXP_RX_DP6")
	)
	(arc
		(start 123.999752 -254.704342)
		(mid 123.984065 -254.564096)
		(end 123.937776 -254.430784)
		(width 0.1016)
		(layer "B.Cu")
		(net "SAS_GF_EXP_RX_DP6")
	)
	(arc
		(start 119.64797 -114.144044)
		(mid 119.432163 -113.058637)
		(end 118.81739 -112.13846)
		(width 0.1016)
		(layer "B.Cu")
		(net "SAS_GF_EXP_RX_DP6")
	)
	(arc
		(start 131.093464 -213.28253)
		(mid 131.182258 -213.177716)
		(end 131.212844 -213.04377)
		(width 0.1016)
		(layer "B.Cu")
		(net "SAS_GF_EXP_RX_DP6")
	)
	(arc
		(start 123.880372 -247.835928)
		(mid 123.84988 -247.701935)
		(end 123.760992 -247.597168)
		(width 0.1016)
		(layer "B.Cu")
		(net "SAS_GF_EXP_RX_DP6")
	)
	(arc
		(start 123.760992 -246.032528)
		(mid 123.672104 -245.927733)
		(end 123.641612 -245.793768)
		(width 0.1016)
		(layer "B.Cu")
		(net "SAS_GF_EXP_RX_DP6")
	)
	(arc
		(start 129.382012 -231.7242)
		(mid 130.560368 -229.960526)
		(end 130.974084 -227.880164)
		(width 0.1016)
		(layer "B.Cu")
		(net "SAS_GF_EXP_RX_DP6")
	)
	(arc
		(start 131.212844 -214.30361)
		(mid 131.182352 -214.169617)
		(end 131.093464 -214.06485)
		(width 0.1016)
		(layer "B.Cu")
		(net "SAS_GF_EXP_RX_DP6")
	)
	(arc
		(start 130.974084 -215.08593)
		(mid 131.004576 -214.951937)
		(end 131.093464 -214.84717)
		(width 0.1016)
		(layer "B.Cu")
		(net "SAS_GF_EXP_RX_DP6")
	)
	(arc
		(start 123.760992 -248.379488)
		(mid 123.84988 -248.274693)
		(end 123.880372 -248.140728)
		(width 0.1016)
		(layer "B.Cu")
		(net "SAS_GF_EXP_RX_DP6")
	)
	(arc
		(start 123.641612 -251.747528)
		(mid 123.672104 -251.613535)
		(end 123.760992 -251.508768)
		(width 0.1016)
		(layer "B.Cu")
		(net "SAS_GF_EXP_RX_DP6")
	)
	(arc
		(start 115.56873 -105.29697)
		(mid 115.432954 -105.093862)
		(end 115.385342 -104.854248)
		(width 0.1016)
		(layer "B.Cu")
		(net "SAS_GF_EXP_RX_DP6")
	)
	(arc
		(start 131.093464 -212.50021)
		(mid 131.00467 -212.395396)
		(end 130.974084 -212.26145)
		(width 0.1016)
		(layer "B.Cu")
		(net "SAS_GF_EXP_RX_DP6")
	)
	(arc
		(start 123.760992 -249.944128)
		(mid 123.84988 -249.839333)
		(end 123.880372 -249.705368)
		(width 0.1016)
		(layer "B.Cu")
		(net "SAS_GF_EXP_RX_DP6")
	)
	(arc
		(start 131.093464 -215.62949)
		(mid 131.00467 -215.524676)
		(end 130.974084 -215.39073)
		(width 0.1016)
		(layer "B.Cu")
		(net "SAS_GF_EXP_RX_DP6")
	)
	(arc
		(start 123.880372 -250.965208)
		(mid 123.84988 -250.831215)
		(end 123.760992 -250.726448)
		(width 0.1016)
		(layer "B.Cu")
		(net "SAS_GF_EXP_RX_DP6")
	)
	(arc
		(start 131.212844 -212.73897)
		(mid 131.182352 -212.604977)
		(end 131.093464 -212.50021)
		(width 0.1016)
		(layer "B.Cu")
		(net "SAS_GF_EXP_RX_DP6")
	)
	(segment
		(start 301.5107 -161.4043)
		(end 300.053248 -161.4043)
		(width 0.127)
		(layer "F.Cu")
		(net "TP_GPIOH3")
	)
	(segment
		(start 296.834814 -165.67531)
		(end 296.834814 -167.440102)
		(width 0.127)
		(layer "F.Cu")
		(net "TP_GPIOH3")
	)
	(segment
		(start 300.053248 -161.4043)
		(end 297.307 -164.150548)
		(width 0.127)
		(layer "F.Cu")
		(net "TP_GPIOH3")
	)
	(segment
		(start 301.752 -161.163)
		(end 301.5107 -161.4043)
		(width 0.127)
		(layer "F.Cu")
		(net "TP_GPIOH3")
	)
	(segment
		(start 297.307 -164.150548)
		(end 297.307 -165.203124)
		(width 0.127)
		(layer "F.Cu")
		(net "TP_GPIOH3")
	)
	(segment
		(start 297.307 -165.203124)
		(end 296.834814 -165.67531)
		(width 0.127)
		(layer "F.Cu")
		(net "TP_GPIOH3")
	)
	(segment
		(start 122.376946 -93.349826)
		(end 122.855482 -93.828362)
		(width 0.1016)
		(layer "F.Cu")
		(net "SAS_GF_EXP_RX_DN3")
	)
	(segment
		(start 122.350022 -93.349826)
		(end 122.376946 -93.349826)
		(width 0.1016)
		(layer "F.Cu")
		(net "SAS_GF_EXP_RX_DN3")
	)
	(via
		(at 122.855482 -93.828362)
		(size 0.508)
		(drill 0.254)
		(layers "F.Cu" "B.Cu")
		(net "SAS_GF_EXP_RX_DN3")
	)
	(segment
		(start 125.386846 -154.94)
		(end 125.3871 -154.94)
		(width 0.1016)
		(layer "B.Cu")
		(net "SAS_GF_EXP_RX_DN3")
	)
	(segment
		(start 137.051288 -168.637458)
		(end 127.399288 -158.985458)
		(width 0.1016)
		(layer "B.Cu")
		(net "SAS_GF_EXP_RX_DN3")
	)
	(segment
		(start 123.23953 -94.374462)
		(end 123.23953 -94.310708)
		(width 0.1016)
		(layer "B.Cu")
		(net "SAS_GF_EXP_RX_DN3")
	)
	(segment
		(start 135.094472 -254.08636)
		(end 135.12165 -254.050546)
		(width 0.1016)
		(layer "B.Cu")
		(net "SAS_GF_EXP_RX_DN3")
	)
	(segment
		(start 127.709168 -96.017588)
		(end 127.708914 -96.017588)
		(width 0.1016)
		(layer "B.Cu")
		(net "SAS_GF_EXP_RX_DN3")
	)
	(segment
		(start 127.708914 -96.017588)
		(end 126.85014 -95.158814)
		(width 0.1016)
		(layer "B.Cu")
		(net "SAS_GF_EXP_RX_DN3")
	)
	(segment
		(start 130.7465 -97.8789)
		(end 129.4892 -96.6216)
		(width 0.1016)
		(layer "B.Cu")
		(net "SAS_GF_EXP_RX_DN3")
	)
	(segment
		(start 136.125712 -234.1245)
		(end 136.506712 -233.7435)
		(width 0.1016)
		(layer "B.Cu")
		(net "SAS_GF_EXP_RX_DN3")
	)
	(segment
		(start 126.643638 -95.072962)
		(end 124.097034 -95.072962)
		(width 0.1016)
		(layer "B.Cu")
		(net "SAS_GF_EXP_RX_DN3")
	)
	(segment
		(start 123.392438 -94.77375)
		(end 123.317762 -94.651322)
		(width 0.1016)
		(layer "B.Cu")
		(net "SAS_GF_EXP_RX_DN3")
	)
	(segment
		(start 135.177784 -253.985776)
		(end 135.199628 -253.963932)
		(width 0.1016)
		(layer "B.Cu")
		(net "SAS_GF_EXP_RX_DN3")
	)
	(segment
		(start 130.98907 -106.094022)
		(end 130.98907 -98.464624)
		(width 0.1016)
		(layer "B.Cu")
		(net "SAS_GF_EXP_RX_DN3")
	)
	(segment
		(start 137.616184 -231.06507)
		(end 137.616184 -170.001184)
		(width 0.1016)
		(layer "B.Cu")
		(net "SAS_GF_EXP_RX_DN3")
	)
	(segment
		(start 126.129288 -112.032542)
		(end 130.226054 -107.935776)
		(width 0.1016)
		(layer "B.Cu")
		(net "SAS_GF_EXP_RX_DN3")
	)
	(segment
		(start 128.853184 -96.358202)
		(end 128.532128 -96.358202)
		(width 0.1016)
		(layer "B.Cu")
		(net "SAS_GF_EXP_RX_DN3")
	)
	(segment
		(start 127.399288 -158.985458)
		(end 126.824486 -158.41091)
		(width 0.1016)
		(layer "B.Cu")
		(net "SAS_GF_EXP_RX_DN3")
	)
	(segment
		(start 135.000492 -256.50444)
		(end 135.000492 -254.313182)
		(width 0.1016)
		(layer "B.Cu")
		(net "SAS_GF_EXP_RX_DN3")
	)
	(segment
		(start 135.251952 -253.837948)
		(end 135.251952 -236.23397)
		(width 0.1016)
		(layer "B.Cu")
		(net "SAS_GF_EXP_RX_DN3")
	)
	(segment
		(start 123.155964 -94.168214)
		(end 122.883422 -93.895672)
		(width 0.1016)
		(layer "B.Cu")
		(net "SAS_GF_EXP_RX_DN3")
	)
	(segment
		(start 125.3871 -154.94)
		(end 125.3871 -113.82502)
		(width 0.1016)
		(layer "B.Cu")
		(net "SAS_GF_EXP_RX_DN3")
	)
	(arc
		(start 137.616184 -170.001184)
		(mid 137.469376 -169.263132)
		(end 137.051288 -168.637458)
		(width 0.1016)
		(layer "B.Cu")
		(net "SAS_GF_EXP_RX_DN3")
	)
	(arc
		(start 126.85014 -95.158814)
		(mid 126.75544 -95.095289)
		(end 126.643638 -95.072962)
		(width 0.1016)
		(layer "B.Cu")
		(net "SAS_GF_EXP_RX_DN3")
	)
	(arc
		(start 128.532128 -96.358202)
		(mid 128.086754 -96.269781)
		(end 127.709168 -96.017588)
		(width 0.1016)
		(layer "B.Cu")
		(net "SAS_GF_EXP_RX_DN3")
	)
	(arc
		(start 136.506712 -233.7435)
		(mid 137.327819 -232.514626)
		(end 137.616184 -231.06507)
		(width 0.1016)
		(layer "B.Cu")
		(net "SAS_GF_EXP_RX_DN3")
	)
	(arc
		(start 123.317762 -94.651322)
		(mid 123.25949 -94.518304)
		(end 123.23953 -94.374462)
		(width 0.1016)
		(layer "B.Cu")
		(net "SAS_GF_EXP_RX_DN3")
	)
	(arc
		(start 135.12165 -254.050546)
		(mid 135.148625 -254.017215)
		(end 135.177784 -253.985776)
		(width 0.1016)
		(layer "B.Cu")
		(net "SAS_GF_EXP_RX_DN3")
	)
	(arc
		(start 126.824486 -158.41091)
		(mid 125.760434 -156.818443)
		(end 125.386846 -154.94)
		(width 0.1016)
		(layer "B.Cu")
		(net "SAS_GF_EXP_RX_DN3")
	)
	(arc
		(start 122.883422 -93.895672)
		(mid 122.862733 -93.864804)
		(end 122.855482 -93.828362)
		(width 0.1016)
		(layer "B.Cu")
		(net "SAS_GF_EXP_RX_DN3")
	)
	(arc
		(start 130.226054 -107.935776)
		(mid 130.790751 -107.090787)
		(end 130.98907 -106.094022)
		(width 0.1016)
		(layer "B.Cu")
		(net "SAS_GF_EXP_RX_DN3")
	)
	(arc
		(start 135.199628 -253.963932)
		(mid 135.238304 -253.906144)
		(end 135.251952 -253.837948)
		(width 0.1016)
		(layer "B.Cu")
		(net "SAS_GF_EXP_RX_DN3")
	)
	(arc
		(start 129.4892 -96.6216)
		(mid 129.197393 -96.426621)
		(end 128.853184 -96.358202)
		(width 0.1016)
		(layer "B.Cu")
		(net "SAS_GF_EXP_RX_DN3")
	)
	(arc
		(start 123.23953 -94.310708)
		(mid 123.20686 -94.234117)
		(end 123.155964 -94.168214)
		(width 0.1016)
		(layer "B.Cu")
		(net "SAS_GF_EXP_RX_DN3")
	)
	(arc
		(start 135.000492 -254.313182)
		(mid 135.024912 -254.190416)
		(end 135.094472 -254.08636)
		(width 0.1016)
		(layer "B.Cu")
		(net "SAS_GF_EXP_RX_DN3")
	)
	(arc
		(start 135.251952 -236.23397)
		(mid 135.479022 -235.092323)
		(end 136.125712 -234.1245)
		(width 0.1016)
		(layer "B.Cu")
		(net "SAS_GF_EXP_RX_DN3")
	)
	(arc
		(start 130.98907 -98.464624)
		(mid 130.92602 -98.14765)
		(end 130.7465 -97.8789)
		(width 0.1016)
		(layer "B.Cu")
		(net "SAS_GF_EXP_RX_DN3")
	)
	(arc
		(start 125.3871 -113.82502)
		(mid 125.579889 -112.854952)
		(end 126.129288 -112.032542)
		(width 0.1016)
		(layer "B.Cu")
		(net "SAS_GF_EXP_RX_DN3")
	)
	(arc
		(start 124.097034 -95.072962)
		(mid 123.714278 -94.995095)
		(end 123.392438 -94.77375)
		(width 0.1016)
		(layer "B.Cu")
		(net "SAS_GF_EXP_RX_DN3")
	)
	(segment
		(start 22.041358 -174.473362)
		(end 20.526502 -172.958506)
		(width 0.1143)
		(layer "F.Cu")
		(net "SAS_HDD_PRE10")
	)
	(segment
		(start 17.186148 -174.208186)
		(end 17.186148 -175.746156)
		(width 0.1143)
		(layer "F.Cu")
		(net "SAS_HDD_PRE10")
	)
	(segment
		(start 21.297646 -186.820302)
		(end 21.297646 -186.798458)
		(width 0.1143)
		(layer "F.Cu")
		(net "SAS_HDD_PRE10")
	)
	(segment
		(start 21.297646 -186.798458)
		(end 21.760688 -186.335416)
		(width 0.1143)
		(layer "F.Cu")
		(net "SAS_HDD_PRE10")
	)
	(segment
		(start 22.041358 -183.95188)
		(end 22.041358 -174.473362)
		(width 0.1143)
		(layer "F.Cu")
		(net "SAS_HDD_PRE10")
	)
	(segment
		(start 18.435828 -172.958506)
		(end 17.186148 -174.208186)
		(width 0.1143)
		(layer "F.Cu")
		(net "SAS_HDD_PRE10")
	)
	(segment
		(start 21.760688 -186.335416)
		(end 21.760688 -185.409586)
		(width 0.1143)
		(layer "F.Cu")
		(net "SAS_HDD_PRE10")
	)
	(segment
		(start 21.760688 -185.409586)
		(end 21.760688 -184.23255)
		(width 0.1143)
		(layer "F.Cu")
		(net "SAS_HDD_PRE10")
	)
	(segment
		(start 20.526502 -172.958506)
		(end 18.435828 -172.958506)
		(width 0.1143)
		(layer "F.Cu")
		(net "SAS_HDD_PRE10")
	)
	(segment
		(start 21.760688 -184.23255)
		(end 22.041358 -183.95188)
		(width 0.1143)
		(layer "F.Cu")
		(net "SAS_HDD_PRE10")
	)
	(via
		(at 12.539726 -194.965828)
		(size 0.7112)
		(drill 0.3556)
		(layers "F.Cu" "B.Cu")
		(net "SAS_HDD_PRE10")
	)
	(via
		(at 21.297646 -186.820302)
		(size 0.5588)
		(drill 0.3048)
		(layers "F.Cu" "B.Cu")
		(net "SAS_HDD_PRE10")
	)
	(segment
		(start 4.172966 -203.054204)
		(end 6.68909 -200.53808)
		(width 0.1143)
		(layer "B.Cu")
		(net "SAS_HDD_PRE10")
	)
	(segment
		(start 37.269166 -253.859792)
		(end 37.269166 -251.817124)
		(width 0.1143)
		(layer "B.Cu")
		(net "SAS_HDD_PRE10")
	)
	(segment
		(start 6.68909 -200.53808)
		(end 6.967474 -200.53808)
		(width 0.1143)
		(layer "B.Cu")
		(net "SAS_HDD_PRE10")
	)
	(segment
		(start 21.297646 -186.820302)
		(end 19.395186 -188.722762)
		(width 0.1143)
		(layer "B.Cu")
		(net "SAS_HDD_PRE10")
	)
	(segment
		(start 4.172966 -237.737904)
		(end 4.172966 -203.054204)
		(width 0.1143)
		(layer "B.Cu")
		(net "SAS_HDD_PRE10")
	)
	(segment
		(start 29.800042 -244.348)
		(end 10.783062 -244.348)
		(width 0.1143)
		(layer "B.Cu")
		(net "SAS_HDD_PRE10")
	)
	(segment
		(start 10.783062 -244.348)
		(end 4.172966 -237.737904)
		(width 0.1143)
		(layer "B.Cu")
		(net "SAS_HDD_PRE10")
	)
	(segment
		(start 18.782792 -188.722762)
		(end 12.539726 -194.965828)
		(width 0.1143)
		(layer "B.Cu")
		(net "SAS_HDD_PRE10")
	)
	(segment
		(start 36.999926 -256.50444)
		(end 36.999926 -254.129032)
		(width 0.1143)
		(layer "B.Cu")
		(net "SAS_HDD_PRE10")
	)
	(segment
		(start 6.967474 -200.53808)
		(end 12.539726 -194.965828)
		(width 0.1143)
		(layer "B.Cu")
		(net "SAS_HDD_PRE10")
	)
	(segment
		(start 37.269166 -251.817124)
		(end 29.800042 -244.348)
		(width 0.1143)
		(layer "B.Cu")
		(net "SAS_HDD_PRE10")
	)
	(segment
		(start 36.999926 -254.129032)
		(end 37.269166 -253.859792)
		(width 0.1143)
		(layer "B.Cu")
		(net "SAS_HDD_PRE10")
	)
	(segment
		(start 19.395186 -188.722762)
		(end 18.782792 -188.722762)
		(width 0.1143)
		(layer "B.Cu")
		(net "SAS_HDD_PRE10")
	)
	(segment
		(start 112.349788 -102.350062)
		(end 111.849662 -102.850188)
		(width 0.1016)
		(layer "F.Cu")
		(net "SAS_GF_EXP_RX_DN10")
	)
	(via
		(at 111.849662 -102.850188)
		(size 0.508)
		(drill 0.254)
		(layers "F.Cu" "B.Cu")
		(net "SAS_GF_EXP_RX_DN10")
	)
	(segment
		(start 110.84179 -114.209068)
		(end 110.84179 -107.460796)
		(width 0.1016)
		(layer "B.Cu")
		(net "SAS_GF_EXP_RX_DN10")
	)
	(segment
		(start 111.287814 -106.609388)
		(end 111.28756 -106.609388)
		(width 0.1016)
		(layer "B.Cu")
		(net "SAS_GF_EXP_RX_DN10")
	)
	(segment
		(start 111.100362 -104.967532)
		(end 111.100362 -104.544114)
		(width 0.1016)
		(layer "B.Cu")
		(net "SAS_GF_EXP_RX_DN10")
	)
	(segment
		(start 96.3295 -248.8565)
		(end 90.424 -242.951)
		(width 0.1016)
		(layer "B.Cu")
		(net "SAS_GF_EXP_RX_DN10")
	)
	(segment
		(start 111.417608 -115.14582)
		(end 111.371634 -115.111276)
		(width 0.1016)
		(layer "B.Cu")
		(net "SAS_GF_EXP_RX_DN10")
	)
	(segment
		(start 90.68943 -219.08643)
		(end 93.73743 -216.03843)
		(width 0.1016)
		(layer "B.Cu")
		(net "SAS_GF_EXP_RX_DN10")
	)
	(segment
		(start 89.768172 -220.853)
		(end 89.767918 -220.853)
		(width 0.1016)
		(layer "B.Cu")
		(net "SAS_GF_EXP_RX_DN10")
	)
	(segment
		(start 111.498888 -115.223036)
		(end 111.448596 -115.172744)
		(width 0.1016)
		(layer "B.Cu")
		(net "SAS_GF_EXP_RX_DN10")
	)
	(segment
		(start 111.128048 -106.769154)
		(end 111.287814 -106.609388)
		(width 0.1016)
		(layer "B.Cu")
		(net "SAS_GF_EXP_RX_DN10")
	)
	(segment
		(start 111.849662 -102.928928)
		(end 111.849662 -102.850188)
		(width 0.1016)
		(layer "B.Cu")
		(net "SAS_GF_EXP_RX_DN10")
	)
	(segment
		(start 111.410242 -103.86441)
		(end 111.410242 -103.710232)
		(width 0.1016)
		(layer "B.Cu")
		(net "SAS_GF_EXP_RX_DN10")
	)
	(segment
		(start 97.339912 -253.553468)
		(end 97.339912 -252.587252)
		(width 0.1016)
		(layer "B.Cu")
		(net "SAS_GF_EXP_RX_DN10")
	)
	(segment
		(start 111.373412 -106.402886)
		(end 111.373412 -105.626916)
		(width 0.1016)
		(layer "B.Cu")
		(net "SAS_GF_EXP_RX_DN10")
	)
	(segment
		(start 96.662494 -250.952254)
		(end 96.662494 -249.555)
		(width 0.1016)
		(layer "B.Cu")
		(net "SAS_GF_EXP_RX_DN10")
	)
	(segment
		(start 90.36558 -219.410026)
		(end 90.68943 -219.08643)
		(width 0.1016)
		(layer "B.Cu")
		(net "SAS_GF_EXP_RX_DN10")
	)
	(segment
		(start 111.68507 -115.671854)
		(end 111.684816 -115.672108)
		(width 0.1016)
		(layer "B.Cu")
		(net "SAS_GF_EXP_RX_DN10")
	)
	(segment
		(start 89.768172 -241.36731)
		(end 89.768172 -220.853)
		(width 0.1016)
		(layer "B.Cu")
		(net "SAS_GF_EXP_RX_DN10")
	)
	(segment
		(start 111.59617 -103.26116)
		(end 111.794036 -103.063294)
		(width 0.1016)
		(layer "B.Cu")
		(net "SAS_GF_EXP_RX_DN10")
	)
	(segment
		(start 111.177578 -104.357678)
		(end 111.254794 -104.280462)
		(width 0.1016)
		(layer "B.Cu")
		(net "SAS_GF_EXP_RX_DN10")
	)
	(segment
		(start 111.68507 -159.09798)
		(end 111.68507 -115.671854)
		(width 0.1016)
		(layer "B.Cu")
		(net "SAS_GF_EXP_RX_DN10")
	)
	(segment
		(start 96.999552 -256.50444)
		(end 96.999552 -254.375158)
		(width 0.1016)
		(layer "B.Cu")
		(net "SAS_GF_EXP_RX_DN10")
	)
	(segment
		(start 111.31804 -115.067842)
		(end 111.178086 -114.94643)
		(width 0.1016)
		(layer "B.Cu")
		(net "SAS_GF_EXP_RX_DN10")
	)
	(segment
		(start 96.403922 -248.931176)
		(end 96.3295 -248.8565)
		(width 0.1016)
		(layer "B.Cu")
		(net "SAS_GF_EXP_RX_DN10")
	)
	(segment
		(start 95.268288 -178.453542)
		(end 109.607096 -164.114734)
		(width 0.1016)
		(layer "B.Cu")
		(net "SAS_GF_EXP_RX_DN10")
	)
	(segment
		(start 94.5261 -214.134446)
		(end 94.5261 -180.24602)
		(width 0.1016)
		(layer "B.Cu")
		(net "SAS_GF_EXP_RX_DN10")
	)
	(arc
		(start 96.999552 -254.375158)
		(mid 97.039942 -254.172104)
		(end 97.155 -254)
		(width 0.1016)
		(layer "B.Cu")
		(net "SAS_GF_EXP_RX_DN10")
	)
	(arc
		(start 111.448596 -115.172744)
		(mid 111.433572 -115.158741)
		(end 111.417608 -115.14582)
		(width 0.1016)
		(layer "B.Cu")
		(net "SAS_GF_EXP_RX_DN10")
	)
	(arc
		(start 97.339912 -252.587252)
		(mid 97.255811 -252.164537)
		(end 97.016316 -251.806202)
		(width 0.1016)
		(layer "B.Cu")
		(net "SAS_GF_EXP_RX_DN10")
	)
	(arc
		(start 109.607096 -164.114734)
		(mid 111.145047 -161.813028)
		(end 111.68507 -159.09798)
		(width 0.1016)
		(layer "B.Cu")
		(net "SAS_GF_EXP_RX_DN10")
	)
	(arc
		(start 111.261144 -104.273096)
		(mid 111.318151 -104.193569)
		(end 111.362236 -104.106218)
		(width 0.1016)
		(layer "B.Cu")
		(net "SAS_GF_EXP_RX_DN10")
	)
	(arc
		(start 110.84179 -107.460796)
		(mid 110.91613 -107.086502)
		(end 111.128048 -106.769154)
		(width 0.1016)
		(layer "B.Cu")
		(net "SAS_GF_EXP_RX_DN10")
	)
	(arc
		(start 96.662494 -249.555)
		(mid 96.595243 -249.217375)
		(end 96.403922 -248.931176)
		(width 0.1016)
		(layer "B.Cu")
		(net "SAS_GF_EXP_RX_DN10")
	)
	(arc
		(start 111.794036 -103.063294)
		(mid 111.835228 -103.001646)
		(end 111.849662 -102.928928)
		(width 0.1016)
		(layer "B.Cu")
		(net "SAS_GF_EXP_RX_DN10")
	)
	(arc
		(start 97.016316 -251.806202)
		(mid 96.754498 -251.414408)
		(end 96.662494 -250.952254)
		(width 0.1016)
		(layer "B.Cu")
		(net "SAS_GF_EXP_RX_DN10")
	)
	(arc
		(start 97.155 -254)
		(mid 97.29189 -253.795129)
		(end 97.339912 -253.553468)
		(width 0.1016)
		(layer "B.Cu")
		(net "SAS_GF_EXP_RX_DN10")
	)
	(arc
		(start 111.100362 -104.544114)
		(mid 111.120431 -104.443219)
		(end 111.177578 -104.357678)
		(width 0.1016)
		(layer "B.Cu")
		(net "SAS_GF_EXP_RX_DN10")
	)
	(arc
		(start 90.424 -242.951)
		(mid 89.938582 -242.224382)
		(end 89.768172 -241.36731)
		(width 0.1016)
		(layer "B.Cu")
		(net "SAS_GF_EXP_RX_DN10")
	)
	(arc
		(start 111.371634 -115.111276)
		(mid 111.344457 -115.090028)
		(end 111.31804 -115.067842)
		(width 0.1016)
		(layer "B.Cu")
		(net "SAS_GF_EXP_RX_DN10")
	)
	(arc
		(start 94.5261 -180.24602)
		(mid 94.718889 -179.275952)
		(end 95.268288 -178.453542)
		(width 0.1016)
		(layer "B.Cu")
		(net "SAS_GF_EXP_RX_DN10")
	)
	(arc
		(start 111.684816 -115.672108)
		(mid 111.636495 -115.42909)
		(end 111.498888 -115.223036)
		(width 0.1016)
		(layer "B.Cu")
		(net "SAS_GF_EXP_RX_DN10")
	)
	(arc
		(start 111.28756 -106.609388)
		(mid 111.351085 -106.514688)
		(end 111.373412 -106.402886)
		(width 0.1016)
		(layer "B.Cu")
		(net "SAS_GF_EXP_RX_DN10")
	)
	(arc
		(start 111.178086 -114.94643)
		(mid 110.929861 -114.614275)
		(end 110.84179 -114.209068)
		(width 0.1016)
		(layer "B.Cu")
		(net "SAS_GF_EXP_RX_DN10")
	)
	(arc
		(start 111.410242 -103.710232)
		(mid 111.458563 -103.467214)
		(end 111.59617 -103.26116)
		(width 0.1016)
		(layer "B.Cu")
		(net "SAS_GF_EXP_RX_DN10")
	)
	(arc
		(start 111.373412 -105.626916)
		(mid 111.363796 -105.579603)
		(end 111.336836 -105.53954)
		(width 0.1016)
		(layer "B.Cu")
		(net "SAS_GF_EXP_RX_DN10")
	)
	(arc
		(start 111.336836 -105.53954)
		(mid 111.161753 -105.277042)
		(end 111.100362 -104.967532)
		(width 0.1016)
		(layer "B.Cu")
		(net "SAS_GF_EXP_RX_DN10")
	)
	(arc
		(start 93.73743 -216.03843)
		(mid 94.321121 -215.164875)
		(end 94.5261 -214.134446)
		(width 0.1016)
		(layer "B.Cu")
		(net "SAS_GF_EXP_RX_DN10")
	)
	(arc
		(start 89.767918 -220.853)
		(mid 89.923252 -220.072082)
		(end 90.36558 -219.410026)
		(width 0.1016)
		(layer "B.Cu")
		(net "SAS_GF_EXP_RX_DN10")
	)
	(arc
		(start 111.362236 -104.106218)
		(mid 111.398093 -103.987666)
		(end 111.410242 -103.86441)
		(width 0.1016)
		(layer "B.Cu")
		(net "SAS_GF_EXP_RX_DN10")
	)
	(arc
		(start 111.254794 -104.280462)
		(mid 111.257983 -104.276791)
		(end 111.261144 -104.273096)
		(width 0.1016)
		(layer "B.Cu")
		(net "SAS_GF_EXP_RX_DN10")
	)
	(segment
		(start 274.8915 -172.327316)
		(end 277.965916 -172.327316)
		(width 0.1143)
		(layer "F.Cu")
		(net "ROMA22")
	)
	(segment
		(start 284.33649 -175.24349)
		(end 284.153356 -175.060356)
		(width 0.1143)
		(layer "F.Cu")
		(net "ROMA22")
	)
	(segment
		(start 284.834838 -175.440086)
		(end 284.638242 -175.24349)
		(width 0.1143)
		(layer "F.Cu")
		(net "ROMA22")
	)
	(segment
		(start 274.6375 -172.593)
		(end 274.6375 -172.581316)
		(width 0.1143)
		(layer "F.Cu")
		(net "ROMA22")
	)
	(segment
		(start 277.965916 -172.327316)
		(end 278.003 -172.3644)
		(width 0.1143)
		(layer "F.Cu")
		(net "ROMA22")
	)
	(segment
		(start 281.283156 -175.060356)
		(end 278.5872 -172.3644)
		(width 0.1143)
		(layer "F.Cu")
		(net "ROMA22")
	)
	(segment
		(start 274.6375 -172.581316)
		(end 274.8915 -172.327316)
		(width 0.1143)
		(layer "F.Cu")
		(net "ROMA22")
	)
	(segment
		(start 278.5872 -172.3644)
		(end 278.003 -172.3644)
		(width 0.1143)
		(layer "F.Cu")
		(net "ROMA22")
	)
	(segment
		(start 284.638242 -175.24349)
		(end 284.33649 -175.24349)
		(width 0.1143)
		(layer "F.Cu")
		(net "ROMA22")
	)
	(segment
		(start 284.153356 -175.060356)
		(end 281.283156 -175.060356)
		(width 0.1143)
		(layer "F.Cu")
		(net "ROMA22")
	)
	(via
		(at 278.003 -172.3644)
		(size 0.7112)
		(drill 0.3556)
		(layers "F.Cu" "B.Cu")
		(net "ROMA22")
	)
	(segment
		(start 112.349788 -103.35006)
		(end 111.849662 -103.850186)
		(width 0.1016)
		(layer "F.Cu")
		(net "SAS_GF_EXP_RX_DP10")
	)
	(via
		(at 111.849662 -103.850186)
		(size 0.508)
		(drill 0.254)
		(layers "F.Cu" "B.Cu")
		(net "SAS_GF_EXP_RX_DP10")
	)
	(segment
		(start 90.230452 -222.844614)
		(end 90.111072 -222.614744)
		(width 0.1016)
		(layer "B.Cu")
		(net "SAS_GF_EXP_RX_DP10")
	)
	(segment
		(start 90.230452 -233.878374)
		(end 90.111072 -233.648504)
		(width 0.1016)
		(layer "B.Cu")
		(net "SAS_GF_EXP_RX_DP10")
	)
	(segment
		(start 90.349832 -231.292654)
		(end 90.349832 -230.987854)
		(width 0.1016)
		(layer "B.Cu")
		(net "SAS_GF_EXP_RX_DP10")
	)
	(segment
		(start 90.60815 -219.652596)
		(end 90.932 -219.329)
		(width 0.1016)
		(layer "B.Cu")
		(net "SAS_GF_EXP_RX_DP10")
	)
	(segment
		(start 90.111072 -231.761284)
		(end 90.230452 -231.531414)
		(width 0.1016)
		(layer "B.Cu")
		(net "SAS_GF_EXP_RX_DP10")
	)
	(segment
		(start 90.230452 -229.184454)
		(end 90.111072 -228.954584)
		(width 0.1016)
		(layer "B.Cu")
		(net "SAS_GF_EXP_RX_DP10")
	)
	(segment
		(start 111.52632 -104.51465)
		(end 111.659162 -104.381808)
		(width 0.1016)
		(layer "B.Cu")
		(net "SAS_GF_EXP_RX_DP10")
	)
	(segment
		(start 95.510858 -178.696112)
		(end 109.849666 -164.357304)
		(width 0.1016)
		(layer "B.Cu")
		(net "SAS_GF_EXP_RX_DP10")
	)
	(segment
		(start 90.111072 -233.325924)
		(end 90.230452 -233.096054)
		(width 0.1016)
		(layer "B.Cu")
		(net "SAS_GF_EXP_RX_DP10")
	)
	(segment
		(start 94.339156 -246.381016)
		(end 90.66657 -242.70843)
		(width 0.1016)
		(layer "B.Cu")
		(net "SAS_GF_EXP_RX_DP10")
	)
	(segment
		(start 90.111072 -221.050104)
		(end 90.111072 -220.853)
		(width 0.1016)
		(layer "B.Cu")
		(net "SAS_GF_EXP_RX_DP10")
	)
	(segment
		(start 112.02797 -159.09798)
		(end 112.02797 -115.672108)
		(width 0.1016)
		(layer "B.Cu")
		(net "SAS_GF_EXP_RX_DP10")
	)
	(segment
		(start 111.623602 -114.871246)
		(end 111.577374 -114.836702)
		(width 0.1016)
		(layer "B.Cu")
		(net "SAS_GF_EXP_RX_DP10")
	)
	(segment
		(start 90.111072 -222.614744)
		(end 90.111072 -222.292164)
		(width 0.1016)
		(layer "B.Cu")
		(net "SAS_GF_EXP_RX_DP10")
	)
	(segment
		(start 97.682812 -253.775464)
		(end 97.682812 -252.586998)
		(width 0.1016)
		(layer "B.Cu")
		(net "SAS_GF_EXP_RX_DP10")
	)
	(segment
		(start 90.111072 -241.36731)
		(end 90.111072 -240.661952)
		(width 0.1016)
		(layer "B.Cu")
		(net "SAS_GF_EXP_RX_DP10")
	)
	(segment
		(start 96.646746 -248.688606)
		(end 95.230188 -247.272048)
		(width 0.1016)
		(layer "B.Cu")
		(net "SAS_GF_EXP_RX_DP10")
	)
	(segment
		(start 111.443262 -104.967532)
		(end 111.443262 -104.656382)
		(width 0.1016)
		(layer "B.Cu")
		(net "SAS_GF_EXP_RX_DP10")
	)
	(segment
		(start 90.111072 -234.890564)
		(end 90.230452 -234.660694)
		(width 0.1016)
		(layer "B.Cu")
		(net "SAS_GF_EXP_RX_DP10")
	)
	(segment
		(start 90.111072 -233.648504)
		(end 90.111072 -233.325924)
		(width 0.1016)
		(layer "B.Cu")
		(net "SAS_GF_EXP_RX_DP10")
	)
	(segment
		(start 90.349832 -240.184432)
		(end 90.349832 -239.879632)
		(width 0.1016)
		(layer "B.Cu")
		(net "SAS_GF_EXP_RX_DP10")
	)
	(segment
		(start 90.111072 -230.519224)
		(end 90.111072 -230.196644)
		(width 0.1016)
		(layer "B.Cu")
		(net "SAS_GF_EXP_RX_DP10")
	)
	(segment
		(start 90.111072 -232.083864)
		(end 90.111072 -231.761284)
		(width 0.1016)
		(layer "B.Cu")
		(net "SAS_GF_EXP_RX_DP10")
	)
	(segment
		(start 90.230452 -221.279974)
		(end 90.111072 -221.050104)
		(width 0.1016)
		(layer "B.Cu")
		(net "SAS_GF_EXP_RX_DP10")
	)
	(segment
		(start 90.349832 -234.421934)
		(end 90.349832 -234.117134)
		(width 0.1016)
		(layer "B.Cu")
		(net "SAS_GF_EXP_RX_DP10")
	)
	(segment
		(start 90.111072 -239.402112)
		(end 90.111072 -234.890564)
		(width 0.1016)
		(layer "B.Cu")
		(net "SAS_GF_EXP_RX_DP10")
	)
	(segment
		(start 90.349832 -229.728014)
		(end 90.349832 -229.423214)
		(width 0.1016)
		(layer "B.Cu")
		(net "SAS_GF_EXP_RX_DP10")
	)
	(segment
		(start 97.005394 -250.952)
		(end 97.005394 -249.554746)
		(width 0.1016)
		(layer "B.Cu")
		(net "SAS_GF_EXP_RX_DP10")
	)
	(segment
		(start 98.000312 -256.50444)
		(end 98.000312 -254.542036)
		(width 0.1016)
		(layer "B.Cu")
		(net "SAS_GF_EXP_RX_DP10")
	)
	(segment
		(start 90.349832 -223.388174)
		(end 90.349832 -223.083374)
		(width 0.1016)
		(layer "B.Cu")
		(net "SAS_GF_EXP_RX_DP10")
	)
	(segment
		(start 95.061278 -246.765572)
		(end 94.845632 -246.549926)
		(width 0.1016)
		(layer "B.Cu")
		(net "SAS_GF_EXP_RX_DP10")
	)
	(segment
		(start 111.849662 -103.95458)
		(end 111.849662 -103.850186)
		(width 0.1016)
		(layer "B.Cu")
		(net "SAS_GF_EXP_RX_DP10")
	)
	(segment
		(start 90.349832 -221.823534)
		(end 90.349832 -221.518734)
		(width 0.1016)
		(layer "B.Cu")
		(net "SAS_GF_EXP_RX_DP10")
	)
	(segment
		(start 90.111072 -228.954584)
		(end 90.111072 -223.856804)
		(width 0.1016)
		(layer "B.Cu")
		(net "SAS_GF_EXP_RX_DP10")
	)
	(segment
		(start 90.111072 -230.196644)
		(end 90.230452 -229.966774)
		(width 0.1016)
		(layer "B.Cu")
		(net "SAS_GF_EXP_RX_DP10")
	)
	(segment
		(start 111.741712 -114.980466)
		(end 111.691674 -114.930428)
		(width 0.1016)
		(layer "B.Cu")
		(net "SAS_GF_EXP_RX_DP10")
	)
	(segment
		(start 90.111072 -223.856804)
		(end 90.230452 -223.626934)
		(width 0.1016)
		(layer "B.Cu")
		(net "SAS_GF_EXP_RX_DP10")
	)
	(segment
		(start 111.825278 -104.09047)
		(end 111.839248 -104.036114)
		(width 0.1016)
		(layer "B.Cu")
		(net "SAS_GF_EXP_RX_DP10")
	)
	(segment
		(start 111.716312 -106.402886)
		(end 111.716312 -105.626916)
		(width 0.1016)
		(layer "B.Cu")
		(net "SAS_GF_EXP_RX_DP10")
	)
	(segment
		(start 90.230452 -232.313734)
		(end 90.111072 -232.083864)
		(width 0.1016)
		(layer "B.Cu")
		(net "SAS_GF_EXP_RX_DP10")
	)
	(segment
		(start 90.111072 -222.292164)
		(end 90.230452 -222.062294)
		(width 0.1016)
		(layer "B.Cu")
		(net "SAS_GF_EXP_RX_DP10")
	)
	(segment
		(start 94.869 -214.1347)
		(end 94.869 -180.245766)
		(width 0.1016)
		(layer "B.Cu")
		(net "SAS_GF_EXP_RX_DP10")
	)
	(segment
		(start 111.54283 -114.808762)
		(end 111.402876 -114.68735)
		(width 0.1016)
		(layer "B.Cu")
		(net "SAS_GF_EXP_RX_DP10")
	)
	(segment
		(start 111.18469 -114.209068)
		(end 111.18469 -107.460796)
		(width 0.1016)
		(layer "B.Cu")
		(net "SAS_GF_EXP_RX_DP10")
	)
	(segment
		(start 90.230452 -230.749094)
		(end 90.111072 -230.519224)
		(width 0.1016)
		(layer "B.Cu")
		(net "SAS_GF_EXP_RX_DP10")
	)
	(segment
		(start 111.484918 -104.556306)
		(end 111.52632 -104.51465)
		(width 0.1016)
		(layer "B.Cu")
		(net "SAS_GF_EXP_RX_DP10")
	)
	(segment
		(start 90.932 -219.329)
		(end 93.98 -216.281)
		(width 0.1016)
		(layer "B.Cu")
		(net "SAS_GF_EXP_RX_DP10")
	)
	(segment
		(start 111.370618 -107.011724)
		(end 111.530384 -106.851958)
		(width 0.1016)
		(layer "B.Cu")
		(net "SAS_GF_EXP_RX_DP10")
	)
	(segment
		(start 90.349832 -232.857294)
		(end 90.349832 -232.552494)
		(width 0.1016)
		(layer "B.Cu")
		(net "SAS_GF_EXP_RX_DP10")
	)
	(arc
		(start 90.230452 -240.423192)
		(mid 90.319246 -240.318378)
		(end 90.349832 -240.184432)
		(width 0.1016)
		(layer "B.Cu")
		(net "SAS_GF_EXP_RX_DP10")
	)
	(arc
		(start 97.682812 -252.586998)
		(mid 97.572643 -252.033143)
		(end 97.258886 -251.563632)
		(width 0.1016)
		(layer "B.Cu")
		(net "SAS_GF_EXP_RX_DP10")
	)
	(arc
		(start 90.349832 -223.083374)
		(mid 90.31934 -222.949381)
		(end 90.230452 -222.844614)
		(width 0.1016)
		(layer "B.Cu")
		(net "SAS_GF_EXP_RX_DP10")
	)
	(arc
		(start 90.230452 -231.531414)
		(mid 90.319246 -231.4266)
		(end 90.349832 -231.292654)
		(width 0.1016)
		(layer "B.Cu")
		(net "SAS_GF_EXP_RX_DP10")
	)
	(arc
		(start 93.98 -216.281)
		(mid 94.637922 -215.296255)
		(end 94.869 -214.1347)
		(width 0.1016)
		(layer "B.Cu")
		(net "SAS_GF_EXP_RX_DP10")
	)
	(arc
		(start 111.577374 -114.836702)
		(mid 111.559855 -114.823037)
		(end 111.54283 -114.808762)
		(width 0.1016)
		(layer "B.Cu")
		(net "SAS_GF_EXP_RX_DP10")
	)
	(arc
		(start 90.349832 -232.552494)
		(mid 90.31934 -232.418501)
		(end 90.230452 -232.313734)
		(width 0.1016)
		(layer "B.Cu")
		(net "SAS_GF_EXP_RX_DP10")
	)
	(arc
		(start 94.845632 -246.549926)
		(mid 94.729307 -246.476866)
		(end 94.592394 -246.465598)
		(width 0.1016)
		(layer "B.Cu")
		(net "SAS_GF_EXP_RX_DP10")
	)
	(arc
		(start 109.849666 -164.357304)
		(mid 111.461897 -161.944291)
		(end 112.02797 -159.09798)
		(width 0.1016)
		(layer "B.Cu")
		(net "SAS_GF_EXP_RX_DP10")
	)
	(arc
		(start 111.691674 -114.930428)
		(mid 111.658684 -114.899634)
		(end 111.623602 -114.871246)
		(width 0.1016)
		(layer "B.Cu")
		(net "SAS_GF_EXP_RX_DP10")
	)
	(arc
		(start 90.230452 -233.096054)
		(mid 90.319246 -232.99124)
		(end 90.349832 -232.857294)
		(width 0.1016)
		(layer "B.Cu")
		(net "SAS_GF_EXP_RX_DP10")
	)
	(arc
		(start 90.111072 -220.853)
		(mid 90.240202 -220.203348)
		(end 90.60815 -219.652596)
		(width 0.1016)
		(layer "B.Cu")
		(net "SAS_GF_EXP_RX_DP10")
	)
	(arc
		(start 98.000312 -254.542036)
		(mid 97.959052 -254.334608)
		(end 97.841562 -254.15875)
		(width 0.1016)
		(layer "B.Cu")
		(net "SAS_GF_EXP_RX_DP10")
	)
	(arc
		(start 95.145606 -247.01881)
		(mid 95.134376 -246.881885)
		(end 95.061278 -246.765572)
		(width 0.1016)
		(layer "B.Cu")
		(net "SAS_GF_EXP_RX_DP10")
	)
	(arc
		(start 90.230452 -223.626934)
		(mid 90.319246 -223.52212)
		(end 90.349832 -223.388174)
		(width 0.1016)
		(layer "B.Cu")
		(net "SAS_GF_EXP_RX_DP10")
	)
	(arc
		(start 90.66657 -242.70843)
		(mid 90.255432 -242.093119)
		(end 90.111072 -241.36731)
		(width 0.1016)
		(layer "B.Cu")
		(net "SAS_GF_EXP_RX_DP10")
	)
	(arc
		(start 97.005394 -249.554746)
		(mid 96.912193 -249.086011)
		(end 96.646746 -248.688606)
		(width 0.1016)
		(layer "B.Cu")
		(net "SAS_GF_EXP_RX_DP10")
	)
	(arc
		(start 90.230452 -239.640872)
		(mid 90.141658 -239.536058)
		(end 90.111072 -239.402112)
		(width 0.1016)
		(layer "B.Cu")
		(net "SAS_GF_EXP_RX_DP10")
	)
	(arc
		(start 90.230452 -234.660694)
		(mid 90.319246 -234.55588)
		(end 90.349832 -234.421934)
		(width 0.1016)
		(layer "B.Cu")
		(net "SAS_GF_EXP_RX_DP10")
	)
	(arc
		(start 90.349832 -229.423214)
		(mid 90.31934 -229.289221)
		(end 90.230452 -229.184454)
		(width 0.1016)
		(layer "B.Cu")
		(net "SAS_GF_EXP_RX_DP10")
	)
	(arc
		(start 90.349832 -239.879632)
		(mid 90.319246 -239.745714)
		(end 90.230452 -239.640872)
		(width 0.1016)
		(layer "B.Cu")
		(net "SAS_GF_EXP_RX_DP10")
	)
	(arc
		(start 112.02797 -115.672108)
		(mid 111.95363 -115.297814)
		(end 111.741712 -114.980466)
		(width 0.1016)
		(layer "B.Cu")
		(net "SAS_GF_EXP_RX_DP10")
	)
	(arc
		(start 111.57966 -105.29697)
		(mid 111.47872 -105.145808)
		(end 111.443262 -104.967532)
		(width 0.1016)
		(layer "B.Cu")
		(net "SAS_GF_EXP_RX_DP10")
	)
	(arc
		(start 95.230188 -247.272048)
		(mid 95.156965 -247.15576)
		(end 95.145606 -247.01881)
		(width 0.1016)
		(layer "B.Cu")
		(net "SAS_GF_EXP_RX_DP10")
	)
	(arc
		(start 90.349832 -230.987854)
		(mid 90.31934 -230.853861)
		(end 90.230452 -230.749094)
		(width 0.1016)
		(layer "B.Cu")
		(net "SAS_GF_EXP_RX_DP10")
	)
	(arc
		(start 90.230452 -222.062294)
		(mid 90.319246 -221.95748)
		(end 90.349832 -221.823534)
		(width 0.1016)
		(layer "B.Cu")
		(net "SAS_GF_EXP_RX_DP10")
	)
	(arc
		(start 111.443262 -104.656382)
		(mid 111.454134 -104.602197)
		(end 111.484918 -104.556306)
		(width 0.1016)
		(layer "B.Cu")
		(net "SAS_GF_EXP_RX_DP10")
	)
	(arc
		(start 111.659162 -104.381808)
		(mid 111.761796 -104.247301)
		(end 111.825278 -104.09047)
		(width 0.1016)
		(layer "B.Cu")
		(net "SAS_GF_EXP_RX_DP10")
	)
	(arc
		(start 94.592394 -246.465598)
		(mid 94.455446 -246.454234)
		(end 94.339156 -246.381016)
		(width 0.1016)
		(layer "B.Cu")
		(net "SAS_GF_EXP_RX_DP10")
	)
	(arc
		(start 94.869 -180.245766)
		(mid 95.035819 -179.407111)
		(end 95.510858 -178.696112)
		(width 0.1016)
		(layer "B.Cu")
		(net "SAS_GF_EXP_RX_DP10")
	)
	(arc
		(start 90.349832 -234.117134)
		(mid 90.31934 -233.983141)
		(end 90.230452 -233.878374)
		(width 0.1016)
		(layer "B.Cu")
		(net "SAS_GF_EXP_RX_DP10")
	)
	(arc
		(start 97.841562 -254.15875)
		(mid 97.724061 -253.982897)
		(end 97.682812 -253.775464)
		(width 0.1016)
		(layer "B.Cu")
		(net "SAS_GF_EXP_RX_DP10")
	)
	(arc
		(start 111.402876 -114.68735)
		(mid 111.241791 -114.471923)
		(end 111.18469 -114.209068)
		(width 0.1016)
		(layer "B.Cu")
		(net "SAS_GF_EXP_RX_DP10")
	)
	(arc
		(start 90.111072 -240.661952)
		(mid 90.141658 -240.528034)
		(end 90.230452 -240.423192)
		(width 0.1016)
		(layer "B.Cu")
		(net "SAS_GF_EXP_RX_DP10")
	)
	(arc
		(start 111.716312 -105.626916)
		(mid 111.680794 -105.448357)
		(end 111.57966 -105.29697)
		(width 0.1016)
		(layer "B.Cu")
		(net "SAS_GF_EXP_RX_DP10")
	)
	(arc
		(start 111.839248 -104.036114)
		(mid 111.847033 -103.995676)
		(end 111.849662 -103.95458)
		(width 0.1016)
		(layer "B.Cu")
		(net "SAS_GF_EXP_RX_DP10")
	)
	(arc
		(start 111.18469 -107.460796)
		(mid 111.233011 -107.217778)
		(end 111.370618 -107.011724)
		(width 0.1016)
		(layer "B.Cu")
		(net "SAS_GF_EXP_RX_DP10")
	)
	(arc
		(start 90.230452 -229.966774)
		(mid 90.319246 -229.86196)
		(end 90.349832 -229.728014)
		(width 0.1016)
		(layer "B.Cu")
		(net "SAS_GF_EXP_RX_DP10")
	)
	(arc
		(start 90.349832 -221.518734)
		(mid 90.31934 -221.384741)
		(end 90.230452 -221.279974)
		(width 0.1016)
		(layer "B.Cu")
		(net "SAS_GF_EXP_RX_DP10")
	)
	(arc
		(start 97.258886 -251.563632)
		(mid 97.071299 -251.283028)
		(end 97.005394 -250.952)
		(width 0.1016)
		(layer "B.Cu")
		(net "SAS_GF_EXP_RX_DP10")
	)
	(arc
		(start 111.530384 -106.851958)
		(mid 111.667999 -106.645908)
		(end 111.716312 -106.402886)
		(width 0.1016)
		(layer "B.Cu")
		(net "SAS_GF_EXP_RX_DP10")
	)
	(segment
		(start 297.220132 -170.225466)
		(end 297.220132 -170.235118)
		(width 0.1143)
		(layer "F.Cu")
		(net "TP_GPIOH4")
	)
	(segment
		(start 297.220132 -170.235118)
		(end 297.225974 -170.24096)
		(width 0.1143)
		(layer "F.Cu")
		(net "TP_GPIOH4")
	)
	(segment
		(start 296.834814 -169.840148)
		(end 297.220132 -170.225466)
		(width 0.1143)
		(layer "F.Cu")
		(net "TP_GPIOH4")
	)
	(via
		(at 297.225974 -170.24096)
		(size 0.508)
		(drill 0.254)
		(layers "F.Cu" "B.Cu")
		(net "TP_GPIOH4")
	)
	(segment
		(start 296.48912 -170.7007)
		(end 296.766234 -170.7007)
		(width 0.1143)
		(layer "B.Cu")
		(net "TP_GPIOH4")
	)
	(segment
		(start 296.766234 -170.7007)
		(end 297.225974 -170.24096)
		(width 0.1143)
		(layer "B.Cu")
		(net "TP_GPIOH4")
	)
	(segment
		(start 106.000042 -253.320042)
		(end 103.251 -250.571)
		(width 0.1143)
		(layer "F.Cu")
		(net "SAS_FAULT_LED10")
	)
	(segment
		(start 85.852 -241.9985)
		(end 86.07298 -241.9985)
		(width 0.1143)
		(layer "F.Cu")
		(net "SAS_FAULT_LED10")
	)
	(segment
		(start 91.186 -235.204)
		(end 94.2594 -235.204)
		(width 0.1143)
		(layer "F.Cu")
		(net "SAS_FAULT_LED10")
	)
	(segment
		(start 95.123 -241.427)
		(end 95.123 -236.0676)
		(width 0.1143)
		(layer "F.Cu")
		(net "SAS_FAULT_LED10")
	)
	(segment
		(start 98.171 -244.475)
		(end 95.123 -241.427)
		(width 0.1143)
		(layer "F.Cu")
		(net "SAS_FAULT_LED10")
	)
	(segment
		(start 86.07298 -241.9985)
		(end 87.9475 -240.35131)
		(width 0.1143)
		(layer "F.Cu")
		(net "SAS_FAULT_LED10")
	)
	(segment
		(start 106.000042 -256.25044)
		(end 106.000042 -253.320042)
		(width 0.1143)
		(layer "F.Cu")
		(net "SAS_FAULT_LED10")
	)
	(segment
		(start 95.123 -236.0676)
		(end 94.2594 -235.204)
		(width 0.1143)
		(layer "F.Cu")
		(net "SAS_FAULT_LED10")
	)
	(segment
		(start 87.9475 -240.35131)
		(end 87.9475 -239.3442)
		(width 0.1143)
		(layer "F.Cu")
		(net "SAS_FAULT_LED10")
	)
	(segment
		(start 87.9475 -239.3442)
		(end 87.9475 -238.4425)
		(width 0.1143)
		(layer "F.Cu")
		(net "SAS_FAULT_LED10")
	)
	(segment
		(start 99.441 -244.475)
		(end 98.171 -244.475)
		(width 0.1143)
		(layer "F.Cu")
		(net "SAS_FAULT_LED10")
	)
	(segment
		(start 103.251 -248.285)
		(end 99.441 -244.475)
		(width 0.1143)
		(layer "F.Cu")
		(net "SAS_FAULT_LED10")
	)
	(segment
		(start 103.251 -250.571)
		(end 103.251 -248.285)
		(width 0.1143)
		(layer "F.Cu")
		(net "SAS_FAULT_LED10")
	)
	(segment
		(start 87.9475 -238.4425)
		(end 91.186 -235.204)
		(width 0.1143)
		(layer "F.Cu")
		(net "SAS_FAULT_LED10")
	)
	(via
		(at 97.3455 -231.3305)
		(size 0.7112)
		(drill 0.3556)
		(layers "F.Cu" "B.Cu")
		(net "SAS_FAULT_LED10")
	)
	(via
		(at 94.2594 -235.204)
		(size 0.5588)
		(drill 0.3048)
		(layers "F.Cu" "B.Cu")
		(net "SAS_FAULT_LED10")
	)
	(segment
		(start 97.3455 -231.3305)
		(end 97.3455 -232.1179)
		(width 0.1143)
		(layer "B.Cu")
		(net "SAS_FAULT_LED10")
	)
	(segment
		(start 97.3455 -232.1179)
		(end 94.2594 -235.204)
		(width 0.1143)
		(layer "B.Cu")
		(net "SAS_FAULT_LED10")
	)
	(segment
		(start 97.3455 -230.124)
		(end 97.3455 -231.3305)
		(width 0.1143)
		(layer "B.Cu")
		(net "SAS_FAULT_LED10")
	)
	(segment
		(start 26.378662 -185.63336)
		(end 29.700728 -182.311294)
		(width 0.1143)
		(layer "F.Cu")
		(net "SAS_HDD_PRE5")
	)
	(segment
		(start 17.578578 -192.47739)
		(end 17.849088 -192.20688)
		(width 0.1143)
		(layer "F.Cu")
		(net "SAS_HDD_PRE5")
	)
	(segment
		(start 26.378662 -185.633614)
		(end 26.378662 -185.63336)
		(width 0.1143)
		(layer "F.Cu")
		(net "SAS_HDD_PRE5")
	)
	(segment
		(start 17.849088 -192.20688)
		(end 17.849088 -191.031876)
		(width 0.1143)
		(layer "F.Cu")
		(net "SAS_HDD_PRE5")
	)
	(segment
		(start 27.941016 -174.063406)
		(end 27.224228 -174.780194)
		(width 0.1143)
		(layer "F.Cu")
		(net "SAS_HDD_PRE5")
	)
	(segment
		(start 29.700728 -182.311294)
		(end 29.700728 -174.856394)
		(width 0.1143)
		(layer "F.Cu")
		(net "SAS_HDD_PRE5")
	)
	(segment
		(start 17.860518 -190.298578)
		(end 20.016216 -188.14288)
		(width 0.1143)
		(layer "F.Cu")
		(net "SAS_HDD_PRE5")
	)
	(segment
		(start 29.700728 -174.856394)
		(end 28.90774 -174.063406)
		(width 0.1143)
		(layer "F.Cu")
		(net "SAS_HDD_PRE5")
	)
	(segment
		(start 17.578578 -193.12763)
		(end 17.578578 -192.47739)
		(width 0.1143)
		(layer "F.Cu")
		(net "SAS_HDD_PRE5")
	)
	(segment
		(start 17.849088 -191.031876)
		(end 17.860518 -191.020446)
		(width 0.1143)
		(layer "F.Cu")
		(net "SAS_HDD_PRE5")
	)
	(segment
		(start 20.016216 -188.14288)
		(end 23.869396 -188.14288)
		(width 0.1143)
		(layer "F.Cu")
		(net "SAS_HDD_PRE5")
	)
	(segment
		(start 27.224228 -174.780194)
		(end 27.224228 -175.746156)
		(width 0.1143)
		(layer "F.Cu")
		(net "SAS_HDD_PRE5")
	)
	(segment
		(start 23.869396 -188.14288)
		(end 26.378662 -185.633614)
		(width 0.1143)
		(layer "F.Cu")
		(net "SAS_HDD_PRE5")
	)
	(segment
		(start 17.50314 -193.203068)
		(end 17.578578 -193.12763)
		(width 0.1143)
		(layer "F.Cu")
		(net "SAS_HDD_PRE5")
	)
	(segment
		(start 28.90774 -174.063406)
		(end 27.941016 -174.063406)
		(width 0.1143)
		(layer "F.Cu")
		(net "SAS_HDD_PRE5")
	)
	(segment
		(start 17.860518 -191.020446)
		(end 17.860518 -190.298578)
		(width 0.1143)
		(layer "F.Cu")
		(net "SAS_HDD_PRE5")
	)
	(via
		(at 9.079738 -202.33767)
		(size 0.7112)
		(drill 0.3556)
		(layers "F.Cu" "B.Cu")
		(net "SAS_HDD_PRE5")
	)
	(via
		(at 17.50314 -193.203068)
		(size 0.5588)
		(drill 0.3048)
		(layers "F.Cu" "B.Cu")
		(net "SAS_HDD_PRE5")
	)
	(segment
		(start 9.079738 -202.33767)
		(end 16.942816 -194.474592)
		(width 0.1143)
		(layer "B.Cu")
		(net "SAS_HDD_PRE5")
	)
	(segment
		(start 41.999916 -252.362716)
		(end 31.9405 -242.3033)
		(width 0.1143)
		(layer "B.Cu")
		(net "SAS_HDD_PRE5")
	)
	(segment
		(start 6.014466 -205.402942)
		(end 9.079738 -202.33767)
		(width 0.1143)
		(layer "B.Cu")
		(net "SAS_HDD_PRE5")
	)
	(segment
		(start 16.942816 -193.763392)
		(end 17.50314 -193.203068)
		(width 0.1143)
		(layer "B.Cu")
		(net "SAS_HDD_PRE5")
	)
	(segment
		(start 41.999916 -256.50444)
		(end 41.999916 -252.362716)
		(width 0.1143)
		(layer "B.Cu")
		(net "SAS_HDD_PRE5")
	)
	(segment
		(start 11.343132 -242.3033)
		(end 6.014466 -236.974634)
		(width 0.1143)
		(layer "B.Cu")
		(net "SAS_HDD_PRE5")
	)
	(segment
		(start 31.9405 -242.3033)
		(end 11.343132 -242.3033)
		(width 0.1143)
		(layer "B.Cu")
		(net "SAS_HDD_PRE5")
	)
	(segment
		(start 6.014466 -236.974634)
		(end 6.014466 -205.402942)
		(width 0.1143)
		(layer "B.Cu")
		(net "SAS_HDD_PRE5")
	)
	(segment
		(start 16.942816 -194.474592)
		(end 16.942816 -193.763392)
		(width 0.1143)
		(layer "B.Cu")
		(net "SAS_HDD_PRE5")
	)
	(segment
		(start 118.35003 -102.350062)
		(end 118.850156 -102.850188)
		(width 0.1016)
		(layer "F.Cu")
		(net "SAS_GF_EXP_RX_DN4")
	)
	(via
		(at 118.850156 -102.850188)
		(size 0.508)
		(drill 0.254)
		(layers "F.Cu" "B.Cu")
		(net "SAS_GF_EXP_RX_DN4")
	)
	(segment
		(start 119.398542 -108.722922)
		(end 119.309388 -108.634276)
		(width 0.1016)
		(layer "B.Cu")
		(net "SAS_GF_EXP_RX_DN4")
	)
	(segment
		(start 118.788688 -107.376468)
		(end 118.38686 -106.974894)
		(width 0.1016)
		(layer "B.Cu")
		(net "SAS_GF_EXP_RX_DN4")
	)
	(segment
		(start 118.387114 -104.03332)
		(end 118.387114 -103.76662)
		(width 0.1016)
		(layer "B.Cu")
		(net "SAS_GF_EXP_RX_DN4")
	)
	(segment
		(start 130.999992 -256.50444)
		(end 130.999992 -254.51689)
		(width 0.1016)
		(layer "B.Cu")
		(net "SAS_GF_EXP_RX_DN4")
	)
	(segment
		(start 122.083068 -111.407448)
		(end 119.398542 -108.722922)
		(width 0.1016)
		(layer "B.Cu")
		(net "SAS_GF_EXP_RX_DN4")
	)
	(segment
		(start 133.293358 -232.534714)
		(end 133.609842 -232.21823)
		(width 0.1016)
		(layer "B.Cu")
		(net "SAS_GF_EXP_RX_DN4")
	)
	(segment
		(start 122.852942 -154.598624)
		(end 122.852942 -113.265966)
		(width 0.1016)
		(layer "B.Cu")
		(net "SAS_GF_EXP_RX_DN4")
	)
	(segment
		(start 118.573042 -103.317548)
		(end 118.715536 -103.175054)
		(width 0.1016)
		(layer "B.Cu")
		(net "SAS_GF_EXP_RX_DN4")
	)
	(segment
		(start 118.100856 -106.283252)
		(end 118.100856 -104.814878)
		(width 0.1016)
		(layer "B.Cu")
		(net "SAS_GF_EXP_RX_DN4")
	)
	(segment
		(start 135.457184 -227.758244)
		(end 135.457184 -170.382184)
		(width 0.1016)
		(layer "B.Cu")
		(net "SAS_GF_EXP_RX_DN4")
	)
	(segment
		(start 134.892288 -169.018458)
		(end 124.5362 -158.66237)
		(width 0.1016)
		(layer "B.Cu")
		(net "SAS_GF_EXP_RX_DN4")
	)
	(segment
		(start 131.325112 -253.73203)
		(end 131.325112 -237.2868)
		(width 0.1016)
		(layer "B.Cu")
		(net "SAS_GF_EXP_RX_DN4")
	)
	(arc
		(start 133.609842 -232.21823)
		(mid 133.733973 -232.090418)
		(end 133.854444 -231.95915)
		(width 0.1016)
		(layer "B.Cu")
		(net "SAS_GF_EXP_RX_DN4")
	)
	(arc
		(start 131.162552 -254.12446)
		(mid 131.282857 -253.944412)
		(end 131.325112 -253.73203)
		(width 0.1016)
		(layer "B.Cu")
		(net "SAS_GF_EXP_RX_DN4")
	)
	(arc
		(start 130.999992 -254.51689)
		(mid 131.042238 -254.304505)
		(end 131.162552 -254.12446)
		(width 0.1016)
		(layer "B.Cu")
		(net "SAS_GF_EXP_RX_DN4")
	)
	(arc
		(start 118.304818 -104.216708)
		(mid 118.365625 -104.133831)
		(end 118.387114 -104.03332)
		(width 0.1016)
		(layer "B.Cu")
		(net "SAS_GF_EXP_RX_DN4")
	)
	(arc
		(start 118.38686 -106.974894)
		(mid 118.175155 -106.657493)
		(end 118.100856 -106.283252)
		(width 0.1016)
		(layer "B.Cu")
		(net "SAS_GF_EXP_RX_DN4")
	)
	(arc
		(start 124.5362 -158.66237)
		(mid 123.290377 -156.797908)
		(end 122.852942 -154.598624)
		(width 0.1016)
		(layer "B.Cu")
		(net "SAS_GF_EXP_RX_DN4")
	)
	(arc
		(start 133.854444 -231.95915)
		(mid 135.042877 -230.006366)
		(end 135.457184 -227.758244)
		(width 0.1016)
		(layer "B.Cu")
		(net "SAS_GF_EXP_RX_DN4")
	)
	(arc
		(start 118.715536 -103.175054)
		(mid 118.815182 -103.026018)
		(end 118.850156 -102.850188)
		(width 0.1016)
		(layer "B.Cu")
		(net "SAS_GF_EXP_RX_DN4")
	)
	(arc
		(start 118.100856 -104.814878)
		(mid 118.153207 -104.49887)
		(end 118.304818 -104.216708)
		(width 0.1016)
		(layer "B.Cu")
		(net "SAS_GF_EXP_RX_DN4")
	)
	(arc
		(start 119.017288 -107.928664)
		(mid 118.957883 -107.629838)
		(end 118.788688 -107.376468)
		(width 0.1016)
		(layer "B.Cu")
		(net "SAS_GF_EXP_RX_DN4")
	)
	(arc
		(start 122.852942 -113.265966)
		(mid 122.652868 -112.260124)
		(end 122.083068 -111.407448)
		(width 0.1016)
		(layer "B.Cu")
		(net "SAS_GF_EXP_RX_DN4")
	)
	(arc
		(start 131.325112 -237.2868)
		(mid 131.836584 -234.714987)
		(end 133.293358 -232.534714)
		(width 0.1016)
		(layer "B.Cu")
		(net "SAS_GF_EXP_RX_DN4")
	)
	(arc
		(start 135.457184 -170.382184)
		(mid 135.310376 -169.644132)
		(end 134.892288 -169.018458)
		(width 0.1016)
		(layer "B.Cu")
		(net "SAS_GF_EXP_RX_DN4")
	)
	(arc
		(start 118.387114 -103.76662)
		(mid 118.435435 -103.523602)
		(end 118.573042 -103.317548)
		(width 0.1016)
		(layer "B.Cu")
		(net "SAS_GF_EXP_RX_DN4")
	)
	(arc
		(start 119.309388 -108.634276)
		(mid 119.093103 -108.310538)
		(end 119.017288 -107.928664)
		(width 0.1016)
		(layer "B.Cu")
		(net "SAS_GF_EXP_RX_DN4")
	)
	(segment
		(start 275.25091 -177.673)
		(end 275.778468 -177.145696)
		(width 0.1143)
		(layer "F.Cu")
		(net "ROMA21")
	)
	(segment
		(start 275.778468 -177.145696)
		(end 275.90115 -177.145696)
		(width 0.1143)
		(layer "F.Cu")
		(net "ROMA21")
	)
	(segment
		(start 275.90115 -177.145696)
		(end 276.0472 -176.999646)
		(width 0.1143)
		(layer "F.Cu")
		(net "ROMA21")
	)
	(segment
		(start 279.127204 -176.85385)
		(end 276.192996 -176.85385)
		(width 0.1143)
		(layer "F.Cu")
		(net "ROMA21")
	)
	(segment
		(start 274.6375 -177.673)
		(end 275.25091 -177.673)
		(width 0.1143)
		(layer "F.Cu")
		(net "ROMA21")
	)
	(segment
		(start 276.192996 -176.85385)
		(end 276.0472 -176.999646)
		(width 0.1143)
		(layer "F.Cu")
		(net "ROMA21")
	)
	(segment
		(start 286.098234 -177.376582)
		(end 284.011878 -177.376582)
		(width 0.1143)
		(layer "F.Cu")
		(net "ROMA21")
	)
	(segment
		(start 286.434784 -177.040032)
		(end 286.098234 -177.376582)
		(width 0.1143)
		(layer "F.Cu")
		(net "ROMA21")
	)
	(segment
		(start 279.4889 -177.215546)
		(end 279.127204 -176.85385)
		(width 0.1143)
		(layer "F.Cu")
		(net "ROMA21")
	)
	(segment
		(start 284.011878 -177.376582)
		(end 283.850842 -177.215546)
		(width 0.1143)
		(layer "F.Cu")
		(net "ROMA21")
	)
	(segment
		(start 283.850842 -177.215546)
		(end 279.4889 -177.215546)
		(width 0.1143)
		(layer "F.Cu")
		(net "ROMA21")
	)
	(via
		(at 276.0472 -176.999646)
		(size 0.7112)
		(drill 0.3556)
		(layers "F.Cu" "B.Cu")
		(net "ROMA21")
	)
	(segment
		(start 20.516088 -191.076326)
		(end 20.516088 -194.079622)
		(width 0.1143)
		(layer "F.Cu")
		(net "SAS_HDD_PRE3")
	)
	(segment
		(start 21.653754 -188.87948)
		(end 20.460208 -190.073026)
		(width 0.1143)
		(layer "F.Cu")
		(net "SAS_HDD_PRE3")
	)
	(segment
		(start 29.213048 -173.326806)
		(end 30.437328 -174.551086)
		(width 0.1143)
		(layer "F.Cu")
		(net "SAS_HDD_PRE3")
	)
	(segment
		(start 30.437582 -182.311548)
		(end 30.437582 -182.616348)
		(width 0.1143)
		(layer "F.Cu")
		(net "SAS_HDD_PRE3")
	)
	(segment
		(start 30.437328 -174.551086)
		(end 30.437328 -182.311294)
		(width 0.1143)
		(layer "F.Cu")
		(net "SAS_HDD_PRE3")
	)
	(segment
		(start 20.460208 -190.073026)
		(end 20.460208 -191.020446)
		(width 0.1143)
		(layer "F.Cu")
		(net "SAS_HDD_PRE3")
	)
	(segment
		(start 20.516088 -194.079622)
		(end 20.478496 -194.117214)
		(width 0.1143)
		(layer "F.Cu")
		(net "SAS_HDD_PRE3")
	)
	(segment
		(start 26.455878 -175.714406)
		(end 26.455878 -174.506636)
		(width 0.1143)
		(layer "F.Cu")
		(net "SAS_HDD_PRE3")
	)
	(segment
		(start 27.635708 -173.326806)
		(end 29.213048 -173.326806)
		(width 0.1143)
		(layer "F.Cu")
		(net "SAS_HDD_PRE3")
	)
	(segment
		(start 24.174704 -188.87948)
		(end 21.653754 -188.87948)
		(width 0.1143)
		(layer "F.Cu")
		(net "SAS_HDD_PRE3")
	)
	(segment
		(start 26.455878 -174.506636)
		(end 27.635708 -173.326806)
		(width 0.1143)
		(layer "F.Cu")
		(net "SAS_HDD_PRE3")
	)
	(segment
		(start 30.437328 -182.311294)
		(end 30.437582 -182.311548)
		(width 0.1143)
		(layer "F.Cu")
		(net "SAS_HDD_PRE3")
	)
	(segment
		(start 20.460208 -191.020446)
		(end 20.516088 -191.076326)
		(width 0.1143)
		(layer "F.Cu")
		(net "SAS_HDD_PRE3")
	)
	(segment
		(start 30.437328 -182.616602)
		(end 27.115516 -185.938668)
		(width 0.1143)
		(layer "F.Cu")
		(net "SAS_HDD_PRE3")
	)
	(segment
		(start 26.424128 -175.746156)
		(end 26.455878 -175.714406)
		(width 0.1143)
		(layer "F.Cu")
		(net "SAS_HDD_PRE3")
	)
	(segment
		(start 27.115516 -185.938668)
		(end 24.174704 -188.87948)
		(width 0.1143)
		(layer "F.Cu")
		(net "SAS_HDD_PRE3")
	)
	(segment
		(start 30.437582 -182.616348)
		(end 30.437328 -182.616602)
		(width 0.1143)
		(layer "F.Cu")
		(net "SAS_HDD_PRE3")
	)
	(via
		(at 16.044418 -197.048882)
		(size 0.7112)
		(drill 0.3556)
		(layers "F.Cu" "B.Cu")
		(net "SAS_HDD_PRE3")
	)
	(via
		(at 20.478496 -194.117214)
		(size 0.5588)
		(drill 0.3048)
		(layers "F.Cu" "B.Cu")
		(net "SAS_HDD_PRE3")
	)
	(segment
		(start 44.000166 -253.320804)
		(end 32.136842 -241.45748)
		(width 0.1143)
		(layer "B.Cu")
		(net "SAS_HDD_PRE3")
	)
	(segment
		(start 6.751066 -206.342234)
		(end 16.044418 -197.048882)
		(width 0.1143)
		(layer "B.Cu")
		(net "SAS_HDD_PRE3")
	)
	(segment
		(start 18.782284 -194.311016)
		(end 20.284694 -194.311016)
		(width 0.1143)
		(layer "B.Cu")
		(net "SAS_HDD_PRE3")
	)
	(segment
		(start 6.751066 -236.669326)
		(end 6.751066 -206.342234)
		(width 0.1143)
		(layer "B.Cu")
		(net "SAS_HDD_PRE3")
	)
	(segment
		(start 16.044418 -197.048882)
		(end 18.782284 -194.311016)
		(width 0.1143)
		(layer "B.Cu")
		(net "SAS_HDD_PRE3")
	)
	(segment
		(start 32.136842 -241.45748)
		(end 11.53922 -241.45748)
		(width 0.1143)
		(layer "B.Cu")
		(net "SAS_HDD_PRE3")
	)
	(segment
		(start 11.53922 -241.45748)
		(end 6.751066 -236.669326)
		(width 0.1143)
		(layer "B.Cu")
		(net "SAS_HDD_PRE3")
	)
	(segment
		(start 20.284694 -194.311016)
		(end 20.478496 -194.117214)
		(width 0.1143)
		(layer "B.Cu")
		(net "SAS_HDD_PRE3")
	)
	(segment
		(start 44.000166 -256.50444)
		(end 44.000166 -253.320804)
		(width 0.1143)
		(layer "B.Cu")
		(net "SAS_HDD_PRE3")
	)
	(segment
		(start 118.35003 -103.35006)
		(end 118.850156 -103.850186)
		(width 0.1016)
		(layer "F.Cu")
		(net "SAS_GF_EXP_RX_DP4")
	)
	(via
		(at 118.850156 -103.850186)
		(size 0.508)
		(drill 0.254)
		(layers "F.Cu" "B.Cu")
		(net "SAS_GF_EXP_RX_DP4")
	)
	(segment
		(start 135.800084 -218.629992)
		(end 135.800084 -170.38193)
		(width 0.1016)
		(layer "B.Cu")
		(net "SAS_GF_EXP_RX_DP4")
	)
	(segment
		(start 135.800084 -227.758244)
		(end 135.800084 -224.583752)
		(width 0.1016)
		(layer "B.Cu")
		(net "SAS_GF_EXP_RX_DP4")
	)
	(segment
		(start 136.038844 -219.412312)
		(end 136.038844 -219.107512)
		(width 0.1016)
		(layer "B.Cu")
		(net "SAS_GF_EXP_RX_DP4")
	)
	(segment
		(start 131.906772 -249.08764)
		(end 131.906772 -248.78284)
		(width 0.1016)
		(layer "B.Cu")
		(net "SAS_GF_EXP_RX_DP4")
	)
	(segment
		(start 135.800084 -220.194632)
		(end 135.800084 -219.889832)
		(width 0.1016)
		(layer "B.Cu")
		(net "SAS_GF_EXP_RX_DP4")
	)
	(segment
		(start 135.800084 -221.759272)
		(end 135.800084 -221.454472)
		(width 0.1016)
		(layer "B.Cu")
		(net "SAS_GF_EXP_RX_DP4")
	)
	(segment
		(start 136.038844 -220.976952)
		(end 136.038844 -220.672152)
		(width 0.1016)
		(layer "B.Cu")
		(net "SAS_GF_EXP_RX_DP4")
	)
	(segment
		(start 131.83362 -254.013462)
		(end 131.833366 -254.013208)
		(width 0.1016)
		(layer "B.Cu")
		(net "SAS_GF_EXP_RX_DP4")
	)
	(segment
		(start 122.325638 -111.164878)
		(end 119.640858 -108.480098)
		(width 0.1016)
		(layer "B.Cu")
		(net "SAS_GF_EXP_RX_DP4")
	)
	(segment
		(start 131.668012 -253.613412)
		(end 131.668012 -251.1298)
		(width 0.1016)
		(layer "B.Cu")
		(net "SAS_GF_EXP_RX_DP4")
	)
	(segment
		(start 135.800084 -223.323912)
		(end 135.800084 -223.019112)
		(width 0.1016)
		(layer "B.Cu")
		(net "SAS_GF_EXP_RX_DP4")
	)
	(segment
		(start 118.850156 -103.88219)
		(end 118.850156 -103.850186)
		(width 0.1016)
		(layer "B.Cu")
		(net "SAS_GF_EXP_RX_DP4")
	)
	(segment
		(start 136.038844 -222.541592)
		(end 136.038844 -222.236792)
		(width 0.1016)
		(layer "B.Cu")
		(net "SAS_GF_EXP_RX_DP4")
	)
	(segment
		(start 131.906772 -247.523)
		(end 131.906772 -247.2182)
		(width 0.1016)
		(layer "B.Cu")
		(net "SAS_GF_EXP_RX_DP4")
	)
	(segment
		(start 119.031258 -107.133898)
		(end 118.629684 -106.732324)
		(width 0.1016)
		(layer "B.Cu")
		(net "SAS_GF_EXP_RX_DP4")
	)
	(segment
		(start 123.195842 -154.59837)
		(end 123.195842 -113.265712)
		(width 0.1016)
		(layer "B.Cu")
		(net "SAS_GF_EXP_RX_DP4")
	)
	(segment
		(start 133.535928 -232.777284)
		(end 133.852412 -232.4608)
		(width 0.1016)
		(layer "B.Cu")
		(net "SAS_GF_EXP_RX_DP4")
	)
	(segment
		(start 131.668012 -249.86996)
		(end 131.668012 -249.56516)
		(width 0.1016)
		(layer "B.Cu")
		(net "SAS_GF_EXP_RX_DP4")
	)
	(segment
		(start 118.443756 -106.283252)
		(end 118.443756 -104.814878)
		(width 0.1016)
		(layer "B.Cu")
		(net "SAS_GF_EXP_RX_DP4")
	)
	(segment
		(start 131.668012 -248.30532)
		(end 131.668012 -248.00052)
		(width 0.1016)
		(layer "B.Cu")
		(net "SAS_GF_EXP_RX_DP4")
	)
	(segment
		(start 135.134858 -168.775888)
		(end 124.77877 -158.4198)
		(width 0.1016)
		(layer "B.Cu")
		(net "SAS_GF_EXP_RX_DP4")
	)
	(segment
		(start 131.906772 -250.65228)
		(end 131.906772 -250.34748)
		(width 0.1016)
		(layer "B.Cu")
		(net "SAS_GF_EXP_RX_DP4")
	)
	(segment
		(start 131.668012 -246.74068)
		(end 131.668012 -237.2868)
		(width 0.1016)
		(layer "B.Cu")
		(net "SAS_GF_EXP_RX_DP4")
	)
	(segment
		(start 119.640858 -108.480098)
		(end 119.551958 -108.391452)
		(width 0.1016)
		(layer "B.Cu")
		(net "SAS_GF_EXP_RX_DP4")
	)
	(segment
		(start 136.038844 -224.106232)
		(end 136.038844 -223.801432)
		(width 0.1016)
		(layer "B.Cu")
		(net "SAS_GF_EXP_RX_DP4")
	)
	(segment
		(start 118.629684 -104.365806)
		(end 118.664228 -104.331262)
		(width 0.1016)
		(layer "B.Cu")
		(net "SAS_GF_EXP_RX_DP4")
	)
	(segment
		(start 131.999482 -256.50444)
		(end 131.999482 -254.413512)
		(width 0.1016)
		(layer "B.Cu")
		(net "SAS_GF_EXP_RX_DP4")
	)
	(arc
		(start 136.038844 -220.672152)
		(mid 136.008352 -220.538159)
		(end 135.919464 -220.433392)
		(width 0.1016)
		(layer "B.Cu")
		(net "SAS_GF_EXP_RX_DP4")
	)
	(arc
		(start 131.787392 -247.76176)
		(mid 131.87628 -247.656965)
		(end 131.906772 -247.523)
		(width 0.1016)
		(layer "B.Cu")
		(net "SAS_GF_EXP_RX_DP4")
	)
	(arc
		(start 134.110476 -232.18775)
		(mid 135.363413 -230.128673)
		(end 135.800084 -227.758244)
		(width 0.1016)
		(layer "B.Cu")
		(net "SAS_GF_EXP_RX_DP4")
	)
	(arc
		(start 135.919464 -224.344992)
		(mid 136.008258 -224.240178)
		(end 136.038844 -224.106232)
		(width 0.1016)
		(layer "B.Cu")
		(net "SAS_GF_EXP_RX_DP4")
	)
	(arc
		(start 118.57609 -104.426258)
		(mid 118.601921 -104.395175)
		(end 118.629684 -104.365806)
		(width 0.1016)
		(layer "B.Cu")
		(net "SAS_GF_EXP_RX_DP4")
	)
	(arc
		(start 131.787392 -249.3264)
		(mid 131.87628 -249.221605)
		(end 131.906772 -249.08764)
		(width 0.1016)
		(layer "B.Cu")
		(net "SAS_GF_EXP_RX_DP4")
	)
	(arc
		(start 118.692168 -104.301036)
		(mid 118.809234 -104.105983)
		(end 118.850156 -103.88219)
		(width 0.1016)
		(layer "B.Cu")
		(net "SAS_GF_EXP_RX_DP4")
	)
	(arc
		(start 131.787392 -248.54408)
		(mid 131.698504 -248.439285)
		(end 131.668012 -248.30532)
		(width 0.1016)
		(layer "B.Cu")
		(net "SAS_GF_EXP_RX_DP4")
	)
	(arc
		(start 131.668012 -251.1298)
		(mid 131.698504 -250.995807)
		(end 131.787392 -250.89104)
		(width 0.1016)
		(layer "B.Cu")
		(net "SAS_GF_EXP_RX_DP4")
	)
	(arc
		(start 131.668012 -249.56516)
		(mid 131.698504 -249.431167)
		(end 131.787392 -249.3264)
		(width 0.1016)
		(layer "B.Cu")
		(net "SAS_GF_EXP_RX_DP4")
	)
	(arc
		(start 135.919464 -222.780352)
		(mid 136.008258 -222.675538)
		(end 136.038844 -222.541592)
		(width 0.1016)
		(layer "B.Cu")
		(net "SAS_GF_EXP_RX_DP4")
	)
	(arc
		(start 131.787392 -246.97944)
		(mid 131.698504 -246.874645)
		(end 131.668012 -246.74068)
		(width 0.1016)
		(layer "B.Cu")
		(net "SAS_GF_EXP_RX_DP4")
	)
	(arc
		(start 131.906772 -250.34748)
		(mid 131.87628 -250.213487)
		(end 131.787392 -250.10872)
		(width 0.1016)
		(layer "B.Cu")
		(net "SAS_GF_EXP_RX_DP4")
	)
	(arc
		(start 135.919464 -219.651072)
		(mid 136.008258 -219.546258)
		(end 136.038844 -219.412312)
		(width 0.1016)
		(layer "B.Cu")
		(net "SAS_GF_EXP_RX_DP4")
	)
	(arc
		(start 131.787392 -250.89104)
		(mid 131.87628 -250.786245)
		(end 131.906772 -250.65228)
		(width 0.1016)
		(layer "B.Cu")
		(net "SAS_GF_EXP_RX_DP4")
	)
	(arc
		(start 135.919464 -220.433392)
		(mid 135.83067 -220.328578)
		(end 135.800084 -220.194632)
		(width 0.1016)
		(layer "B.Cu")
		(net "SAS_GF_EXP_RX_DP4")
	)
	(arc
		(start 123.195842 -113.265712)
		(mid 122.969617 -112.128784)
		(end 122.325638 -111.164878)
		(width 0.1016)
		(layer "B.Cu")
		(net "SAS_GF_EXP_RX_DP4")
	)
	(arc
		(start 136.038844 -223.801432)
		(mid 136.008352 -223.667439)
		(end 135.919464 -223.562672)
		(width 0.1016)
		(layer "B.Cu")
		(net "SAS_GF_EXP_RX_DP4")
	)
	(arc
		(start 118.664228 -104.331262)
		(mid 118.678444 -104.316377)
		(end 118.692168 -104.301036)
		(width 0.1016)
		(layer "B.Cu")
		(net "SAS_GF_EXP_RX_DP4")
	)
	(arc
		(start 124.77877 -158.4198)
		(mid 123.607261 -156.666513)
		(end 123.195842 -154.59837)
		(width 0.1016)
		(layer "B.Cu")
		(net "SAS_GF_EXP_RX_DP4")
	)
	(arc
		(start 133.852412 -232.4608)
		(mid 133.98337 -232.326096)
		(end 134.110476 -232.18775)
		(width 0.1016)
		(layer "B.Cu")
		(net "SAS_GF_EXP_RX_DP4")
	)
	(arc
		(start 135.800084 -170.38193)
		(mid 135.627209 -169.512739)
		(end 135.134858 -168.775888)
		(width 0.1016)
		(layer "B.Cu")
		(net "SAS_GF_EXP_RX_DP4")
	)
	(arc
		(start 131.668012 -248.00052)
		(mid 131.698504 -247.866527)
		(end 131.787392 -247.76176)
		(width 0.1016)
		(layer "B.Cu")
		(net "SAS_GF_EXP_RX_DP4")
	)
	(arc
		(start 118.443756 -104.814878)
		(mid 118.477657 -104.609577)
		(end 118.57609 -104.426258)
		(width 0.1016)
		(layer "B.Cu")
		(net "SAS_GF_EXP_RX_DP4")
	)
	(arc
		(start 131.787392 -250.10872)
		(mid 131.698504 -250.003925)
		(end 131.668012 -249.86996)
		(width 0.1016)
		(layer "B.Cu")
		(net "SAS_GF_EXP_RX_DP4")
	)
	(arc
		(start 135.800084 -223.019112)
		(mid 135.830576 -222.885119)
		(end 135.919464 -222.780352)
		(width 0.1016)
		(layer "B.Cu")
		(net "SAS_GF_EXP_RX_DP4")
	)
	(arc
		(start 131.999482 -254.413512)
		(mid 131.956322 -254.197001)
		(end 131.83362 -254.013462)
		(width 0.1016)
		(layer "B.Cu")
		(net "SAS_GF_EXP_RX_DP4")
	)
	(arc
		(start 131.906772 -247.2182)
		(mid 131.87628 -247.084207)
		(end 131.787392 -246.97944)
		(width 0.1016)
		(layer "B.Cu")
		(net "SAS_GF_EXP_RX_DP4")
	)
	(arc
		(start 136.038844 -219.107512)
		(mid 136.008352 -218.973519)
		(end 135.919464 -218.868752)
		(width 0.1016)
		(layer "B.Cu")
		(net "SAS_GF_EXP_RX_DP4")
	)
	(arc
		(start 135.919464 -221.215712)
		(mid 136.008258 -221.110898)
		(end 136.038844 -220.976952)
		(width 0.1016)
		(layer "B.Cu")
		(net "SAS_GF_EXP_RX_DP4")
	)
	(arc
		(start 131.833366 -254.013208)
		(mid 131.710964 -253.829737)
		(end 131.668012 -253.613412)
		(width 0.1016)
		(layer "B.Cu")
		(net "SAS_GF_EXP_RX_DP4")
	)
	(arc
		(start 135.919464 -218.868752)
		(mid 135.83067 -218.763938)
		(end 135.800084 -218.629992)
		(width 0.1016)
		(layer "B.Cu")
		(net "SAS_GF_EXP_RX_DP4")
	)
	(arc
		(start 135.800084 -219.889832)
		(mid 135.830576 -219.755839)
		(end 135.919464 -219.651072)
		(width 0.1016)
		(layer "B.Cu")
		(net "SAS_GF_EXP_RX_DP4")
	)
	(arc
		(start 135.919464 -221.998032)
		(mid 135.83067 -221.893218)
		(end 135.800084 -221.759272)
		(width 0.1016)
		(layer "B.Cu")
		(net "SAS_GF_EXP_RX_DP4")
	)
	(arc
		(start 119.360442 -107.928664)
		(mid 119.274901 -107.498533)
		(end 119.031258 -107.133898)
		(width 0.1016)
		(layer "B.Cu")
		(net "SAS_GF_EXP_RX_DP4")
	)
	(arc
		(start 131.668012 -237.2868)
		(mid 132.153465 -234.846262)
		(end 133.535928 -232.777284)
		(width 0.1016)
		(layer "B.Cu")
		(net "SAS_GF_EXP_RX_DP4")
	)
	(arc
		(start 119.551958 -108.391452)
		(mid 119.410167 -108.179108)
		(end 119.360442 -107.928664)
		(width 0.1016)
		(layer "B.Cu")
		(net "SAS_GF_EXP_RX_DP4")
	)
	(arc
		(start 135.919464 -223.562672)
		(mid 135.83067 -223.457858)
		(end 135.800084 -223.323912)
		(width 0.1016)
		(layer "B.Cu")
		(net "SAS_GF_EXP_RX_DP4")
	)
	(arc
		(start 135.800084 -221.454472)
		(mid 135.830576 -221.320479)
		(end 135.919464 -221.215712)
		(width 0.1016)
		(layer "B.Cu")
		(net "SAS_GF_EXP_RX_DP4")
	)
	(arc
		(start 118.629684 -106.732324)
		(mid 118.492069 -106.526274)
		(end 118.443756 -106.283252)
		(width 0.1016)
		(layer "B.Cu")
		(net "SAS_GF_EXP_RX_DP4")
	)
	(arc
		(start 135.800084 -224.583752)
		(mid 135.830576 -224.449759)
		(end 135.919464 -224.344992)
		(width 0.1016)
		(layer "B.Cu")
		(net "SAS_GF_EXP_RX_DP4")
	)
	(arc
		(start 131.906772 -248.78284)
		(mid 131.87628 -248.648847)
		(end 131.787392 -248.54408)
		(width 0.1016)
		(layer "B.Cu")
		(net "SAS_GF_EXP_RX_DP4")
	)
	(arc
		(start 136.038844 -222.236792)
		(mid 136.008352 -222.102799)
		(end 135.919464 -221.998032)
		(width 0.1016)
		(layer "B.Cu")
		(net "SAS_GF_EXP_RX_DP4")
	)
	(segment
		(start 300.228 -163.322)
		(end 299.964856 -163.322)
		(width 0.127)
		(layer "F.Cu")
		(net "TP_GPIOH5")
	)
	(segment
		(start 298.577 -164.709856)
		(end 298.577 -165.194742)
		(width 0.127)
		(layer "F.Cu")
		(net "TP_GPIOH5")
	)
	(segment
		(start 298.577 -165.194742)
		(end 298.031408 -165.740334)
		(width 0.127)
		(layer "F.Cu")
		(net "TP_GPIOH5")
	)
	(segment
		(start 298.031408 -165.740334)
		(end 298.031408 -167.804592)
		(width 0.127)
		(layer "F.Cu")
		(net "TP_GPIOH5")
	)
	(segment
		(start 299.964856 -163.322)
		(end 298.577 -164.709856)
		(width 0.127)
		(layer "F.Cu")
		(net "TP_GPIOH5")
	)
	(segment
		(start 298.031408 -167.804592)
		(end 297.634914 -168.201086)
		(width 0.127)
		(layer "F.Cu")
		(net "TP_GPIOH5")
	)
	(segment
		(start 297.634914 -168.201086)
		(end 297.634914 -168.240202)
		(width 0.127)
		(layer "F.Cu")
		(net "TP_GPIOH5")
	)
	(segment
		(start 268.5542 -176.3268)
		(end 267.843 -177.038)
		(width 0.1143)
		(layer "F.Cu")
		(net "ROMA23")
	)
	(segment
		(start 288.034984 -174.64024)
		(end 287.63976 -174.245016)
		(width 0.1143)
		(layer "F.Cu")
		(net "ROMA23")
	)
	(segment
		(start 266.5095 -177.038)
		(end 267.843 -177.038)
		(width 0.1143)
		(layer "F.Cu")
		(net "ROMA23")
	)
	(via
		(at 267.843 -177.038)
		(size 0.5588)
		(drill 0.3048)
		(layers "F.Cu" "B.Cu")
		(net "ROMA23")
	)
	(via
		(at 287.63976 -174.245016)
		(size 0.508)
		(drill 0.254)
		(layers "F.Cu" "B.Cu")
		(net "ROMA23")
	)
	(via
		(at 268.5542 -176.3268)
		(size 0.7112)
		(drill 0.3556)
		(layers "F.Cu" "B.Cu")
		(net "ROMA23")
	)
	(segment
		(start 285.001208 -175.1076)
		(end 285.47187 -174.636938)
		(width 0.127)
		(layer "In2.Cu")
		(net "ROMA23")
	)
	(segment
		(start 285.47187 -174.636938)
		(end 285.488634 -174.636938)
		(width 0.0889)
		(layer "In2.Cu")
		(net "ROMA23")
	)
	(segment
		(start 272.5801 -175.167544)
		(end 272.689574 -175.05807)
		(width 0.127)
		(layer "In2.Cu")
		(net "ROMA23")
	)
	(segment
		(start 285.497016 -174.64532)
		(end 287.020508 -174.64532)
		(width 0.0889)
		(layer "In2.Cu")
		(net "ROMA23")
	)
	(segment
		(start 267.843 -177.038)
		(end 268.732 -176.149)
		(width 0.127)
		(layer "In2.Cu")
		(net "ROMA23")
	)
	(segment
		(start 273.100038 -175.05807)
		(end 273.149568 -175.1076)
		(width 0.127)
		(layer "In2.Cu")
		(net "ROMA23")
	)
	(segment
		(start 273.149568 -175.1076)
		(end 285.001208 -175.1076)
		(width 0.127)
		(layer "In2.Cu")
		(net "ROMA23")
	)
	(segment
		(start 287.244282 -174.4218)
		(end 287.421066 -174.245016)
		(width 0.0889)
		(layer "In2.Cu")
		(net "ROMA23")
	)
	(segment
		(start 272.689574 -175.05807)
		(end 273.100038 -175.05807)
		(width 0.127)
		(layer "In2.Cu")
		(net "ROMA23")
	)
	(segment
		(start 287.421066 -174.245016)
		(end 287.63976 -174.245016)
		(width 0.0889)
		(layer "In2.Cu")
		(net "ROMA23")
	)
	(segment
		(start 271.399 -176.149)
		(end 272.380456 -175.167544)
		(width 0.127)
		(layer "In2.Cu")
		(net "ROMA23")
	)
	(segment
		(start 287.020508 -174.64532)
		(end 287.244282 -174.4218)
		(width 0.0889)
		(layer "In2.Cu")
		(net "ROMA23")
	)
	(segment
		(start 268.732 -176.149)
		(end 271.399 -176.149)
		(width 0.127)
		(layer "In2.Cu")
		(net "ROMA23")
	)
	(segment
		(start 285.488634 -174.636938)
		(end 285.497016 -174.64532)
		(width 0.0889)
		(layer "In2.Cu")
		(net "ROMA23")
	)
	(segment
		(start 272.380456 -175.167544)
		(end 272.5801 -175.167544)
		(width 0.127)
		(layer "In2.Cu")
		(net "ROMA23")
	)
	(segment
		(start 103.6955 -241.935)
		(end 103.6955 -241.173)
		(width 0.1143)
		(layer "F.Cu")
		(net "SAS_FAULT_LED4")
	)
	(segment
		(start 103.6955 -241.173)
		(end 103.6955 -239.4712)
		(width 0.1143)
		(layer "F.Cu")
		(net "SAS_FAULT_LED4")
	)
	(segment
		(start 104.2035 -242.443)
		(end 103.6955 -241.935)
		(width 0.1143)
		(layer "F.Cu")
		(net "SAS_FAULT_LED4")
	)
	(segment
		(start 104.267 -242.443)
		(end 104.2035 -242.443)
		(width 0.1143)
		(layer "F.Cu")
		(net "SAS_FAULT_LED4")
	)
	(via
		(at 104.267 -242.443)
		(size 0.5588)
		(drill 0.3048)
		(layers "F.Cu" "B.Cu")
		(net "SAS_FAULT_LED4")
	)
	(via
		(at 103.6955 -241.173)
		(size 0.5588)
		(drill 0.3048)
		(layers "F.Cu" "B.Cu")
		(net "SAS_FAULT_LED4")
	)
	(via
		(at 104.539796 -246.869204)
		(size 0.7112)
		(drill 0.3556)
		(layers "F.Cu" "B.Cu")
		(net "SAS_FAULT_LED4")
	)
	(segment
		(start 107.696 -234.480862)
		(end 107.696 -239.014)
		(width 0.1143)
		(layer "B.Cu")
		(net "SAS_FAULT_LED4")
	)
	(segment
		(start 106.27995 -248.609358)
		(end 104.539796 -246.869204)
		(width 0.1143)
		(layer "B.Cu")
		(net "SAS_FAULT_LED4")
	)
	(segment
		(start 103.999792 -253.886208)
		(end 106.27995 -251.60605)
		(width 0.1143)
		(layer "B.Cu")
		(net "SAS_FAULT_LED4")
	)
	(segment
		(start 108.070142 -241.307366)
		(end 106.934508 -242.443)
		(width 0.1143)
		(layer "B.Cu")
		(net "SAS_FAULT_LED4")
	)
	(segment
		(start 108.070142 -239.388142)
		(end 108.070142 -241.307366)
		(width 0.1143)
		(layer "B.Cu")
		(net "SAS_FAULT_LED4")
	)
	(segment
		(start 104.267 -246.596408)
		(end 104.539796 -246.869204)
		(width 0.1143)
		(layer "B.Cu")
		(net "SAS_FAULT_LED4")
	)
	(segment
		(start 104.267 -242.443)
		(end 104.267 -246.596408)
		(width 0.1143)
		(layer "B.Cu")
		(net "SAS_FAULT_LED4")
	)
	(segment
		(start 103.999792 -256.50444)
		(end 103.999792 -253.886208)
		(width 0.1143)
		(layer "B.Cu")
		(net "SAS_FAULT_LED4")
	)
	(segment
		(start 106.934508 -242.443)
		(end 104.267 -242.443)
		(width 0.1143)
		(layer "B.Cu")
		(net "SAS_FAULT_LED4")
	)
	(segment
		(start 103.886 -240.9825)
		(end 103.6955 -241.173)
		(width 0.1143)
		(layer "B.Cu")
		(net "SAS_FAULT_LED4")
	)
	(segment
		(start 107.696 -239.014)
		(end 108.070142 -239.388142)
		(width 0.1143)
		(layer "B.Cu")
		(net "SAS_FAULT_LED4")
	)
	(segment
		(start 103.886 -239.8395)
		(end 103.886 -240.9825)
		(width 0.1143)
		(layer "B.Cu")
		(net "SAS_FAULT_LED4")
	)
	(segment
		(start 106.27995 -251.60605)
		(end 106.27995 -248.609358)
		(width 0.1143)
		(layer "B.Cu")
		(net "SAS_FAULT_LED4")
	)
	(segment
		(start 104.267 -231.051862)
		(end 107.696 -234.480862)
		(width 0.1143)
		(layer "B.Cu")
		(net "SAS_FAULT_LED4")
	)
	(segment
		(start 104.267 -230.8225)
		(end 104.267 -231.051862)
		(width 0.1143)
		(layer "B.Cu")
		(net "SAS_FAULT_LED4")
	)
	(segment
		(start 103.4415 -229.997)
		(end 104.267 -230.8225)
		(width 0.1143)
		(layer "B.Cu")
		(net "SAS_FAULT_LED4")
	)
	(segment
		(start 135.86587 -169.67073)
		(end 124.195332 -158.000192)
		(width 0.1016)
		(layer "F.Cu")
		(net "SAS_EXP_GF_TX_DP3")
	)
	(segment
		(start 134.258558 -229.819708)
		(end 136.678924 -227.399342)
		(width 0.1016)
		(layer "F.Cu")
		(net "SAS_EXP_GF_TX_DP3")
	)
	(segment
		(start 133.649212 -238.349282)
		(end 133.649212 -231.290876)
		(width 0.1016)
		(layer "F.Cu")
		(net "SAS_EXP_GF_TX_DP3")
	)
	(segment
		(start 133.887972 -242.260882)
		(end 133.887972 -241.956082)
		(width 0.1016)
		(layer "F.Cu")
		(net "SAS_EXP_GF_TX_DP3")
	)
	(segment
		(start 124.109734 -115.793266)
		(end 130.899408 -109.003592)
		(width 0.1016)
		(layer "F.Cu")
		(net "SAS_EXP_GF_TX_DP3")
	)
	(segment
		(start 133.965188 -254.058166)
		(end 133.9596 -254.052324)
		(width 0.1016)
		(layer "F.Cu")
		(net "SAS_EXP_GF_TX_DP3")
	)
	(segment
		(start 123.50242 -156.327348)
		(end 123.50242 -117.259354)
		(width 0.1016)
		(layer "F.Cu")
		(net "SAS_EXP_GF_TX_DP3")
	)
	(segment
		(start 133.887972 -239.131602)
		(end 133.887972 -238.826802)
		(width 0.1016)
		(layer "F.Cu")
		(net "SAS_EXP_GF_TX_DP3")
	)
	(segment
		(start 133.649212 -239.913922)
		(end 133.649212 -239.609122)
		(width 0.1016)
		(layer "F.Cu")
		(net "SAS_EXP_GF_TX_DP3")
	)
	(segment
		(start 133.649212 -241.478562)
		(end 133.649212 -241.173762)
		(width 0.1016)
		(layer "F.Cu")
		(net "SAS_EXP_GF_TX_DP3")
	)
	(segment
		(start 133.649212 -253.703836)
		(end 133.649212 -242.738402)
		(width 0.1016)
		(layer "F.Cu")
		(net "SAS_EXP_GF_TX_DP3")
	)
	(segment
		(start 133.999732 -256.25044)
		(end 133.999732 -254.20193)
		(width 0.1016)
		(layer "F.Cu")
		(net "SAS_EXP_GF_TX_DP3")
	)
	(segment
		(start 131.49707 -107.560618)
		(end 131.49707 -99.5934)
		(width 0.1016)
		(layer "F.Cu")
		(net "SAS_EXP_GF_TX_DP3")
	)
	(segment
		(start 131.655058 -99.211638)
		(end 131.66471 -99.20224)
		(width 0.1016)
		(layer "F.Cu")
		(net "SAS_EXP_GF_TX_DP3")
	)
	(segment
		(start 133.887972 -240.696242)
		(end 133.887972 -240.391442)
		(width 0.1016)
		(layer "F.Cu")
		(net "SAS_EXP_GF_TX_DP3")
	)
	(segment
		(start 137.524236 -225.358452)
		(end 137.524236 -173.674786)
		(width 0.1016)
		(layer "F.Cu")
		(net "SAS_EXP_GF_TX_DP3")
	)
	(segment
		(start 133.892798 -254.007874)
		(end 133.750812 -253.9492)
		(width 0.1016)
		(layer "F.Cu")
		(net "SAS_EXP_GF_TX_DP3")
	)
	(arc
		(start 133.649212 -239.609122)
		(mid 133.679704 -239.475129)
		(end 133.768592 -239.370362)
		(width 0.1016)
		(layer "F.Cu")
		(net "SAS_EXP_GF_TX_DP3")
	)
	(arc
		(start 133.768592 -240.152682)
		(mid 133.679798 -240.047868)
		(end 133.649212 -239.913922)
		(width 0.1016)
		(layer "F.Cu")
		(net "SAS_EXP_GF_TX_DP3")
	)
	(arc
		(start 133.768592 -240.935002)
		(mid 133.857386 -240.830188)
		(end 133.887972 -240.696242)
		(width 0.1016)
		(layer "F.Cu")
		(net "SAS_EXP_GF_TX_DP3")
	)
	(arc
		(start 133.887972 -241.956082)
		(mid 133.85748 -241.822089)
		(end 133.768592 -241.717322)
		(width 0.1016)
		(layer "F.Cu")
		(net "SAS_EXP_GF_TX_DP3")
	)
	(arc
		(start 133.9596 -254.052324)
		(mid 133.928422 -254.026755)
		(end 133.892798 -254.007874)
		(width 0.1016)
		(layer "F.Cu")
		(net "SAS_EXP_GF_TX_DP3")
	)
	(arc
		(start 133.649212 -241.173762)
		(mid 133.679704 -241.039769)
		(end 133.768592 -240.935002)
		(width 0.1016)
		(layer "F.Cu")
		(net "SAS_EXP_GF_TX_DP3")
	)
	(arc
		(start 133.768592 -241.717322)
		(mid 133.679798 -241.612508)
		(end 133.649212 -241.478562)
		(width 0.1016)
		(layer "F.Cu")
		(net "SAS_EXP_GF_TX_DP3")
	)
	(arc
		(start 124.195332 -158.000192)
		(mid 123.6825 -157.232685)
		(end 123.50242 -156.327348)
		(width 0.1016)
		(layer "F.Cu")
		(net "SAS_EXP_GF_TX_DP3")
	)
	(arc
		(start 133.887972 -240.391442)
		(mid 133.85748 -240.257449)
		(end 133.768592 -240.152682)
		(width 0.1016)
		(layer "F.Cu")
		(net "SAS_EXP_GF_TX_DP3")
	)
	(arc
		(start 133.649212 -242.738402)
		(mid 133.679704 -242.604409)
		(end 133.768592 -242.499642)
		(width 0.1016)
		(layer "F.Cu")
		(net "SAS_EXP_GF_TX_DP3")
	)
	(arc
		(start 137.524236 -173.674786)
		(mid 137.093308 -171.507803)
		(end 135.86587 -169.67073)
		(width 0.1016)
		(layer "F.Cu")
		(net "SAS_EXP_GF_TX_DP3")
	)
	(arc
		(start 133.999732 -254.20193)
		(mid 133.991013 -254.127991)
		(end 133.965188 -254.058166)
		(width 0.1016)
		(layer "F.Cu")
		(net "SAS_EXP_GF_TX_DP3")
	)
	(arc
		(start 123.50242 -117.259354)
		(mid 123.660248 -116.465897)
		(end 124.109734 -115.793266)
		(width 0.1016)
		(layer "F.Cu")
		(net "SAS_EXP_GF_TX_DP3")
	)
	(arc
		(start 133.768592 -238.588042)
		(mid 133.679798 -238.483228)
		(end 133.649212 -238.349282)
		(width 0.1016)
		(layer "F.Cu")
		(net "SAS_EXP_GF_TX_DP3")
	)
	(arc
		(start 136.678924 -227.399342)
		(mid 137.304532 -226.462959)
		(end 137.524236 -225.358452)
		(width 0.1016)
		(layer "F.Cu")
		(net "SAS_EXP_GF_TX_DP3")
	)
	(arc
		(start 133.750812 -253.9492)
		(mid 133.675592 -253.836626)
		(end 133.649212 -253.703836)
		(width 0.1016)
		(layer "F.Cu")
		(net "SAS_EXP_GF_TX_DP3")
	)
	(arc
		(start 133.768592 -242.499642)
		(mid 133.857386 -242.394828)
		(end 133.887972 -242.260882)
		(width 0.1016)
		(layer "F.Cu")
		(net "SAS_EXP_GF_TX_DP3")
	)
	(arc
		(start 133.649212 -231.290876)
		(mid 133.807582 -230.494698)
		(end 134.258558 -229.819708)
		(width 0.1016)
		(layer "F.Cu")
		(net "SAS_EXP_GF_TX_DP3")
	)
	(arc
		(start 130.899408 -109.003592)
		(mid 131.341717 -108.341536)
		(end 131.49707 -107.560618)
		(width 0.1016)
		(layer "F.Cu")
		(net "SAS_EXP_GF_TX_DP3")
	)
	(arc
		(start 133.768592 -239.370362)
		(mid 133.857386 -239.265548)
		(end 133.887972 -239.131602)
		(width 0.1016)
		(layer "F.Cu")
		(net "SAS_EXP_GF_TX_DP3")
	)
	(arc
		(start 133.887972 -238.826802)
		(mid 133.85748 -238.692809)
		(end 133.768592 -238.588042)
		(width 0.1016)
		(layer "F.Cu")
		(net "SAS_EXP_GF_TX_DP3")
	)
	(arc
		(start 131.49707 -99.5934)
		(mid 131.538073 -99.386793)
		(end 131.655058 -99.211638)
		(width 0.1016)
		(layer "F.Cu")
		(net "SAS_EXP_GF_TX_DP3")
	)
	(segment
		(start 319.659 -173.736)
		(end 320.802 -172.593)
		(width 0.1143)
		(layer "F.Cu")
		(net "BMC_RXD5")
	)
	(segment
		(start 320.802 -172.593)
		(end 320.802 -172.400468)
		(width 0.1143)
		(layer "F.Cu")
		(net "BMC_RXD5")
	)
	(segment
		(start 332.435454 -171.529756)
		(end 333.27721 -170.688)
		(width 0.1143)
		(layer "F.Cu")
		(net "BMC_RXD5")
	)
	(segment
		(start 331.372972 -171.529756)
		(end 332.435454 -171.529756)
		(width 0.1143)
		(layer "F.Cu")
		(net "BMC_RXD5")
	)
	(segment
		(start 48.7172 -116.1542)
		(end 48.7172 -115.2017)
		(width 0.1143)
		(layer "F.Cu")
		(net "BMC_RXD5")
	)
	(segment
		(start 318.4525 -173.736)
		(end 319.659 -173.736)
		(width 0.1143)
		(layer "F.Cu")
		(net "BMC_RXD5")
	)
	(segment
		(start 320.802 -172.400468)
		(end 320.832734 -172.369734)
		(width 0.1143)
		(layer "F.Cu")
		(net "BMC_RXD5")
	)
	(via
		(at 322.834 -156.845)
		(size 0.5588)
		(drill 0.3048)
		(layers "F.Cu" "B.Cu")
		(net "BMC_RXD5")
	)
	(via
		(at 320.832734 -172.369734)
		(size 0.5588)
		(drill 0.3048)
		(layers "F.Cu" "B.Cu")
		(net "BMC_RXD5")
	)
	(via
		(at 319.659 -173.736)
		(size 0.7112)
		(drill 0.3556)
		(layers "F.Cu" "B.Cu")
		(net "BMC_RXD5")
	)
	(via
		(at 333.27721 -170.688)
		(size 0.5588)
		(drill 0.3048)
		(layers "F.Cu" "B.Cu")
		(net "BMC_RXD5")
	)
	(via
		(at 253.21514 -118.50624)
		(size 0.5588)
		(drill 0.3048)
		(layers "F.Cu" "B.Cu")
		(net "BMC_RXD5")
	)
	(via
		(at 247.65 -178.054)
		(size 0.5588)
		(drill 0.3048)
		(layers "F.Cu" "B.Cu")
		(net "BMC_RXD5")
	)
	(via
		(at 48.7172 -116.1542)
		(size 0.5588)
		(drill 0.3048)
		(layers "F.Cu" "B.Cu")
		(net "BMC_RXD5")
	)
	(segment
		(start 295.008554 -119.69115)
		(end 294.748204 -119.9515)
		(width 0.1143)
		(layer "B.Cu")
		(net "BMC_RXD5")
	)
	(segment
		(start 304.620168 -119.69115)
		(end 304.619914 -119.690896)
		(width 0.1143)
		(layer "B.Cu")
		(net "BMC_RXD5")
	)
	(segment
		(start 333.27721 -170.688)
		(end 333.08671 -170.8785)
		(width 0.1143)
		(layer "B.Cu")
		(net "BMC_RXD5")
	)
	(segment
		(start 274.2311 -119.9515)
		(end 272.82775 -118.54815)
		(width 0.1143)
		(layer "B.Cu")
		(net "BMC_RXD5")
	)
	(segment
		(start 322.56095 -141.589506)
		(end 322.56095 -134.498842)
		(width 0.1143)
		(layer "B.Cu")
		(net "BMC_RXD5")
	)
	(segment
		(start 322.226178 -134.164324)
		(end 319.056004 -130.99415)
		(width 0.1143)
		(layer "B.Cu")
		(net "BMC_RXD5")
	)
	(segment
		(start 322.56095 -156.57195)
		(end 322.56095 -151.926544)
		(width 0.1143)
		(layer "B.Cu")
		(net "BMC_RXD5")
	)
	(segment
		(start 322.072 -151.437594)
		(end 322.072 -142.078456)
		(width 0.1143)
		(layer "B.Cu")
		(net "BMC_RXD5")
	)
	(segment
		(start 330.857352 -171.935648)
		(end 326.748648 -171.935648)
		(width 0.1143)
		(layer "B.Cu")
		(net "BMC_RXD5")
	)
	(segment
		(start 322.56095 -134.498842)
		(end 322.226432 -134.164324)
		(width 0.1143)
		(layer "B.Cu")
		(net "BMC_RXD5")
	)
	(segment
		(start 325.10095 -171.72305)
		(end 324.612 -172.212)
		(width 0.1143)
		(layer "B.Cu")
		(net "BMC_RXD5")
	)
	(segment
		(start 303.200054 -119.690896)
		(end 303.1998 -119.69115)
		(width 0.1143)
		(layer "B.Cu")
		(net "BMC_RXD5")
	)
	(segment
		(start 303.1998 -119.69115)
		(end 295.008554 -119.69115)
		(width 0.1143)
		(layer "B.Cu")
		(net "BMC_RXD5")
	)
	(segment
		(start 331.9145 -170.8785)
		(end 330.857352 -171.935648)
		(width 0.1143)
		(layer "B.Cu")
		(net "BMC_RXD5")
	)
	(segment
		(start 333.08671 -170.8785)
		(end 331.9145 -170.8785)
		(width 0.1143)
		(layer "B.Cu")
		(net "BMC_RXD5")
	)
	(segment
		(start 304.619914 -119.690896)
		(end 303.200054 -119.690896)
		(width 0.1143)
		(layer "B.Cu")
		(net "BMC_RXD5")
	)
	(segment
		(start 294.748204 -119.9515)
		(end 274.2311 -119.9515)
		(width 0.1143)
		(layer "B.Cu")
		(net "BMC_RXD5")
	)
	(segment
		(start 272.82775 -118.54815)
		(end 253.25705 -118.54815)
		(width 0.1143)
		(layer "B.Cu")
		(net "BMC_RXD5")
	)
	(segment
		(start 322.226432 -134.164324)
		(end 322.226178 -134.164324)
		(width 0.1143)
		(layer "B.Cu")
		(net "BMC_RXD5")
	)
	(segment
		(start 319.056004 -130.99415)
		(end 317.15202 -130.99415)
		(width 0.1143)
		(layer "B.Cu")
		(net "BMC_RXD5")
	)
	(segment
		(start 322.072 -142.078456)
		(end 322.56095 -141.589506)
		(width 0.1143)
		(layer "B.Cu")
		(net "BMC_RXD5")
	)
	(segment
		(start 322.56095 -151.926544)
		(end 322.072 -151.437594)
		(width 0.1143)
		(layer "B.Cu")
		(net "BMC_RXD5")
	)
	(segment
		(start 305.84902 -119.69115)
		(end 304.620168 -119.69115)
		(width 0.1143)
		(layer "B.Cu")
		(net "BMC_RXD5")
	)
	(segment
		(start 320.990468 -172.212)
		(end 320.832734 -172.369734)
		(width 0.1143)
		(layer "B.Cu")
		(net "BMC_RXD5")
	)
	(segment
		(start 324.612 -172.212)
		(end 320.990468 -172.212)
		(width 0.1143)
		(layer "B.Cu")
		(net "BMC_RXD5")
	)
	(segment
		(start 317.15202 -130.99415)
		(end 305.84902 -119.69115)
		(width 0.1143)
		(layer "B.Cu")
		(net "BMC_RXD5")
	)
	(segment
		(start 253.25705 -118.54815)
		(end 253.21514 -118.50624)
		(width 0.1143)
		(layer "B.Cu")
		(net "BMC_RXD5")
	)
	(segment
		(start 326.748648 -171.935648)
		(end 326.53605 -171.72305)
		(width 0.1143)
		(layer "B.Cu")
		(net "BMC_RXD5")
	)
	(segment
		(start 322.834 -156.845)
		(end 322.56095 -156.57195)
		(width 0.1143)
		(layer "B.Cu")
		(net "BMC_RXD5")
	)
	(segment
		(start 326.53605 -171.72305)
		(end 325.10095 -171.72305)
		(width 0.1143)
		(layer "B.Cu")
		(net "BMC_RXD5")
	)
	(segment
		(start 54.289198 -170.1165)
		(end 38.353492 -154.180794)
		(width 0.127)
		(layer "In2.Cu")
		(net "BMC_RXD5")
	)
	(segment
		(start 47.816516 -116.7384)
		(end 48.400716 -116.1542)
		(width 0.127)
		(layer "In2.Cu")
		(net "BMC_RXD5")
	)
	(segment
		(start 322.0593 -169.9387)
		(end 322.0593 -168.9227)
		(width 0.127)
		(layer "In2.Cu")
		(net "BMC_RXD5")
	)
	(segment
		(start 247.65 -178.054)
		(end 247.4595 -177.8635)
		(width 0.127)
		(layer "In2.Cu")
		(net "BMC_RXD5")
	)
	(segment
		(start 96.8375 -170.1165)
		(end 54.289198 -170.1165)
		(width 0.127)
		(layer "In2.Cu")
		(net "BMC_RXD5")
	)
	(segment
		(start 36.703 -140.462)
		(end 36.703 -118.745)
		(width 0.127)
		(layer "In2.Cu")
		(net "BMC_RXD5")
	)
	(segment
		(start 322.707254 -156.971746)
		(end 322.834 -156.845)
		(width 0.127)
		(layer "In2.Cu")
		(net "BMC_RXD5")
	)
	(segment
		(start 99.314 -172.593)
		(end 96.8375 -170.1165)
		(width 0.127)
		(layer "In2.Cu")
		(net "BMC_RXD5")
	)
	(segment
		(start 36.703 -118.745)
		(end 38.989 -116.459)
		(width 0.127)
		(layer "In2.Cu")
		(net "BMC_RXD5")
	)
	(segment
		(start 208.660238 -177.8635)
		(end 205.358238 -181.1655)
		(width 0.127)
		(layer "In2.Cu")
		(net "BMC_RXD5")
	)
	(segment
		(start 46.6852 -116.459)
		(end 46.9646 -116.7384)
		(width 0.127)
		(layer "In2.Cu")
		(net "BMC_RXD5")
	)
	(segment
		(start 164.211 -172.593)
		(end 99.314 -172.593)
		(width 0.127)
		(layer "In2.Cu")
		(net "BMC_RXD5")
	)
	(segment
		(start 247.4595 -177.8635)
		(end 208.660238 -177.8635)
		(width 0.127)
		(layer "In2.Cu")
		(net "BMC_RXD5")
	)
	(segment
		(start 205.358238 -181.1655)
		(end 197.96125 -181.1655)
		(width 0.127)
		(layer "In2.Cu")
		(net "BMC_RXD5")
	)
	(segment
		(start 38.353492 -142.112492)
		(end 36.703 -140.462)
		(width 0.127)
		(layer "In2.Cu")
		(net "BMC_RXD5")
	)
	(segment
		(start 320.832734 -171.165266)
		(end 322.0593 -169.9387)
		(width 0.127)
		(layer "In2.Cu")
		(net "BMC_RXD5")
	)
	(segment
		(start 320.832734 -172.369734)
		(end 320.832734 -171.165266)
		(width 0.127)
		(layer "In2.Cu")
		(net "BMC_RXD5")
	)
	(segment
		(start 197.96125 -181.1655)
		(end 197.51675 -180.721)
		(width 0.127)
		(layer "In2.Cu")
		(net "BMC_RXD5")
	)
	(segment
		(start 322.707254 -163.449254)
		(end 322.707254 -156.971746)
		(width 0.127)
		(layer "In2.Cu")
		(net "BMC_RXD5")
	)
	(segment
		(start 197.51675 -180.721)
		(end 172.339 -180.721)
		(width 0.127)
		(layer "In2.Cu")
		(net "BMC_RXD5")
	)
	(segment
		(start 38.353492 -154.180794)
		(end 38.353492 -142.112492)
		(width 0.127)
		(layer "In2.Cu")
		(net "BMC_RXD5")
	)
	(segment
		(start 48.400716 -116.1542)
		(end 48.7172 -116.1542)
		(width 0.127)
		(layer "In2.Cu")
		(net "BMC_RXD5")
	)
	(segment
		(start 323.35597 -167.62603)
		(end 323.35597 -164.09797)
		(width 0.127)
		(layer "In2.Cu")
		(net "BMC_RXD5")
	)
	(segment
		(start 46.9646 -116.7384)
		(end 47.816516 -116.7384)
		(width 0.127)
		(layer "In2.Cu")
		(net "BMC_RXD5")
	)
	(segment
		(start 323.35597 -164.09797)
		(end 322.707254 -163.449254)
		(width 0.127)
		(layer "In2.Cu")
		(net "BMC_RXD5")
	)
	(segment
		(start 38.989 -116.459)
		(end 46.6852 -116.459)
		(width 0.127)
		(layer "In2.Cu")
		(net "BMC_RXD5")
	)
	(segment
		(start 172.339 -180.721)
		(end 164.211 -172.593)
		(width 0.127)
		(layer "In2.Cu")
		(net "BMC_RXD5")
	)
	(segment
		(start 322.0593 -168.9227)
		(end 323.35597 -167.62603)
		(width 0.127)
		(layer "In2.Cu")
		(net "BMC_RXD5")
	)
	(segment
		(start 248.9073 -123.54814)
		(end 248.9073 -176.0347)
		(width 0.127)
		(layer "In5.Cu")
		(net "BMC_RXD5")
	)
	(segment
		(start 253.21514 -118.50624)
		(end 253.21514 -119.2403)
		(width 0.127)
		(layer "In5.Cu")
		(net "BMC_RXD5")
	)
	(segment
		(start 253.21514 -119.2403)
		(end 248.9073 -123.54814)
		(width 0.127)
		(layer "In5.Cu")
		(net "BMC_RXD5")
	)
	(segment
		(start 248.9073 -176.0347)
		(end 247.65 -177.292)
		(width 0.127)
		(layer "In5.Cu")
		(net "BMC_RXD5")
	)
	(segment
		(start 247.65 -177.292)
		(end 247.65 -178.054)
		(width 0.127)
		(layer "In5.Cu")
		(net "BMC_RXD5")
	)
	(segment
		(start 88.138 -241.9985)
		(end 89.2175 -241.173)
		(width 0.1143)
		(layer "F.Cu")
		(net "SAS_FAULT_LED12")
	)
	(segment
		(start 88.011 -231.3305)
		(end 88.011 -231.267)
		(width 0.1143)
		(layer "F.Cu")
		(net "SAS_FAULT_LED12")
	)
	(segment
		(start 89.2175 -238.5695)
		(end 91.186 -236.601)
		(width 0.1143)
		(layer "F.Cu")
		(net "SAS_FAULT_LED12")
	)
	(segment
		(start 89.2175 -239.3442)
		(end 89.2175 -238.5695)
		(width 0.1143)
		(layer "F.Cu")
		(net "SAS_FAULT_LED12")
	)
	(segment
		(start 89.2175 -241.173)
		(end 89.2175 -239.3442)
		(width 0.1143)
		(layer "F.Cu")
		(net "SAS_FAULT_LED12")
	)
	(segment
		(start 90.958924 -230.0478)
		(end 91.263724 -229.743)
		(width 0.1143)
		(layer "F.Cu")
		(net "SAS_FAULT_LED12")
	)
	(segment
		(start 98.933 -245.237)
		(end 97.663 -245.237)
		(width 0.1143)
		(layer "F.Cu")
		(net "SAS_FAULT_LED12")
	)
	(segment
		(start 91.263724 -229.743)
		(end 91.948 -229.743)
		(width 0.1143)
		(layer "F.Cu")
		(net "SAS_FAULT_LED12")
	)
	(segment
		(start 103.999792 -256.25044)
		(end 103.999792 -252.589792)
		(width 0.1143)
		(layer "F.Cu")
		(net "SAS_FAULT_LED12")
	)
	(segment
		(start 88.011 -231.267)
		(end 89.2302 -230.0478)
		(width 0.1143)
		(layer "F.Cu")
		(net "SAS_FAULT_LED12")
	)
	(segment
		(start 95.631 -243.967)
		(end 95.504 -243.84)
		(width 0.1143)
		(layer "F.Cu")
		(net "SAS_FAULT_LED12")
	)
	(segment
		(start 96.393 -243.967)
		(end 95.631 -243.967)
		(width 0.1143)
		(layer "F.Cu")
		(net "SAS_FAULT_LED12")
	)
	(segment
		(start 97.663 -245.237)
		(end 96.393 -243.967)
		(width 0.1143)
		(layer "F.Cu")
		(net "SAS_FAULT_LED12")
	)
	(segment
		(start 89.2302 -230.0478)
		(end 90.958924 -230.0478)
		(width 0.1143)
		(layer "F.Cu")
		(net "SAS_FAULT_LED12")
	)
	(segment
		(start 102.362 -250.952)
		(end 102.362 -248.666)
		(width 0.1143)
		(layer "F.Cu")
		(net "SAS_FAULT_LED12")
	)
	(segment
		(start 102.362 -248.666)
		(end 98.933 -245.237)
		(width 0.1143)
		(layer "F.Cu")
		(net "SAS_FAULT_LED12")
	)
	(segment
		(start 103.999792 -252.589792)
		(end 102.362 -250.952)
		(width 0.1143)
		(layer "F.Cu")
		(net "SAS_FAULT_LED12")
	)
	(via
		(at 95.504 -243.84)
		(size 0.5588)
		(drill 0.3048)
		(layers "F.Cu" "B.Cu")
		(net "SAS_FAULT_LED12")
	)
	(via
		(at 91.694 -235.07446)
		(size 0.7112)
		(drill 0.3556)
		(layers "F.Cu" "B.Cu")
		(net "SAS_FAULT_LED12")
	)
	(via
		(at 91.948 -229.743)
		(size 0.5588)
		(drill 0.3048)
		(layers "F.Cu" "B.Cu")
		(net "SAS_FAULT_LED12")
	)
	(via
		(at 91.186 -236.601)
		(size 0.5588)
		(drill 0.3048)
		(layers "F.Cu" "B.Cu")
		(net "SAS_FAULT_LED12")
	)
	(segment
		(start 91.186 -236.601)
		(end 91.694 -236.093)
		(width 0.1143)
		(layer "B.Cu")
		(net "SAS_FAULT_LED12")
	)
	(segment
		(start 91.821 -234.94746)
		(end 91.821 -229.87)
		(width 0.1143)
		(layer "B.Cu")
		(net "SAS_FAULT_LED12")
	)
	(segment
		(start 91.694 -235.07446)
		(end 91.821 -234.94746)
		(width 0.1143)
		(layer "B.Cu")
		(net "SAS_FAULT_LED12")
	)
	(segment
		(start 91.567 -238.379)
		(end 95.504 -242.316)
		(width 0.1143)
		(layer "B.Cu")
		(net "SAS_FAULT_LED12")
	)
	(segment
		(start 91.186 -236.601)
		(end 91.567 -236.982)
		(width 0.1143)
		(layer "B.Cu")
		(net "SAS_FAULT_LED12")
	)
	(segment
		(start 91.567 -236.982)
		(end 91.567 -238.379)
		(width 0.1143)
		(layer "B.Cu")
		(net "SAS_FAULT_LED12")
	)
	(segment
		(start 91.694 -236.093)
		(end 91.694 -235.07446)
		(width 0.1143)
		(layer "B.Cu")
		(net "SAS_FAULT_LED12")
	)
	(segment
		(start 91.821 -229.87)
		(end 91.948 -229.743)
		(width 0.1143)
		(layer "B.Cu")
		(net "SAS_FAULT_LED12")
	)
	(segment
		(start 95.504 -242.316)
		(end 95.504 -243.84)
		(width 0.1143)
		(layer "B.Cu")
		(net "SAS_FAULT_LED12")
	)
	(segment
		(start 127.5334 -150.19274)
		(end 127.5334 -118.185946)
		(width 0.1016)
		(layer "F.Cu")
		(net "SAS_EXP_GF_TX_DP1")
	)
	(segment
		(start 143.758412 -250.248166)
		(end 143.758412 -249.943366)
		(width 0.1016)
		(layer "F.Cu")
		(net "SAS_EXP_GF_TX_DP1")
	)
	(segment
		(start 143.997172 -243.360448)
		(end 143.997172 -243.055648)
		(width 0.1016)
		(layer "F.Cu")
		(net "SAS_EXP_GF_TX_DP1")
	)
	(segment
		(start 143.997172 -244.925088)
		(end 143.997172 -244.620288)
		(width 0.1016)
		(layer "F.Cu")
		(net "SAS_EXP_GF_TX_DP1")
	)
	(segment
		(start 143.758412 -244.142768)
		(end 143.758412 -243.837968)
		(width 0.1016)
		(layer "F.Cu")
		(net "SAS_EXP_GF_TX_DP1")
	)
	(segment
		(start 143.997172 -241.795808)
		(end 143.997172 -241.491008)
		(width 0.1016)
		(layer "F.Cu")
		(net "SAS_EXP_GF_TX_DP1")
	)
	(segment
		(start 127.874522 -117.362478)
		(end 134.359904 -110.877096)
		(width 0.1016)
		(layer "F.Cu")
		(net "SAS_EXP_GF_TX_DP1")
	)
	(segment
		(start 143.999712 -256.25044)
		(end 143.999712 -254.268478)
		(width 0.1016)
		(layer "F.Cu")
		(net "SAS_EXP_GF_TX_DP1")
	)
	(segment
		(start 143.758412 -253.686056)
		(end 143.758412 -251.508006)
		(width 0.1016)
		(layer "F.Cu")
		(net "SAS_EXP_GF_TX_DP1")
	)
	(segment
		(start 143.758412 -234.17149)
		(end 143.758666 -234.171744)
		(width 0.1016)
		(layer "F.Cu")
		(net "SAS_EXP_GF_TX_DP1")
	)
	(segment
		(start 143.758412 -242.578128)
		(end 143.758412 -242.273328)
		(width 0.1016)
		(layer "F.Cu")
		(net "SAS_EXP_GF_TX_DP1")
	)
	(segment
		(start 143.758412 -248.683526)
		(end 143.758412 -245.402608)
		(width 0.1016)
		(layer "F.Cu")
		(net "SAS_EXP_GF_TX_DP1")
	)
	(segment
		(start 135.00227 -109.325918)
		(end 135.00227 -99.422712)
		(width 0.1016)
		(layer "F.Cu")
		(net "SAS_EXP_GF_TX_DP1")
	)
	(segment
		(start 144.131792 -233.270552)
		(end 144.178782 -233.223562)
		(width 0.1016)
		(layer "F.Cu")
		(net "SAS_EXP_GF_TX_DP1")
	)
	(segment
		(start 143.758412 -241.013488)
		(end 143.758412 -234.17149)
		(width 0.1016)
		(layer "F.Cu")
		(net "SAS_EXP_GF_TX_DP1")
	)
	(segment
		(start 143.997172 -251.030486)
		(end 143.997172 -250.725686)
		(width 0.1016)
		(layer "F.Cu")
		(net "SAS_EXP_GF_TX_DP1")
	)
	(segment
		(start 144.821656 -231.678734)
		(end 144.821656 -169.371772)
		(width 0.1016)
		(layer "F.Cu")
		(net "SAS_EXP_GF_TX_DP1")
	)
	(segment
		(start 143.997172 -249.465846)
		(end 143.997172 -249.161046)
		(width 0.1016)
		(layer "F.Cu")
		(net "SAS_EXP_GF_TX_DP1")
	)
	(segment
		(start 143.886428 -167.113204)
		(end 127.934466 -151.161496)
		(width 0.1016)
		(layer "F.Cu")
		(net "SAS_EXP_GF_TX_DP1")
	)
	(arc
		(start 143.997172 -241.491008)
		(mid 143.96668 -241.357015)
		(end 143.877792 -241.252248)
		(width 0.1016)
		(layer "F.Cu")
		(net "SAS_EXP_GF_TX_DP1")
	)
	(arc
		(start 143.758412 -249.943366)
		(mid 143.788904 -249.809373)
		(end 143.877792 -249.704606)
		(width 0.1016)
		(layer "F.Cu")
		(net "SAS_EXP_GF_TX_DP1")
	)
	(arc
		(start 143.997172 -243.055648)
		(mid 143.96668 -242.921655)
		(end 143.877792 -242.816888)
		(width 0.1016)
		(layer "F.Cu")
		(net "SAS_EXP_GF_TX_DP1")
	)
	(arc
		(start 134.359904 -110.877096)
		(mid 134.835355 -110.165394)
		(end 135.00227 -109.325918)
		(width 0.1016)
		(layer "F.Cu")
		(net "SAS_EXP_GF_TX_DP1")
	)
	(arc
		(start 143.999712 -254.268478)
		(mid 143.966708 -254.102555)
		(end 143.872712 -253.9619)
		(width 0.1016)
		(layer "F.Cu")
		(net "SAS_EXP_GF_TX_DP1")
	)
	(arc
		(start 143.877792 -245.163848)
		(mid 143.96668 -245.059053)
		(end 143.997172 -244.925088)
		(width 0.1016)
		(layer "F.Cu")
		(net "SAS_EXP_GF_TX_DP1")
	)
	(arc
		(start 143.877792 -242.034568)
		(mid 143.96668 -241.929773)
		(end 143.997172 -241.795808)
		(width 0.1016)
		(layer "F.Cu")
		(net "SAS_EXP_GF_TX_DP1")
	)
	(arc
		(start 143.877792 -249.704606)
		(mid 143.96668 -249.599811)
		(end 143.997172 -249.465846)
		(width 0.1016)
		(layer "F.Cu")
		(net "SAS_EXP_GF_TX_DP1")
	)
	(arc
		(start 143.877792 -242.816888)
		(mid 143.788904 -242.712093)
		(end 143.758412 -242.578128)
		(width 0.1016)
		(layer "F.Cu")
		(net "SAS_EXP_GF_TX_DP1")
	)
	(arc
		(start 143.877792 -250.486926)
		(mid 143.788904 -250.382131)
		(end 143.758412 -250.248166)
		(width 0.1016)
		(layer "F.Cu")
		(net "SAS_EXP_GF_TX_DP1")
	)
	(arc
		(start 144.465294 -167.905176)
		(mid 144.206453 -167.486829)
		(end 143.886428 -167.113204)
		(width 0.1016)
		(layer "F.Cu")
		(net "SAS_EXP_GF_TX_DP1")
	)
	(arc
		(start 143.997172 -249.161046)
		(mid 143.96668 -249.027053)
		(end 143.877792 -248.922286)
		(width 0.1016)
		(layer "F.Cu")
		(net "SAS_EXP_GF_TX_DP1")
	)
	(arc
		(start 143.758412 -243.837968)
		(mid 143.788904 -243.703975)
		(end 143.877792 -243.599208)
		(width 0.1016)
		(layer "F.Cu")
		(net "SAS_EXP_GF_TX_DP1")
	)
	(arc
		(start 143.877792 -244.381528)
		(mid 143.788904 -244.276733)
		(end 143.758412 -244.142768)
		(width 0.1016)
		(layer "F.Cu")
		(net "SAS_EXP_GF_TX_DP1")
	)
	(arc
		(start 143.768064 -253.772924)
		(mid 143.760785 -253.729762)
		(end 143.758412 -253.686056)
		(width 0.1016)
		(layer "F.Cu")
		(net "SAS_EXP_GF_TX_DP1")
	)
	(arc
		(start 135.00227 -99.422712)
		(mid 135.03858 -99.240167)
		(end 135.14197 -99.0854)
		(width 0.1016)
		(layer "F.Cu")
		(net "SAS_EXP_GF_TX_DP1")
	)
	(arc
		(start 127.57023 -117.895624)
		(mid 127.686626 -117.608649)
		(end 127.874522 -117.362478)
		(width 0.1016)
		(layer "F.Cu")
		(net "SAS_EXP_GF_TX_DP1")
	)
	(arc
		(start 143.758666 -234.171744)
		(mid 143.85557 -233.684016)
		(end 144.131792 -233.270552)
		(width 0.1016)
		(layer "F.Cu")
		(net "SAS_EXP_GF_TX_DP1")
	)
	(arc
		(start 143.758412 -245.402608)
		(mid 143.788904 -245.268615)
		(end 143.877792 -245.163848)
		(width 0.1016)
		(layer "F.Cu")
		(net "SAS_EXP_GF_TX_DP1")
	)
	(arc
		(start 143.758412 -251.508006)
		(mid 143.788904 -251.374013)
		(end 143.877792 -251.269246)
		(width 0.1016)
		(layer "F.Cu")
		(net "SAS_EXP_GF_TX_DP1")
	)
	(arc
		(start 143.802354 -253.865888)
		(mid 143.782254 -253.820497)
		(end 143.768064 -253.772924)
		(width 0.1016)
		(layer "F.Cu")
		(net "SAS_EXP_GF_TX_DP1")
	)
	(arc
		(start 143.877792 -251.269246)
		(mid 143.96668 -251.164451)
		(end 143.997172 -251.030486)
		(width 0.1016)
		(layer "F.Cu")
		(net "SAS_EXP_GF_TX_DP1")
	)
	(arc
		(start 143.877792 -243.599208)
		(mid 143.96668 -243.494413)
		(end 143.997172 -243.360448)
		(width 0.1016)
		(layer "F.Cu")
		(net "SAS_EXP_GF_TX_DP1")
	)
	(arc
		(start 144.819624 -231.769412)
		(mid 144.821146 -231.724084)
		(end 144.821656 -231.678734)
		(width 0.1016)
		(layer "F.Cu")
		(net "SAS_EXP_GF_TX_DP1")
	)
	(arc
		(start 143.997172 -250.725686)
		(mid 143.96668 -250.591693)
		(end 143.877792 -250.486926)
		(width 0.1016)
		(layer "F.Cu")
		(net "SAS_EXP_GF_TX_DP1")
	)
	(arc
		(start 143.872712 -253.9619)
		(mid 143.833858 -253.916588)
		(end 143.802354 -253.865888)
		(width 0.1016)
		(layer "F.Cu")
		(net "SAS_EXP_GF_TX_DP1")
	)
	(arc
		(start 143.877792 -248.922286)
		(mid 143.788904 -248.817491)
		(end 143.758412 -248.683526)
		(width 0.1016)
		(layer "F.Cu")
		(net "SAS_EXP_GF_TX_DP1")
	)
	(arc
		(start 144.178782 -233.223562)
		(mid 144.635383 -232.556501)
		(end 144.819624 -231.769412)
		(width 0.1016)
		(layer "F.Cu")
		(net "SAS_EXP_GF_TX_DP1")
	)
	(arc
		(start 143.997172 -244.620288)
		(mid 143.96668 -244.486295)
		(end 143.877792 -244.381528)
		(width 0.1016)
		(layer "F.Cu")
		(net "SAS_EXP_GF_TX_DP1")
	)
	(arc
		(start 143.877792 -241.252248)
		(mid 143.788904 -241.147453)
		(end 143.758412 -241.013488)
		(width 0.1016)
		(layer "F.Cu")
		(net "SAS_EXP_GF_TX_DP1")
	)
	(arc
		(start 144.821656 -169.371772)
		(mid 144.73135 -168.617121)
		(end 144.465294 -167.905176)
		(width 0.1016)
		(layer "F.Cu")
		(net "SAS_EXP_GF_TX_DP1")
	)
	(arc
		(start 127.934466 -151.161496)
		(mid 127.637564 -150.717012)
		(end 127.5334 -150.19274)
		(width 0.1016)
		(layer "F.Cu")
		(net "SAS_EXP_GF_TX_DP1")
	)
	(arc
		(start 127.5334 -118.185946)
		(mid 127.542661 -118.039624)
		(end 127.57023 -117.895624)
		(width 0.1016)
		(layer "F.Cu")
		(net "SAS_EXP_GF_TX_DP1")
	)
	(arc
		(start 143.758412 -242.273328)
		(mid 143.788904 -242.139335)
		(end 143.877792 -242.034568)
		(width 0.1016)
		(layer "F.Cu")
		(net "SAS_EXP_GF_TX_DP1")
	)
	(segment
		(start 300.225968 -162.5219)
		(end 301.0281 -162.5219)
		(width 0.127)
		(layer "F.Cu")
		(net "TP_GPIOH6")
	)
	(segment
		(start 298.196 -164.551868)
		(end 300.225968 -162.5219)
		(width 0.127)
		(layer "F.Cu")
		(net "TP_GPIOH6")
	)
	(segment
		(start 297.634914 -167.440102)
		(end 297.634914 -165.777418)
		(width 0.127)
		(layer "F.Cu")
		(net "TP_GPIOH6")
	)
	(segment
		(start 297.634914 -165.777418)
		(end 298.196 -165.216332)
		(width 0.127)
		(layer "F.Cu")
		(net "TP_GPIOH6")
	)
	(segment
		(start 298.196 -165.216332)
		(end 298.196 -164.551868)
		(width 0.127)
		(layer "F.Cu")
		(net "TP_GPIOH6")
	)
	(segment
		(start 301.0281 -162.5219)
		(end 301.117 -162.433)
		(width 0.127)
		(layer "F.Cu")
		(net "TP_GPIOH6")
	)
	(segment
		(start 89.8525 -239.3442)
		(end 89.8525 -238.5695)
		(width 0.1143)
		(layer "F.Cu")
		(net "SAS_FAULT_LED13")
	)
	(segment
		(start 89.154 -231.3305)
		(end 89.154 -231.267)
		(width 0.1143)
		(layer "F.Cu")
		(net "SAS_FAULT_LED13")
	)
	(segment
		(start 97.282 -245.618)
		(end 96.393 -244.729)
		(width 0.1143)
		(layer "F.Cu")
		(net "SAS_FAULT_LED13")
	)
	(segment
		(start 89.8525 -241.681)
		(end 89.8525 -239.3442)
		(width 0.1143)
		(layer "F.Cu")
		(net "SAS_FAULT_LED13")
	)
	(segment
		(start 101.981 -251.206)
		(end 101.981 -248.92)
		(width 0.1143)
		(layer "F.Cu")
		(net "SAS_FAULT_LED13")
	)
	(segment
		(start 89.8525 -238.5695)
		(end 91.059 -237.363)
		(width 0.1143)
		(layer "F.Cu")
		(net "SAS_FAULT_LED13")
	)
	(segment
		(start 98.679 -245.618)
		(end 97.282 -245.618)
		(width 0.1143)
		(layer "F.Cu")
		(net "SAS_FAULT_LED13")
	)
	(segment
		(start 89.90965 -230.51135)
		(end 92.258388 -230.51135)
		(width 0.1143)
		(layer "F.Cu")
		(net "SAS_FAULT_LED13")
	)
	(segment
		(start 103.000302 -252.225302)
		(end 101.981 -251.206)
		(width 0.1143)
		(layer "F.Cu")
		(net "SAS_FAULT_LED13")
	)
	(segment
		(start 101.981 -248.92)
		(end 98.679 -245.618)
		(width 0.1143)
		(layer "F.Cu")
		(net "SAS_FAULT_LED13")
	)
	(segment
		(start 103.000302 -256.25044)
		(end 103.000302 -252.225302)
		(width 0.1143)
		(layer "F.Cu")
		(net "SAS_FAULT_LED13")
	)
	(segment
		(start 91.694 -237.363)
		(end 92.202 -236.855)
		(width 0.1143)
		(layer "F.Cu")
		(net "SAS_FAULT_LED13")
	)
	(segment
		(start 89.154 -231.267)
		(end 89.90965 -230.51135)
		(width 0.1143)
		(layer "F.Cu")
		(net "SAS_FAULT_LED13")
	)
	(segment
		(start 92.202 -236.855)
		(end 92.202 -236.601)
		(width 0.1143)
		(layer "F.Cu")
		(net "SAS_FAULT_LED13")
	)
	(segment
		(start 92.258388 -230.51135)
		(end 92.32392 -230.576882)
		(width 0.1143)
		(layer "F.Cu")
		(net "SAS_FAULT_LED13")
	)
	(segment
		(start 89.281 -241.9985)
		(end 89.8525 -241.681)
		(width 0.1143)
		(layer "F.Cu")
		(net "SAS_FAULT_LED13")
	)
	(segment
		(start 91.059 -237.363)
		(end 91.694 -237.363)
		(width 0.1143)
		(layer "F.Cu")
		(net "SAS_FAULT_LED13")
	)
	(via
		(at 92.202 -236.601)
		(size 0.5588)
		(drill 0.3048)
		(layers "F.Cu" "B.Cu")
		(net "SAS_FAULT_LED13")
	)
	(via
		(at 96.393 -244.729)
		(size 0.508)
		(drill 0.254)
		(layers "F.Cu" "B.Cu")
		(net "SAS_FAULT_LED13")
	)
	(via
		(at 92.202 -237.744)
		(size 0.7112)
		(drill 0.3556)
		(layers "F.Cu" "B.Cu")
		(net "SAS_FAULT_LED13")
	)
	(via
		(at 92.32392 -230.576882)
		(size 0.5588)
		(drill 0.3048)
		(layers "F.Cu" "B.Cu")
		(net "SAS_FAULT_LED13")
	)
	(segment
		(start 92.32392 -230.805228)
		(end 92.32392 -230.576882)
		(width 0.1143)
		(layer "B.Cu")
		(net "SAS_FAULT_LED13")
	)
	(segment
		(start 92.202 -230.927148)
		(end 92.32392 -230.805228)
		(width 0.1143)
		(layer "B.Cu")
		(net "SAS_FAULT_LED13")
	)
	(segment
		(start 92.202 -237.744)
		(end 92.202 -238.379)
		(width 0.1143)
		(layer "B.Cu")
		(net "SAS_FAULT_LED13")
	)
	(segment
		(start 96.393 -242.57)
		(end 96.393 -244.729)
		(width 0.1143)
		(layer "B.Cu")
		(net "SAS_FAULT_LED13")
	)
	(segment
		(start 92.202 -234.823)
		(end 92.202 -230.927148)
		(width 0.1143)
		(layer "B.Cu")
		(net "SAS_FAULT_LED13")
	)
	(segment
		(start 92.202 -238.379)
		(end 96.393 -242.57)
		(width 0.1143)
		(layer "B.Cu")
		(net "SAS_FAULT_LED13")
	)
	(segment
		(start 92.202 -236.601)
		(end 92.202 -237.744)
		(width 0.1143)
		(layer "B.Cu")
		(net "SAS_FAULT_LED13")
	)
	(segment
		(start 92.583 -235.204)
		(end 92.202 -234.823)
		(width 0.1143)
		(layer "B.Cu")
		(net "SAS_FAULT_LED13")
	)
	(segment
		(start 92.202 -236.601)
		(end 92.583 -236.22)
		(width 0.1143)
		(layer "B.Cu")
		(net "SAS_FAULT_LED13")
	)
	(segment
		(start 92.583 -236.22)
		(end 92.583 -235.204)
		(width 0.1143)
		(layer "B.Cu")
		(net "SAS_FAULT_LED13")
	)
	(segment
		(start 134.65937 -109.325918)
		(end 134.65937 -99.453446)
		(width 0.1016)
		(layer "F.Cu")
		(net "SAS_EXP_GF_TX_DN1")
	)
	(segment
		(start 143.415512 -253.700026)
		(end 143.415512 -234.171744)
		(width 0.1016)
		(layer "F.Cu")
		(net "SAS_EXP_GF_TX_DN1")
	)
	(segment
		(start 143.108426 -253.9238)
		(end 143.21663 -253.9238)
		(width 0.1016)
		(layer "F.Cu")
		(net "SAS_EXP_GF_TX_DN1")
	)
	(segment
		(start 143.329914 -253.872746)
		(end 143.368268 -253.82982)
		(width 0.1016)
		(layer "F.Cu")
		(net "SAS_EXP_GF_TX_DN1")
	)
	(segment
		(start 143.40332 -167.11549)
		(end 127.691896 -151.404066)
		(width 0.1016)
		(layer "F.Cu")
		(net "SAS_EXP_GF_TX_DN1")
	)
	(segment
		(start 127.1905 -150.192486)
		(end 127.1905 -118.185692)
		(width 0.1016)
		(layer "F.Cu")
		(net "SAS_EXP_GF_TX_DN1")
	)
	(segment
		(start 127.631952 -117.119908)
		(end 134.117334 -110.634526)
		(width 0.1016)
		(layer "F.Cu")
		(net "SAS_EXP_GF_TX_DN1")
	)
	(segment
		(start 144.478756 -231.671114)
		(end 144.478756 -169.371772)
		(width 0.1016)
		(layer "F.Cu")
		(net "SAS_EXP_GF_TX_DN1")
	)
	(segment
		(start 143.000222 -256.25044)
		(end 143.000222 -254.062738)
		(width 0.1016)
		(layer "F.Cu")
		(net "SAS_EXP_GF_TX_DN1")
	)
	(segment
		(start 143.889222 -233.027982)
		(end 143.936212 -232.980992)
		(width 0.1016)
		(layer "F.Cu")
		(net "SAS_EXP_GF_TX_DN1")
	)
	(segment
		(start 143.643858 -167.355774)
		(end 143.40332 -167.11549)
		(width 0.1016)
		(layer "F.Cu")
		(net "SAS_EXP_GF_TX_DN1")
	)
	(arc
		(start 143.000222 -254.062738)
		(mid 143.012441 -254.001307)
		(end 143.047212 -253.9492)
		(width 0.1016)
		(layer "F.Cu")
		(net "SAS_EXP_GF_TX_DN1")
	)
	(arc
		(start 127.237998 -117.810026)
		(mid 127.388685 -117.438542)
		(end 127.631952 -117.119908)
		(width 0.1016)
		(layer "F.Cu")
		(net "SAS_EXP_GF_TX_DN1")
	)
	(arc
		(start 134.65937 -99.453446)
		(mid 134.619753 -99.25428)
		(end 134.50697 -99.0854)
		(width 0.1016)
		(layer "F.Cu")
		(net "SAS_EXP_GF_TX_DN1")
	)
	(arc
		(start 143.368268 -253.82982)
		(mid 143.403235 -253.76906)
		(end 143.415512 -253.700026)
		(width 0.1016)
		(layer "F.Cu")
		(net "SAS_EXP_GF_TX_DN1")
	)
	(arc
		(start 143.936212 -232.980992)
		(mid 144.337772 -232.380015)
		(end 144.478756 -231.671114)
		(width 0.1016)
		(layer "F.Cu")
		(net "SAS_EXP_GF_TX_DN1")
	)
	(arc
		(start 143.047212 -253.9492)
		(mid 143.075297 -253.930434)
		(end 143.108426 -253.9238)
		(width 0.1016)
		(layer "F.Cu")
		(net "SAS_EXP_GF_TX_DN1")
	)
	(arc
		(start 127.691896 -151.404066)
		(mid 127.320666 -150.848157)
		(end 127.1905 -150.192486)
		(width 0.1016)
		(layer "F.Cu")
		(net "SAS_EXP_GF_TX_DN1")
	)
	(arc
		(start 143.21663 -253.9238)
		(mid 143.278727 -253.910388)
		(end 143.329914 -253.872746)
		(width 0.1016)
		(layer "F.Cu")
		(net "SAS_EXP_GF_TX_DN1")
	)
	(arc
		(start 134.117334 -110.634526)
		(mid 134.518505 -110.034132)
		(end 134.65937 -109.325918)
		(width 0.1016)
		(layer "F.Cu")
		(net "SAS_EXP_GF_TX_DN1")
	)
	(arc
		(start 143.415512 -234.171744)
		(mid 143.538635 -233.552764)
		(end 143.889222 -233.027982)
		(width 0.1016)
		(layer "F.Cu")
		(net "SAS_EXP_GF_TX_DN1")
	)
	(arc
		(start 144.478756 -169.371772)
		(mid 144.261827 -168.280728)
		(end 143.643858 -167.355774)
		(width 0.1016)
		(layer "F.Cu")
		(net "SAS_EXP_GF_TX_DN1")
	)
	(arc
		(start 127.1905 -118.185692)
		(mid 127.202404 -117.996361)
		(end 127.237998 -117.810026)
		(width 0.1016)
		(layer "F.Cu")
		(net "SAS_EXP_GF_TX_DN1")
	)
	(segment
		(start 104.3305 -239.4712)
		(end 104.3305 -240.950496)
		(width 0.1143)
		(layer "F.Cu")
		(net "SAS_FAULT_LED5")
	)
	(segment
		(start 104.3305 -240.950496)
		(end 105.21061 -241.830606)
		(width 0.1143)
		(layer "F.Cu")
		(net "SAS_FAULT_LED5")
	)
	(via
		(at 105.156 -248.285)
		(size 0.7112)
		(drill 0.3556)
		(layers "F.Cu" "B.Cu")
		(net "SAS_FAULT_LED5")
	)
	(via
		(at 105.21061 -241.830606)
		(size 0.5588)
		(drill 0.3048)
		(layers "F.Cu" "B.Cu")
		(net "SAS_FAULT_LED5")
	)
	(segment
		(start 107.315 -239.268)
		(end 107.701842 -239.654842)
		(width 0.1143)
		(layer "B.Cu")
		(net "SAS_FAULT_LED5")
	)
	(segment
		(start 104.902 -239.8395)
		(end 104.902 -240.538)
		(width 0.1143)
		(layer "B.Cu")
		(net "SAS_FAULT_LED5")
	)
	(segment
		(start 107.025948 -241.830606)
		(end 105.21061 -241.830606)
		(width 0.1143)
		(layer "B.Cu")
		(net "SAS_FAULT_LED5")
	)
	(segment
		(start 103.4415 -231.013)
		(end 103.707184 -231.013)
		(width 0.1143)
		(layer "B.Cu")
		(net "SAS_FAULT_LED5")
	)
	(segment
		(start 103.000302 -256.50444)
		(end 103.000302 -254.250698)
		(width 0.1143)
		(layer "B.Cu")
		(net "SAS_FAULT_LED5")
	)
	(segment
		(start 107.315 -234.620816)
		(end 107.315 -239.268)
		(width 0.1143)
		(layer "B.Cu")
		(net "SAS_FAULT_LED5")
	)
	(segment
		(start 104.79405 -241.414046)
		(end 105.188004 -241.808)
		(width 0.1143)
		(layer "B.Cu")
		(net "SAS_FAULT_LED5")
	)
	(segment
		(start 104.902 -240.538)
		(end 104.79405 -240.64595)
		(width 0.1143)
		(layer "B.Cu")
		(net "SAS_FAULT_LED5")
	)
	(segment
		(start 103.77805 -246.90705)
		(end 103.77805 -242.240308)
		(width 0.1143)
		(layer "B.Cu")
		(net "SAS_FAULT_LED5")
	)
	(segment
		(start 107.701842 -239.654842)
		(end 107.701842 -241.154712)
		(width 0.1143)
		(layer "B.Cu")
		(net "SAS_FAULT_LED5")
	)
	(segment
		(start 107.701842 -241.154712)
		(end 107.025948 -241.830606)
		(width 0.1143)
		(layer "B.Cu")
		(net "SAS_FAULT_LED5")
	)
	(segment
		(start 105.188004 -241.808)
		(end 105.21061 -241.830606)
		(width 0.1143)
		(layer "B.Cu")
		(net "SAS_FAULT_LED5")
	)
	(segment
		(start 105.91165 -249.04065)
		(end 105.156 -248.285)
		(width 0.1143)
		(layer "B.Cu")
		(net "SAS_FAULT_LED5")
	)
	(segment
		(start 105.91165 -251.33935)
		(end 105.91165 -249.04065)
		(width 0.1143)
		(layer "B.Cu")
		(net "SAS_FAULT_LED5")
	)
	(segment
		(start 104.210358 -241.808)
		(end 105.188004 -241.808)
		(width 0.1143)
		(layer "B.Cu")
		(net "SAS_FAULT_LED5")
	)
	(segment
		(start 105.156 -248.285)
		(end 103.77805 -246.90705)
		(width 0.1143)
		(layer "B.Cu")
		(net "SAS_FAULT_LED5")
	)
	(segment
		(start 104.79405 -240.64595)
		(end 104.79405 -241.414046)
		(width 0.1143)
		(layer "B.Cu")
		(net "SAS_FAULT_LED5")
	)
	(segment
		(start 103.77805 -242.240308)
		(end 104.210358 -241.808)
		(width 0.1143)
		(layer "B.Cu")
		(net "SAS_FAULT_LED5")
	)
	(segment
		(start 103.000302 -254.250698)
		(end 105.91165 -251.33935)
		(width 0.1143)
		(layer "B.Cu")
		(net "SAS_FAULT_LED5")
	)
	(segment
		(start 103.707184 -231.013)
		(end 107.315 -234.620816)
		(width 0.1143)
		(layer "B.Cu")
		(net "SAS_FAULT_LED5")
	)
	(segment
		(start 86.999572 -256.25044)
		(end 86.999572 -254.28194)
		(width 0.1016)
		(layer "F.Cu")
		(net "SAS_EXP_GF_TX_DN11")
	)
	(segment
		(start 81.732628 -195.093082)
		(end 81.797652 -195.027804)
		(width 0.1016)
		(layer "F.Cu")
		(net "SAS_EXP_GF_TX_DN11")
	)
	(segment
		(start 108.85297 -114.658648)
		(end 108.85297 -114.5794)
		(width 0.1016)
		(layer "F.Cu")
		(net "SAS_EXP_GF_TX_DN11")
	)
	(segment
		(start 108.99902 -167.068754)
		(end 108.99902 -114.987578)
		(width 0.1016)
		(layer "F.Cu")
		(net "SAS_EXP_GF_TX_DN11")
	)
	(segment
		(start 108.926122 -114.811048)
		(end 108.909358 -114.794284)
		(width 0.1016)
		(layer "F.Cu")
		(net "SAS_EXP_GF_TX_DN11")
	)
	(segment
		(start 87.101172 -254.18034)
		(end 87.226902 -254.18034)
		(width 0.1016)
		(layer "F.Cu")
		(net "SAS_EXP_GF_TX_DN11")
	)
	(segment
		(start 86.933024 -251.53874)
		(end 81.536032 -246.141748)
		(width 0.1016)
		(layer "F.Cu")
		(net "SAS_EXP_GF_TX_DN11")
	)
	(segment
		(start 87.328502 -252.493018)
		(end 87.328248 -252.493272)
		(width 0.1016)
		(layer "F.Cu")
		(net "SAS_EXP_GF_TX_DN11")
	)
	(segment
		(start 80.772 -244.2972)
		(end 80.772 -197.412356)
		(width 0.1016)
		(layer "F.Cu")
		(net "SAS_EXP_GF_TX_DN11")
	)
	(segment
		(start 87.328502 -254.07874)
		(end 87.328502 -252.493018)
		(width 0.1016)
		(layer "F.Cu")
		(net "SAS_EXP_GF_TX_DN11")
	)
	(segment
		(start 81.797652 -195.027804)
		(end 108.463334 -168.362122)
		(width 0.1016)
		(layer "F.Cu")
		(net "SAS_EXP_GF_TX_DN11")
	)
	(arc
		(start 87.328248 -252.493272)
		(mid 87.225602 -251.976675)
		(end 86.933024 -251.53874)
		(width 0.1016)
		(layer "F.Cu")
		(net "SAS_EXP_GF_TX_DN11")
	)
	(arc
		(start 86.999572 -254.28194)
		(mid 87.02933 -254.210098)
		(end 87.101172 -254.18034)
		(width 0.1016)
		(layer "F.Cu")
		(net "SAS_EXP_GF_TX_DN11")
	)
	(arc
		(start 87.226902 -254.18034)
		(mid 87.298744 -254.150582)
		(end 87.328502 -254.07874)
		(width 0.1016)
		(layer "F.Cu")
		(net "SAS_EXP_GF_TX_DN11")
	)
	(arc
		(start 80.772 -197.412356)
		(mid 81.021706 -196.157203)
		(end 81.732628 -195.093082)
		(width 0.1016)
		(layer "F.Cu")
		(net "SAS_EXP_GF_TX_DN11")
	)
	(arc
		(start 81.536032 -246.141748)
		(mid 80.970616 -245.295448)
		(end 80.772 -244.2972)
		(width 0.1016)
		(layer "F.Cu")
		(net "SAS_EXP_GF_TX_DN11")
	)
	(arc
		(start 108.463334 -168.362122)
		(mid 108.859833 -167.76872)
		(end 108.99902 -167.068754)
		(width 0.1016)
		(layer "F.Cu")
		(net "SAS_EXP_GF_TX_DN11")
	)
	(arc
		(start 108.99902 -114.987578)
		(mid 108.980116 -114.892072)
		(end 108.926122 -114.811048)
		(width 0.1016)
		(layer "F.Cu")
		(net "SAS_EXP_GF_TX_DN11")
	)
	(arc
		(start 108.909358 -114.794284)
		(mid 108.867615 -114.732097)
		(end 108.85297 -114.658648)
		(width 0.1016)
		(layer "F.Cu")
		(net "SAS_EXP_GF_TX_DN11")
	)
	(segment
		(start 293.7256 -162.7759)
		(end 293.7256 -163.2204)
		(width 0.1143)
		(layer "F.Cu")
		(net "RMII0_BMC_C_PHY_TXD0")
	)
	(segment
		(start 293.7256 -163.2204)
		(end 293.37889 -163.56711)
		(width 0.1143)
		(layer "F.Cu")
		(net "RMII0_BMC_C_PHY_TXD0")
	)
	(segment
		(start 293.37889 -163.56711)
		(end 293.37889 -165.840918)
		(width 0.1143)
		(layer "F.Cu")
		(net "RMII0_BMC_C_PHY_TXD0")
	)
	(segment
		(start 293.189152 -168.478454)
		(end 292.834822 -168.832784)
		(width 0.1143)
		(layer "F.Cu")
		(net "RMII0_BMC_C_PHY_TXD0")
	)
	(segment
		(start 293.189152 -166.030656)
		(end 293.189152 -168.478454)
		(width 0.1143)
		(layer "F.Cu")
		(net "RMII0_BMC_C_PHY_TXD0")
	)
	(segment
		(start 293.37889 -165.840918)
		(end 293.189152 -166.030656)
		(width 0.1143)
		(layer "F.Cu")
		(net "RMII0_BMC_C_PHY_TXD0")
	)
	(segment
		(start 292.834822 -168.832784)
		(end 292.834822 -169.040048)
		(width 0.1143)
		(layer "F.Cu")
		(net "RMII0_BMC_C_PHY_TXD0")
	)
	(segment
		(start 294.513 -161.9885)
		(end 293.7256 -162.7759)
		(width 0.1143)
		(layer "F.Cu")
		(net "RMII0_BMC_C_PHY_TXD0")
	)
	(via
		(at 293.7256 -163.2204)
		(size 0.7112)
		(drill 0.3556)
		(layers "F.Cu" "B.Cu")
		(net "RMII0_BMC_C_PHY_TXD0")
	)
	(segment
		(start 92.38615 -231.694228)
		(end 92.709492 -232.01757)
		(width 0.1143)
		(layer "F.Cu")
		(net "SAS_FAULT_LED14")
	)
	(segment
		(start 91.186 -237.871)
		(end 92.329 -237.871)
		(width 0.1143)
		(layer "F.Cu")
		(net "SAS_FAULT_LED14")
	)
	(segment
		(start 90.4875 -238.5695)
		(end 91.186 -237.871)
		(width 0.1143)
		(layer "F.Cu")
		(net "SAS_FAULT_LED14")
	)
	(segment
		(start 90.4875 -242.189)
		(end 90.4875 -239.3442)
		(width 0.1143)
		(layer "F.Cu")
		(net "SAS_FAULT_LED14")
	)
	(segment
		(start 98.000312 -252.900688)
		(end 98.933 -251.968)
		(width 0.1143)
		(layer "F.Cu")
		(net "SAS_FAULT_LED14")
	)
	(segment
		(start 90.297 -231.3305)
		(end 90.506296 -231.3305)
		(width 0.1143)
		(layer "F.Cu")
		(net "SAS_FAULT_LED14")
	)
	(segment
		(start 90.957146 -230.87965)
		(end 91.609164 -230.87965)
		(width 0.1143)
		(layer "F.Cu")
		(net "SAS_FAULT_LED14")
	)
	(segment
		(start 92.38615 -231.656636)
		(end 92.38615 -231.694228)
		(width 0.1143)
		(layer "F.Cu")
		(net "SAS_FAULT_LED14")
	)
	(segment
		(start 93.07957 -232.01757)
		(end 93.726 -232.664)
		(width 0.1143)
		(layer "F.Cu")
		(net "SAS_FAULT_LED14")
	)
	(segment
		(start 91.609164 -230.87965)
		(end 92.38615 -231.656636)
		(width 0.1143)
		(layer "F.Cu")
		(net "SAS_FAULT_LED14")
	)
	(segment
		(start 92.709492 -232.01757)
		(end 93.07957 -232.01757)
		(width 0.1143)
		(layer "F.Cu")
		(net "SAS_FAULT_LED14")
	)
	(segment
		(start 98.000312 -256.25044)
		(end 98.000312 -252.900688)
		(width 0.1143)
		(layer "F.Cu")
		(net "SAS_FAULT_LED14")
	)
	(segment
		(start 90.424 -241.9985)
		(end 90.4875 -242.189)
		(width 0.1143)
		(layer "F.Cu")
		(net "SAS_FAULT_LED14")
	)
	(segment
		(start 90.4875 -239.3442)
		(end 90.4875 -238.5695)
		(width 0.1143)
		(layer "F.Cu")
		(net "SAS_FAULT_LED14")
	)
	(segment
		(start 93.726 -232.664)
		(end 93.782896 -232.664)
		(width 0.1143)
		(layer "F.Cu")
		(net "SAS_FAULT_LED14")
	)
	(segment
		(start 93.782896 -232.664)
		(end 93.812614 -232.693718)
		(width 0.1143)
		(layer "F.Cu")
		(net "SAS_FAULT_LED14")
	)
	(segment
		(start 92.329 -237.871)
		(end 93.472 -236.728)
		(width 0.1143)
		(layer "F.Cu")
		(net "SAS_FAULT_LED14")
	)
	(segment
		(start 90.506296 -231.3305)
		(end 90.957146 -230.87965)
		(width 0.1143)
		(layer "F.Cu")
		(net "SAS_FAULT_LED14")
	)
	(via
		(at 93.472 -236.728)
		(size 0.5588)
		(drill 0.3048)
		(layers "F.Cu" "B.Cu")
		(net "SAS_FAULT_LED14")
	)
	(via
		(at 98.933 -251.968)
		(size 0.508)
		(drill 0.254)
		(layers "F.Cu" "B.Cu")
		(net "SAS_FAULT_LED14")
	)
	(via
		(at 93.812614 -232.693718)
		(size 0.5588)
		(drill 0.3048)
		(layers "F.Cu" "B.Cu")
		(net "SAS_FAULT_LED14")
	)
	(via
		(at 95.758 -239.268)
		(size 0.7112)
		(drill 0.3556)
		(layers "F.Cu" "B.Cu")
		(net "SAS_FAULT_LED14")
	)
	(segment
		(start 95.758 -239.268)
		(end 95.758 -239.014)
		(width 0.1143)
		(layer "B.Cu")
		(net "SAS_FAULT_LED14")
	)
	(segment
		(start 97.91065 -242.30965)
		(end 97.91065 -245.72595)
		(width 0.1143)
		(layer "B.Cu")
		(net "SAS_FAULT_LED14")
	)
	(segment
		(start 98.933 -246.7483)
		(end 98.933 -251.968)
		(width 0.1143)
		(layer "B.Cu")
		(net "SAS_FAULT_LED14")
	)
	(segment
		(start 95.758 -240.157)
		(end 97.91065 -242.30965)
		(width 0.1143)
		(layer "B.Cu")
		(net "SAS_FAULT_LED14")
	)
	(segment
		(start 93.812614 -232.693718)
		(end 93.472 -233.034332)
		(width 0.1143)
		(layer "B.Cu")
		(net "SAS_FAULT_LED14")
	)
	(segment
		(start 97.91065 -245.72595)
		(end 98.933 -246.7483)
		(width 0.1143)
		(layer "B.Cu")
		(net "SAS_FAULT_LED14")
	)
	(segment
		(start 95.758 -239.014)
		(end 93.472 -236.728)
		(width 0.1143)
		(layer "B.Cu")
		(net "SAS_FAULT_LED14")
	)
	(segment
		(start 93.472 -233.034332)
		(end 93.472 -236.728)
		(width 0.1143)
		(layer "B.Cu")
		(net "SAS_FAULT_LED14")
	)
	(segment
		(start 95.758 -239.268)
		(end 95.758 -240.157)
		(width 0.1143)
		(layer "B.Cu")
		(net "SAS_FAULT_LED14")
	)
	(segment
		(start 109.34192 -167.068754)
		(end 109.34192 -114.961924)
		(width 0.1016)
		(layer "F.Cu")
		(net "SAS_EXP_GF_TX_DP11")
	)
	(segment
		(start 100.374196 -176.9364)
		(end 108.705904 -168.604692)
		(width 0.1016)
		(layer "F.Cu")
		(net "SAS_EXP_GF_TX_DP11")
	)
	(segment
		(start 81.975452 -195.335398)
		(end 82.04073 -195.269866)
		(width 0.1016)
		(layer "F.Cu")
		(net "SAS_EXP_GF_TX_DP11")
	)
	(segment
		(start 99.989894 -177.658268)
		(end 100.20554 -177.442876)
		(width 0.1016)
		(layer "F.Cu")
		(net "SAS_EXP_GF_TX_DP11")
	)
	(segment
		(start 98.161602 -179.148994)
		(end 98.376994 -178.933602)
		(width 0.1016)
		(layer "F.Cu")
		(net "SAS_EXP_GF_TX_DP11")
	)
	(segment
		(start 98.88347 -178.764692)
		(end 99.099116 -178.549046)
		(width 0.1016)
		(layer "F.Cu")
		(net "SAS_EXP_GF_TX_DP11")
	)
	(segment
		(start 81.1149 -244.296946)
		(end 81.1149 -197.41261)
		(width 0.1016)
		(layer "F.Cu")
		(net "SAS_EXP_GF_TX_DP11")
	)
	(segment
		(start 92.572332 -184.738264)
		(end 92.787724 -184.522872)
		(width 0.1016)
		(layer "F.Cu")
		(net "SAS_EXP_GF_TX_DP11")
	)
	(segment
		(start 86.982808 -190.327788)
		(end 90.57513 -186.735466)
		(width 0.1016)
		(layer "F.Cu")
		(net "SAS_EXP_GF_TX_DP11")
	)
	(segment
		(start 86.598506 -191.049656)
		(end 86.814152 -190.834264)
		(width 0.1016)
		(layer "F.Cu")
		(net "SAS_EXP_GF_TX_DP11")
	)
	(segment
		(start 91.465908 -185.844688)
		(end 91.6813 -185.629296)
		(width 0.1016)
		(layer "F.Cu")
		(net "SAS_EXP_GF_TX_DP11")
	)
	(segment
		(start 92.187776 -185.460386)
		(end 92.403422 -185.24474)
		(width 0.1016)
		(layer "F.Cu")
		(net "SAS_EXP_GF_TX_DP11")
	)
	(segment
		(start 82.04073 -195.269866)
		(end 84.985606 -192.32499)
		(width 0.1016)
		(layer "F.Cu")
		(net "SAS_EXP_GF_TX_DP11")
	)
	(segment
		(start 88.000332 -256.25044)
		(end 88.000332 -254.28194)
		(width 0.1016)
		(layer "F.Cu")
		(net "SAS_EXP_GF_TX_DP11")
	)
	(segment
		(start 109.48797 -114.609372)
		(end 109.48797 -114.5794)
		(width 0.1016)
		(layer "F.Cu")
		(net "SAS_EXP_GF_TX_DP11")
	)
	(segment
		(start 109.414564 -114.785902)
		(end 109.414818 -114.785648)
		(width 0.1016)
		(layer "F.Cu")
		(net "SAS_EXP_GF_TX_DP11")
	)
	(segment
		(start 91.081606 -186.56681)
		(end 91.296998 -186.351164)
		(width 0.1016)
		(layer "F.Cu")
		(net "SAS_EXP_GF_TX_DP11")
	)
	(segment
		(start 93.2942 -184.353962)
		(end 93.509846 -184.13857)
		(width 0.1016)
		(layer "F.Cu")
		(net "SAS_EXP_GF_TX_DP11")
	)
	(segment
		(start 87.671402 -254.07874)
		(end 87.671402 -252.493272)
		(width 0.1016)
		(layer "F.Cu")
		(net "SAS_EXP_GF_TX_DP11")
	)
	(segment
		(start 85.492082 -192.15608)
		(end 85.707728 -191.940434)
		(width 0.1016)
		(layer "F.Cu")
		(net "SAS_EXP_GF_TX_DP11")
	)
	(segment
		(start 97.7773 -179.871116)
		(end 97.992692 -179.65547)
		(width 0.1016)
		(layer "F.Cu")
		(net "SAS_EXP_GF_TX_DP11")
	)
	(segment
		(start 99.268026 -178.04257)
		(end 99.483418 -177.827178)
		(width 0.1016)
		(layer "F.Cu")
		(net "SAS_EXP_GF_TX_DP11")
	)
	(segment
		(start 87.898732 -254.18034)
		(end 87.773002 -254.18034)
		(width 0.1016)
		(layer "F.Cu")
		(net "SAS_EXP_GF_TX_DP11")
	)
	(segment
		(start 87.175594 -251.29617)
		(end 81.778602 -245.899178)
		(width 0.1016)
		(layer "F.Cu")
		(net "SAS_EXP_GF_TX_DP11")
	)
	(segment
		(start 93.678502 -183.632094)
		(end 97.270824 -180.039772)
		(width 0.1016)
		(layer "F.Cu")
		(net "SAS_EXP_GF_TX_DP11")
	)
	(segment
		(start 85.876638 -191.433958)
		(end 86.09203 -191.218566)
		(width 0.1016)
		(layer "F.Cu")
		(net "SAS_EXP_GF_TX_DP11")
	)
	(arc
		(start 86.814152 -190.834264)
		(mid 86.887212 -190.717939)
		(end 86.89848 -190.581026)
		(width 0.1016)
		(layer "F.Cu")
		(net "SAS_EXP_GF_TX_DP11")
	)
	(arc
		(start 91.296998 -186.351164)
		(mid 91.370221 -186.234876)
		(end 91.38158 -186.097926)
		(width 0.1016)
		(layer "F.Cu")
		(net "SAS_EXP_GF_TX_DP11")
	)
	(arc
		(start 100.20554 -177.442876)
		(mid 100.2786 -177.326551)
		(end 100.289868 -177.189638)
		(width 0.1016)
		(layer "F.Cu")
		(net "SAS_EXP_GF_TX_DP11")
	)
	(arc
		(start 108.705904 -168.604692)
		(mid 109.176683 -167.899983)
		(end 109.34192 -167.068754)
		(width 0.1016)
		(layer "F.Cu")
		(net "SAS_EXP_GF_TX_DP11")
	)
	(arc
		(start 88.000332 -254.28194)
		(mid 87.970574 -254.210098)
		(end 87.898732 -254.18034)
		(width 0.1016)
		(layer "F.Cu")
		(net "SAS_EXP_GF_TX_DP11")
	)
	(arc
		(start 92.403422 -185.24474)
		(mid 92.476482 -185.128415)
		(end 92.48775 -184.991502)
		(width 0.1016)
		(layer "F.Cu")
		(net "SAS_EXP_GF_TX_DP11")
	)
	(arc
		(start 87.773002 -254.18034)
		(mid 87.70116 -254.150582)
		(end 87.671402 -254.07874)
		(width 0.1016)
		(layer "F.Cu")
		(net "SAS_EXP_GF_TX_DP11")
	)
	(arc
		(start 86.09203 -191.218566)
		(mid 86.208318 -191.145343)
		(end 86.345268 -191.133984)
		(width 0.1016)
		(layer "F.Cu")
		(net "SAS_EXP_GF_TX_DP11")
	)
	(arc
		(start 97.992692 -179.65547)
		(mid 98.065752 -179.539145)
		(end 98.07702 -179.402232)
		(width 0.1016)
		(layer "F.Cu")
		(net "SAS_EXP_GF_TX_DP11")
	)
	(arc
		(start 98.07702 -179.402232)
		(mid 98.088384 -179.265284)
		(end 98.161602 -179.148994)
		(width 0.1016)
		(layer "F.Cu")
		(net "SAS_EXP_GF_TX_DP11")
	)
	(arc
		(start 91.6813 -185.629296)
		(mid 91.797588 -185.556073)
		(end 91.934538 -185.544714)
		(width 0.1016)
		(layer "F.Cu")
		(net "SAS_EXP_GF_TX_DP11")
	)
	(arc
		(start 86.89848 -190.581026)
		(mid 86.90971 -190.444101)
		(end 86.982808 -190.327788)
		(width 0.1016)
		(layer "F.Cu")
		(net "SAS_EXP_GF_TX_DP11")
	)
	(arc
		(start 99.183444 -178.295808)
		(mid 99.194808 -178.15886)
		(end 99.268026 -178.04257)
		(width 0.1016)
		(layer "F.Cu")
		(net "SAS_EXP_GF_TX_DP11")
	)
	(arc
		(start 92.787724 -184.522872)
		(mid 92.904049 -184.449812)
		(end 93.040962 -184.438544)
		(width 0.1016)
		(layer "F.Cu")
		(net "SAS_EXP_GF_TX_DP11")
	)
	(arc
		(start 85.238844 -192.240408)
		(mid 85.375769 -192.229178)
		(end 85.492082 -192.15608)
		(width 0.1016)
		(layer "F.Cu")
		(net "SAS_EXP_GF_TX_DP11")
	)
	(arc
		(start 93.509846 -184.13857)
		(mid 93.582906 -184.022245)
		(end 93.594174 -183.885332)
		(width 0.1016)
		(layer "F.Cu")
		(net "SAS_EXP_GF_TX_DP11")
	)
	(arc
		(start 97.524062 -179.955444)
		(mid 97.660987 -179.944214)
		(end 97.7773 -179.871116)
		(width 0.1016)
		(layer "F.Cu")
		(net "SAS_EXP_GF_TX_DP11")
	)
	(arc
		(start 90.828368 -186.651138)
		(mid 90.965293 -186.639908)
		(end 91.081606 -186.56681)
		(width 0.1016)
		(layer "F.Cu")
		(net "SAS_EXP_GF_TX_DP11")
	)
	(arc
		(start 99.099116 -178.549046)
		(mid 99.172176 -178.432721)
		(end 99.183444 -178.295808)
		(width 0.1016)
		(layer "F.Cu")
		(net "SAS_EXP_GF_TX_DP11")
	)
	(arc
		(start 98.630232 -178.84902)
		(mid 98.767157 -178.83779)
		(end 98.88347 -178.764692)
		(width 0.1016)
		(layer "F.Cu")
		(net "SAS_EXP_GF_TX_DP11")
	)
	(arc
		(start 92.48775 -184.991502)
		(mid 92.499114 -184.854554)
		(end 92.572332 -184.738264)
		(width 0.1016)
		(layer "F.Cu")
		(net "SAS_EXP_GF_TX_DP11")
	)
	(arc
		(start 97.270824 -180.039772)
		(mid 97.387149 -179.966712)
		(end 97.524062 -179.955444)
		(width 0.1016)
		(layer "F.Cu")
		(net "SAS_EXP_GF_TX_DP11")
	)
	(arc
		(start 81.1149 -197.41261)
		(mid 81.338607 -196.28843)
		(end 81.975452 -195.335398)
		(width 0.1016)
		(layer "F.Cu")
		(net "SAS_EXP_GF_TX_DP11")
	)
	(arc
		(start 90.57513 -186.735466)
		(mid 90.691455 -186.662406)
		(end 90.828368 -186.651138)
		(width 0.1016)
		(layer "F.Cu")
		(net "SAS_EXP_GF_TX_DP11")
	)
	(arc
		(start 91.934538 -185.544714)
		(mid 92.071463 -185.533484)
		(end 92.187776 -185.460386)
		(width 0.1016)
		(layer "F.Cu")
		(net "SAS_EXP_GF_TX_DP11")
	)
	(arc
		(start 98.376994 -178.933602)
		(mid 98.493282 -178.860379)
		(end 98.630232 -178.84902)
		(width 0.1016)
		(layer "F.Cu")
		(net "SAS_EXP_GF_TX_DP11")
	)
	(arc
		(start 86.345268 -191.133984)
		(mid 86.482193 -191.122754)
		(end 86.598506 -191.049656)
		(width 0.1016)
		(layer "F.Cu")
		(net "SAS_EXP_GF_TX_DP11")
	)
	(arc
		(start 84.985606 -192.32499)
		(mid 85.101894 -192.251767)
		(end 85.238844 -192.240408)
		(width 0.1016)
		(layer "F.Cu")
		(net "SAS_EXP_GF_TX_DP11")
	)
	(arc
		(start 99.736656 -177.74285)
		(mid 99.873604 -177.731486)
		(end 99.989894 -177.658268)
		(width 0.1016)
		(layer "F.Cu")
		(net "SAS_EXP_GF_TX_DP11")
	)
	(arc
		(start 100.289868 -177.189638)
		(mid 100.301098 -177.052713)
		(end 100.374196 -176.9364)
		(width 0.1016)
		(layer "F.Cu")
		(net "SAS_EXP_GF_TX_DP11")
	)
	(arc
		(start 93.040962 -184.438544)
		(mid 93.17791 -184.42718)
		(end 93.2942 -184.353962)
		(width 0.1016)
		(layer "F.Cu")
		(net "SAS_EXP_GF_TX_DP11")
	)
	(arc
		(start 99.483418 -177.827178)
		(mid 99.599743 -177.754118)
		(end 99.736656 -177.74285)
		(width 0.1016)
		(layer "F.Cu")
		(net "SAS_EXP_GF_TX_DP11")
	)
	(arc
		(start 109.414818 -114.785648)
		(mid 109.468965 -114.7048)
		(end 109.48797 -114.609372)
		(width 0.1016)
		(layer "F.Cu")
		(net "SAS_EXP_GF_TX_DP11")
	)
	(arc
		(start 109.34192 -114.961924)
		(mid 109.360789 -114.866707)
		(end 109.414564 -114.785902)
		(width 0.1016)
		(layer "F.Cu")
		(net "SAS_EXP_GF_TX_DP11")
	)
	(arc
		(start 85.707728 -191.940434)
		(mid 85.780788 -191.824109)
		(end 85.792056 -191.687196)
		(width 0.1016)
		(layer "F.Cu")
		(net "SAS_EXP_GF_TX_DP11")
	)
	(arc
		(start 81.778602 -245.899178)
		(mid 81.287417 -245.164068)
		(end 81.1149 -244.296946)
		(width 0.1016)
		(layer "F.Cu")
		(net "SAS_EXP_GF_TX_DP11")
	)
	(arc
		(start 93.594174 -183.885332)
		(mid 93.605404 -183.748407)
		(end 93.678502 -183.632094)
		(width 0.1016)
		(layer "F.Cu")
		(net "SAS_EXP_GF_TX_DP11")
	)
	(arc
		(start 85.792056 -191.687196)
		(mid 85.80342 -191.550248)
		(end 85.876638 -191.433958)
		(width 0.1016)
		(layer "F.Cu")
		(net "SAS_EXP_GF_TX_DP11")
	)
	(arc
		(start 91.38158 -186.097926)
		(mid 91.39281 -185.961001)
		(end 91.465908 -185.844688)
		(width 0.1016)
		(layer "F.Cu")
		(net "SAS_EXP_GF_TX_DP11")
	)
	(arc
		(start 87.671402 -252.493272)
		(mid 87.542537 -251.845423)
		(end 87.175594 -251.29617)
		(width 0.1016)
		(layer "F.Cu")
		(net "SAS_EXP_GF_TX_DP11")
	)
	(segment
		(start 296.593768 -170.881294)
		(end 296.593768 -171.448984)
		(width 0.1143)
		(layer "F.Cu")
		(net "TP_GPIOH7")
	)
	(segment
		(start 296.834814 -170.640248)
		(end 296.593768 -170.881294)
		(width 0.1143)
		(layer "F.Cu")
		(net "TP_GPIOH7")
	)
	(via
		(at 296.593768 -171.448984)
		(size 0.508)
		(drill 0.254)
		(layers "F.Cu" "B.Cu")
		(net "TP_GPIOH7")
	)
	(segment
		(start 297.318684 -171.448984)
		(end 296.593768 -171.448984)
		(width 0.1143)
		(layer "B.Cu")
		(net "TP_GPIOH7")
	)
	(segment
		(start 297.45432 -171.58462)
		(end 297.318684 -171.448984)
		(width 0.1143)
		(layer "B.Cu")
		(net "TP_GPIOH7")
	)
	(segment
		(start 104.9655 -240.6015)
		(end 105.283 -240.919)
		(width 0.1143)
		(layer "F.Cu")
		(net "SAS_FAULT_LED6")
	)
	(segment
		(start 99.631246 -233.29265)
		(end 99.024948 -233.898948)
		(width 0.1143)
		(layer "F.Cu")
		(net "SAS_FAULT_LED6")
	)
	(segment
		(start 105.283 -241.211354)
		(end 105.283 -240.919)
		(width 0.1143)
		(layer "F.Cu")
		(net "SAS_FAULT_LED6")
	)
	(segment
		(start 103.4415 -232.537)
		(end 103.0605 -232.918)
		(width 0.1143)
		(layer "F.Cu")
		(net "SAS_FAULT_LED6")
	)
	(segment
		(start 95.95485 -238.252)
		(end 95.95485 -240.910364)
		(width 0.1143)
		(layer "F.Cu")
		(net "SAS_FAULT_LED6")
	)
	(segment
		(start 95.95485 -240.910364)
		(end 98.757486 -243.713)
		(width 0.1143)
		(layer "F.Cu")
		(net "SAS_FAULT_LED6")
	)
	(segment
		(start 103.0605 -232.918)
		(end 102.616 -232.918)
		(width 0.1143)
		(layer "F.Cu")
		(net "SAS_FAULT_LED6")
	)
	(segment
		(start 102.24135 -233.29265)
		(end 99.631246 -233.29265)
		(width 0.1143)
		(layer "F.Cu")
		(net "SAS_FAULT_LED6")
	)
	(segment
		(start 99.024948 -235.874052)
		(end 98.044 -236.855)
		(width 0.1143)
		(layer "F.Cu")
		(net "SAS_FAULT_LED6")
	)
	(segment
		(start 98.044 -236.855)
		(end 97.35185 -236.855)
		(width 0.1143)
		(layer "F.Cu")
		(net "SAS_FAULT_LED6")
	)
	(segment
		(start 105.537 -246.761)
		(end 107.16895 -245.12905)
		(width 0.1143)
		(layer "F.Cu")
		(net "SAS_FAULT_LED6")
	)
	(segment
		(start 104.14 -249.809)
		(end 105.537 -248.412)
		(width 0.1143)
		(layer "F.Cu")
		(net "SAS_FAULT_LED6")
	)
	(segment
		(start 102.616 -232.918)
		(end 102.24135 -233.29265)
		(width 0.1143)
		(layer "F.Cu")
		(net "SAS_FAULT_LED6")
	)
	(segment
		(start 98.757486 -243.713)
		(end 99.720908 -243.713)
		(width 0.1143)
		(layer "F.Cu")
		(net "SAS_FAULT_LED6")
	)
	(segment
		(start 104.9655 -239.4712)
		(end 104.9655 -240.6015)
		(width 0.1143)
		(layer "F.Cu")
		(net "SAS_FAULT_LED6")
	)
	(segment
		(start 99.720908 -243.713)
		(end 104.14 -248.132092)
		(width 0.1143)
		(layer "F.Cu")
		(net "SAS_FAULT_LED6")
	)
	(segment
		(start 104.14 -248.132092)
		(end 104.14 -249.809)
		(width 0.1143)
		(layer "F.Cu")
		(net "SAS_FAULT_LED6")
	)
	(segment
		(start 107.16895 -245.12905)
		(end 107.16895 -243.097304)
		(width 0.1143)
		(layer "F.Cu")
		(net "SAS_FAULT_LED6")
	)
	(segment
		(start 99.024948 -233.898948)
		(end 99.024948 -235.874052)
		(width 0.1143)
		(layer "F.Cu")
		(net "SAS_FAULT_LED6")
	)
	(segment
		(start 97.35185 -236.855)
		(end 95.95485 -238.252)
		(width 0.1143)
		(layer "F.Cu")
		(net "SAS_FAULT_LED6")
	)
	(segment
		(start 107.16895 -243.097304)
		(end 105.283 -241.211354)
		(width 0.1143)
		(layer "F.Cu")
		(net "SAS_FAULT_LED6")
	)
	(segment
		(start 105.537 -248.412)
		(end 105.537 -246.761)
		(width 0.1143)
		(layer "F.Cu")
		(net "SAS_FAULT_LED6")
	)
	(via
		(at 105.283 -240.919)
		(size 0.5588)
		(drill 0.3048)
		(layers "F.Cu" "B.Cu")
		(net "SAS_FAULT_LED6")
	)
	(via
		(at 104.14 -249.809)
		(size 0.5588)
		(drill 0.3048)
		(layers "F.Cu" "B.Cu")
		(net "SAS_FAULT_LED6")
	)
	(via
		(at 103.886 -251.968)
		(size 0.7112)
		(drill 0.3556)
		(layers "F.Cu" "B.Cu")
		(net "SAS_FAULT_LED6")
	)
	(segment
		(start 103.886 -251.968)
		(end 104.521 -251.968)
		(width 0.1143)
		(layer "B.Cu")
		(net "SAS_FAULT_LED6")
	)
	(segment
		(start 105.54335 -249.606308)
		(end 105.257092 -249.32005)
		(width 0.1143)
		(layer "B.Cu")
		(net "SAS_FAULT_LED6")
	)
	(segment
		(start 104.62895 -249.32005)
		(end 104.14 -249.809)
		(width 0.1143)
		(layer "B.Cu")
		(net "SAS_FAULT_LED6")
	)
	(segment
		(start 101.999542 -253.854458)
		(end 103.886 -251.968)
		(width 0.1143)
		(layer "B.Cu")
		(net "SAS_FAULT_LED6")
	)
	(segment
		(start 104.521 -251.968)
		(end 105.54335 -250.94565)
		(width 0.1143)
		(layer "B.Cu")
		(net "SAS_FAULT_LED6")
	)
	(segment
		(start 105.54335 -250.94565)
		(end 105.54335 -249.606308)
		(width 0.1143)
		(layer "B.Cu")
		(net "SAS_FAULT_LED6")
	)
	(segment
		(start 105.918 -239.8395)
		(end 105.918 -240.284)
		(width 0.1143)
		(layer "B.Cu")
		(net "SAS_FAULT_LED6")
	)
	(segment
		(start 105.257092 -249.32005)
		(end 104.62895 -249.32005)
		(width 0.1143)
		(layer "B.Cu")
		(net "SAS_FAULT_LED6")
	)
	(segment
		(start 105.918 -240.284)
		(end 105.283 -240.919)
		(width 0.1143)
		(layer "B.Cu")
		(net "SAS_FAULT_LED6")
	)
	(segment
		(start 101.999542 -256.50444)
		(end 101.999542 -253.854458)
		(width 0.1143)
		(layer "B.Cu")
		(net "SAS_FAULT_LED6")
	)
	(segment
		(start 121.789952 -237.391194)
		(end 121.789952 -236.692694)
		(width 0.1016)
		(layer "F.Cu")
		(net "SAS_EXP_GF_TX_DP6")
	)
	(segment
		(start 122.028712 -248.558812)
		(end 122.028712 -248.254012)
		(width 0.1016)
		(layer "F.Cu")
		(net "SAS_EXP_GF_TX_DP6")
	)
	(segment
		(start 121.789952 -249.341132)
		(end 121.789952 -249.036332)
		(width 0.1016)
		(layer "F.Cu")
		(net "SAS_EXP_GF_TX_DP6")
	)
	(segment
		(start 122.028712 -242.767866)
		(end 122.028712 -242.463066)
		(width 0.1016)
		(layer "F.Cu")
		(net "SAS_EXP_GF_TX_DP6")
	)
	(segment
		(start 122.028712 -241.203226)
		(end 122.028712 -240.898426)
		(width 0.1016)
		(layer "F.Cu")
		(net "SAS_EXP_GF_TX_DP6")
	)
	(segment
		(start 131.907534 -220.621352)
		(end 131.90728 -220.621352)
		(width 0.1016)
		(layer "F.Cu")
		(net "SAS_EXP_GF_TX_DP6")
	)
	(segment
		(start 122.028712 -238.173514)
		(end 122.028712 -237.868714)
		(width 0.1016)
		(layer "F.Cu")
		(net "SAS_EXP_GF_TX_DP6")
	)
	(segment
		(start 121.789952 -254.020066)
		(end 121.789952 -250.600972)
		(width 0.1016)
		(layer "F.Cu")
		(net "SAS_EXP_GF_TX_DP6")
	)
	(segment
		(start 126.152148 -230.105204)
		(end 129.271014 -226.986592)
		(width 0.1016)
		(layer "F.Cu")
		(net "SAS_EXP_GF_TX_DP6")
	)
	(segment
		(start 121.999502 -256.25044)
		(end 121.999502 -254.397764)
		(width 0.1016)
		(layer "F.Cu")
		(net "SAS_EXP_GF_TX_DP6")
	)
	(segment
		(start 121.789952 -243.550186)
		(end 121.789952 -243.245386)
		(width 0.1016)
		(layer "F.Cu")
		(net "SAS_EXP_GF_TX_DP6")
	)
	(segment
		(start 121.789952 -247.776492)
		(end 121.789952 -247.471692)
		(width 0.1016)
		(layer "F.Cu")
		(net "SAS_EXP_GF_TX_DP6")
	)
	(segment
		(start 121.789952 -246.211852)
		(end 121.789952 -244.810026)
		(width 0.1016)
		(layer "F.Cu")
		(net "SAS_EXP_GF_TX_DP6")
	)
	(segment
		(start 121.940066 -254.254254)
		(end 121.849388 -254.163576)
		(width 0.1016)
		(layer "F.Cu")
		(net "SAS_EXP_GF_TX_DP6")
	)
	(segment
		(start 121.789952 -241.985546)
		(end 121.789952 -241.680746)
		(width 0.1016)
		(layer "F.Cu")
		(net "SAS_EXP_GF_TX_DP6")
	)
	(segment
		(start 118.23192 -160.641792)
		(end 118.23192 -114.931952)
		(width 0.1016)
		(layer "F.Cu")
		(net "SAS_EXP_GF_TX_DP6")
	)
	(segment
		(start 122.028712 -246.994172)
		(end 122.028712 -246.689372)
		(width 0.1016)
		(layer "F.Cu")
		(net "SAS_EXP_GF_TX_DP6")
	)
	(segment
		(start 121.789952 -240.420906)
		(end 121.789952 -238.651034)
		(width 0.1016)
		(layer "F.Cu")
		(net "SAS_EXP_GF_TX_DP6")
	)
	(segment
		(start 129.598166 -173.055026)
		(end 118.97233 -162.42919)
		(width 0.1016)
		(layer "F.Cu")
		(net "SAS_EXP_GF_TX_DP6")
	)
	(segment
		(start 123.363482 -232.89387)
		(end 126.152148 -230.105204)
		(width 0.1016)
		(layer "F.Cu")
		(net "SAS_EXP_GF_TX_DP6")
	)
	(segment
		(start 122.028712 -244.332506)
		(end 122.028712 -244.027706)
		(width 0.1016)
		(layer "F.Cu")
		(net "SAS_EXP_GF_TX_DP6")
	)
	(segment
		(start 131.90728 -220.621352)
		(end 131.90728 -178.630072)
		(width 0.1016)
		(layer "F.Cu")
		(net "SAS_EXP_GF_TX_DP6")
	)
	(segment
		(start 122.028712 -250.123452)
		(end 122.028712 -249.818652)
		(width 0.1016)
		(layer "F.Cu")
		(net "SAS_EXP_GF_TX_DP6")
	)
	(arc
		(start 121.909332 -250.362212)
		(mid 121.99822 -250.257417)
		(end 122.028712 -250.123452)
		(width 0.1016)
		(layer "F.Cu")
		(net "SAS_EXP_GF_TX_DP6")
	)
	(arc
		(start 118.23192 -114.931952)
		(mid 118.259375 -114.793926)
		(end 118.337584 -114.676936)
		(width 0.1016)
		(layer "F.Cu")
		(net "SAS_EXP_GF_TX_DP6")
	)
	(arc
		(start 121.909332 -249.579892)
		(mid 121.820444 -249.475097)
		(end 121.789952 -249.341132)
		(width 0.1016)
		(layer "F.Cu")
		(net "SAS_EXP_GF_TX_DP6")
	)
	(arc
		(start 122.028712 -240.898426)
		(mid 121.99822 -240.764433)
		(end 121.909332 -240.659666)
		(width 0.1016)
		(layer "F.Cu")
		(net "SAS_EXP_GF_TX_DP6")
	)
	(arc
		(start 122.028712 -249.818652)
		(mid 121.99822 -249.684659)
		(end 121.909332 -249.579892)
		(width 0.1016)
		(layer "F.Cu")
		(net "SAS_EXP_GF_TX_DP6")
	)
	(arc
		(start 121.909332 -247.232932)
		(mid 121.99822 -247.128137)
		(end 122.028712 -246.994172)
		(width 0.1016)
		(layer "F.Cu")
		(net "SAS_EXP_GF_TX_DP6")
	)
	(arc
		(start 122.028712 -248.254012)
		(mid 121.99822 -248.120019)
		(end 121.909332 -248.015252)
		(width 0.1016)
		(layer "F.Cu")
		(net "SAS_EXP_GF_TX_DP6")
	)
	(arc
		(start 121.849388 -254.163576)
		(mid 121.805393 -254.097733)
		(end 121.789952 -254.020066)
		(width 0.1016)
		(layer "F.Cu")
		(net "SAS_EXP_GF_TX_DP6")
	)
	(arc
		(start 121.789952 -241.680746)
		(mid 121.820444 -241.546753)
		(end 121.909332 -241.441986)
		(width 0.1016)
		(layer "F.Cu")
		(net "SAS_EXP_GF_TX_DP6")
	)
	(arc
		(start 122.028712 -246.689372)
		(mid 121.99822 -246.555379)
		(end 121.909332 -246.450612)
		(width 0.1016)
		(layer "F.Cu")
		(net "SAS_EXP_GF_TX_DP6")
	)
	(arc
		(start 121.789952 -249.036332)
		(mid 121.820444 -248.902339)
		(end 121.909332 -248.797572)
		(width 0.1016)
		(layer "F.Cu")
		(net "SAS_EXP_GF_TX_DP6")
	)
	(arc
		(start 121.909332 -243.006626)
		(mid 121.998126 -242.901812)
		(end 122.028712 -242.767866)
		(width 0.1016)
		(layer "F.Cu")
		(net "SAS_EXP_GF_TX_DP6")
	)
	(arc
		(start 131.90728 -178.630072)
		(mid 131.307164 -175.612906)
		(end 129.598166 -173.055026)
		(width 0.1016)
		(layer "F.Cu")
		(net "SAS_EXP_GF_TX_DP6")
	)
	(arc
		(start 121.789952 -238.651034)
		(mid 121.820444 -238.517041)
		(end 121.909332 -238.412274)
		(width 0.1016)
		(layer "F.Cu")
		(net "SAS_EXP_GF_TX_DP6")
	)
	(arc
		(start 129.271014 -226.986592)
		(mid 131.222361 -224.066195)
		(end 131.907534 -220.621352)
		(width 0.1016)
		(layer "F.Cu")
		(net "SAS_EXP_GF_TX_DP6")
	)
	(arc
		(start 121.909332 -248.797572)
		(mid 121.99822 -248.692777)
		(end 122.028712 -248.558812)
		(width 0.1016)
		(layer "F.Cu")
		(net "SAS_EXP_GF_TX_DP6")
	)
	(arc
		(start 118.97233 -162.42919)
		(mid 118.42438 -161.609125)
		(end 118.23192 -160.641792)
		(width 0.1016)
		(layer "F.Cu")
		(net "SAS_EXP_GF_TX_DP6")
	)
	(arc
		(start 121.789952 -247.471692)
		(mid 121.820444 -247.337699)
		(end 121.909332 -247.232932)
		(width 0.1016)
		(layer "F.Cu")
		(net "SAS_EXP_GF_TX_DP6")
	)
	(arc
		(start 121.909332 -240.659666)
		(mid 121.820538 -240.554852)
		(end 121.789952 -240.420906)
		(width 0.1016)
		(layer "F.Cu")
		(net "SAS_EXP_GF_TX_DP6")
	)
	(arc
		(start 122.028712 -244.027706)
		(mid 121.99822 -243.893713)
		(end 121.909332 -243.788946)
		(width 0.1016)
		(layer "F.Cu")
		(net "SAS_EXP_GF_TX_DP6")
	)
	(arc
		(start 121.789952 -244.810026)
		(mid 121.820444 -244.676033)
		(end 121.909332 -244.571266)
		(width 0.1016)
		(layer "F.Cu")
		(net "SAS_EXP_GF_TX_DP6")
	)
	(arc
		(start 121.909332 -242.224306)
		(mid 121.820538 -242.119492)
		(end 121.789952 -241.985546)
		(width 0.1016)
		(layer "F.Cu")
		(net "SAS_EXP_GF_TX_DP6")
	)
	(arc
		(start 121.789952 -243.245386)
		(mid 121.820444 -243.111393)
		(end 121.909332 -243.006626)
		(width 0.1016)
		(layer "F.Cu")
		(net "SAS_EXP_GF_TX_DP6")
	)
	(arc
		(start 121.789952 -236.692694)
		(mid 122.198898 -234.636783)
		(end 123.363482 -232.89387)
		(width 0.1016)
		(layer "F.Cu")
		(net "SAS_EXP_GF_TX_DP6")
	)
	(arc
		(start 121.909332 -238.412274)
		(mid 121.998126 -238.30746)
		(end 122.028712 -238.173514)
		(width 0.1016)
		(layer "F.Cu")
		(net "SAS_EXP_GF_TX_DP6")
	)
	(arc
		(start 122.028712 -237.868714)
		(mid 121.99822 -237.734721)
		(end 121.909332 -237.629954)
		(width 0.1016)
		(layer "F.Cu")
		(net "SAS_EXP_GF_TX_DP6")
	)
	(arc
		(start 121.909332 -241.441986)
		(mid 121.998126 -241.337172)
		(end 122.028712 -241.203226)
		(width 0.1016)
		(layer "F.Cu")
		(net "SAS_EXP_GF_TX_DP6")
	)
	(arc
		(start 121.909332 -248.015252)
		(mid 121.820444 -247.910457)
		(end 121.789952 -247.776492)
		(width 0.1016)
		(layer "F.Cu")
		(net "SAS_EXP_GF_TX_DP6")
	)
	(arc
		(start 121.909332 -237.629954)
		(mid 121.820538 -237.52514)
		(end 121.789952 -237.391194)
		(width 0.1016)
		(layer "F.Cu")
		(net "SAS_EXP_GF_TX_DP6")
	)
	(arc
		(start 121.999502 -254.397764)
		(mid 121.984054 -254.3201)
		(end 121.940066 -254.254254)
		(width 0.1016)
		(layer "F.Cu")
		(net "SAS_EXP_GF_TX_DP6")
	)
	(arc
		(start 121.909332 -246.450612)
		(mid 121.820444 -246.345817)
		(end 121.789952 -246.211852)
		(width 0.1016)
		(layer "F.Cu")
		(net "SAS_EXP_GF_TX_DP6")
	)
	(arc
		(start 122.028712 -242.463066)
		(mid 121.99822 -242.329073)
		(end 121.909332 -242.224306)
		(width 0.1016)
		(layer "F.Cu")
		(net "SAS_EXP_GF_TX_DP6")
	)
	(arc
		(start 121.909332 -243.788946)
		(mid 121.820538 -243.684132)
		(end 121.789952 -243.550186)
		(width 0.1016)
		(layer "F.Cu")
		(net "SAS_EXP_GF_TX_DP6")
	)
	(arc
		(start 121.789952 -250.600972)
		(mid 121.820444 -250.466979)
		(end 121.909332 -250.362212)
		(width 0.1016)
		(layer "F.Cu")
		(net "SAS_EXP_GF_TX_DP6")
	)
	(arc
		(start 121.909332 -244.571266)
		(mid 121.998126 -244.466452)
		(end 122.028712 -244.332506)
		(width 0.1016)
		(layer "F.Cu")
		(net "SAS_EXP_GF_TX_DP6")
	)
	(arc
		(start 118.337584 -114.676936)
		(mid 118.367485 -114.632186)
		(end 118.37797 -114.5794)
		(width 0.1016)
		(layer "F.Cu")
		(net "SAS_EXP_GF_TX_DP6")
	)
	(segment
		(start 17.860518 -183.793384)
		(end 17.584928 -183.517794)
		(width 0.1143)
		(layer "F.Cu")
		(net "SAS_HDD_PRE14")
	)
	(segment
		(start 17.860518 -185.409586)
		(end 17.860518 -183.793384)
		(width 0.1143)
		(layer "F.Cu")
		(net "SAS_HDD_PRE14")
	)
	(segment
		(start 19.046444 -174.431706)
		(end 19.915886 -174.431706)
		(width 0.1143)
		(layer "F.Cu")
		(net "SAS_HDD_PRE14")
	)
	(segment
		(start 17.730216 -180.44033)
		(end 17.730216 -183.096916)
		(width 0.1143)
		(layer "F.Cu")
		(net "SAS_HDD_PRE14")
	)
	(segment
		(start 18.785078 -174.693072)
		(end 19.046444 -174.431706)
		(width 0.1143)
		(layer "F.Cu")
		(net "SAS_HDD_PRE14")
	)
	(segment
		(start 20.493228 -177.677318)
		(end 17.730216 -180.44033)
		(width 0.1143)
		(layer "F.Cu")
		(net "SAS_HDD_PRE14")
	)
	(segment
		(start 17.730216 -183.096916)
		(end 17.309338 -183.517794)
		(width 0.1143)
		(layer "F.Cu")
		(net "SAS_HDD_PRE14")
	)
	(segment
		(start 19.915886 -174.431706)
		(end 20.493228 -175.009048)
		(width 0.1143)
		(layer "F.Cu")
		(net "SAS_HDD_PRE14")
	)
	(segment
		(start 20.493228 -175.009048)
		(end 20.493228 -177.677318)
		(width 0.1143)
		(layer "F.Cu")
		(net "SAS_HDD_PRE14")
	)
	(segment
		(start 18.785078 -175.746156)
		(end 18.785078 -174.693072)
		(width 0.1143)
		(layer "F.Cu")
		(net "SAS_HDD_PRE14")
	)
	(segment
		(start 17.584928 -183.517794)
		(end 17.309338 -183.517794)
		(width 0.1143)
		(layer "F.Cu")
		(net "SAS_HDD_PRE14")
	)
	(via
		(at 17.309338 -183.517794)
		(size 0.5588)
		(drill 0.3048)
		(layers "F.Cu" "B.Cu")
		(net "SAS_HDD_PRE14")
	)
	(via
		(at 17.309338 -186.66968)
		(size 0.7112)
		(drill 0.3556)
		(layers "F.Cu" "B.Cu")
		(net "SAS_HDD_PRE14")
	)
	(segment
		(start 17.309338 -186.66968)
		(end 17.309338 -183.517794)
		(width 0.1143)
		(layer "B.Cu")
		(net "SAS_HDD_PRE14")
	)
	(segment
		(start 2.699766 -201.805286)
		(end 17.309338 -187.195714)
		(width 0.1143)
		(layer "B.Cu")
		(net "SAS_HDD_PRE14")
	)
	(segment
		(start 31.000446 -249.313446)
		(end 28.099004 -246.412004)
		(width 0.1143)
		(layer "B.Cu")
		(net "SAS_HDD_PRE14")
	)
	(segment
		(start 31.000446 -256.50444)
		(end 31.000446 -249.313446)
		(width 0.1143)
		(layer "B.Cu")
		(net "SAS_HDD_PRE14")
	)
	(segment
		(start 2.699766 -238.34852)
		(end 2.699766 -201.805286)
		(width 0.1143)
		(layer "B.Cu")
		(net "SAS_HDD_PRE14")
	)
	(segment
		(start 10.76325 -246.412004)
		(end 2.699766 -238.34852)
		(width 0.1143)
		(layer "B.Cu")
		(net "SAS_HDD_PRE14")
	)
	(segment
		(start 17.309338 -187.195714)
		(end 17.309338 -186.66968)
		(width 0.1143)
		(layer "B.Cu")
		(net "SAS_HDD_PRE14")
	)
	(segment
		(start 28.099004 -246.412004)
		(end 10.76325 -246.412004)
		(width 0.1143)
		(layer "B.Cu")
		(net "SAS_HDD_PRE14")
	)
	(segment
		(start 104.00792 -163.907216)
		(end 104.00792 -114.932206)
		(width 0.1016)
		(layer "F.Cu")
		(net "SAS_EXP_GF_TX_DP14")
	)
	(segment
		(start 80.588104 -188.541152)
		(end 80.80375 -188.32576)
		(width 0.1016)
		(layer "F.Cu")
		(net "SAS_EXP_GF_TX_DP14")
	)
	(segment
		(start 89.966038 -179.163218)
		(end 90.181684 -178.947572)
		(width 0.1016)
		(layer "F.Cu")
		(net "SAS_EXP_GF_TX_DP14")
	)
	(segment
		(start 97.062798 -171.728892)
		(end 103.38816 -165.40353)
		(width 0.1016)
		(layer "F.Cu")
		(net "SAS_EXP_GF_TX_DP14")
	)
	(segment
		(start 92.178886 -176.95037)
		(end 92.394278 -176.734978)
		(width 0.1016)
		(layer "F.Cu")
		(net "SAS_EXP_GF_TX_DP14")
	)
	(segment
		(start 96.678496 -172.451014)
		(end 96.893888 -172.235368)
		(width 0.1016)
		(layer "F.Cu")
		(net "SAS_EXP_GF_TX_DP14")
	)
	(segment
		(start 90.350594 -178.441096)
		(end 90.565986 -178.225704)
		(width 0.1016)
		(layer "F.Cu")
		(net "SAS_EXP_GF_TX_DP14")
	)
	(segment
		(start 91.456764 -177.334926)
		(end 91.67241 -177.11928)
		(width 0.1016)
		(layer "F.Cu")
		(net "SAS_EXP_GF_TX_DP14")
	)
	(segment
		(start 80.972406 -187.819284)
		(end 81.188052 -187.603638)
		(width 0.1016)
		(layer "F.Cu")
		(net "SAS_EXP_GF_TX_DP14")
	)
	(segment
		(start 91.072462 -178.056794)
		(end 91.288108 -177.841402)
		(width 0.1016)
		(layer "F.Cu")
		(net "SAS_EXP_GF_TX_DP14")
	)
	(segment
		(start 79.866236 -188.925454)
		(end 80.081628 -188.710062)
		(width 0.1016)
		(layer "F.Cu")
		(net "SAS_EXP_GF_TX_DP14")
	)
	(segment
		(start 75.711812 -253.897638)
		(end 75.711812 -193.936112)
		(width 0.1016)
		(layer "F.Cu")
		(net "SAS_EXP_GF_TX_DP14")
	)
	(segment
		(start 76.000102 -256.25044)
		(end 76.000102 -254.593598)
		(width 0.1016)
		(layer "F.Cu")
		(net "SAS_EXP_GF_TX_DP14")
	)
	(segment
		(start 81.694528 -187.434728)
		(end 81.90992 -187.219336)
		(width 0.1016)
		(layer "F.Cu")
		(net "SAS_EXP_GF_TX_DP14")
	)
	(segment
		(start 82.07883 -186.71286)
		(end 89.459562 -179.332128)
		(width 0.1016)
		(layer "F.Cu")
		(net "SAS_EXP_GF_TX_DP14")
	)
	(segment
		(start 76.317348 -192.474342)
		(end 78.975204 -189.816486)
		(width 0.1016)
		(layer "F.Cu")
		(net "SAS_EXP_GF_TX_DP14")
	)
	(segment
		(start 79.48168 -189.647576)
		(end 79.697326 -189.43193)
		(width 0.1016)
		(layer "F.Cu")
		(net "SAS_EXP_GF_TX_DP14")
	)
	(segment
		(start 92.563188 -176.228502)
		(end 96.17202 -172.61967)
		(width 0.1016)
		(layer "F.Cu")
		(net "SAS_EXP_GF_TX_DP14")
	)
	(arc
		(start 81.188052 -187.603638)
		(mid 81.304377 -187.530578)
		(end 81.44129 -187.51931)
		(width 0.1016)
		(layer "F.Cu")
		(net "SAS_EXP_GF_TX_DP14")
	)
	(arc
		(start 91.925648 -177.034952)
		(mid 92.062596 -177.023588)
		(end 92.178886 -176.95037)
		(width 0.1016)
		(layer "F.Cu")
		(net "SAS_EXP_GF_TX_DP14")
	)
	(arc
		(start 81.44129 -187.51931)
		(mid 81.578238 -187.507946)
		(end 81.694528 -187.434728)
		(width 0.1016)
		(layer "F.Cu")
		(net "SAS_EXP_GF_TX_DP14")
	)
	(arc
		(start 89.7128 -179.247546)
		(mid 89.849725 -179.236316)
		(end 89.966038 -179.163218)
		(width 0.1016)
		(layer "F.Cu")
		(net "SAS_EXP_GF_TX_DP14")
	)
	(arc
		(start 80.334866 -188.625734)
		(mid 80.471814 -188.61437)
		(end 80.588104 -188.541152)
		(width 0.1016)
		(layer "F.Cu")
		(net "SAS_EXP_GF_TX_DP14")
	)
	(arc
		(start 103.38816 -165.40353)
		(mid 103.846821 -164.717001)
		(end 104.00792 -163.907216)
		(width 0.1016)
		(layer "F.Cu")
		(net "SAS_EXP_GF_TX_DP14")
	)
	(arc
		(start 96.97847 -171.98213)
		(mid 96.9897 -171.845205)
		(end 97.062798 -171.728892)
		(width 0.1016)
		(layer "F.Cu")
		(net "SAS_EXP_GF_TX_DP14")
	)
	(arc
		(start 81.994502 -186.966098)
		(mid 82.005732 -186.829173)
		(end 82.07883 -186.71286)
		(width 0.1016)
		(layer "F.Cu")
		(net "SAS_EXP_GF_TX_DP14")
	)
	(arc
		(start 96.17202 -172.61967)
		(mid 96.288345 -172.54661)
		(end 96.425258 -172.535342)
		(width 0.1016)
		(layer "F.Cu")
		(net "SAS_EXP_GF_TX_DP14")
	)
	(arc
		(start 104.131618 -114.633502)
		(mid 104.14815 -114.608666)
		(end 104.15397 -114.5794)
		(width 0.1016)
		(layer "F.Cu")
		(net "SAS_EXP_GF_TX_DP14")
	)
	(arc
		(start 81.90992 -187.219336)
		(mid 81.983143 -187.103048)
		(end 81.994502 -186.966098)
		(width 0.1016)
		(layer "F.Cu")
		(net "SAS_EXP_GF_TX_DP14")
	)
	(arc
		(start 78.975204 -189.816486)
		(mid 79.091492 -189.743263)
		(end 79.228442 -189.731904)
		(width 0.1016)
		(layer "F.Cu")
		(net "SAS_EXP_GF_TX_DP14")
	)
	(arc
		(start 91.372436 -177.588164)
		(mid 91.383666 -177.451239)
		(end 91.456764 -177.334926)
		(width 0.1016)
		(layer "F.Cu")
		(net "SAS_EXP_GF_TX_DP14")
	)
	(arc
		(start 90.266012 -178.694334)
		(mid 90.277376 -178.557386)
		(end 90.350594 -178.441096)
		(width 0.1016)
		(layer "F.Cu")
		(net "SAS_EXP_GF_TX_DP14")
	)
	(arc
		(start 79.697326 -189.43193)
		(mid 79.770386 -189.315605)
		(end 79.781654 -189.178692)
		(width 0.1016)
		(layer "F.Cu")
		(net "SAS_EXP_GF_TX_DP14")
	)
	(arc
		(start 80.80375 -188.32576)
		(mid 80.87681 -188.209435)
		(end 80.888078 -188.072522)
		(width 0.1016)
		(layer "F.Cu")
		(net "SAS_EXP_GF_TX_DP14")
	)
	(arc
		(start 80.081628 -188.710062)
		(mid 80.197953 -188.637002)
		(end 80.334866 -188.625734)
		(width 0.1016)
		(layer "F.Cu")
		(net "SAS_EXP_GF_TX_DP14")
	)
	(arc
		(start 92.394278 -176.734978)
		(mid 92.467501 -176.61869)
		(end 92.47886 -176.48174)
		(width 0.1016)
		(layer "F.Cu")
		(net "SAS_EXP_GF_TX_DP14")
	)
	(arc
		(start 91.67241 -177.11928)
		(mid 91.788735 -177.04622)
		(end 91.925648 -177.034952)
		(width 0.1016)
		(layer "F.Cu")
		(net "SAS_EXP_GF_TX_DP14")
	)
	(arc
		(start 89.459562 -179.332128)
		(mid 89.57585 -179.258905)
		(end 89.7128 -179.247546)
		(width 0.1016)
		(layer "F.Cu")
		(net "SAS_EXP_GF_TX_DP14")
	)
	(arc
		(start 96.893888 -172.235368)
		(mid 96.967111 -172.11908)
		(end 96.97847 -171.98213)
		(width 0.1016)
		(layer "F.Cu")
		(net "SAS_EXP_GF_TX_DP14")
	)
	(arc
		(start 79.228442 -189.731904)
		(mid 79.365367 -189.720674)
		(end 79.48168 -189.647576)
		(width 0.1016)
		(layer "F.Cu")
		(net "SAS_EXP_GF_TX_DP14")
	)
	(arc
		(start 104.00792 -114.932206)
		(mid 104.040073 -114.77056)
		(end 104.131618 -114.633502)
		(width 0.1016)
		(layer "F.Cu")
		(net "SAS_EXP_GF_TX_DP14")
	)
	(arc
		(start 96.425258 -172.535342)
		(mid 96.562183 -172.524112)
		(end 96.678496 -172.451014)
		(width 0.1016)
		(layer "F.Cu")
		(net "SAS_EXP_GF_TX_DP14")
	)
	(arc
		(start 90.819224 -178.141376)
		(mid 90.956172 -178.130012)
		(end 91.072462 -178.056794)
		(width 0.1016)
		(layer "F.Cu")
		(net "SAS_EXP_GF_TX_DP14")
	)
	(arc
		(start 75.856084 -254.245872)
		(mid 75.749328 -254.086101)
		(end 75.711812 -253.897638)
		(width 0.1016)
		(layer "F.Cu")
		(net "SAS_EXP_GF_TX_DP14")
	)
	(arc
		(start 92.47886 -176.48174)
		(mid 92.49009 -176.344815)
		(end 92.563188 -176.228502)
		(width 0.1016)
		(layer "F.Cu")
		(net "SAS_EXP_GF_TX_DP14")
	)
	(arc
		(start 91.288108 -177.841402)
		(mid 91.361168 -177.725077)
		(end 91.372436 -177.588164)
		(width 0.1016)
		(layer "F.Cu")
		(net "SAS_EXP_GF_TX_DP14")
	)
	(arc
		(start 80.888078 -188.072522)
		(mid 80.899308 -187.935597)
		(end 80.972406 -187.819284)
		(width 0.1016)
		(layer "F.Cu")
		(net "SAS_EXP_GF_TX_DP14")
	)
	(arc
		(start 76.000102 -254.593598)
		(mid 75.96267 -254.405416)
		(end 75.856084 -254.245872)
		(width 0.1016)
		(layer "F.Cu")
		(net "SAS_EXP_GF_TX_DP14")
	)
	(arc
		(start 90.565986 -178.225704)
		(mid 90.682311 -178.152644)
		(end 90.819224 -178.141376)
		(width 0.1016)
		(layer "F.Cu")
		(net "SAS_EXP_GF_TX_DP14")
	)
	(arc
		(start 75.711812 -193.936112)
		(mid 75.869191 -193.145002)
		(end 76.317348 -192.474342)
		(width 0.1016)
		(layer "F.Cu")
		(net "SAS_EXP_GF_TX_DP14")
	)
	(arc
		(start 90.181684 -178.947572)
		(mid 90.254744 -178.831247)
		(end 90.266012 -178.694334)
		(width 0.1016)
		(layer "F.Cu")
		(net "SAS_EXP_GF_TX_DP14")
	)
	(arc
		(start 79.781654 -189.178692)
		(mid 79.793018 -189.041744)
		(end 79.866236 -188.925454)
		(width 0.1016)
		(layer "F.Cu")
		(net "SAS_EXP_GF_TX_DP14")
	)
	(segment
		(start 113.349786 -103.35006)
		(end 112.84966 -103.850186)
		(width 0.1016)
		(layer "F.Cu")
		(net "SAS_GF_EXP_RX_DP9")
	)
	(via
		(at 112.84966 -103.850186)
		(size 0.508)
		(drill 0.254)
		(layers "F.Cu" "B.Cu")
		(net "SAS_GF_EXP_RX_DP9")
	)
	(segment
		(start 101.147372 -201.29119)
		(end 101.147372 -200.98639)
		(width 0.1016)
		(layer "B.Cu")
		(net "SAS_GF_EXP_RX_DP9")
	)
	(segment
		(start 112.42167 -107.064556)
		(end 112.42167 -105.559098)
		(width 0.1016)
		(layer "B.Cu")
		(net "SAS_GF_EXP_RX_DP9")
	)
	(segment
		(start 101.147372 -210.385152)
		(end 101.147372 -210.080352)
		(width 0.1016)
		(layer "B.Cu")
		(net "SAS_GF_EXP_RX_DP9")
	)
	(segment
		(start 112.175798 -107.573572)
		(end 112.235742 -107.513628)
		(width 0.1016)
		(layer "B.Cu")
		(net "SAS_GF_EXP_RX_DP9")
	)
	(segment
		(start 112.631728 -104.02697)
		(end 112.667288 -103.941372)
		(width 0.1016)
		(layer "B.Cu")
		(net "SAS_GF_EXP_RX_DP9")
	)
	(segment
		(start 112.468152 -105.320846)
		(end 112.557306 -105.100374)
		(width 0.1016)
		(layer "B.Cu")
		(net "SAS_GF_EXP_RX_DP9")
	)
	(segment
		(start 101.147372 -211.949792)
		(end 101.147372 -211.644992)
		(width 0.1016)
		(layer "B.Cu")
		(net "SAS_GF_EXP_RX_DP9")
	)
	(segment
		(start 101.568758 -184.881012)
		(end 109.76483 -176.68494)
		(width 0.1016)
		(layer "B.Cu")
		(net "SAS_GF_EXP_RX_DP9")
	)
	(segment
		(start 112.598962 -104.886506)
		(end 112.598962 -104.19207)
		(width 0.1016)
		(layer "B.Cu")
		(net "SAS_GF_EXP_RX_DP9")
	)
	(segment
		(start 101.147372 -208.820512)
		(end 101.147372 -208.515712)
		(width 0.1016)
		(layer "B.Cu")
		(net "SAS_GF_EXP_RX_DP9")
	)
	(segment
		(start 111.835438 -254.117602)
		(end 111.76 -254.042164)
		(width 0.1016)
		(layer "B.Cu")
		(net "SAS_GF_EXP_RX_DP9")
	)
	(segment
		(start 101.147372 -199.72655)
		(end 101.147372 -199.42175)
		(width 0.1016)
		(layer "B.Cu")
		(net "SAS_GF_EXP_RX_DP9")
	)
	(segment
		(start 101.451664 -184.99836)
		(end 101.568758 -184.881012)
		(width 0.1016)
		(layer "B.Cu")
		(net "SAS_GF_EXP_RX_DP9")
	)
	(segment
		(start 100.908612 -206.473552)
		(end 100.908612 -203.33335)
		(width 0.1016)
		(layer "B.Cu")
		(net "SAS_GF_EXP_RX_DP9")
	)
	(segment
		(start 101.147372 -202.85583)
		(end 101.147372 -202.55103)
		(width 0.1016)
		(layer "B.Cu")
		(net "SAS_GF_EXP_RX_DP9")
	)
	(segment
		(start 113.80597 -166.928292)
		(end 113.80597 -114.906552)
		(width 0.1016)
		(layer "B.Cu")
		(net "SAS_GF_EXP_RX_DP9")
	)
	(segment
		(start 100.908612 -208.038192)
		(end 100.908612 -207.733392)
		(width 0.1016)
		(layer "B.Cu")
		(net "SAS_GF_EXP_RX_DP9")
	)
	(segment
		(start 112.789716 -103.850186)
		(end 112.84966 -103.850186)
		(width 0.1016)
		(layer "B.Cu")
		(net "SAS_GF_EXP_RX_DP9")
	)
	(segment
		(start 111.999522 -256.50444)
		(end 111.999522 -254.281686)
		(width 0.1016)
		(layer "B.Cu")
		(net "SAS_GF_EXP_RX_DP9")
	)
	(segment
		(start 100.908612 -198.94423)
		(end 100.908612 -186.309)
		(width 0.1016)
		(layer "B.Cu")
		(net "SAS_GF_EXP_RX_DP9")
	)
	(segment
		(start 111.98987 -110.52175)
		(end 111.98987 -108.022644)
		(width 0.1016)
		(layer "B.Cu")
		(net "SAS_GF_EXP_RX_DP9")
	)
	(segment
		(start 110.334044 -228.063044)
		(end 102.934262 -220.663262)
		(width 0.1016)
		(layer "B.Cu")
		(net "SAS_GF_EXP_RX_DP9")
	)
	(segment
		(start 100.908612 -202.07351)
		(end 100.908612 -201.76871)
		(width 0.1016)
		(layer "B.Cu")
		(net "SAS_GF_EXP_RX_DP9")
	)
	(segment
		(start 100.908612 -211.167472)
		(end 100.908612 -210.862672)
		(width 0.1016)
		(layer "B.Cu")
		(net "SAS_GF_EXP_RX_DP9")
	)
	(segment
		(start 100.908612 -209.602832)
		(end 100.908612 -209.298032)
		(width 0.1016)
		(layer "B.Cu")
		(net "SAS_GF_EXP_RX_DP9")
	)
	(segment
		(start 101.147372 -207.255872)
		(end 101.147372 -206.951072)
		(width 0.1016)
		(layer "B.Cu")
		(net "SAS_GF_EXP_RX_DP9")
	)
	(segment
		(start 100.908612 -200.50887)
		(end 100.908612 -200.20407)
		(width 0.1016)
		(layer "B.Cu")
		(net "SAS_GF_EXP_RX_DP9")
	)
	(segment
		(start 111.76 -254.042164)
		(end 111.76 -231.505506)
		(width 0.1016)
		(layer "B.Cu")
		(net "SAS_GF_EXP_RX_DP9")
	)
	(segment
		(start 100.908612 -215.773)
		(end 100.908612 -212.427312)
		(width 0.1016)
		(layer "B.Cu")
		(net "SAS_GF_EXP_RX_DP9")
	)
	(arc
		(start 112.598962 -104.19207)
		(mid 112.607213 -104.107907)
		(end 112.631728 -104.02697)
		(width 0.1016)
		(layer "B.Cu")
		(net "SAS_GF_EXP_RX_DP9")
	)
	(arc
		(start 112.7506 -103.85806)
		(mid 112.76977 -103.852203)
		(end 112.789716 -103.850186)
		(width 0.1016)
		(layer "B.Cu")
		(net "SAS_GF_EXP_RX_DP9")
	)
	(arc
		(start 101.027992 -207.494632)
		(mid 101.116786 -207.389818)
		(end 101.147372 -207.255872)
		(width 0.1016)
		(layer "B.Cu")
		(net "SAS_GF_EXP_RX_DP9")
	)
	(arc
		(start 109.76483 -176.68494)
		(mid 112.755798 -172.20855)
		(end 113.80597 -166.928292)
		(width 0.1016)
		(layer "B.Cu")
		(net "SAS_GF_EXP_RX_DP9")
	)
	(arc
		(start 101.027992 -209.059272)
		(mid 101.116786 -208.954458)
		(end 101.147372 -208.820512)
		(width 0.1016)
		(layer "B.Cu")
		(net "SAS_GF_EXP_RX_DP9")
	)
	(arc
		(start 101.147372 -202.55103)
		(mid 101.11688 -202.417037)
		(end 101.027992 -202.31227)
		(width 0.1016)
		(layer "B.Cu")
		(net "SAS_GF_EXP_RX_DP9")
	)
	(arc
		(start 101.027992 -199.96531)
		(mid 101.116786 -199.860496)
		(end 101.147372 -199.72655)
		(width 0.1016)
		(layer "B.Cu")
		(net "SAS_GF_EXP_RX_DP9")
	)
	(arc
		(start 101.027992 -211.406232)
		(mid 100.939198 -211.301418)
		(end 100.908612 -211.167472)
		(width 0.1016)
		(layer "B.Cu")
		(net "SAS_GF_EXP_RX_DP9")
	)
	(arc
		(start 101.147372 -210.080352)
		(mid 101.11688 -209.946359)
		(end 101.027992 -209.841592)
		(width 0.1016)
		(layer "B.Cu")
		(net "SAS_GF_EXP_RX_DP9")
	)
	(arc
		(start 101.027992 -201.52995)
		(mid 101.116786 -201.425136)
		(end 101.147372 -201.29119)
		(width 0.1016)
		(layer "B.Cu")
		(net "SAS_GF_EXP_RX_DP9")
	)
	(arc
		(start 100.908612 -203.33335)
		(mid 100.939104 -203.199357)
		(end 101.027992 -203.09459)
		(width 0.1016)
		(layer "B.Cu")
		(net "SAS_GF_EXP_RX_DP9")
	)
	(arc
		(start 113.80597 -114.906552)
		(mid 113.558802 -113.663484)
		(end 112.85474 -112.60963)
		(width 0.1016)
		(layer "B.Cu")
		(net "SAS_GF_EXP_RX_DP9")
	)
	(arc
		(start 100.908612 -207.733392)
		(mid 100.939104 -207.599399)
		(end 101.027992 -207.494632)
		(width 0.1016)
		(layer "B.Cu")
		(net "SAS_GF_EXP_RX_DP9")
	)
	(arc
		(start 101.027992 -209.841592)
		(mid 100.939198 -209.736778)
		(end 100.908612 -209.602832)
		(width 0.1016)
		(layer "B.Cu")
		(net "SAS_GF_EXP_RX_DP9")
	)
	(arc
		(start 101.027992 -208.276952)
		(mid 100.939198 -208.172138)
		(end 100.908612 -208.038192)
		(width 0.1016)
		(layer "B.Cu")
		(net "SAS_GF_EXP_RX_DP9")
	)
	(arc
		(start 101.027992 -202.31227)
		(mid 100.939198 -202.207456)
		(end 100.908612 -202.07351)
		(width 0.1016)
		(layer "B.Cu")
		(net "SAS_GF_EXP_RX_DP9")
	)
	(arc
		(start 101.147372 -199.42175)
		(mid 101.11688 -199.287757)
		(end 101.027992 -199.18299)
		(width 0.1016)
		(layer "B.Cu")
		(net "SAS_GF_EXP_RX_DP9")
	)
	(arc
		(start 112.667288 -103.941372)
		(mid 112.700659 -103.891431)
		(end 112.7506 -103.85806)
		(width 0.1016)
		(layer "B.Cu")
		(net "SAS_GF_EXP_RX_DP9")
	)
	(arc
		(start 112.557306 -105.100374)
		(mid 112.58843 -104.995447)
		(end 112.598962 -104.886506)
		(width 0.1016)
		(layer "B.Cu")
		(net "SAS_GF_EXP_RX_DP9")
	)
	(arc
		(start 101.027992 -200.74763)
		(mid 100.939198 -200.642816)
		(end 100.908612 -200.50887)
		(width 0.1016)
		(layer "B.Cu")
		(net "SAS_GF_EXP_RX_DP9")
	)
	(arc
		(start 101.147372 -211.644992)
		(mid 101.11688 -211.510999)
		(end 101.027992 -211.406232)
		(width 0.1016)
		(layer "B.Cu")
		(net "SAS_GF_EXP_RX_DP9")
	)
	(arc
		(start 100.908612 -212.427312)
		(mid 100.939104 -212.293319)
		(end 101.027992 -212.188552)
		(width 0.1016)
		(layer "B.Cu")
		(net "SAS_GF_EXP_RX_DP9")
	)
	(arc
		(start 101.147372 -200.98639)
		(mid 101.11688 -200.852397)
		(end 101.027992 -200.74763)
		(width 0.1016)
		(layer "B.Cu")
		(net "SAS_GF_EXP_RX_DP9")
	)
	(arc
		(start 100.908612 -209.298032)
		(mid 100.939104 -209.164039)
		(end 101.027992 -209.059272)
		(width 0.1016)
		(layer "B.Cu")
		(net "SAS_GF_EXP_RX_DP9")
	)
	(arc
		(start 111.999522 -254.281686)
		(mid 111.951463 -254.165661)
		(end 111.835438 -254.117602)
		(width 0.1016)
		(layer "B.Cu")
		(net "SAS_GF_EXP_RX_DP9")
	)
	(arc
		(start 101.027992 -212.188552)
		(mid 101.116786 -212.083738)
		(end 101.147372 -211.949792)
		(width 0.1016)
		(layer "B.Cu")
		(net "SAS_GF_EXP_RX_DP9")
	)
	(arc
		(start 111.76 -231.505506)
		(mid 111.389414 -229.642443)
		(end 110.334044 -228.063044)
		(width 0.1016)
		(layer "B.Cu")
		(net "SAS_GF_EXP_RX_DP9")
	)
	(arc
		(start 101.147372 -206.951072)
		(mid 101.11688 -206.817079)
		(end 101.027992 -206.712312)
		(width 0.1016)
		(layer "B.Cu")
		(net "SAS_GF_EXP_RX_DP9")
	)
	(arc
		(start 101.027992 -203.09459)
		(mid 101.116786 -202.989776)
		(end 101.147372 -202.85583)
		(width 0.1016)
		(layer "B.Cu")
		(net "SAS_GF_EXP_RX_DP9")
	)
	(arc
		(start 101.147372 -208.515712)
		(mid 101.11688 -208.381719)
		(end 101.027992 -208.276952)
		(width 0.1016)
		(layer "B.Cu")
		(net "SAS_GF_EXP_RX_DP9")
	)
	(arc
		(start 111.98987 -108.022644)
		(mid 112.038191 -107.779626)
		(end 112.175798 -107.573572)
		(width 0.1016)
		(layer "B.Cu")
		(net "SAS_GF_EXP_RX_DP9")
	)
	(arc
		(start 100.908612 -210.862672)
		(mid 100.939104 -210.728679)
		(end 101.027992 -210.623912)
		(width 0.1016)
		(layer "B.Cu")
		(net "SAS_GF_EXP_RX_DP9")
	)
	(arc
		(start 112.235742 -107.513628)
		(mid 112.373357 -107.307578)
		(end 112.42167 -107.064556)
		(width 0.1016)
		(layer "B.Cu")
		(net "SAS_GF_EXP_RX_DP9")
	)
	(arc
		(start 102.934262 -220.663262)
		(mid 101.435089 -218.419591)
		(end 100.908612 -215.773)
		(width 0.1016)
		(layer "B.Cu")
		(net "SAS_GF_EXP_RX_DP9")
	)
	(arc
		(start 101.027992 -210.623912)
		(mid 101.116786 -210.519098)
		(end 101.147372 -210.385152)
		(width 0.1016)
		(layer "B.Cu")
		(net "SAS_GF_EXP_RX_DP9")
	)
	(arc
		(start 101.027992 -199.18299)
		(mid 100.939198 -199.078176)
		(end 100.908612 -198.94423)
		(width 0.1016)
		(layer "B.Cu")
		(net "SAS_GF_EXP_RX_DP9")
	)
	(arc
		(start 100.908612 -186.309)
		(mid 101.049799 -185.599676)
		(end 101.451664 -184.99836)
		(width 0.1016)
		(layer "B.Cu")
		(net "SAS_GF_EXP_RX_DP9")
	)
	(arc
		(start 112.85474 -112.60963)
		(mid 112.21462 -111.651717)
		(end 111.98987 -110.52175)
		(width 0.1016)
		(layer "B.Cu")
		(net "SAS_GF_EXP_RX_DP9")
	)
	(arc
		(start 112.42167 -105.559098)
		(mid 112.433426 -105.437732)
		(end 112.468152 -105.320846)
		(width 0.1016)
		(layer "B.Cu")
		(net "SAS_GF_EXP_RX_DP9")
	)
	(arc
		(start 100.908612 -200.20407)
		(mid 100.939104 -200.070077)
		(end 101.027992 -199.96531)
		(width 0.1016)
		(layer "B.Cu")
		(net "SAS_GF_EXP_RX_DP9")
	)
	(arc
		(start 100.908612 -201.76871)
		(mid 100.939104 -201.634717)
		(end 101.027992 -201.52995)
		(width 0.1016)
		(layer "B.Cu")
		(net "SAS_GF_EXP_RX_DP9")
	)
	(arc
		(start 101.027992 -206.712312)
		(mid 100.939198 -206.607498)
		(end 100.908612 -206.473552)
		(width 0.1016)
		(layer "B.Cu")
		(net "SAS_GF_EXP_RX_DP9")
	)
	(segment
		(start 336.685382 -163.483036)
		(end 336.685382 -162.729926)
		(width 0.1143)
		(layer "F.Cu")
		(net "DEBUG_CARD_RX")
	)
	(segment
		(start 312.9026 -142.399258)
		(end 312.574178 -142.070836)
		(width 0.1143)
		(layer "F.Cu")
		(net "DEBUG_CARD_RX")
	)
	(segment
		(start 312.574178 -142.070836)
		(end 312.574178 -137.838434)
		(width 0.1143)
		(layer "F.Cu")
		(net "DEBUG_CARD_RX")
	)
	(segment
		(start 335.932526 -161.97707)
		(end 333.383382 -161.97707)
		(width 0.1143)
		(layer "F.Cu")
		(net "DEBUG_CARD_RX")
	)
	(segment
		(start 336.685382 -162.729926)
		(end 335.932526 -161.97707)
		(width 0.1143)
		(layer "F.Cu")
		(net "DEBUG_CARD_RX")
	)
	(segment
		(start 312.574178 -137.838434)
		(end 312.834528 -137.578084)
		(width 0.1143)
		(layer "F.Cu")
		(net "DEBUG_CARD_RX")
	)
	(segment
		(start 312.834528 -137.578084)
		(end 312.834528 -136.398)
		(width 0.1143)
		(layer "F.Cu")
		(net "DEBUG_CARD_RX")
	)
	(segment
		(start 327.743312 -156.337)
		(end 315.696092 -156.337)
		(width 0.1143)
		(layer "F.Cu")
		(net "DEBUG_CARD_RX")
	)
	(segment
		(start 315.696092 -156.337)
		(end 312.9026 -153.543508)
		(width 0.1143)
		(layer "F.Cu")
		(net "DEBUG_CARD_RX")
	)
	(segment
		(start 333.383382 -161.97707)
		(end 327.743312 -156.337)
		(width 0.1143)
		(layer "F.Cu")
		(net "DEBUG_CARD_RX")
	)
	(segment
		(start 312.9026 -153.543508)
		(end 312.9026 -142.399258)
		(width 0.1143)
		(layer "F.Cu")
		(net "DEBUG_CARD_RX")
	)
	(via
		(at 312.834528 -136.398)
		(size 0.5588)
		(drill 0.3048)
		(layers "F.Cu" "B.Cu")
		(net "DEBUG_CARD_RX")
	)
	(segment
		(start 334.678528 -14.478)
		(end 338.28101 -14.478)
		(width 0.127)
		(layer "In5.Cu")
		(net "DEBUG_CARD_RX")
	)
	(segment
		(start 316.484 -99.06)
		(end 327.279 -88.265)
		(width 0.127)
		(layer "In5.Cu")
		(net "DEBUG_CARD_RX")
	)
	(segment
		(start 313.055 -136.177528)
		(end 313.055 -130.302)
		(width 0.127)
		(layer "In5.Cu")
		(net "DEBUG_CARD_RX")
	)
	(segment
		(start 344.810334 -6.326124)
		(end 343.984834 -5.500624)
		(width 0.127)
		(layer "In5.Cu")
		(net "DEBUG_CARD_RX")
	)
	(segment
		(start 327.279 -21.877528)
		(end 334.678528 -14.478)
		(width 0.127)
		(layer "In5.Cu")
		(net "DEBUG_CARD_RX")
	)
	(segment
		(start 311.023 -111.948722)
		(end 311.023 -109.982)
		(width 0.127)
		(layer "In5.Cu")
		(net "DEBUG_CARD_RX")
	)
	(segment
		(start 313.055 -130.302)
		(end 310.2991 -127.5461)
		(width 0.127)
		(layer "In5.Cu")
		(net "DEBUG_CARD_RX")
	)
	(segment
		(start 311.023 -109.982)
		(end 316.484 -104.521)
		(width 0.127)
		(layer "In5.Cu")
		(net "DEBUG_CARD_RX")
	)
	(segment
		(start 342.958166 -9.849104)
		(end 344.810334 -7.996936)
		(width 0.127)
		(layer "In5.Cu")
		(net "DEBUG_CARD_RX")
	)
	(segment
		(start 327.279 -88.265)
		(end 327.279 -21.877528)
		(width 0.127)
		(layer "In5.Cu")
		(net "DEBUG_CARD_RX")
	)
	(segment
		(start 342.909906 -9.849104)
		(end 342.958166 -9.849104)
		(width 0.127)
		(layer "In5.Cu")
		(net "DEBUG_CARD_RX")
	)
	(segment
		(start 344.810334 -7.996936)
		(end 344.810334 -6.326124)
		(width 0.127)
		(layer "In5.Cu")
		(net "DEBUG_CARD_RX")
	)
	(segment
		(start 338.28101 -14.478)
		(end 342.909906 -9.849104)
		(width 0.127)
		(layer "In5.Cu")
		(net "DEBUG_CARD_RX")
	)
	(segment
		(start 312.834528 -136.398)
		(end 313.055 -136.177528)
		(width 0.127)
		(layer "In5.Cu")
		(net "DEBUG_CARD_RX")
	)
	(segment
		(start 310.2991 -127.5461)
		(end 310.2991 -112.672622)
		(width 0.127)
		(layer "In5.Cu")
		(net "DEBUG_CARD_RX")
	)
	(segment
		(start 316.484 -104.521)
		(end 316.484 -99.06)
		(width 0.127)
		(layer "In5.Cu")
		(net "DEBUG_CARD_RX")
	)
	(segment
		(start 310.2991 -112.672622)
		(end 311.023 -111.948722)
		(width 0.127)
		(layer "In5.Cu")
		(net "DEBUG_CARD_RX")
	)
	(segment
		(start 18.741136 -173.695106)
		(end 17.984978 -174.451264)
		(width 0.1143)
		(layer "F.Cu")
		(net "SAS_HDD_PRE12")
	)
	(segment
		(start 18.917666 -184.090818)
		(end 18.917666 -181.864)
		(width 0.1143)
		(layer "F.Cu")
		(net "SAS_HDD_PRE12")
	)
	(segment
		(start 19.159728 -185.409586)
		(end 19.159728 -184.33288)
		(width 0.1143)
		(layer "F.Cu")
		(net "SAS_HDD_PRE12")
	)
	(segment
		(start 17.984978 -174.451264)
		(end 17.984978 -175.746156)
		(width 0.1143)
		(layer "F.Cu")
		(net "SAS_HDD_PRE12")
	)
	(segment
		(start 20.221194 -173.695106)
		(end 18.741136 -173.695106)
		(width 0.1143)
		(layer "F.Cu")
		(net "SAS_HDD_PRE12")
	)
	(segment
		(start 18.816066 -181.7624)
		(end 18.816066 -180.396388)
		(width 0.1143)
		(layer "F.Cu")
		(net "SAS_HDD_PRE12")
	)
	(segment
		(start 19.159728 -186.704986)
		(end 19.159728 -185.409586)
		(width 0.1143)
		(layer "F.Cu")
		(net "SAS_HDD_PRE12")
	)
	(segment
		(start 19.159728 -184.33288)
		(end 18.917666 -184.090818)
		(width 0.1143)
		(layer "F.Cu")
		(net "SAS_HDD_PRE12")
	)
	(segment
		(start 18.917666 -181.864)
		(end 18.816066 -181.7624)
		(width 0.1143)
		(layer "F.Cu")
		(net "SAS_HDD_PRE12")
	)
	(segment
		(start 21.229828 -174.70374)
		(end 20.221194 -173.695106)
		(width 0.1143)
		(layer "F.Cu")
		(net "SAS_HDD_PRE12")
	)
	(segment
		(start 21.229828 -177.982626)
		(end 21.229828 -174.70374)
		(width 0.1143)
		(layer "F.Cu")
		(net "SAS_HDD_PRE12")
	)
	(segment
		(start 18.816066 -180.396388)
		(end 21.229828 -177.982626)
		(width 0.1143)
		(layer "F.Cu")
		(net "SAS_HDD_PRE12")
	)
	(via
		(at 6.859016 -198.98868)
		(size 0.7112)
		(drill 0.3556)
		(layers "F.Cu" "B.Cu")
		(net "SAS_HDD_PRE12")
	)
	(via
		(at 19.159728 -186.704986)
		(size 0.5588)
		(drill 0.3048)
		(layers "F.Cu" "B.Cu")
		(net "SAS_HDD_PRE12")
	)
	(segment
		(start 19.159728 -186.704986)
		(end 6.876034 -198.98868)
		(width 0.1143)
		(layer "B.Cu")
		(net "SAS_HDD_PRE12")
	)
	(segment
		(start 3.436366 -202.41133)
		(end 6.859016 -198.98868)
		(width 0.1143)
		(layer "B.Cu")
		(net "SAS_HDD_PRE12")
	)
	(segment
		(start 28.062936 -245.105936)
		(end 10.49909 -245.105936)
		(width 0.1143)
		(layer "B.Cu")
		(net "SAS_HDD_PRE12")
	)
	(segment
		(start 3.436366 -238.043212)
		(end 3.436366 -202.41133)
		(width 0.1143)
		(layer "B.Cu")
		(net "SAS_HDD_PRE12")
	)
	(segment
		(start 6.876034 -198.98868)
		(end 6.859016 -198.98868)
		(width 0.1143)
		(layer "B.Cu")
		(net "SAS_HDD_PRE12")
	)
	(segment
		(start 32.999426 -250.042426)
		(end 28.062936 -245.105936)
		(width 0.1143)
		(layer "B.Cu")
		(net "SAS_HDD_PRE12")
	)
	(segment
		(start 10.49909 -245.105936)
		(end 3.436366 -238.043212)
		(width 0.1143)
		(layer "B.Cu")
		(net "SAS_HDD_PRE12")
	)
	(segment
		(start 32.999426 -256.50444)
		(end 32.999426 -250.042426)
		(width 0.1143)
		(layer "B.Cu")
		(net "SAS_HDD_PRE12")
	)
	(segment
		(start 286.04464 -179.830222)
		(end 286.04464 -179.838096)
		(width 0.1143)
		(layer "F.Cu")
		(net "ROMD2")
	)
	(segment
		(start 286.434784 -179.440078)
		(end 286.04464 -179.830222)
		(width 0.1143)
		(layer "F.Cu")
		(net "ROMD2")
	)
	(segment
		(start 334.518 -85.344)
		(end 334.518 -84.3915)
		(width 0.1143)
		(layer "F.Cu")
		(net "ROMD2")
	)
	(segment
		(start 286.04464 -179.838096)
		(end 286.04337 -179.839366)
		(width 0.1143)
		(layer "F.Cu")
		(net "ROMD2")
	)
	(via
		(at 276.2504 -184.665366)
		(size 0.5588)
		(drill 0.3048)
		(layers "F.Cu" "B.Cu")
		(net "ROMD2")
	)
	(via
		(at 298.323 -92.964)
		(size 0.5588)
		(drill 0.3048)
		(layers "F.Cu" "B.Cu")
		(net "ROMD2")
	)
	(via
		(at 286.04337 -179.839366)
		(size 0.508)
		(drill 0.254)
		(layers "F.Cu" "B.Cu")
		(net "ROMD2")
	)
	(via
		(at 281.0256 -181.4576)
		(size 0.7112)
		(drill 0.3556)
		(layers "F.Cu" "B.Cu")
		(net "ROMD2")
	)
	(via
		(at 334.518 -85.344)
		(size 0.5588)
		(drill 0.3048)
		(layers "F.Cu" "B.Cu")
		(net "ROMD2")
	)
	(segment
		(start 333.502 -85.344)
		(end 331.724 -87.122)
		(width 0.1143)
		(layer "B.Cu")
		(net "ROMD2")
	)
	(segment
		(start 280.045414 -181.976014)
		(end 277.356062 -184.665366)
		(width 0.1143)
		(layer "B.Cu")
		(net "ROMD2")
	)
	(segment
		(start 280.507186 -181.976014)
		(end 280.045414 -181.976014)
		(width 0.1143)
		(layer "B.Cu")
		(net "ROMD2")
	)
	(segment
		(start 309.245 -87.122)
		(end 303.403 -92.964)
		(width 0.1143)
		(layer "B.Cu")
		(net "ROMD2")
	)
	(segment
		(start 277.356062 -184.665366)
		(end 276.2504 -184.665366)
		(width 0.1143)
		(layer "B.Cu")
		(net "ROMD2")
	)
	(segment
		(start 334.518 -85.344)
		(end 333.502 -85.344)
		(width 0.1143)
		(layer "B.Cu")
		(net "ROMD2")
	)
	(segment
		(start 285.905956 -179.97678)
		(end 286.04337 -179.839366)
		(width 0.1143)
		(layer "B.Cu")
		(net "ROMD2")
	)
	(segment
		(start 281.0256 -181.4576)
		(end 282.50642 -179.97678)
		(width 0.1143)
		(layer "B.Cu")
		(net "ROMD2")
	)
	(segment
		(start 274.6375 -183.769)
		(end 275.354034 -183.769)
		(width 0.1143)
		(layer "B.Cu")
		(net "ROMD2")
	)
	(segment
		(start 275.354034 -183.769)
		(end 276.2504 -184.665366)
		(width 0.1143)
		(layer "B.Cu")
		(net "ROMD2")
	)
	(segment
		(start 303.403 -92.964)
		(end 298.323 -92.964)
		(width 0.1143)
		(layer "B.Cu")
		(net "ROMD2")
	)
	(segment
		(start 331.724 -87.122)
		(end 309.245 -87.122)
		(width 0.1143)
		(layer "B.Cu")
		(net "ROMD2")
	)
	(segment
		(start 282.50642 -179.97678)
		(end 285.905956 -179.97678)
		(width 0.1143)
		(layer "B.Cu")
		(net "ROMD2")
	)
	(segment
		(start 281.0256 -181.4576)
		(end 280.507186 -181.976014)
		(width 0.1143)
		(layer "B.Cu")
		(net "ROMD2")
	)
	(segment
		(start 277.6093 -181.964838)
		(end 277.6093 -167.5511)
		(width 0.127)
		(layer "In5.Cu")
		(net "ROMD2")
	)
	(segment
		(start 273.6469 -137.893298)
		(end 278.825198 -132.715)
		(width 0.127)
		(layer "In5.Cu")
		(net "ROMD2")
	)
	(segment
		(start 294.513 -114.177064)
		(end 294.513 -96.774)
		(width 0.127)
		(layer "In5.Cu")
		(net "ROMD2")
	)
	(segment
		(start 273.6469 -149.1869)
		(end 273.6469 -137.893298)
		(width 0.127)
		(layer "In5.Cu")
		(net "ROMD2")
	)
	(segment
		(start 275.6916 -151.2316)
		(end 273.6469 -149.1869)
		(width 0.127)
		(layer "In5.Cu")
		(net "ROMD2")
	)
	(segment
		(start 277.6093 -167.5511)
		(end 276.5171 -166.4589)
		(width 0.127)
		(layer "In5.Cu")
		(net "ROMD2")
	)
	(segment
		(start 276.5171 -165.879018)
		(end 275.6916 -165.053518)
		(width 0.127)
		(layer "In5.Cu")
		(net "ROMD2")
	)
	(segment
		(start 283.464 -125.226064)
		(end 294.513 -114.177064)
		(width 0.127)
		(layer "In5.Cu")
		(net "ROMD2")
	)
	(segment
		(start 294.513 -96.774)
		(end 298.323 -92.964)
		(width 0.127)
		(layer "In5.Cu")
		(net "ROMD2")
	)
	(segment
		(start 276.5171 -166.4589)
		(end 276.5171 -165.879018)
		(width 0.127)
		(layer "In5.Cu")
		(net "ROMD2")
	)
	(segment
		(start 283.464 -131.002532)
		(end 283.464 -125.226064)
		(width 0.127)
		(layer "In5.Cu")
		(net "ROMD2")
	)
	(segment
		(start 275.6916 -165.053518)
		(end 275.6916 -151.2316)
		(width 0.127)
		(layer "In5.Cu")
		(net "ROMD2")
	)
	(segment
		(start 276.2504 -184.665366)
		(end 276.2504 -183.323738)
		(width 0.127)
		(layer "In5.Cu")
		(net "ROMD2")
	)
	(segment
		(start 276.2504 -183.323738)
		(end 277.6093 -181.964838)
		(width 0.127)
		(layer "In5.Cu")
		(net "ROMD2")
	)
	(segment
		(start 278.825198 -132.715)
		(end 281.751532 -132.715)
		(width 0.127)
		(layer "In5.Cu")
		(net "ROMD2")
	)
	(segment
		(start 281.751532 -132.715)
		(end 283.464 -131.002532)
		(width 0.127)
		(layer "In5.Cu")
		(net "ROMD2")
	)
	(segment
		(start 103.008684 -243.724684)
		(end 105.675684 -243.724684)
		(width 0.1143)
		(layer "F.Cu")
		(net "SAS_FAULT_LED2")
	)
	(segment
		(start 102.4255 -243.1415)
		(end 103.008684 -243.724684)
		(width 0.1143)
		(layer "F.Cu")
		(net "SAS_FAULT_LED2")
	)
	(segment
		(start 102.4255 -241.046)
		(end 102.4255 -243.1415)
		(width 0.1143)
		(layer "F.Cu")
		(net "SAS_FAULT_LED2")
	)
	(segment
		(start 102.4255 -239.4712)
		(end 102.4255 -241.046)
		(width 0.1143)
		(layer "F.Cu")
		(net "SAS_FAULT_LED2")
	)
	(via
		(at 105.675684 -243.724684)
		(size 0.5588)
		(drill 0.3048)
		(layers "F.Cu" "B.Cu")
		(net "SAS_FAULT_LED2")
	)
	(via
		(at 102.4255 -241.046)
		(size 0.5588)
		(drill 0.3048)
		(layers "F.Cu" "B.Cu")
		(net "SAS_FAULT_LED2")
	)
	(via
		(at 105.918 -246.126)
		(size 0.7112)
		(drill 0.3556)
		(layers "F.Cu" "B.Cu")
		(net "SAS_FAULT_LED2")
	)
	(segment
		(start 105.687368 -243.713)
		(end 105.675684 -243.724684)
		(width 0.1143)
		(layer "B.Cu")
		(net "SAS_FAULT_LED2")
	)
	(segment
		(start 106.706416 -243.713)
		(end 105.687368 -243.713)
		(width 0.1143)
		(layer "B.Cu")
		(net "SAS_FAULT_LED2")
	)
	(segment
		(start 103.4415 -227.965)
		(end 103.632 -227.965)
		(width 0.1143)
		(layer "B.Cu")
		(net "SAS_FAULT_LED2")
	)
	(segment
		(start 108.806742 -238.854742)
		(end 108.806742 -241.612674)
		(width 0.1143)
		(layer "B.Cu")
		(net "SAS_FAULT_LED2")
	)
	(segment
		(start 106.000042 -256.50444)
		(end 106.000042 -253.409958)
		(width 0.1143)
		(layer "B.Cu")
		(net "SAS_FAULT_LED2")
	)
	(segment
		(start 108.458 -238.506)
		(end 108.806742 -238.854742)
		(width 0.1143)
		(layer "B.Cu")
		(net "SAS_FAULT_LED2")
	)
	(segment
		(start 101.854 -239.8395)
		(end 101.854 -240.4745)
		(width 0.1143)
		(layer "B.Cu")
		(net "SAS_FAULT_LED2")
	)
	(segment
		(start 105.675684 -244.152674)
		(end 105.17505 -244.653308)
		(width 0.1143)
		(layer "B.Cu")
		(net "SAS_FAULT_LED2")
	)
	(segment
		(start 108.806742 -241.612674)
		(end 106.706416 -243.713)
		(width 0.1143)
		(layer "B.Cu")
		(net "SAS_FAULT_LED2")
	)
	(segment
		(start 107.01655 -252.39345)
		(end 107.01655 -247.22455)
		(width 0.1143)
		(layer "B.Cu")
		(net "SAS_FAULT_LED2")
	)
	(segment
		(start 103.632 -227.965)
		(end 108.458 -232.791)
		(width 0.1143)
		(layer "B.Cu")
		(net "SAS_FAULT_LED2")
	)
	(segment
		(start 101.854 -240.4745)
		(end 102.4255 -241.046)
		(width 0.1143)
		(layer "B.Cu")
		(net "SAS_FAULT_LED2")
	)
	(segment
		(start 106.000042 -253.409958)
		(end 107.01655 -252.39345)
		(width 0.1143)
		(layer "B.Cu")
		(net "SAS_FAULT_LED2")
	)
	(segment
		(start 105.675684 -243.724684)
		(end 105.675684 -244.152674)
		(width 0.1143)
		(layer "B.Cu")
		(net "SAS_FAULT_LED2")
	)
	(segment
		(start 107.01655 -247.22455)
		(end 105.918 -246.126)
		(width 0.1143)
		(layer "B.Cu")
		(net "SAS_FAULT_LED2")
	)
	(segment
		(start 108.458 -232.791)
		(end 108.458 -238.506)
		(width 0.1143)
		(layer "B.Cu")
		(net "SAS_FAULT_LED2")
	)
	(segment
		(start 105.17505 -244.653308)
		(end 105.17505 -245.38305)
		(width 0.1143)
		(layer "B.Cu")
		(net "SAS_FAULT_LED2")
	)
	(segment
		(start 105.17505 -245.38305)
		(end 105.918 -246.126)
		(width 0.1143)
		(layer "B.Cu")
		(net "SAS_FAULT_LED2")
	)
	(segment
		(start 74.999342 -256.25044)
		(end 74.999342 -254.689356)
		(width 0.1016)
		(layer "F.Cu")
		(net "SAS_EXP_GF_TX_DN14")
	)
	(segment
		(start 76.074778 -192.231772)
		(end 103.14559 -165.16096)
		(width 0.1016)
		(layer "F.Cu")
		(net "SAS_EXP_GF_TX_DN14")
	)
	(segment
		(start 103.66502 -163.906962)
		(end 103.66502 -114.885978)
		(width 0.1016)
		(layer "F.Cu")
		(net "SAS_EXP_GF_TX_DN14")
	)
	(segment
		(start 103.51897 -114.607848)
		(end 103.51897 -114.5794)
		(width 0.1016)
		(layer "F.Cu")
		(net "SAS_EXP_GF_TX_DN14")
	)
	(segment
		(start 75.368912 -253.7968)
		(end 75.368912 -193.935858)
		(width 0.1016)
		(layer "F.Cu")
		(net "SAS_EXP_GF_TX_DN14")
	)
	(segment
		(start 103.592122 -114.709448)
		(end 103.53929 -114.65687)
		(width 0.1016)
		(layer "F.Cu")
		(net "SAS_EXP_GF_TX_DN14")
	)
	(arc
		(start 103.53929 -114.65687)
		(mid 103.524262 -114.634379)
		(end 103.51897 -114.607848)
		(width 0.1016)
		(layer "F.Cu")
		(net "SAS_EXP_GF_TX_DN14")
	)
	(arc
		(start 103.66502 -114.885978)
		(mid 103.646116 -114.790472)
		(end 103.592122 -114.709448)
		(width 0.1016)
		(layer "F.Cu")
		(net "SAS_EXP_GF_TX_DN14")
	)
	(arc
		(start 103.14559 -165.16096)
		(mid 103.530019 -164.585621)
		(end 103.66502 -163.906962)
		(width 0.1016)
		(layer "F.Cu")
		(net "SAS_EXP_GF_TX_DN14")
	)
	(arc
		(start 75.180444 -254.252222)
		(mid 75.319977 -254.043258)
		(end 75.368912 -253.7968)
		(width 0.1016)
		(layer "F.Cu")
		(net "SAS_EXP_GF_TX_DN14")
	)
	(arc
		(start 75.368912 -193.935858)
		(mid 75.552359 -193.013609)
		(end 76.074778 -192.231772)
		(width 0.1016)
		(layer "F.Cu")
		(net "SAS_EXP_GF_TX_DN14")
	)
	(arc
		(start 74.999342 -254.689356)
		(mid 75.046402 -254.452767)
		(end 75.180444 -254.252222)
		(width 0.1016)
		(layer "F.Cu")
		(net "SAS_EXP_GF_TX_DN14")
	)
	(segment
		(start 275.082 -183.515)
		(end 275.971 -182.626)
		(width 0.1143)
		(layer "F.Cu")
		(net "ROMD3")
	)
	(segment
		(start 275.971 -182.418228)
		(end 275.971 -182.626)
		(width 0.1143)
		(layer "F.Cu")
		(net "ROMD3")
	)
	(segment
		(start 278.021034 -180.157628)
		(end 276.4282 -181.750462)
		(width 0.1143)
		(layer "F.Cu")
		(net "ROMD3")
	)
	(segment
		(start 274.6375 -183.515)
		(end 275.082 -183.515)
		(width 0.1143)
		(layer "F.Cu")
		(net "ROMD3")
	)
	(segment
		(start 276.4282 -181.750462)
		(end 276.4282 -181.960774)
		(width 0.1143)
		(layer "F.Cu")
		(net "ROMD3")
	)
	(segment
		(start 276.4282 -181.960774)
		(end 275.971 -182.418228)
		(width 0.1143)
		(layer "F.Cu")
		(net "ROMD3")
	)
	(segment
		(start 283.46654 -180.240178)
		(end 283.38399 -180.157628)
		(width 0.1143)
		(layer "F.Cu")
		(net "ROMD3")
	)
	(segment
		(start 284.834838 -180.240178)
		(end 283.46654 -180.240178)
		(width 0.1143)
		(layer "F.Cu")
		(net "ROMD3")
	)
	(segment
		(start 283.38399 -180.157628)
		(end 278.021034 -180.157628)
		(width 0.1143)
		(layer "F.Cu")
		(net "ROMD3")
	)
	(via
		(at 275.971 -182.626)
		(size 0.7112)
		(drill 0.3556)
		(layers "F.Cu" "B.Cu")
		(net "ROMD3")
	)
	(segment
		(start 288.034984 -175.440086)
		(end 287.63976 -175.83531)
		(width 0.1143)
		(layer "F.Cu")
		(net "ROMA12")
	)
	(via
		(at 287.63976 -175.83531)
		(size 0.508)
		(drill 0.254)
		(layers "F.Cu" "B.Cu")
		(net "ROMA12")
	)
	(via
		(at 275.9964 -178.816)
		(size 0.7112)
		(drill 0.3556)
		(layers "F.Cu" "B.Cu")
		(net "ROMA12")
	)
	(segment
		(start 274.7645 -178.816)
		(end 275.9964 -178.816)
		(width 0.1143)
		(layer "B.Cu")
		(net "ROMA12")
	)
	(segment
		(start 274.6375 -178.689)
		(end 274.7645 -178.816)
		(width 0.1143)
		(layer "B.Cu")
		(net "ROMA12")
	)
	(segment
		(start 286.296354 -177.05324)
		(end 287.514284 -175.83531)
		(width 0.1143)
		(layer "B.Cu")
		(net "ROMA12")
	)
	(segment
		(start 279.580848 -176.92878)
		(end 283.63926 -176.92878)
		(width 0.1143)
		(layer "B.Cu")
		(net "ROMA12")
	)
	(segment
		(start 275.9964 -178.816)
		(end 277.693628 -178.816)
		(width 0.1143)
		(layer "B.Cu")
		(net "ROMA12")
	)
	(segment
		(start 283.63926 -176.92878)
		(end 283.76372 -177.05324)
		(width 0.1143)
		(layer "B.Cu")
		(net "ROMA12")
	)
	(segment
		(start 287.514284 -175.83531)
		(end 287.63976 -175.83531)
		(width 0.1143)
		(layer "B.Cu")
		(net "ROMA12")
	)
	(segment
		(start 277.693628 -178.816)
		(end 279.580848 -176.92878)
		(width 0.1143)
		(layer "B.Cu")
		(net "ROMA12")
	)
	(segment
		(start 283.76372 -177.05324)
		(end 286.296354 -177.05324)
		(width 0.1143)
		(layer "B.Cu")
		(net "ROMA12")
	)
	(segment
		(start 129.440178 -117.955822)
		(end 135.763 -111.633)
		(width 0.1016)
		(layer "F.Cu")
		(net "SAS_EXP_GF_TX_DN0")
	)
	(segment
		(start 145.949162 -167.143938)
		(end 139.57427 -160.769046)
		(width 0.1016)
		(layer "F.Cu")
		(net "SAS_EXP_GF_TX_DN0")
	)
	(segment
		(start 136.41705 -110.054136)
		(end 136.41705 -99.599496)
		(width 0.1016)
		(layer "F.Cu")
		(net "SAS_EXP_GF_TX_DN0")
	)
	(segment
		(start 139.07897 -160.274)
		(end 129.75082 -150.94585)
		(width 0.1016)
		(layer "F.Cu")
		(net "SAS_EXP_GF_TX_DN0")
	)
	(segment
		(start 136.387332 -99.527614)
		(end 136.300718 -99.441)
		(width 0.1016)
		(layer "F.Cu")
		(net "SAS_EXP_GF_TX_DN0")
	)
	(segment
		(start 139.57427 -160.769046)
		(end 139.07897 -160.274)
		(width 0.1016)
		(layer "F.Cu")
		(net "SAS_EXP_GF_TX_DN0")
	)
	(segment
		(start 146.999452 -256.25044)
		(end 146.999452 -254.170434)
		(width 0.1016)
		(layer "F.Cu")
		(net "SAS_EXP_GF_TX_DN0")
	)
	(segment
		(start 147.339812 -253.661926)
		(end 147.339812 -170.50131)
		(width 0.1016)
		(layer "F.Cu")
		(net "SAS_EXP_GF_TX_DN0")
	)
	(segment
		(start 147.058888 -254.026924)
		(end 147.280376 -253.805436)
		(width 0.1016)
		(layer "F.Cu")
		(net "SAS_EXP_GF_TX_DN0")
	)
	(segment
		(start 128.905 -148.903436)
		(end 128.905 -119.24792)
		(width 0.1016)
		(layer "F.Cu")
		(net "SAS_EXP_GF_TX_DN0")
	)
	(segment
		(start 136.271 -99.369118)
		(end 136.271 -99.0854)
		(width 0.1016)
		(layer "F.Cu")
		(net "SAS_EXP_GF_TX_DN0")
	)
	(arc
		(start 129.75082 -150.94585)
		(mid 129.124774 -150.008767)
		(end 128.905 -148.903436)
		(width 0.1016)
		(layer "F.Cu")
		(net "SAS_EXP_GF_TX_DN0")
	)
	(arc
		(start 147.339812 -170.50131)
		(mid 146.97839 -168.684321)
		(end 145.949162 -167.143938)
		(width 0.1016)
		(layer "F.Cu")
		(net "SAS_EXP_GF_TX_DN0")
	)
	(arc
		(start 136.300718 -99.441)
		(mid 136.278735 -99.408006)
		(end 136.271 -99.369118)
		(width 0.1016)
		(layer "F.Cu")
		(net "SAS_EXP_GF_TX_DN0")
	)
	(arc
		(start 146.999452 -254.170434)
		(mid 147.0149 -254.09277)
		(end 147.058888 -254.026924)
		(width 0.1016)
		(layer "F.Cu")
		(net "SAS_EXP_GF_TX_DN0")
	)
	(arc
		(start 135.763 -111.633)
		(mid 136.247075 -110.908625)
		(end 136.41705 -110.054136)
		(width 0.1016)
		(layer "F.Cu")
		(net "SAS_EXP_GF_TX_DN0")
	)
	(arc
		(start 136.41705 -99.599496)
		(mid 136.409331 -99.560601)
		(end 136.387332 -99.527614)
		(width 0.1016)
		(layer "F.Cu")
		(net "SAS_EXP_GF_TX_DN0")
	)
	(arc
		(start 147.280376 -253.805436)
		(mid 147.324371 -253.739593)
		(end 147.339812 -253.661926)
		(width 0.1016)
		(layer "F.Cu")
		(net "SAS_EXP_GF_TX_DN0")
	)
	(arc
		(start 128.905 -119.24792)
		(mid 129.044078 -118.548638)
		(end 129.440178 -117.955822)
		(width 0.1016)
		(layer "F.Cu")
		(net "SAS_EXP_GF_TX_DN0")
	)
	(segment
		(start 303.149 -144.907)
		(end 303.149 -154.94)
		(width 0.1143)
		(layer "F.Cu")
		(net "RMII_BMC_MDC")
	)
	(segment
		(start 297.77055 -165.14445)
		(end 297.23969 -165.67531)
		(width 0.1143)
		(layer "F.Cu")
		(net "RMII_BMC_MDC")
	)
	(segment
		(start 261.9248 -93.350334)
		(end 268.05255 -99.478084)
		(width 0.1143)
		(layer "F.Cu")
		(net "RMII_BMC_MDC")
	)
	(segment
		(start 193.294 -21.7424)
		(end 195.1228 -23.5712)
		(width 0.1143)
		(layer "F.Cu")
		(net "RMII_BMC_MDC")
	)
	(segment
		(start 261.9248 -91.8718)
		(end 261.9248 -93.350334)
		(width 0.1143)
		(layer "F.Cu")
		(net "RMII_BMC_MDC")
	)
	(segment
		(start 192.1891 -21.7424)
		(end 193.294 -21.7424)
		(width 0.1143)
		(layer "F.Cu")
		(net "RMII_BMC_MDC")
	)
	(segment
		(start 303.81575 -155.60675)
		(end 303.81575 -159.862774)
		(width 0.1143)
		(layer "F.Cu")
		(net "RMII_BMC_MDC")
	)
	(segment
		(start 269.0495 -134.528306)
		(end 275.256244 -140.73505)
		(width 0.1143)
		(layer "F.Cu")
		(net "RMII_BMC_MDC")
	)
	(segment
		(start 268.05255 -99.478084)
		(end 268.05255 -118.87835)
		(width 0.1143)
		(layer "F.Cu")
		(net "RMII_BMC_MDC")
	)
	(segment
		(start 301.848774 -161.82975)
		(end 300.229524 -161.82975)
		(width 0.1143)
		(layer "F.Cu")
		(net "RMII_BMC_MDC")
	)
	(segment
		(start 303.81575 -159.862774)
		(end 301.848774 -161.82975)
		(width 0.1143)
		(layer "F.Cu")
		(net "RMII_BMC_MDC")
	)
	(segment
		(start 275.256244 -140.73505)
		(end 276.046692 -140.73505)
		(width 0.1143)
		(layer "F.Cu")
		(net "RMII_BMC_MDC")
	)
	(segment
		(start 196.0118 -24.4602)
		(end 196.0118 -25.9588)
		(width 0.1143)
		(layer "F.Cu")
		(net "RMII_BMC_MDC")
	)
	(segment
		(start 297.23969 -168.71569)
		(end 297.564048 -169.040048)
		(width 0.1143)
		(layer "F.Cu")
		(net "RMII_BMC_MDC")
	)
	(segment
		(start 288.56305 -142.00505)
		(end 300.24705 -142.00505)
		(width 0.1143)
		(layer "F.Cu")
		(net "RMII_BMC_MDC")
	)
	(segment
		(start 300.229524 -161.82975)
		(end 297.77055 -164.288724)
		(width 0.1143)
		(layer "F.Cu")
		(net "RMII_BMC_MDC")
	)
	(segment
		(start 303.149 -154.94)
		(end 303.81575 -155.60675)
		(width 0.1143)
		(layer "F.Cu")
		(net "RMII_BMC_MDC")
	)
	(segment
		(start 268.05255 -118.87835)
		(end 269.0495 -119.8753)
		(width 0.1143)
		(layer "F.Cu")
		(net "RMII_BMC_MDC")
	)
	(segment
		(start 269.0495 -119.8753)
		(end 269.0495 -134.528306)
		(width 0.1143)
		(layer "F.Cu")
		(net "RMII_BMC_MDC")
	)
	(segment
		(start 195.1228 -23.5712)
		(end 196.0118 -24.4602)
		(width 0.1143)
		(layer "F.Cu")
		(net "RMII_BMC_MDC")
	)
	(segment
		(start 196.0118 -25.9588)
		(end 261.9248 -91.8718)
		(width 0.1143)
		(layer "F.Cu")
		(net "RMII_BMC_MDC")
	)
	(segment
		(start 297.564048 -169.040048)
		(end 297.634914 -169.040048)
		(width 0.1143)
		(layer "F.Cu")
		(net "RMII_BMC_MDC")
	)
	(segment
		(start 276.046692 -140.73505)
		(end 277.316692 -142.00505)
		(width 0.1143)
		(layer "F.Cu")
		(net "RMII_BMC_MDC")
	)
	(segment
		(start 277.316692 -142.00505)
		(end 279.54605 -142.00505)
		(width 0.1143)
		(layer "F.Cu")
		(net "RMII_BMC_MDC")
	)
	(segment
		(start 191.4525 -22.479)
		(end 190.3095 -22.479)
		(width 0.1143)
		(layer "F.Cu")
		(net "RMII_BMC_MDC")
	)
	(segment
		(start 297.77055 -164.288724)
		(end 297.77055 -165.14445)
		(width 0.1143)
		(layer "F.Cu")
		(net "RMII_BMC_MDC")
	)
	(segment
		(start 300.24705 -142.00505)
		(end 303.149 -144.907)
		(width 0.1143)
		(layer "F.Cu")
		(net "RMII_BMC_MDC")
	)
	(segment
		(start 191.4525 -22.479)
		(end 192.1891 -21.7424)
		(width 0.1143)
		(layer "F.Cu")
		(net "RMII_BMC_MDC")
	)
	(segment
		(start 297.23969 -165.67531)
		(end 297.23969 -168.71569)
		(width 0.1143)
		(layer "F.Cu")
		(net "RMII_BMC_MDC")
	)
	(via
		(at 279.54605 -142.00505)
		(size 0.5588)
		(drill 0.3048)
		(layers "F.Cu" "B.Cu")
		(net "RMII_BMC_MDC")
	)
	(via
		(at 195.1228 -23.5712)
		(size 0.7112)
		(drill 0.3556)
		(layers "F.Cu" "B.Cu")
		(net "RMII_BMC_MDC")
	)
	(via
		(at 288.56305 -142.00505)
		(size 0.5588)
		(drill 0.3048)
		(layers "F.Cu" "B.Cu")
		(net "RMII_BMC_MDC")
	)
	(segment
		(start 288.56305 -142.00505)
		(end 279.54605 -142.00505)
		(width 0.127)
		(layer "In5.Cu")
		(net "RMII_BMC_MDC")
	)
	(segment
		(start 101.000052 -256.25044)
		(end 101.000052 -254.28194)
		(width 0.1016)
		(layer "F.Cu")
		(net "SAS_EXP_GF_TX_DP10")
	)
	(segment
		(start 94.036896 -186.03722)
		(end 97.628964 -182.445152)
		(width 0.1016)
		(layer "F.Cu")
		(net "SAS_EXP_GF_TX_DP10")
	)
	(segment
		(start 92.930472 -187.143644)
		(end 93.146118 -186.927998)
		(width 0.1016)
		(layer "F.Cu")
		(net "SAS_EXP_GF_TX_DP10")
	)
	(segment
		(start 100.348288 -180.063648)
		(end 100.56368 -179.848002)
		(width 0.1016)
		(layer "F.Cu")
		(net "SAS_EXP_GF_TX_DP10")
	)
	(segment
		(start 83.660488 -196.413628)
		(end 90.93327 -189.140846)
		(width 0.1016)
		(layer "F.Cu")
		(net "SAS_EXP_GF_TX_DP10")
	)
	(segment
		(start 99.821746 -249.284998)
		(end 98.830638 -248.29389)
		(width 0.1016)
		(layer "F.Cu")
		(net "SAS_EXP_GF_TX_DP10")
	)
	(segment
		(start 100.671884 -254.07874)
		(end 100.671884 -251.337318)
		(width 0.1016)
		(layer "F.Cu")
		(net "SAS_EXP_GF_TX_DP10")
	)
	(segment
		(start 92.54617 -187.865512)
		(end 92.761562 -187.65012)
		(width 0.1016)
		(layer "F.Cu")
		(net "SAS_EXP_GF_TX_DP10")
	)
	(segment
		(start 98.519742 -181.554374)
		(end 98.735388 -181.338728)
		(width 0.1016)
		(layer "F.Cu")
		(net "SAS_EXP_GF_TX_DP10")
	)
	(segment
		(start 93.652594 -186.759342)
		(end 93.867986 -186.543696)
		(width 0.1016)
		(layer "F.Cu")
		(net "SAS_EXP_GF_TX_DP10")
	)
	(segment
		(start 100.898452 -254.18034)
		(end 100.773484 -254.18034)
		(width 0.1016)
		(layer "F.Cu")
		(net "SAS_EXP_GF_TX_DP10")
	)
	(segment
		(start 111.26597 -114.583972)
		(end 111.26597 -114.5794)
		(width 0.1016)
		(layer "F.Cu")
		(net "SAS_EXP_GF_TX_DP10")
	)
	(segment
		(start 91.439746 -188.971936)
		(end 91.655392 -188.756544)
		(width 0.1016)
		(layer "F.Cu")
		(net "SAS_EXP_GF_TX_DP10")
	)
	(segment
		(start 98.13544 -182.276242)
		(end 98.351086 -182.06085)
		(width 0.1016)
		(layer "F.Cu")
		(net "SAS_EXP_GF_TX_DP10")
	)
	(segment
		(start 93.135196 -244.973094)
		(end 84.059268 -244.973094)
		(width 0.1016)
		(layer "F.Cu")
		(net "SAS_EXP_GF_TX_DP10")
	)
	(segment
		(start 99.626166 -180.44795)
		(end 99.841812 -180.232304)
		(width 0.1016)
		(layer "F.Cu")
		(net "SAS_EXP_GF_TX_DP10")
	)
	(segment
		(start 91.824048 -188.250068)
		(end 92.039694 -188.034422)
		(width 0.1016)
		(layer "F.Cu")
		(net "SAS_EXP_GF_TX_DP10")
	)
	(segment
		(start 96.760792 -247.43664)
		(end 95.118936 -245.794784)
		(width 0.1016)
		(layer "F.Cu")
		(net "SAS_EXP_GF_TX_DP10")
	)
	(segment
		(start 111.192564 -114.760502)
		(end 111.192818 -114.760248)
		(width 0.1016)
		(layer "F.Cu")
		(net "SAS_EXP_GF_TX_DP10")
	)
	(segment
		(start 99.241864 -181.170072)
		(end 99.457256 -180.954426)
		(width 0.1016)
		(layer "F.Cu")
		(net "SAS_EXP_GF_TX_DP10")
	)
	(segment
		(start 82.8929 -243.462302)
		(end 82.8929 -198.266812)
		(width 0.1016)
		(layer "F.Cu")
		(net "SAS_EXP_GF_TX_DP10")
	)
	(segment
		(start 100.73259 -179.341526)
		(end 110.660688 -169.413428)
		(width 0.1016)
		(layer "F.Cu")
		(net "SAS_EXP_GF_TX_DP10")
	)
	(segment
		(start 111.11992 -168.304718)
		(end 111.11992 -114.936524)
		(width 0.1016)
		(layer "F.Cu")
		(net "SAS_EXP_GF_TX_DP10")
	)
	(arc
		(start 91.73972 -188.503306)
		(mid 91.75095 -188.366381)
		(end 91.824048 -188.250068)
		(width 0.1016)
		(layer "F.Cu")
		(net "SAS_EXP_GF_TX_DP10")
	)
	(arc
		(start 93.399356 -186.84367)
		(mid 93.536281 -186.83244)
		(end 93.652594 -186.759342)
		(width 0.1016)
		(layer "F.Cu")
		(net "SAS_EXP_GF_TX_DP10")
	)
	(arc
		(start 97.882202 -182.360824)
		(mid 98.01915 -182.34946)
		(end 98.13544 -182.276242)
		(width 0.1016)
		(layer "F.Cu")
		(net "SAS_EXP_GF_TX_DP10")
	)
	(arc
		(start 98.435414 -181.807612)
		(mid 98.446644 -181.670687)
		(end 98.519742 -181.554374)
		(width 0.1016)
		(layer "F.Cu")
		(net "SAS_EXP_GF_TX_DP10")
	)
	(arc
		(start 98.988626 -181.2544)
		(mid 99.125551 -181.24317)
		(end 99.241864 -181.170072)
		(width 0.1016)
		(layer "F.Cu")
		(net "SAS_EXP_GF_TX_DP10")
	)
	(arc
		(start 92.039694 -188.034422)
		(mid 92.156019 -187.961362)
		(end 92.292932 -187.950094)
		(width 0.1016)
		(layer "F.Cu")
		(net "SAS_EXP_GF_TX_DP10")
	)
	(arc
		(start 92.761562 -187.65012)
		(mid 92.834785 -187.533832)
		(end 92.846144 -187.396882)
		(width 0.1016)
		(layer "F.Cu")
		(net "SAS_EXP_GF_TX_DP10")
	)
	(arc
		(start 99.841812 -180.232304)
		(mid 99.958137 -180.159244)
		(end 100.09505 -180.147976)
		(width 0.1016)
		(layer "F.Cu")
		(net "SAS_EXP_GF_TX_DP10")
	)
	(arc
		(start 83.406996 -244.702838)
		(mid 83.026581 -244.133691)
		(end 82.8929 -243.462302)
		(width 0.1016)
		(layer "F.Cu")
		(net "SAS_EXP_GF_TX_DP10")
	)
	(arc
		(start 93.952568 -186.290458)
		(mid 93.963798 -186.153533)
		(end 94.036896 -186.03722)
		(width 0.1016)
		(layer "F.Cu")
		(net "SAS_EXP_GF_TX_DP10")
	)
	(arc
		(start 82.8929 -198.266812)
		(mid 83.092394 -197.263886)
		(end 83.660488 -196.413628)
		(width 0.1016)
		(layer "F.Cu")
		(net "SAS_EXP_GF_TX_DP10")
	)
	(arc
		(start 100.671884 -251.337318)
		(mid 100.450948 -250.226595)
		(end 99.821746 -249.284998)
		(width 0.1016)
		(layer "F.Cu")
		(net "SAS_EXP_GF_TX_DP10")
	)
	(arc
		(start 93.867986 -186.543696)
		(mid 93.941209 -186.427408)
		(end 93.952568 -186.290458)
		(width 0.1016)
		(layer "F.Cu")
		(net "SAS_EXP_GF_TX_DP10")
	)
	(arc
		(start 92.292932 -187.950094)
		(mid 92.42988 -187.93873)
		(end 92.54617 -187.865512)
		(width 0.1016)
		(layer "F.Cu")
		(net "SAS_EXP_GF_TX_DP10")
	)
	(arc
		(start 97.628964 -182.445152)
		(mid 97.745289 -182.372092)
		(end 97.882202 -182.360824)
		(width 0.1016)
		(layer "F.Cu")
		(net "SAS_EXP_GF_TX_DP10")
	)
	(arc
		(start 101.000052 -254.28194)
		(mid 100.970294 -254.210098)
		(end 100.898452 -254.18034)
		(width 0.1016)
		(layer "F.Cu")
		(net "SAS_EXP_GF_TX_DP10")
	)
	(arc
		(start 93.146118 -186.927998)
		(mid 93.262443 -186.854938)
		(end 93.399356 -186.84367)
		(width 0.1016)
		(layer "F.Cu")
		(net "SAS_EXP_GF_TX_DP10")
	)
	(arc
		(start 99.457256 -180.954426)
		(mid 99.530479 -180.838138)
		(end 99.541838 -180.701188)
		(width 0.1016)
		(layer "F.Cu")
		(net "SAS_EXP_GF_TX_DP10")
	)
	(arc
		(start 111.11992 -114.936524)
		(mid 111.138789 -114.841307)
		(end 111.192564 -114.760502)
		(width 0.1016)
		(layer "F.Cu")
		(net "SAS_EXP_GF_TX_DP10")
	)
	(arc
		(start 92.846144 -187.396882)
		(mid 92.857374 -187.259957)
		(end 92.930472 -187.143644)
		(width 0.1016)
		(layer "F.Cu")
		(net "SAS_EXP_GF_TX_DP10")
	)
	(arc
		(start 91.655392 -188.756544)
		(mid 91.728452 -188.640219)
		(end 91.73972 -188.503306)
		(width 0.1016)
		(layer "F.Cu")
		(net "SAS_EXP_GF_TX_DP10")
	)
	(arc
		(start 98.351086 -182.06085)
		(mid 98.424146 -181.944525)
		(end 98.435414 -181.807612)
		(width 0.1016)
		(layer "F.Cu")
		(net "SAS_EXP_GF_TX_DP10")
	)
	(arc
		(start 84.059268 -244.973094)
		(mid 83.706246 -244.902856)
		(end 83.406996 -244.702838)
		(width 0.1016)
		(layer "F.Cu")
		(net "SAS_EXP_GF_TX_DP10")
	)
	(arc
		(start 99.541838 -180.701188)
		(mid 99.553068 -180.564263)
		(end 99.626166 -180.44795)
		(width 0.1016)
		(layer "F.Cu")
		(net "SAS_EXP_GF_TX_DP10")
	)
	(arc
		(start 98.735388 -181.338728)
		(mid 98.851713 -181.265668)
		(end 98.988626 -181.2544)
		(width 0.1016)
		(layer "F.Cu")
		(net "SAS_EXP_GF_TX_DP10")
	)
	(arc
		(start 98.830638 -248.29389)
		(mid 98.448283 -248.038408)
		(end 97.997264 -247.948704)
		(width 0.1016)
		(layer "F.Cu")
		(net "SAS_EXP_GF_TX_DP10")
	)
	(arc
		(start 111.192818 -114.760248)
		(mid 111.246965 -114.6794)
		(end 111.26597 -114.583972)
		(width 0.1016)
		(layer "F.Cu")
		(net "SAS_EXP_GF_TX_DP10")
	)
	(arc
		(start 100.09505 -180.147976)
		(mid 100.231975 -180.136746)
		(end 100.348288 -180.063648)
		(width 0.1016)
		(layer "F.Cu")
		(net "SAS_EXP_GF_TX_DP10")
	)
	(arc
		(start 95.118936 -245.794784)
		(mid 94.208774 -245.186696)
		(end 93.135196 -244.973094)
		(width 0.1016)
		(layer "F.Cu")
		(net "SAS_EXP_GF_TX_DP10")
	)
	(arc
		(start 91.186508 -189.056518)
		(mid 91.323456 -189.045154)
		(end 91.439746 -188.971936)
		(width 0.1016)
		(layer "F.Cu")
		(net "SAS_EXP_GF_TX_DP10")
	)
	(arc
		(start 97.997264 -247.948704)
		(mid 97.328114 -247.81562)
		(end 96.760792 -247.43664)
		(width 0.1016)
		(layer "F.Cu")
		(net "SAS_EXP_GF_TX_DP10")
	)
	(arc
		(start 100.773484 -254.18034)
		(mid 100.701642 -254.150582)
		(end 100.671884 -254.07874)
		(width 0.1016)
		(layer "F.Cu")
		(net "SAS_EXP_GF_TX_DP10")
	)
	(arc
		(start 100.56368 -179.848002)
		(mid 100.63674 -179.731677)
		(end 100.648008 -179.594764)
		(width 0.1016)
		(layer "F.Cu")
		(net "SAS_EXP_GF_TX_DP10")
	)
	(arc
		(start 110.660688 -169.413428)
		(mid 111.000524 -168.904733)
		(end 111.11992 -168.304718)
		(width 0.1016)
		(layer "F.Cu")
		(net "SAS_EXP_GF_TX_DP10")
	)
	(arc
		(start 90.93327 -189.140846)
		(mid 91.049595 -189.067786)
		(end 91.186508 -189.056518)
		(width 0.1016)
		(layer "F.Cu")
		(net "SAS_EXP_GF_TX_DP10")
	)
	(arc
		(start 100.648008 -179.594764)
		(mid 100.659372 -179.457816)
		(end 100.73259 -179.341526)
		(width 0.1016)
		(layer "F.Cu")
		(net "SAS_EXP_GF_TX_DP10")
	)
	(segment
		(start 338.684362 -162.281362)
		(end 336.677 -160.274)
		(width 0.1143)
		(layer "F.Cu")
		(net "DEBUG_CARD_TX")
	)
	(segment
		(start 313.744102 -140.643102)
		(end 313.323478 -140.222478)
		(width 0.1143)
		(layer "F.Cu")
		(net "DEBUG_CARD_TX")
	)
	(segment
		(start 313.583828 -136.412478)
		(end 312.55335 -135.382)
		(width 0.1143)
		(layer "F.Cu")
		(net "DEBUG_CARD_TX")
	)
	(segment
		(start 332.74 -160.274)
		(end 328.0537 -155.5877)
		(width 0.1143)
		(layer "F.Cu")
		(net "DEBUG_CARD_TX")
	)
	(segment
		(start 328.0537 -155.5877)
		(end 316.00648 -155.5877)
		(width 0.1143)
		(layer "F.Cu")
		(net "DEBUG_CARD_TX")
	)
	(segment
		(start 316.00648 -155.5877)
		(end 313.744102 -153.325322)
		(width 0.1143)
		(layer "F.Cu")
		(net "DEBUG_CARD_TX")
	)
	(segment
		(start 312.55335 -135.382)
		(end 312.293 -135.382)
		(width 0.1143)
		(layer "F.Cu")
		(net "DEBUG_CARD_TX")
	)
	(segment
		(start 338.684362 -163.483036)
		(end 338.684362 -162.281362)
		(width 0.1143)
		(layer "F.Cu")
		(net "DEBUG_CARD_TX")
	)
	(segment
		(start 313.323478 -138.148822)
		(end 313.583828 -137.888472)
		(width 0.1143)
		(layer "F.Cu")
		(net "DEBUG_CARD_TX")
	)
	(segment
		(start 313.583828 -137.888472)
		(end 313.583828 -136.412478)
		(width 0.1143)
		(layer "F.Cu")
		(net "DEBUG_CARD_TX")
	)
	(segment
		(start 336.677 -160.274)
		(end 332.74 -160.274)
		(width 0.1143)
		(layer "F.Cu")
		(net "DEBUG_CARD_TX")
	)
	(segment
		(start 313.323478 -140.222478)
		(end 313.323478 -138.148822)
		(width 0.1143)
		(layer "F.Cu")
		(net "DEBUG_CARD_TX")
	)
	(segment
		(start 313.744102 -153.325322)
		(end 313.744102 -140.643102)
		(width 0.1143)
		(layer "F.Cu")
		(net "DEBUG_CARD_TX")
	)
	(via
		(at 312.293 -135.382)
		(size 0.5588)
		(drill 0.3048)
		(layers "F.Cu" "B.Cu")
		(net "DEBUG_CARD_TX")
	)
	(segment
		(start 326.517 -87.781892)
		(end 323.874892 -90.424)
		(width 0.127)
		(layer "In5.Cu")
		(net "DEBUG_CARD_TX")
	)
	(segment
		(start 321.574922 -90.424)
		(end 315.722 -96.276922)
		(width 0.127)
		(layer "In5.Cu")
		(net "DEBUG_CARD_TX")
	)
	(segment
		(start 342.642444 -9.087104)
		(end 342.594184 -9.087104)
		(width 0.127)
		(layer "In5.Cu")
		(net "DEBUG_CARD_TX")
	)
	(segment
		(start 343.984834 -7.744714)
		(end 342.642444 -9.087104)
		(width 0.127)
		(layer "In5.Cu")
		(net "DEBUG_CARD_TX")
	)
	(segment
		(start 326.517 -21.561806)
		(end 326.517 -87.781892)
		(width 0.127)
		(layer "In5.Cu")
		(net "DEBUG_CARD_TX")
	)
	(segment
		(start 323.874892 -90.424)
		(end 321.574922 -90.424)
		(width 0.127)
		(layer "In5.Cu")
		(net "DEBUG_CARD_TX")
	)
	(segment
		(start 342.594184 -9.087104)
		(end 337.965288 -13.716)
		(width 0.127)
		(layer "In5.Cu")
		(net "DEBUG_CARD_TX")
	)
	(segment
		(start 310.261 -111.633)
		(end 308.6227 -113.2713)
		(width 0.127)
		(layer "In5.Cu")
		(net "DEBUG_CARD_TX")
	)
	(segment
		(start 337.965288 -13.716)
		(end 334.362806 -13.716)
		(width 0.127)
		(layer "In5.Cu")
		(net "DEBUG_CARD_TX")
	)
	(segment
		(start 312.293 -130.81)
		(end 312.293 -135.382)
		(width 0.127)
		(layer "In5.Cu")
		(net "DEBUG_CARD_TX")
	)
	(segment
		(start 343.984834 -7.499604)
		(end 343.984834 -7.744714)
		(width 0.127)
		(layer "In5.Cu")
		(net "DEBUG_CARD_TX")
	)
	(segment
		(start 310.261 -109.601)
		(end 310.261 -111.633)
		(width 0.127)
		(layer "In5.Cu")
		(net "DEBUG_CARD_TX")
	)
	(segment
		(start 308.6227 -127.1397)
		(end 312.293 -130.81)
		(width 0.127)
		(layer "In5.Cu")
		(net "DEBUG_CARD_TX")
	)
	(segment
		(start 334.362806 -13.716)
		(end 326.517 -21.561806)
		(width 0.127)
		(layer "In5.Cu")
		(net "DEBUG_CARD_TX")
	)
	(segment
		(start 315.722 -96.276922)
		(end 315.722 -104.14)
		(width 0.127)
		(layer "In5.Cu")
		(net "DEBUG_CARD_TX")
	)
	(segment
		(start 308.6227 -113.2713)
		(end 308.6227 -127.1397)
		(width 0.127)
		(layer "In5.Cu")
		(net "DEBUG_CARD_TX")
	)
	(segment
		(start 315.722 -104.14)
		(end 310.261 -109.601)
		(width 0.127)
		(layer "In5.Cu")
		(net "DEBUG_CARD_TX")
	)
	(segment
		(start 93.000322 -251.72289)
		(end 93.136212 -251.587)
		(width 0.1143)
		(layer "B.Cu")
		(net "SAS_I2C_D_BUF_SCL_R")
	)
	(segment
		(start 93.000322 -256.50444)
		(end 93.000322 -251.72289)
		(width 0.1143)
		(layer "B.Cu")
		(net "SAS_I2C_D_BUF_SCL_R")
	)
	(segment
		(start 113.349786 -102.350062)
		(end 112.84966 -102.850188)
		(width 0.1016)
		(layer "F.Cu")
		(net "SAS_GF_EXP_RX_DN9")
	)
	(via
		(at 112.84966 -102.850188)
		(size 0.508)
		(drill 0.254)
		(layers "F.Cu" "B.Cu")
		(net "SAS_GF_EXP_RX_DN9")
	)
	(segment
		(start 112.150144 -105.192322)
		(end 112.194594 -105.082086)
		(width 0.1016)
		(layer "B.Cu")
		(net "SAS_GF_EXP_RX_DN9")
	)
	(segment
		(start 112.07877 -107.064556)
		(end 112.07877 -105.558844)
		(width 0.1016)
		(layer "B.Cu")
		(net "SAS_GF_EXP_RX_DN9")
	)
	(segment
		(start 111.000032 -256.50444)
		(end 111.000032 -254.768604)
		(width 0.1016)
		(layer "B.Cu")
		(net "SAS_GF_EXP_RX_DN9")
	)
	(segment
		(start 111.933228 -107.331002)
		(end 111.992918 -107.271058)
		(width 0.1016)
		(layer "B.Cu")
		(net "SAS_GF_EXP_RX_DN9")
	)
	(segment
		(start 113.46307 -166.928546)
		(end 113.46307 -114.906552)
		(width 0.1016)
		(layer "B.Cu")
		(net "SAS_GF_EXP_RX_DN9")
	)
	(segment
		(start 111.64697 -110.521496)
		(end 111.64697 -108.022644)
		(width 0.1016)
		(layer "B.Cu")
		(net "SAS_GF_EXP_RX_DN9")
	)
	(segment
		(start 112.256062 -104.886252)
		(end 112.256062 -103.70693)
		(width 0.1016)
		(layer "B.Cu")
		(net "SAS_GF_EXP_RX_DN9")
	)
	(segment
		(start 111.4171 -253.761748)
		(end 111.4171 -231.50576)
		(width 0.1016)
		(layer "B.Cu")
		(net "SAS_GF_EXP_RX_DN9")
	)
	(segment
		(start 112.44199 -103.257858)
		(end 112.84966 -102.850188)
		(width 0.1016)
		(layer "B.Cu")
		(net "SAS_GF_EXP_RX_DN9")
	)
	(segment
		(start 100.565712 -215.773)
		(end 100.565712 -186.308746)
		(width 0.1016)
		(layer "B.Cu")
		(net "SAS_GF_EXP_RX_DN9")
	)
	(segment
		(start 101.20884 -184.75579)
		(end 109.52226 -176.44237)
		(width 0.1016)
		(layer "B.Cu")
		(net "SAS_GF_EXP_RX_DN9")
	)
	(segment
		(start 110.091474 -228.305614)
		(end 102.691692 -220.905832)
		(width 0.1016)
		(layer "B.Cu")
		(net "SAS_GF_EXP_RX_DN9")
	)
	(segment
		(start 112.194594 -105.082086)
		(end 112.239298 -104.971596)
		(width 0.1016)
		(layer "B.Cu")
		(net "SAS_GF_EXP_RX_DN9")
	)
	(arc
		(start 112.61217 -112.8522)
		(mid 111.897721 -111.782862)
		(end 111.64697 -110.521496)
		(width 0.1016)
		(layer "B.Cu")
		(net "SAS_GF_EXP_RX_DN9")
	)
	(arc
		(start 109.52226 -176.44237)
		(mid 112.4389 -172.077405)
		(end 113.46307 -166.928546)
		(width 0.1016)
		(layer "B.Cu")
		(net "SAS_GF_EXP_RX_DN9")
	)
	(arc
		(start 112.239298 -104.971596)
		(mid 112.251784 -104.929732)
		(end 112.256062 -104.886252)
		(width 0.1016)
		(layer "B.Cu")
		(net "SAS_GF_EXP_RX_DN9")
	)
	(arc
		(start 113.46307 -114.906552)
		(mid 113.241921 -113.79476)
		(end 112.61217 -112.8522)
		(width 0.1016)
		(layer "B.Cu")
		(net "SAS_GF_EXP_RX_DN9")
	)
	(arc
		(start 111.298736 -254.047498)
		(mid 111.386336 -253.916395)
		(end 111.4171 -253.761748)
		(width 0.1016)
		(layer "B.Cu")
		(net "SAS_GF_EXP_RX_DN9")
	)
	(arc
		(start 100.565712 -186.308746)
		(mid 100.732849 -185.468313)
		(end 101.20884 -184.75579)
		(width 0.1016)
		(layer "B.Cu")
		(net "SAS_GF_EXP_RX_DN9")
	)
	(arc
		(start 112.256062 -103.70693)
		(mid 112.304383 -103.463912)
		(end 112.44199 -103.257858)
		(width 0.1016)
		(layer "B.Cu")
		(net "SAS_GF_EXP_RX_DN9")
	)
	(arc
		(start 111.4171 -231.50576)
		(mid 111.072581 -229.773836)
		(end 110.091474 -228.305614)
		(width 0.1016)
		(layer "B.Cu")
		(net "SAS_GF_EXP_RX_DN9")
	)
	(arc
		(start 111.992918 -107.271058)
		(mid 112.056443 -107.176358)
		(end 112.07877 -107.064556)
		(width 0.1016)
		(layer "B.Cu")
		(net "SAS_GF_EXP_RX_DN9")
	)
	(arc
		(start 111.000032 -254.768604)
		(mid 111.07766 -254.37834)
		(end 111.298736 -254.047498)
		(width 0.1016)
		(layer "B.Cu")
		(net "SAS_GF_EXP_RX_DN9")
	)
	(arc
		(start 102.691692 -220.905832)
		(mid 101.118239 -218.550854)
		(end 100.565712 -215.773)
		(width 0.1016)
		(layer "B.Cu")
		(net "SAS_GF_EXP_RX_DN9")
	)
	(arc
		(start 111.64697 -108.022644)
		(mid 111.72131 -107.64835)
		(end 111.933228 -107.331002)
		(width 0.1016)
		(layer "B.Cu")
		(net "SAS_GF_EXP_RX_DN9")
	)
	(arc
		(start 112.07877 -105.558844)
		(mid 112.096807 -105.372147)
		(end 112.150144 -105.192322)
		(width 0.1016)
		(layer "B.Cu")
		(net "SAS_GF_EXP_RX_DN9")
	)
	(segment
		(start 225.0948 -21.463)
		(end 225.044 -21.463)
		(width 0.1778)
		(layer "F.Cu")
		(net "LED_PWR_N_R")
	)
	(segment
		(start 96.901 -2.54)
		(end 97.79 -3.429)
		(width 0.1778)
		(layer "F.Cu")
		(net "LED_PWR_N_R")
	)
	(segment
		(start 223.139 -19.558)
		(end 221.742 -18.161)
		(width 0.1778)
		(layer "F.Cu")
		(net "LED_PWR_N_R")
	)
	(segment
		(start 225.044 -21.463)
		(end 223.139 -19.558)
		(width 0.1778)
		(layer "F.Cu")
		(net "LED_PWR_N_R")
	)
	(segment
		(start 221.742 -18.161)
		(end 221.742 -17.399)
		(width 0.1778)
		(layer "F.Cu")
		(net "LED_PWR_N_R")
	)
	(segment
		(start 94.969076 -2.029968)
		(end 95.479108 -2.54)
		(width 0.1778)
		(layer "F.Cu")
		(net "LED_PWR_N_R")
	)
	(segment
		(start 95.479108 -2.54)
		(end 96.901 -2.54)
		(width 0.1778)
		(layer "F.Cu")
		(net "LED_PWR_N_R")
	)
	(via
		(at 97.79 -3.429)
		(size 0.5588)
		(drill 0.3048)
		(layers "F.Cu" "B.Cu")
		(net "LED_PWR_N_R")
	)
	(via
		(at 221.742 -17.399)
		(size 0.5588)
		(drill 0.3048)
		(layers "F.Cu" "B.Cu")
		(net "LED_PWR_N_R")
	)
	(via
		(at 223.139 -19.558)
		(size 0.7112)
		(drill 0.3556)
		(layers "F.Cu" "B.Cu")
		(net "LED_PWR_N_R")
	)
	(segment
		(start 145.853912 -24.16683)
		(end 136.779 -15.091918)
		(width 0.1778)
		(layer "In2.Cu")
		(net "LED_PWR_N_R")
	)
	(segment
		(start 221.742 -17.399)
		(end 219.075 -17.399)
		(width 0.1778)
		(layer "In2.Cu")
		(net "LED_PWR_N_R")
	)
	(segment
		(start 104.013 -4.191)
		(end 98.552 -4.191)
		(width 0.1778)
		(layer "In2.Cu")
		(net "LED_PWR_N_R")
	)
	(segment
		(start 190.8683 -12.573)
		(end 190.5 -12.2047)
		(width 0.1778)
		(layer "In2.Cu")
		(net "LED_PWR_N_R")
	)
	(segment
		(start 170.307 -17.34566)
		(end 170.307 -17.907)
		(width 0.1778)
		(layer "In2.Cu")
		(net "LED_PWR_N_R")
	)
	(segment
		(start 104.353868 -4.531868)
		(end 104.013 -4.191)
		(width 0.1778)
		(layer "In2.Cu")
		(net "LED_PWR_N_R")
	)
	(segment
		(start 136.779 -15.091918)
		(end 124.772928 -15.091918)
		(width 0.1778)
		(layer "In2.Cu")
		(net "LED_PWR_N_R")
	)
	(segment
		(start 114.212878 -4.531868)
		(end 104.353868 -4.531868)
		(width 0.1778)
		(layer "In2.Cu")
		(net "LED_PWR_N_R")
	)
	(segment
		(start 174.8663 -12.2047)
		(end 172.847 -14.224)
		(width 0.1778)
		(layer "In2.Cu")
		(net "LED_PWR_N_R")
	)
	(segment
		(start 172.847 -14.224)
		(end 172.847 -14.54912)
		(width 0.1778)
		(layer "In2.Cu")
		(net "LED_PWR_N_R")
	)
	(segment
		(start 124.772928 -15.091918)
		(end 114.212878 -4.531868)
		(width 0.1778)
		(layer "In2.Cu")
		(net "LED_PWR_N_R")
	)
	(segment
		(start 214.249 -12.573)
		(end 190.8683 -12.573)
		(width 0.1778)
		(layer "In2.Cu")
		(net "LED_PWR_N_R")
	)
	(segment
		(start 171.831 -15.56512)
		(end 171.831 -15.82166)
		(width 0.1778)
		(layer "In2.Cu")
		(net "LED_PWR_N_R")
	)
	(segment
		(start 170.307 -17.907)
		(end 164.04717 -24.16683)
		(width 0.1778)
		(layer "In2.Cu")
		(net "LED_PWR_N_R")
	)
	(segment
		(start 164.04717 -24.16683)
		(end 145.853912 -24.16683)
		(width 0.1778)
		(layer "In2.Cu")
		(net "LED_PWR_N_R")
	)
	(segment
		(start 172.847 -14.54912)
		(end 171.831 -15.56512)
		(width 0.1778)
		(layer "In2.Cu")
		(net "LED_PWR_N_R")
	)
	(segment
		(start 171.831 -15.82166)
		(end 170.307 -17.34566)
		(width 0.1778)
		(layer "In2.Cu")
		(net "LED_PWR_N_R")
	)
	(segment
		(start 219.075 -17.399)
		(end 214.249 -12.573)
		(width 0.1778)
		(layer "In2.Cu")
		(net "LED_PWR_N_R")
	)
	(segment
		(start 98.552 -4.191)
		(end 97.79 -3.429)
		(width 0.1778)
		(layer "In2.Cu")
		(net "LED_PWR_N_R")
	)
	(segment
		(start 190.5 -12.2047)
		(end 174.8663 -12.2047)
		(width 0.1778)
		(layer "In2.Cu")
		(net "LED_PWR_N_R")
	)
	(segment
		(start 284.584648 -176.043336)
		(end 284.637988 -176.043336)
		(width 0.1143)
		(layer "F.Cu")
		(net "ROMA11")
	)
	(segment
		(start 277.666704 -174.300896)
		(end 278.638 -174.300896)
		(width 0.1143)
		(layer "F.Cu")
		(net "ROMA11")
	)
	(segment
		(start 277.3426 -174.625)
		(end 277.666704 -174.300896)
		(width 0.1143)
		(layer "F.Cu")
		(net "ROMA11")
	)
	(segment
		(start 284.637988 -176.043336)
		(end 284.834838 -176.240186)
		(width 0.1143)
		(layer "F.Cu")
		(net "ROMA11")
	)
	(segment
		(start 278.638 -174.300896)
		(end 279.338024 -174.300896)
		(width 0.1143)
		(layer "F.Cu")
		(net "ROMA11")
	)
	(segment
		(start 284.439868 -175.898556)
		(end 284.584648 -176.043336)
		(width 0.1143)
		(layer "F.Cu")
		(net "ROMA11")
	)
	(segment
		(start 279.338024 -174.300896)
		(end 280.935684 -175.898556)
		(width 0.1143)
		(layer "F.Cu")
		(net "ROMA11")
	)
	(segment
		(start 280.935684 -175.898556)
		(end 284.439868 -175.898556)
		(width 0.1143)
		(layer "F.Cu")
		(net "ROMA11")
	)
	(segment
		(start 274.6375 -174.625)
		(end 277.3426 -174.625)
		(width 0.1143)
		(layer "F.Cu")
		(net "ROMA11")
	)
	(via
		(at 278.638 -174.300896)
		(size 0.7112)
		(drill 0.3556)
		(layers "F.Cu" "B.Cu")
		(net "ROMA11")
	)
	(segment
		(start 91.999562 -256.50444)
		(end 91.999562 -251.800614)
		(width 0.1143)
		(layer "B.Cu")
		(net "SAS_I2C_D_BUF_SDA_R")
	)
	(segment
		(start 91.999562 -251.800614)
		(end 91.858084 -251.659136)
		(width 0.1143)
		(layer "B.Cu")
		(net "SAS_I2C_D_BUF_SDA_R")
	)
	(segment
		(start 353.061016 -29.75483)
		(end 353.061016 -31.1404)
		(width 0.1143)
		(layer "F.Cu")
		(net "SHUTDOWN_RELEASE")
	)
	(segment
		(start 349.34017 -29.75483)
		(end 347.90888 -29.75483)
		(width 0.1143)
		(layer "F.Cu")
		(net "SHUTDOWN_RELEASE")
	)
	(segment
		(start 349.885 -29.21)
		(end 349.34017 -29.75483)
		(width 0.1143)
		(layer "F.Cu")
		(net "SHUTDOWN_RELEASE")
	)
	(segment
		(start 351.409 -29.21)
		(end 349.885 -29.21)
		(width 0.1143)
		(layer "F.Cu")
		(net "SHUTDOWN_RELEASE")
	)
	(segment
		(start 353.024186 -29.718)
		(end 351.917 -29.718)
		(width 0.1143)
		(layer "F.Cu")
		(net "SHUTDOWN_RELEASE")
	)
	(segment
		(start 351.917 -29.718)
		(end 351.409 -29.21)
		(width 0.1143)
		(layer "F.Cu")
		(net "SHUTDOWN_RELEASE")
	)
	(segment
		(start 353.061016 -29.75483)
		(end 353.024186 -29.718)
		(width 0.1143)
		(layer "F.Cu")
		(net "SHUTDOWN_RELEASE")
	)
	(via
		(at 353.061016 -31.1404)
		(size 0.5588)
		(drill 0.3048)
		(layers "F.Cu" "B.Cu")
		(net "SHUTDOWN_RELEASE")
	)
	(via
		(at 109.911642 -246.436642)
		(size 0.7112)
		(drill 0.3556)
		(layers "F.Cu" "B.Cu")
		(net "SHUTDOWN_RELEASE")
	)
	(via
		(at 109.728 -237.109)
		(size 0.5588)
		(drill 0.3048)
		(layers "F.Cu" "B.Cu")
		(net "SHUTDOWN_RELEASE")
	)
	(segment
		(start 108.999782 -256.50444)
		(end 108.999782 -250.664218)
		(width 0.1143)
		(layer "B.Cu")
		(net "SHUTDOWN_RELEASE")
	)
	(segment
		(start 109.728 -237.871)
		(end 109.911642 -238.054642)
		(width 0.1143)
		(layer "B.Cu")
		(net "SHUTDOWN_RELEASE")
	)
	(segment
		(start 109.728 -237.109)
		(end 109.728 -237.871)
		(width 0.1143)
		(layer "B.Cu")
		(net "SHUTDOWN_RELEASE")
	)
	(segment
		(start 108.999782 -250.664218)
		(end 109.911642 -249.752358)
		(width 0.1143)
		(layer "B.Cu")
		(net "SHUTDOWN_RELEASE")
	)
	(segment
		(start 109.911642 -249.752358)
		(end 109.911642 -246.436642)
		(width 0.1143)
		(layer "B.Cu")
		(net "SHUTDOWN_RELEASE")
	)
	(segment
		(start 109.911642 -238.054642)
		(end 109.911642 -246.436642)
		(width 0.1143)
		(layer "B.Cu")
		(net "SHUTDOWN_RELEASE")
	)
	(segment
		(start 295.6433 -244.203982)
		(end 295.353232 -244.49405)
		(width 0.127)
		(layer "In5.Cu")
		(net "SHUTDOWN_RELEASE")
	)
	(segment
		(start 337.1215 -191.1985)
		(end 337.1215 -214.142066)
		(width 0.127)
		(layer "In5.Cu")
		(net "SHUTDOWN_RELEASE")
	)
	(segment
		(start 211.406232 -220.10878)
		(end 210.405472 -221.10954)
		(width 0.127)
		(layer "In5.Cu")
		(net "SHUTDOWN_RELEASE")
	)
	(segment
		(start 333.598266 -217.6653)
		(end 315.594746 -217.6653)
		(width 0.127)
		(layer "In5.Cu")
		(net "SHUTDOWN_RELEASE")
	)
	(segment
		(start 211.406232 -213.694264)
		(end 211.406232 -220.10878)
		(width 0.127)
		(layer "In5.Cu")
		(net "SHUTDOWN_RELEASE")
	)
	(segment
		(start 232.338372 -192.762124)
		(end 211.406232 -213.694264)
		(width 0.127)
		(layer "In5.Cu")
		(net "SHUTDOWN_RELEASE")
	)
	(segment
		(start 295.6433 -243.79301)
		(end 295.6433 -244.203982)
		(width 0.127)
		(layer "In5.Cu")
		(net "SHUTDOWN_RELEASE")
	)
	(segment
		(start 315.594746 -217.6653)
		(end 295.6433 -237.616746)
		(width 0.127)
		(layer "In5.Cu")
		(net "SHUTDOWN_RELEASE")
	)
	(segment
		(start 253.238 -196.0118)
		(end 249.988324 -192.762124)
		(width 0.127)
		(layer "In5.Cu")
		(net "SHUTDOWN_RELEASE")
	)
	(segment
		(start 249.988324 -192.762124)
		(end 232.338372 -192.762124)
		(width 0.127)
		(layer "In5.Cu")
		(net "SHUTDOWN_RELEASE")
	)
	(segment
		(start 271.399 -212.598)
		(end 267.589 -208.788)
		(width 0.127)
		(layer "In5.Cu")
		(net "SHUTDOWN_RELEASE")
	)
	(segment
		(start 353.061016 -31.1404)
		(end 354.2284 -31.1404)
		(width 0.127)
		(layer "In5.Cu")
		(net "SHUTDOWN_RELEASE")
	)
	(segment
		(start 354.584 -31.496)
		(end 354.584 -173.736)
		(width 0.127)
		(layer "In5.Cu")
		(net "SHUTDOWN_RELEASE")
	)
	(segment
		(start 295.6433 -237.616746)
		(end 295.6433 -237.617254)
		(width 0.127)
		(layer "In5.Cu")
		(net "SHUTDOWN_RELEASE")
	)
	(segment
		(start 354.584 -173.736)
		(end 337.1215 -191.1985)
		(width 0.127)
		(layer "In5.Cu")
		(net "SHUTDOWN_RELEASE")
	)
	(segment
		(start 294.942768 -244.49405)
		(end 294.828468 -244.37975)
		(width 0.127)
		(layer "In5.Cu")
		(net "SHUTDOWN_RELEASE")
	)
	(segment
		(start 295.5417 -243.69141)
		(end 295.6433 -243.79301)
		(width 0.127)
		(layer "In5.Cu")
		(net "SHUTDOWN_RELEASE")
	)
	(segment
		(start 295.5417 -237.718854)
		(end 295.5417 -243.69141)
		(width 0.127)
		(layer "In5.Cu")
		(net "SHUTDOWN_RELEASE")
	)
	(segment
		(start 267.589 -208.788)
		(end 264.934954 -208.788)
		(width 0.127)
		(layer "In5.Cu")
		(net "SHUTDOWN_RELEASE")
	)
	(segment
		(start 253.238 -197.091046)
		(end 253.238 -196.0118)
		(width 0.127)
		(layer "In5.Cu")
		(net "SHUTDOWN_RELEASE")
	)
	(segment
		(start 271.399 -240.45672)
		(end 271.399 -212.598)
		(width 0.127)
		(layer "In5.Cu")
		(net "SHUTDOWN_RELEASE")
	)
	(segment
		(start 112.014 -234.823)
		(end 109.728 -237.109)
		(width 0.127)
		(layer "In5.Cu")
		(net "SHUTDOWN_RELEASE")
	)
	(segment
		(start 337.1215 -214.142066)
		(end 333.598266 -217.6653)
		(width 0.127)
		(layer "In5.Cu")
		(net "SHUTDOWN_RELEASE")
	)
	(segment
		(start 210.405472 -221.10954)
		(end 207.13446 -221.10954)
		(width 0.127)
		(layer "In5.Cu")
		(net "SHUTDOWN_RELEASE")
	)
	(segment
		(start 294.828468 -244.37975)
		(end 275.32203 -244.37975)
		(width 0.127)
		(layer "In5.Cu")
		(net "SHUTDOWN_RELEASE")
	)
	(segment
		(start 193.421 -234.823)
		(end 112.014 -234.823)
		(width 0.127)
		(layer "In5.Cu")
		(net "SHUTDOWN_RELEASE")
	)
	(segment
		(start 264.934954 -208.788)
		(end 253.238 -197.091046)
		(width 0.127)
		(layer "In5.Cu")
		(net "SHUTDOWN_RELEASE")
	)
	(segment
		(start 275.32203 -244.37975)
		(end 271.399 -240.45672)
		(width 0.127)
		(layer "In5.Cu")
		(net "SHUTDOWN_RELEASE")
	)
	(segment
		(start 295.353232 -244.49405)
		(end 294.942768 -244.49405)
		(width 0.127)
		(layer "In5.Cu")
		(net "SHUTDOWN_RELEASE")
	)
	(segment
		(start 354.2284 -31.1404)
		(end 354.584 -31.496)
		(width 0.127)
		(layer "In5.Cu")
		(net "SHUTDOWN_RELEASE")
	)
	(segment
		(start 207.13446 -221.10954)
		(end 193.421 -234.823)
		(width 0.127)
		(layer "In5.Cu")
		(net "SHUTDOWN_RELEASE")
	)
	(segment
		(start 295.6433 -237.617254)
		(end 295.5417 -237.718854)
		(width 0.127)
		(layer "In5.Cu")
		(net "SHUTDOWN_RELEASE")
	)
	(segment
		(start 82.55 -243.462048)
		(end 82.55 -198.266812)
		(width 0.1016)
		(layer "F.Cu")
		(net "SAS_EXP_GF_TX_DN10")
	)
	(segment
		(start 100.000562 -256.25044)
		(end 100.000562 -254.28194)
		(width 0.1016)
		(layer "F.Cu")
		(net "SAS_EXP_GF_TX_DN10")
	)
	(segment
		(start 110.704122 -114.754152)
		(end 110.666784 -114.716814)
		(width 0.1016)
		(layer "F.Cu")
		(net "SAS_EXP_GF_TX_DN10")
	)
	(segment
		(start 96.518222 -247.67921)
		(end 94.876366 -246.037354)
		(width 0.1016)
		(layer "F.Cu")
		(net "SAS_EXP_GF_TX_DN10")
	)
	(segment
		(start 100.102162 -254.18034)
		(end 100.227384 -254.18034)
		(width 0.1016)
		(layer "F.Cu")
		(net "SAS_EXP_GF_TX_DN10")
	)
	(segment
		(start 110.77702 -168.304464)
		(end 110.77702 -114.930428)
		(width 0.1016)
		(layer "F.Cu")
		(net "SAS_EXP_GF_TX_DN10")
	)
	(segment
		(start 110.63097 -114.6302)
		(end 110.63097 -114.5794)
		(width 0.1016)
		(layer "F.Cu")
		(net "SAS_EXP_GF_TX_DN10")
	)
	(segment
		(start 99.579176 -249.527568)
		(end 98.588068 -248.53646)
		(width 0.1016)
		(layer "F.Cu")
		(net "SAS_EXP_GF_TX_DN10")
	)
	(segment
		(start 100.328984 -254.07874)
		(end 100.328984 -251.337572)
		(width 0.1016)
		(layer "F.Cu")
		(net "SAS_EXP_GF_TX_DN10")
	)
	(segment
		(start 93.134942 -245.315994)
		(end 84.059014 -245.315994)
		(width 0.1016)
		(layer "F.Cu")
		(net "SAS_EXP_GF_TX_DN10")
	)
	(segment
		(start 83.417918 -196.171058)
		(end 110.418118 -169.170858)
		(width 0.1016)
		(layer "F.Cu")
		(net "SAS_EXP_GF_TX_DN10")
	)
	(arc
		(start 82.55 -198.266812)
		(mid 82.775513 -197.13261)
		(end 83.417918 -196.171058)
		(width 0.1016)
		(layer "F.Cu")
		(net "SAS_EXP_GF_TX_DN10")
	)
	(arc
		(start 94.876366 -246.037354)
		(mid 94.077394 -245.503498)
		(end 93.134942 -245.315994)
		(width 0.1016)
		(layer "F.Cu")
		(net "SAS_EXP_GF_TX_DN10")
	)
	(arc
		(start 100.000562 -254.28194)
		(mid 100.03032 -254.210098)
		(end 100.102162 -254.18034)
		(width 0.1016)
		(layer "F.Cu")
		(net "SAS_EXP_GF_TX_DN10")
	)
	(arc
		(start 84.059014 -245.315994)
		(mid 83.574853 -245.219688)
		(end 83.164426 -244.945408)
		(width 0.1016)
		(layer "F.Cu")
		(net "SAS_EXP_GF_TX_DN10")
	)
	(arc
		(start 100.328984 -251.337572)
		(mid 100.134115 -250.357989)
		(end 99.579176 -249.527568)
		(width 0.1016)
		(layer "F.Cu")
		(net "SAS_EXP_GF_TX_DN10")
	)
	(arc
		(start 83.164426 -244.945408)
		(mid 82.709683 -244.264837)
		(end 82.55 -243.462048)
		(width 0.1016)
		(layer "F.Cu")
		(net "SAS_EXP_GF_TX_DN10")
	)
	(arc
		(start 98.588068 -248.53646)
		(mid 98.31699 -248.355424)
		(end 97.997264 -248.291858)
		(width 0.1016)
		(layer "F.Cu")
		(net "SAS_EXP_GF_TX_DN10")
	)
	(arc
		(start 110.77702 -114.930428)
		(mid 110.758083 -114.835045)
		(end 110.704122 -114.754152)
		(width 0.1016)
		(layer "F.Cu")
		(net "SAS_EXP_GF_TX_DN10")
	)
	(arc
		(start 97.997264 -248.291858)
		(mid 97.196795 -248.132653)
		(end 96.518222 -247.67921)
		(width 0.1016)
		(layer "F.Cu")
		(net "SAS_EXP_GF_TX_DN10")
	)
	(arc
		(start 110.418118 -169.170858)
		(mid 110.683722 -168.773353)
		(end 110.77702 -168.304464)
		(width 0.1016)
		(layer "F.Cu")
		(net "SAS_EXP_GF_TX_DN10")
	)
	(arc
		(start 100.227384 -254.18034)
		(mid 100.299226 -254.150582)
		(end 100.328984 -254.07874)
		(width 0.1016)
		(layer "F.Cu")
		(net "SAS_EXP_GF_TX_DN10")
	)
	(arc
		(start 110.666784 -114.716814)
		(mid 110.640285 -114.677061)
		(end 110.63097 -114.6302)
		(width 0.1016)
		(layer "F.Cu")
		(net "SAS_EXP_GF_TX_DN10")
	)
	(segment
		(start 222.028004 -20.923504)
		(end 220.976698 -20.923504)
		(width 0.1778)
		(layer "F.Cu")
		(net "LED_PWR_N_ON")
	)
	(segment
		(start 98.111056 -2.029968)
		(end 98.111056 -2.480056)
		(width 0.1778)
		(layer "F.Cu")
		(net "LED_PWR_N_ON")
	)
	(segment
		(start 218.154504 -20.923504)
		(end 217.678 -20.447)
		(width 0.1778)
		(layer "F.Cu")
		(net "LED_PWR_N_ON")
	)
	(segment
		(start 223.393 -22.2885)
		(end 222.028004 -20.923504)
		(width 0.1778)
		(layer "F.Cu")
		(net "LED_PWR_N_ON")
	)
	(segment
		(start 219.075 -16.51)
		(end 217.678 -17.907)
		(width 0.1778)
		(layer "F.Cu")
		(net "LED_PWR_N_ON")
	)
	(segment
		(start 217.678 -17.907)
		(end 217.678 -20.447)
		(width 0.1778)
		(layer "F.Cu")
		(net "LED_PWR_N_ON")
	)
	(segment
		(start 220.976698 -20.923504)
		(end 218.154504 -20.923504)
		(width 0.1778)
		(layer "F.Cu")
		(net "LED_PWR_N_ON")
	)
	(segment
		(start 98.111056 -2.480056)
		(end 99.06 -3.429)
		(width 0.1778)
		(layer "F.Cu")
		(net "LED_PWR_N_ON")
	)
	(via
		(at 99.06 -3.429)
		(size 0.5588)
		(drill 0.3048)
		(layers "F.Cu" "B.Cu")
		(net "LED_PWR_N_ON")
	)
	(via
		(at 217.678 -20.447)
		(size 0.7112)
		(drill 0.3556)
		(layers "F.Cu" "B.Cu")
		(net "LED_PWR_N_ON")
	)
	(via
		(at 219.075 -16.51)
		(size 0.508)
		(drill 0.254)
		(layers "F.Cu" "B.Cu")
		(net "LED_PWR_N_ON")
	)
	(segment
		(start 146.403822 -23.521924)
		(end 163.591748 -23.521924)
		(width 0.1778)
		(layer "In2.Cu")
		(net "LED_PWR_N_ON")
	)
	(segment
		(start 169.566336 -16.615664)
		(end 174.625 -11.557)
		(width 0.1778)
		(layer "In2.Cu")
		(net "LED_PWR_N_ON")
	)
	(segment
		(start 174.625 -11.557)
		(end 214.122 -11.557)
		(width 0.1778)
		(layer "In2.Cu")
		(net "LED_PWR_N_ON")
	)
	(segment
		(start 114.808 -3.937)
		(end 125.222 -14.351)
		(width 0.1778)
		(layer "In2.Cu")
		(net "LED_PWR_N_ON")
	)
	(segment
		(start 104.47401 -3.429)
		(end 104.98201 -3.937)
		(width 0.1778)
		(layer "In2.Cu")
		(net "LED_PWR_N_ON")
	)
	(segment
		(start 137.232898 -14.351)
		(end 146.403822 -23.521924)
		(width 0.1778)
		(layer "In2.Cu")
		(net "LED_PWR_N_ON")
	)
	(segment
		(start 214.122 -11.557)
		(end 219.075 -16.51)
		(width 0.1778)
		(layer "In2.Cu")
		(net "LED_PWR_N_ON")
	)
	(segment
		(start 163.591748 -23.521924)
		(end 169.566336 -17.547336)
		(width 0.1778)
		(layer "In2.Cu")
		(net "LED_PWR_N_ON")
	)
	(segment
		(start 99.06 -3.429)
		(end 104.47401 -3.429)
		(width 0.1778)
		(layer "In2.Cu")
		(net "LED_PWR_N_ON")
	)
	(segment
		(start 125.222 -14.351)
		(end 137.232898 -14.351)
		(width 0.1778)
		(layer "In2.Cu")
		(net "LED_PWR_N_ON")
	)
	(segment
		(start 104.98201 -3.937)
		(end 114.808 -3.937)
		(width 0.1778)
		(layer "In2.Cu")
		(net "LED_PWR_N_ON")
	)
	(segment
		(start 169.566336 -17.547336)
		(end 169.566336 -16.615664)
		(width 0.1778)
		(layer "In2.Cu")
		(net "LED_PWR_N_ON")
	)
	(segment
		(start 135.703818 -223.05772)
		(end 135.703818 -175.149764)
		(width 0.1016)
		(layer "F.Cu")
		(net "SAS_EXP_GF_TX_DP4")
	)
	(segment
		(start 134.319518 -171.807378)
		(end 122.230388 -159.718248)
		(width 0.1016)
		(layer "F.Cu")
		(net "SAS_EXP_GF_TX_DP4")
	)
	(segment
		(start 130.000502 -256.25044)
		(end 130.000502 -254.155194)
		(width 0.1016)
		(layer "F.Cu")
		(net "SAS_EXP_GF_TX_DP4")
	)
	(segment
		(start 129.661412 -249.391932)
		(end 129.661412 -249.087132)
		(width 0.1016)
		(layer "F.Cu")
		(net "SAS_EXP_GF_TX_DP4")
	)
	(segment
		(start 129.900172 -250.174252)
		(end 129.900172 -249.869452)
		(width 0.1016)
		(layer "F.Cu")
		(net "SAS_EXP_GF_TX_DP4")
	)
	(segment
		(start 121.78792 -158.649924)
		(end 121.78792 -114.797586)
		(width 0.1016)
		(layer "F.Cu")
		(net "SAS_EXP_GF_TX_DP4")
	)
	(segment
		(start 129.99212 -254.113538)
		(end 129.98323 -254.091948)
		(width 0.1016)
		(layer "F.Cu")
		(net "SAS_EXP_GF_TX_DP4")
	)
	(segment
		(start 129.764536 -253.95047)
		(end 129.720848 -253.907036)
		(width 0.1016)
		(layer "F.Cu")
		(net "SAS_EXP_GF_TX_DP4")
	)
	(segment
		(start 129.900172 -248.609612)
		(end 129.900172 -248.304812)
		(width 0.1016)
		(layer "F.Cu")
		(net "SAS_EXP_GF_TX_DP4")
	)
	(segment
		(start 129.900172 -242.274344)
		(end 129.900172 -241.969544)
		(width 0.1016)
		(layer "F.Cu")
		(net "SAS_EXP_GF_TX_DP4")
	)
	(segment
		(start 129.661412 -241.492024)
		(end 129.661412 -234.499658)
		(width 0.1016)
		(layer "F.Cu")
		(net "SAS_EXP_GF_TX_DP4")
	)
	(segment
		(start 129.661412 -243.056664)
		(end 129.661412 -242.751864)
		(width 0.1016)
		(layer "F.Cu")
		(net "SAS_EXP_GF_TX_DP4")
	)
	(segment
		(start 129.661412 -253.763526)
		(end 129.661412 -250.651772)
		(width 0.1016)
		(layer "F.Cu")
		(net "SAS_EXP_GF_TX_DP4")
	)
	(segment
		(start 129.661412 -247.827292)
		(end 129.661412 -245.881144)
		(width 0.1016)
		(layer "F.Cu")
		(net "SAS_EXP_GF_TX_DP4")
	)
	(segment
		(start 121.803414 -114.719862)
		(end 121.835672 -114.642138)
		(width 0.1016)
		(layer "F.Cu")
		(net "SAS_EXP_GF_TX_DP4")
	)
	(segment
		(start 129.661412 -244.621304)
		(end 129.661412 -244.316504)
		(width 0.1016)
		(layer "F.Cu")
		(net "SAS_EXP_GF_TX_DP4")
	)
	(segment
		(start 129.900172 -243.838984)
		(end 129.900172 -243.534184)
		(width 0.1016)
		(layer "F.Cu")
		(net "SAS_EXP_GF_TX_DP4")
	)
	(segment
		(start 131.649724 -229.699566)
		(end 133.874256 -227.475034)
		(width 0.1016)
		(layer "F.Cu")
		(net "SAS_EXP_GF_TX_DP4")
	)
	(segment
		(start 129.900172 -245.403624)
		(end 129.900172 -245.098824)
		(width 0.1016)
		(layer "F.Cu")
		(net "SAS_EXP_GF_TX_DP4")
	)
	(segment
		(start 129.92481 -254.033274)
		(end 129.830322 -253.994412)
		(width 0.1016)
		(layer "F.Cu")
		(net "SAS_EXP_GF_TX_DP4")
	)
	(segment
		(start 121.929398 -114.5794)
		(end 121.93397 -114.5794)
		(width 0.1016)
		(layer "F.Cu")
		(net "SAS_EXP_GF_TX_DP4")
	)
	(arc
		(start 135.703818 -175.149764)
		(mid 135.344103 -173.340886)
		(end 134.319518 -171.807378)
		(width 0.1016)
		(layer "F.Cu")
		(net "SAS_EXP_GF_TX_DP4")
	)
	(arc
		(start 129.780792 -244.860064)
		(mid 129.691998 -244.75525)
		(end 129.661412 -244.621304)
		(width 0.1016)
		(layer "F.Cu")
		(net "SAS_EXP_GF_TX_DP4")
	)
	(arc
		(start 129.661412 -242.751864)
		(mid 129.691904 -242.617871)
		(end 129.780792 -242.513104)
		(width 0.1016)
		(layer "F.Cu")
		(net "SAS_EXP_GF_TX_DP4")
	)
	(arc
		(start 129.830322 -253.994412)
		(mid 129.79526 -253.975685)
		(end 129.764536 -253.95047)
		(width 0.1016)
		(layer "F.Cu")
		(net "SAS_EXP_GF_TX_DP4")
	)
	(arc
		(start 129.661412 -245.881144)
		(mid 129.691904 -245.747151)
		(end 129.780792 -245.642384)
		(width 0.1016)
		(layer "F.Cu")
		(net "SAS_EXP_GF_TX_DP4")
	)
	(arc
		(start 129.780792 -245.642384)
		(mid 129.869586 -245.53757)
		(end 129.900172 -245.403624)
		(width 0.1016)
		(layer "F.Cu")
		(net "SAS_EXP_GF_TX_DP4")
	)
	(arc
		(start 129.900172 -243.534184)
		(mid 129.86968 -243.400191)
		(end 129.780792 -243.295424)
		(width 0.1016)
		(layer "F.Cu")
		(net "SAS_EXP_GF_TX_DP4")
	)
	(arc
		(start 121.78792 -114.797586)
		(mid 121.791822 -114.757956)
		(end 121.803414 -114.719862)
		(width 0.1016)
		(layer "F.Cu")
		(net "SAS_EXP_GF_TX_DP4")
	)
	(arc
		(start 129.900172 -245.098824)
		(mid 129.86968 -244.964831)
		(end 129.780792 -244.860064)
		(width 0.1016)
		(layer "F.Cu")
		(net "SAS_EXP_GF_TX_DP4")
	)
	(arc
		(start 129.780792 -250.413012)
		(mid 129.869586 -250.308198)
		(end 129.900172 -250.174252)
		(width 0.1016)
		(layer "F.Cu")
		(net "SAS_EXP_GF_TX_DP4")
	)
	(arc
		(start 133.874256 -227.475034)
		(mid 135.228358 -225.448338)
		(end 135.703818 -223.05772)
		(width 0.1016)
		(layer "F.Cu")
		(net "SAS_EXP_GF_TX_DP4")
	)
	(arc
		(start 129.780792 -242.513104)
		(mid 129.869586 -242.40829)
		(end 129.900172 -242.274344)
		(width 0.1016)
		(layer "F.Cu")
		(net "SAS_EXP_GF_TX_DP4")
	)
	(arc
		(start 129.661412 -250.651772)
		(mid 129.691998 -250.517854)
		(end 129.780792 -250.413012)
		(width 0.1016)
		(layer "F.Cu")
		(net "SAS_EXP_GF_TX_DP4")
	)
	(arc
		(start 129.900172 -241.969544)
		(mid 129.86968 -241.835551)
		(end 129.780792 -241.730784)
		(width 0.1016)
		(layer "F.Cu")
		(net "SAS_EXP_GF_TX_DP4")
	)
	(arc
		(start 129.780792 -248.848372)
		(mid 129.869586 -248.743558)
		(end 129.900172 -248.609612)
		(width 0.1016)
		(layer "F.Cu")
		(net "SAS_EXP_GF_TX_DP4")
	)
	(arc
		(start 129.780792 -241.730784)
		(mid 129.691998 -241.62597)
		(end 129.661412 -241.492024)
		(width 0.1016)
		(layer "F.Cu")
		(net "SAS_EXP_GF_TX_DP4")
	)
	(arc
		(start 130.000502 -254.155194)
		(mid 129.998361 -254.133953)
		(end 129.99212 -254.113538)
		(width 0.1016)
		(layer "F.Cu")
		(net "SAS_EXP_GF_TX_DP4")
	)
	(arc
		(start 129.900172 -249.869452)
		(mid 129.869586 -249.735534)
		(end 129.780792 -249.630692)
		(width 0.1016)
		(layer "F.Cu")
		(net "SAS_EXP_GF_TX_DP4")
	)
	(arc
		(start 129.661412 -244.316504)
		(mid 129.691904 -244.182511)
		(end 129.780792 -244.077744)
		(width 0.1016)
		(layer "F.Cu")
		(net "SAS_EXP_GF_TX_DP4")
	)
	(arc
		(start 129.780792 -249.630692)
		(mid 129.691998 -249.525878)
		(end 129.661412 -249.391932)
		(width 0.1016)
		(layer "F.Cu")
		(net "SAS_EXP_GF_TX_DP4")
	)
	(arc
		(start 129.98323 -254.091948)
		(mid 129.959867 -254.056784)
		(end 129.92481 -254.033274)
		(width 0.1016)
		(layer "F.Cu")
		(net "SAS_EXP_GF_TX_DP4")
	)
	(arc
		(start 129.780792 -243.295424)
		(mid 129.691998 -243.19061)
		(end 129.661412 -243.056664)
		(width 0.1016)
		(layer "F.Cu")
		(net "SAS_EXP_GF_TX_DP4")
	)
	(arc
		(start 129.720848 -253.907036)
		(mid 129.676853 -253.841193)
		(end 129.661412 -253.763526)
		(width 0.1016)
		(layer "F.Cu")
		(net "SAS_EXP_GF_TX_DP4")
	)
	(arc
		(start 129.661412 -234.499658)
		(mid 130.178148 -231.901848)
		(end 131.649724 -229.699566)
		(width 0.1016)
		(layer "F.Cu")
		(net "SAS_EXP_GF_TX_DP4")
	)
	(arc
		(start 129.661412 -249.087132)
		(mid 129.691998 -248.953214)
		(end 129.780792 -248.848372)
		(width 0.1016)
		(layer "F.Cu")
		(net "SAS_EXP_GF_TX_DP4")
	)
	(arc
		(start 129.780792 -248.066052)
		(mid 129.691998 -247.961238)
		(end 129.661412 -247.827292)
		(width 0.1016)
		(layer "F.Cu")
		(net "SAS_EXP_GF_TX_DP4")
	)
	(arc
		(start 122.230388 -159.718248)
		(mid 121.902879 -159.228097)
		(end 121.78792 -158.649924)
		(width 0.1016)
		(layer "F.Cu")
		(net "SAS_EXP_GF_TX_DP4")
	)
	(arc
		(start 129.900172 -248.304812)
		(mid 129.869586 -248.170894)
		(end 129.780792 -248.066052)
		(width 0.1016)
		(layer "F.Cu")
		(net "SAS_EXP_GF_TX_DP4")
	)
	(arc
		(start 121.835672 -114.642138)
		(mid 121.873021 -114.596529)
		(end 121.929398 -114.5794)
		(width 0.1016)
		(layer "F.Cu")
		(net "SAS_EXP_GF_TX_DP4")
	)
	(arc
		(start 129.780792 -244.077744)
		(mid 129.869586 -243.97293)
		(end 129.900172 -243.838984)
		(width 0.1016)
		(layer "F.Cu")
		(net "SAS_EXP_GF_TX_DP4")
	)
	(segment
		(start 274.6375 -176.657)
		(end 274.860004 -176.434496)
		(width 0.1143)
		(layer "F.Cu")
		(net "ROMA20")
	)
	(segment
		(start 284.834838 -177.040032)
		(end 284.719268 -176.924462)
		(width 0.1143)
		(layer "F.Cu")
		(net "ROMA20")
	)
	(segment
		(start 283.353256 -176.736756)
		(end 279.93086 -176.736756)
		(width 0.1143)
		(layer "F.Cu")
		(net "ROMA20")
	)
	(segment
		(start 274.860004 -176.434496)
		(end 279.6286 -176.434496)
		(width 0.1143)
		(layer "F.Cu")
		(net "ROMA20")
	)
	(segment
		(start 279.93086 -176.736756)
		(end 279.6286 -176.434496)
		(width 0.1143)
		(layer "F.Cu")
		(net "ROMA20")
	)
	(segment
		(start 283.540962 -176.924462)
		(end 283.353256 -176.736756)
		(width 0.1143)
		(layer "F.Cu")
		(net "ROMA20")
	)
	(segment
		(start 284.719268 -176.924462)
		(end 283.540962 -176.924462)
		(width 0.1143)
		(layer "F.Cu")
		(net "ROMA20")
	)
	(via
		(at 279.6286 -176.434496)
		(size 0.7112)
		(drill 0.3556)
		(layers "F.Cu" "B.Cu")
		(net "ROMA20")
	)
	(segment
		(start 17.210278 -185.409586)
		(end 17.210278 -187.138818)
		(width 0.1143)
		(layer "F.Cu")
		(net "SAS_HDD_PRE15")
	)
	(segment
		(start 150.999952 -256.25044)
		(end 150.999952 -254.127)
		(width 0.1143)
		(layer "F.Cu")
		(net "SAS_HDD_PRE15")
	)
	(segment
		(start 150.667212 -253.79426)
		(end 150.667212 -234.523788)
		(width 0.1143)
		(layer "F.Cu")
		(net "SAS_HDD_PRE15")
	)
	(segment
		(start 20.124928 -177.524664)
		(end 17.095216 -180.554376)
		(width 0.1143)
		(layer "F.Cu")
		(net "SAS_HDD_PRE15")
	)
	(segment
		(start 17.095216 -180.554376)
		(end 17.095216 -181.79288)
		(width 0.1143)
		(layer "F.Cu")
		(net "SAS_HDD_PRE15")
	)
	(segment
		(start 16.820388 -182.067708)
		(end 16.820388 -184.138316)
		(width 0.1143)
		(layer "F.Cu")
		(net "SAS_HDD_PRE15")
	)
	(segment
		(start 19.763232 -174.800006)
		(end 20.124928 -175.161702)
		(width 0.1143)
		(layer "F.Cu")
		(net "SAS_HDD_PRE15")
	)
	(segment
		(start 17.210278 -187.138818)
		(end 16.485616 -187.86348)
		(width 0.1143)
		(layer "F.Cu")
		(net "SAS_HDD_PRE15")
	)
	(segment
		(start 19.381216 -174.800006)
		(end 19.763232 -174.800006)
		(width 0.1143)
		(layer "F.Cu")
		(net "SAS_HDD_PRE15")
	)
	(segment
		(start 19.185128 -174.996094)
		(end 19.381216 -174.800006)
		(width 0.1143)
		(layer "F.Cu")
		(net "SAS_HDD_PRE15")
	)
	(segment
		(start 16.485616 -187.86348)
		(end 15.926816 -187.86348)
		(width 0.1143)
		(layer "F.Cu")
		(net "SAS_HDD_PRE15")
	)
	(segment
		(start 17.095216 -181.79288)
		(end 16.820388 -182.067708)
		(width 0.1143)
		(layer "F.Cu")
		(net "SAS_HDD_PRE15")
	)
	(segment
		(start 151.683212 -204.678788)
		(end 152.146 -204.216)
		(width 0.1143)
		(layer "F.Cu")
		(net "SAS_HDD_PRE15")
	)
	(segment
		(start 150.999952 -254.127)
		(end 150.667212 -253.79426)
		(width 0.1143)
		(layer "F.Cu")
		(net "SAS_HDD_PRE15")
	)
	(segment
		(start 150.667212 -234.523788)
		(end 151.683212 -233.507788)
		(width 0.1143)
		(layer "F.Cu")
		(net "SAS_HDD_PRE15")
	)
	(segment
		(start 16.820388 -184.138316)
		(end 17.210278 -184.528206)
		(width 0.1143)
		(layer "F.Cu")
		(net "SAS_HDD_PRE15")
	)
	(segment
		(start 19.185128 -175.746156)
		(end 19.185128 -174.996094)
		(width 0.1143)
		(layer "F.Cu")
		(net "SAS_HDD_PRE15")
	)
	(segment
		(start 20.124928 -175.161702)
		(end 20.124928 -177.524664)
		(width 0.1143)
		(layer "F.Cu")
		(net "SAS_HDD_PRE15")
	)
	(segment
		(start 17.210278 -184.528206)
		(end 17.210278 -185.409586)
		(width 0.1143)
		(layer "F.Cu")
		(net "SAS_HDD_PRE15")
	)
	(segment
		(start 151.683212 -233.507788)
		(end 151.683212 -204.678788)
		(width 0.1143)
		(layer "F.Cu")
		(net "SAS_HDD_PRE15")
	)
	(via
		(at 15.926816 -187.86348)
		(size 0.5588)
		(drill 0.3048)
		(layers "F.Cu" "B.Cu")
		(net "SAS_HDD_PRE15")
	)
	(via
		(at 152.146 -204.216)
		(size 0.508)
		(drill 0.254)
		(layers "F.Cu" "B.Cu")
		(net "SAS_HDD_PRE15")
	)
	(via
		(at 17.095216 -181.79288)
		(size 0.7112)
		(drill 0.3556)
		(layers "F.Cu" "B.Cu")
		(net "SAS_HDD_PRE15")
	)
	(segment
		(start 15.926816 -187.86348)
		(end 16.053816 -187.86348)
		(width 0.127)
		(layer "In2.Cu")
		(net "SAS_HDD_PRE15")
	)
	(segment
		(start 151.765 -203.835)
		(end 152.146 -204.216)
		(width 0.127)
		(layer "In2.Cu")
		(net "SAS_HDD_PRE15")
	)
	(segment
		(start 16.053816 -187.86348)
		(end 19.198336 -191.008)
		(width 0.127)
		(layer "In2.Cu")
		(net "SAS_HDD_PRE15")
	)
	(segment
		(start 138.303 -191.008)
		(end 151.13 -203.835)
		(width 0.127)
		(layer "In2.Cu")
		(net "SAS_HDD_PRE15")
	)
	(segment
		(start 19.198336 -191.008)
		(end 138.303 -191.008)
		(width 0.127)
		(layer "In2.Cu")
		(net "SAS_HDD_PRE15")
	)
	(segment
		(start 151.13 -203.835)
		(end 151.765 -203.835)
		(width 0.127)
		(layer "In2.Cu")
		(net "SAS_HDD_PRE15")
	)
	(segment
		(start 95.000572 -250.46686)
		(end 95.000572 -251.714)
		(width 0.127)
		(layer "F.Cu")
		(net "HB_INPUT")
	)
	(segment
		(start 94.914212 -250.3805)
		(end 95.000572 -250.46686)
		(width 0.127)
		(layer "F.Cu")
		(net "HB_INPUT")
	)
	(segment
		(start 95.000572 -251.714)
		(end 95.000572 -256.25044)
		(width 0.127)
		(layer "F.Cu")
		(net "HB_INPUT")
	)
	(via
		(at 95.000572 -251.714)
		(size 0.7112)
		(drill 0.3556)
		(layers "F.Cu" "B.Cu")
		(net "HB_INPUT")
	)
	(segment
		(start 118.999762 -256.50444)
		(end 118.999762 -254.536194)
		(width 0.1016)
		(layer "B.Cu")
		(net "SAS_GF_EXP_RX_DN7")
	)
	(segment
		(start 117.685312 -225.6536)
		(end 117.685312 -223.141794)
		(width 0.1016)
		(layer "B.Cu")
		(net "SAS_GF_EXP_RX_DN7")
	)
	(segment
		(start 117.643148 -222.93072)
		(end 117.55247 -222.71228)
		(width 0.1016)
		(layer "B.Cu")
		(net "SAS_GF_EXP_RX_DN7")
	)
	(segment
		(start 118.877842 -227.49637)
		(end 118.144798 -226.763326)
		(width 0.1016)
		(layer "B.Cu")
		(net "SAS_GF_EXP_RX_DN7")
	)
	(segment
		(start 117.408198 -222.568008)
		(end 117.113558 -222.446088)
		(width 0.1016)
		(layer "B.Cu")
		(net "SAS_GF_EXP_RX_DN7")
	)
	(segment
		(start 119.336312 -253.723902)
		(end 119.336312 -228.603302)
		(width 0.1016)
		(layer "B.Cu")
		(net "SAS_GF_EXP_RX_DN7")
	)
	(segment
		(start 117.084856 -222.4405)
		(end 117.037612 -222.4405)
		(width 0.1016)
		(layer "B.Cu")
		(net "SAS_GF_EXP_RX_DN7")
	)
	(segment
		(start 119.167656 -254.130302)
		(end 119.16791 -254.130048)
		(width 0.1016)
		(layer "B.Cu")
		(net "SAS_GF_EXP_RX_DN7")
	)
	(arc
		(start 119.336312 -228.603302)
		(mid 119.217153 -228.004249)
		(end 118.877842 -227.49637)
		(width 0.1016)
		(layer "B.Cu")
		(net "SAS_GF_EXP_RX_DN7")
	)
	(arc
		(start 118.144798 -226.763326)
		(mid 117.804734 -226.25415)
		(end 117.685312 -225.6536)
		(width 0.1016)
		(layer "B.Cu")
		(net "SAS_GF_EXP_RX_DN7")
	)
	(arc
		(start 119.16791 -254.130048)
		(mid 119.292502 -253.943722)
		(end 119.336312 -253.723902)
		(width 0.1016)
		(layer "B.Cu")
		(net "SAS_GF_EXP_RX_DN7")
	)
	(arc
		(start 118.999762 -254.536194)
		(mid 119.043394 -254.316573)
		(end 119.167656 -254.130302)
		(width 0.1016)
		(layer "B.Cu")
		(net "SAS_GF_EXP_RX_DN7")
	)
	(arc
		(start 117.55247 -222.71228)
		(mid 117.527783 -222.666116)
		(end 117.494558 -222.625666)
		(width 0.1016)
		(layer "B.Cu")
		(net "SAS_GF_EXP_RX_DN7")
	)
	(arc
		(start 117.113558 -222.446088)
		(mid 117.099481 -222.441885)
		(end 117.084856 -222.4405)
		(width 0.1016)
		(layer "B.Cu")
		(net "SAS_GF_EXP_RX_DN7")
	)
	(arc
		(start 117.685312 -223.141794)
		(mid 117.674648 -223.034175)
		(end 117.643148 -222.93072)
		(width 0.1016)
		(layer "B.Cu")
		(net "SAS_GF_EXP_RX_DN7")
	)
	(arc
		(start 117.494558 -222.625666)
		(mid 117.454227 -222.592566)
		(end 117.408198 -222.568008)
		(width 0.1016)
		(layer "B.Cu")
		(net "SAS_GF_EXP_RX_DN7")
	)
	(segment
		(start 117.350032 -102.350062)
		(end 117.850158 -102.850188)
		(width 0.1016)
		(layer "F.Cu")
		(net "SAS_GF_EXP_RX_DN5")
	)
	(via
		(at 117.850158 -102.850188)
		(size 0.508)
		(drill 0.254)
		(layers "F.Cu" "B.Cu")
		(net "SAS_GF_EXP_RX_DN5")
	)
	(segment
		(start 117.645688 -103.077264)
		(end 117.734588 -102.968552)
		(width 0.1016)
		(layer "B.Cu")
		(net "SAS_GF_EXP_RX_DN5")
	)
	(segment
		(start 117.734588 -102.968552)
		(end 117.740938 -102.960932)
		(width 0.1016)
		(layer "B.Cu")
		(net "SAS_GF_EXP_RX_DN5")
	)
	(segment
		(start 117.447568 -103.411274)
		(end 117.547898 -103.201978)
		(width 0.1016)
		(layer "B.Cu")
		(net "SAS_GF_EXP_RX_DN5")
	)
	(segment
		(start 132.098288 -169.145458)
		(end 122.9106 -159.95777)
		(width 0.1016)
		(layer "B.Cu")
		(net "SAS_GF_EXP_RX_DN5")
	)
	(segment
		(start 120.537986 -113.037366)
		(end 117.681502 -110.180628)
		(width 0.1016)
		(layer "B.Cu")
		(net "SAS_GF_EXP_RX_DN5")
	)
	(segment
		(start 117.395244 -109.489494)
		(end 117.395244 -104.120696)
		(width 0.1016)
		(layer "B.Cu")
		(net "SAS_GF_EXP_RX_DN5")
	)
	(segment
		(start 121.08307 -155.545028)
		(end 121.08307 -114.35334)
		(width 0.1016)
		(layer "B.Cu")
		(net "SAS_GF_EXP_RX_DN5")
	)
	(segment
		(start 117.7544 -102.945946)
		(end 117.850158 -102.850188)
		(width 0.1016)
		(layer "B.Cu")
		(net "SAS_GF_EXP_RX_DN5")
	)
	(segment
		(start 127.047752 -254.52959)
		(end 127.314452 -253.884684)
		(width 0.1016)
		(layer "B.Cu")
		(net "SAS_GF_EXP_RX_DN5")
	)
	(segment
		(start 117.395244 -103.9622)
		(end 117.395244 -103.641652)
		(width 0.1016)
		(layer "B.Cu")
		(net "SAS_GF_EXP_RX_DN5")
	)
	(segment
		(start 127.362712 -253.64186)
		(end 127.362712 -237.449868)
		(width 0.1016)
		(layer "B.Cu")
		(net "SAS_GF_EXP_RX_DN5")
	)
	(segment
		(start 132.151374 -169.198798)
		(end 132.098288 -169.145458)
		(width 0.1016)
		(layer "B.Cu")
		(net "SAS_GF_EXP_RX_DN5")
	)
	(segment
		(start 132.663184 -228.910134)
		(end 132.663184 -170.434)
		(width 0.1016)
		(layer "B.Cu")
		(net "SAS_GF_EXP_RX_DN5")
	)
	(segment
		(start 128.611884 -234.434126)
		(end 131.621784 -231.424226)
		(width 0.1016)
		(layer "B.Cu")
		(net "SAS_GF_EXP_RX_DN5")
	)
	(segment
		(start 126.999492 -256.50444)
		(end 126.999492 -254.772414)
		(width 0.1016)
		(layer "B.Cu")
		(net "SAS_GF_EXP_RX_DN5")
	)
	(arc
		(start 127.362712 -237.449868)
		(mid 127.687427 -235.817796)
		(end 128.611884 -234.434126)
		(width 0.1016)
		(layer "B.Cu")
		(net "SAS_GF_EXP_RX_DN5")
	)
	(arc
		(start 127.35941 -253.705614)
		(mid 127.361867 -253.673779)
		(end 127.362712 -253.64186)
		(width 0.1016)
		(layer "B.Cu")
		(net "SAS_GF_EXP_RX_DN5")
	)
	(arc
		(start 131.621784 -231.424226)
		(mid 132.392511 -230.270751)
		(end 132.663184 -228.910134)
		(width 0.1016)
		(layer "B.Cu")
		(net "SAS_GF_EXP_RX_DN5")
	)
	(arc
		(start 117.395244 -104.120696)
		(mid 117.39093 -104.041448)
		(end 117.395244 -103.9622)
		(width 0.1016)
		(layer "B.Cu")
		(net "SAS_GF_EXP_RX_DN5")
	)
	(arc
		(start 117.547898 -103.201978)
		(mid 117.572266 -103.160631)
		(end 117.60327 -103.124)
		(width 0.1016)
		(layer "B.Cu")
		(net "SAS_GF_EXP_RX_DN5")
	)
	(arc
		(start 127.314452 -253.884684)
		(mid 127.343486 -253.796794)
		(end 127.35941 -253.705614)
		(width 0.1016)
		(layer "B.Cu")
		(net "SAS_GF_EXP_RX_DN5")
	)
	(arc
		(start 132.663184 -170.434)
		(mid 132.530118 -169.765501)
		(end 132.151374 -169.198798)
		(width 0.1016)
		(layer "B.Cu")
		(net "SAS_GF_EXP_RX_DN5")
	)
	(arc
		(start 121.08307 -114.35334)
		(mid 120.941405 -113.641144)
		(end 120.537986 -113.037366)
		(width 0.1016)
		(layer "B.Cu")
		(net "SAS_GF_EXP_RX_DN5")
	)
	(arc
		(start 122.9106 -159.95777)
		(mid 121.557929 -157.933171)
		(end 121.08307 -155.545028)
		(width 0.1016)
		(layer "B.Cu")
		(net "SAS_GF_EXP_RX_DN5")
	)
	(arc
		(start 117.681502 -110.180628)
		(mid 117.46965 -109.86352)
		(end 117.395244 -109.489494)
		(width 0.1016)
		(layer "B.Cu")
		(net "SAS_GF_EXP_RX_DN5")
	)
	(arc
		(start 117.740938 -102.960932)
		(mid 117.747484 -102.953273)
		(end 117.7544 -102.945946)
		(width 0.1016)
		(layer "B.Cu")
		(net "SAS_GF_EXP_RX_DN5")
	)
	(arc
		(start 126.999492 -254.772414)
		(mid 127.011674 -254.648628)
		(end 127.047752 -254.52959)
		(width 0.1016)
		(layer "B.Cu")
		(net "SAS_GF_EXP_RX_DN5")
	)
	(arc
		(start 117.395244 -103.641652)
		(mid 117.408488 -103.523529)
		(end 117.447568 -103.411274)
		(width 0.1016)
		(layer "B.Cu")
		(net "SAS_GF_EXP_RX_DN5")
	)
	(arc
		(start 117.60327 -103.124)
		(mid 117.625056 -103.101155)
		(end 117.645688 -103.077264)
		(width 0.1016)
		(layer "B.Cu")
		(net "SAS_GF_EXP_RX_DN5")
	)
	(segment
		(start 93.999812 -256.25044)
		(end 93.999812 -249.462036)
		(width 0.1143)
		(layer "F.Cu")
		(net "SAS_I2C_B_BUF_SCL_R")
	)
	(segment
		(start 93.999812 -249.462036)
		(end 94.2721 -249.189494)
		(width 0.1143)
		(layer "F.Cu")
		(net "SAS_I2C_B_BUF_SCL_R")
	)
	(segment
		(start 94.2721 -249.189494)
		(end 94.2721 -248.734072)
		(width 0.1143)
		(layer "F.Cu")
		(net "SAS_I2C_B_BUF_SCL_R")
	)
	(segment
		(start 173.07306 -202.637136)
		(end 170.300396 -205.4098)
		(width 0.1143)
		(layer "F.Cu")
		(net "SAS_I2C_B_BUF_SCL_R")
	)
	(segment
		(start 173.537372 -202.637136)
		(end 173.07306 -202.637136)
		(width 0.1143)
		(layer "F.Cu")
		(net "SAS_I2C_B_BUF_SCL_R")
	)
	(segment
		(start 94.2721 -248.734072)
		(end 94.615 -248.391172)
		(width 0.1143)
		(layer "F.Cu")
		(net "SAS_I2C_B_BUF_SCL_R")
	)
	(via
		(at 169.418 -246.3038)
		(size 0.5588)
		(drill 0.3048)
		(layers "F.Cu" "B.Cu")
		(net "SAS_I2C_B_BUF_SCL_R")
	)
	(via
		(at 170.300396 -205.4098)
		(size 0.5588)
		(drill 0.3048)
		(layers "F.Cu" "B.Cu")
		(net "SAS_I2C_B_BUF_SCL_R")
	)
	(via
		(at 94.615 -248.391172)
		(size 0.5588)
		(drill 0.3048)
		(layers "F.Cu" "B.Cu")
		(net "SAS_I2C_B_BUF_SCL_R")
	)
	(via
		(at 169.926 -225.39579)
		(size 0.7112)
		(drill 0.3556)
		(layers "F.Cu" "B.Cu")
		(net "SAS_I2C_B_BUF_SCL_R")
	)
	(segment
		(start 170.300396 -205.4098)
		(end 170.1546 -205.4098)
		(width 0.1143)
		(layer "B.Cu")
		(net "SAS_I2C_B_BUF_SCL_R")
	)
	(segment
		(start 169.926 -245.7958)
		(end 169.418 -246.3038)
		(width 0.1143)
		(layer "B.Cu")
		(net "SAS_I2C_B_BUF_SCL_R")
	)
	(segment
		(start 169.926 -205.6384)
		(end 169.926 -225.39579)
		(width 0.1143)
		(layer "B.Cu")
		(net "SAS_I2C_B_BUF_SCL_R")
	)
	(segment
		(start 169.926 -225.39579)
		(end 169.926 -245.7958)
		(width 0.1143)
		(layer "B.Cu")
		(net "SAS_I2C_B_BUF_SCL_R")
	)
	(segment
		(start 170.1546 -205.4098)
		(end 169.926 -205.6384)
		(width 0.1143)
		(layer "B.Cu")
		(net "SAS_I2C_B_BUF_SCL_R")
	)
	(segment
		(start 121.359422 -248.083578)
		(end 96.962976 -248.083578)
		(width 0.127)
		(layer "In2.Cu")
		(net "SAS_I2C_B_BUF_SCL_R")
	)
	(segment
		(start 169.3672 -246.253)
		(end 123.19 -246.253)
		(width 0.127)
		(layer "In2.Cu")
		(net "SAS_I2C_B_BUF_SCL_R")
	)
	(segment
		(start 123.19 -246.253)
		(end 121.359422 -248.083578)
		(width 0.127)
		(layer "In2.Cu")
		(net "SAS_I2C_B_BUF_SCL_R")
	)
	(segment
		(start 96.934528 -248.112026)
		(end 94.894146 -248.112026)
		(width 0.127)
		(layer "In2.Cu")
		(net "SAS_I2C_B_BUF_SCL_R")
	)
	(segment
		(start 169.418 -246.3038)
		(end 169.3672 -246.253)
		(width 0.127)
		(layer "In2.Cu")
		(net "SAS_I2C_B_BUF_SCL_R")
	)
	(segment
		(start 94.894146 -248.112026)
		(end 94.615 -248.391172)
		(width 0.127)
		(layer "In2.Cu")
		(net "SAS_I2C_B_BUF_SCL_R")
	)
	(segment
		(start 96.962976 -248.083578)
		(end 96.934528 -248.112026)
		(width 0.127)
		(layer "In2.Cu")
		(net "SAS_I2C_B_BUF_SCL_R")
	)
	(segment
		(start 347.235018 -10.750042)
		(end 353.734878 -10.750042)
		(width 0.127)
		(layer "F.Cu")
		(net "FP_PWR_BTN_N")
	)
	(segment
		(start 294.080692 -133.416294)
		(end 286.549846 -133.416294)
		(width 0.127)
		(layer "F.Cu")
		(net "FP_PWR_BTN_N")
	)
	(segment
		(start 323.469 -82.169)
		(end 317.627 -88.011)
		(width 0.127)
		(layer "F.Cu")
		(net "FP_PWR_BTN_N")
	)
	(segment
		(start 183.9595 -228.346)
		(end 184.9755 -229.362)
		(width 0.127)
		(layer "F.Cu")
		(net "FP_PWR_BTN_N")
	)
	(segment
		(start 304.546 -109.093)
		(end 304.546 -116.586)
		(width 0.127)
		(layer "F.Cu")
		(net "FP_PWR_BTN_N")
	)
	(segment
		(start 300.1645 -127.332486)
		(end 294.080692 -133.416294)
		(width 0.127)
		(layer "F.Cu")
		(net "FP_PWR_BTN_N")
	)
	(segment
		(start 326.009 -16.002)
		(end 325.58355 -16.42745)
		(width 0.127)
		(layer "F.Cu")
		(net "FP_PWR_BTN_N")
	)
	(segment
		(start 304.546 -116.586)
		(end 300.1645 -120.9675)
		(width 0.127)
		(layer "F.Cu")
		(net "FP_PWR_BTN_N")
	)
	(segment
		(start 300.1645 -120.9675)
		(end 300.1645 -127.332486)
		(width 0.127)
		(layer "F.Cu")
		(net "FP_PWR_BTN_N")
	)
	(segment
		(start 323.469 -67.851274)
		(end 323.469 -82.169)
		(width 0.127)
		(layer "F.Cu")
		(net "FP_PWR_BTN_N")
	)
	(segment
		(start 325.58355 -16.42745)
		(end 325.58355 -65.736724)
		(width 0.127)
		(layer "F.Cu")
		(net "FP_PWR_BTN_N")
	)
	(segment
		(start 317.627 -93.853)
		(end 305.054 -106.426)
		(width 0.127)
		(layer "F.Cu")
		(net "FP_PWR_BTN_N")
	)
	(segment
		(start 42.164 -169.291)
		(end 40.9575 -169.291)
		(width 0.127)
		(layer "F.Cu")
		(net "FP_PWR_BTN_N")
	)
	(segment
		(start 184.9755 -229.362)
		(end 187.27166 -229.362)
		(width 0.127)
		(layer "F.Cu")
		(net "FP_PWR_BTN_N")
	)
	(segment
		(start 346.408502 -11.576558)
		(end 345.408504 -11.576558)
		(width 0.127)
		(layer "F.Cu")
		(net "FP_PWR_BTN_N")
	)
	(segment
		(start 340.983062 -16.002)
		(end 339.753448 -16.002)
		(width 0.127)
		(layer "F.Cu")
		(net "FP_PWR_BTN_N")
	)
	(segment
		(start 339.753448 -16.002)
		(end 326.009 -16.002)
		(width 0.127)
		(layer "F.Cu")
		(net "FP_PWR_BTN_N")
	)
	(segment
		(start 325.58355 -65.736724)
		(end 323.469 -67.851274)
		(width 0.127)
		(layer "F.Cu")
		(net "FP_PWR_BTN_N")
	)
	(segment
		(start 347.235018 -10.750042)
		(end 346.408502 -11.576558)
		(width 0.127)
		(layer "F.Cu")
		(net "FP_PWR_BTN_N")
	)
	(segment
		(start 345.408504 -11.576558)
		(end 340.983062 -16.002)
		(width 0.127)
		(layer "F.Cu")
		(net "FP_PWR_BTN_N")
	)
	(segment
		(start 42.164 -168.275)
		(end 42.164 -169.291)
		(width 0.127)
		(layer "F.Cu")
		(net "FP_PWR_BTN_N")
	)
	(segment
		(start 317.627 -88.011)
		(end 317.627 -93.853)
		(width 0.127)
		(layer "F.Cu")
		(net "FP_PWR_BTN_N")
	)
	(segment
		(start 305.054 -106.426)
		(end 305.054 -108.585)
		(width 0.127)
		(layer "F.Cu")
		(net "FP_PWR_BTN_N")
	)
	(segment
		(start 305.054 -108.585)
		(end 304.546 -109.093)
		(width 0.127)
		(layer "F.Cu")
		(net "FP_PWR_BTN_N")
	)
	(via
		(at 187.27166 -229.362)
		(size 0.5588)
		(drill 0.3048)
		(layers "F.Cu" "B.Cu")
		(net "FP_PWR_BTN_N")
	)
	(via
		(at 286.549846 -133.416294)
		(size 0.5588)
		(drill 0.3048)
		(layers "F.Cu" "B.Cu")
		(net "FP_PWR_BTN_N")
	)
	(via
		(at 207.2386 -143.256)
		(size 0.5588)
		(drill 0.3048)
		(layers "F.Cu" "B.Cu")
		(net "FP_PWR_BTN_N")
	)
	(via
		(at 191.77 -184.785)
		(size 0.5588)
		(drill 0.3048)
		(layers "F.Cu" "B.Cu")
		(net "FP_PWR_BTN_N")
	)
	(via
		(at 42.164 -168.275)
		(size 0.5588)
		(drill 0.3048)
		(layers "F.Cu" "B.Cu")
		(net "FP_PWR_BTN_N")
	)
	(via
		(at 339.753448 -16.002)
		(size 0.7112)
		(drill 0.3556)
		(layers "F.Cu" "B.Cu")
		(net "FP_PWR_BTN_N")
	)
	(segment
		(start 187.27166 -224.08134)
		(end 187.27166 -229.362)
		(width 0.127)
		(layer "B.Cu")
		(net "FP_PWR_BTN_N")
	)
	(segment
		(start 191.77 -165.1)
		(end 191.77 -184.785)
		(width 0.127)
		(layer "B.Cu")
		(net "FP_PWR_BTN_N")
	)
	(segment
		(start 191.77 -185.293)
		(end 190.3603 -186.7027)
		(width 0.127)
		(layer "B.Cu")
		(net "FP_PWR_BTN_N")
	)
	(segment
		(start 188.722 -222.631)
		(end 187.27166 -224.08134)
		(width 0.127)
		(layer "B.Cu")
		(net "FP_PWR_BTN_N")
	)
	(segment
		(start 190.3603 -186.7027)
		(end 190.3603 -204.2287)
		(width 0.127)
		(layer "B.Cu")
		(net "FP_PWR_BTN_N")
	)
	(segment
		(start 207.137 -149.733)
		(end 191.77 -165.1)
		(width 0.127)
		(layer "B.Cu")
		(net "FP_PWR_BTN_N")
	)
	(segment
		(start 207.137 -143.3576)
		(end 207.137 -149.733)
		(width 0.127)
		(layer "B.Cu")
		(net "FP_PWR_BTN_N")
	)
	(segment
		(start 190.3603 -204.2287)
		(end 188.722 -205.867)
		(width 0.127)
		(layer "B.Cu")
		(net "FP_PWR_BTN_N")
	)
	(segment
		(start 191.77 -184.785)
		(end 191.77 -185.293)
		(width 0.127)
		(layer "B.Cu")
		(net "FP_PWR_BTN_N")
	)
	(segment
		(start 207.2386 -143.256)
		(end 207.137 -143.3576)
		(width 0.127)
		(layer "B.Cu")
		(net "FP_PWR_BTN_N")
	)
	(segment
		(start 188.722 -205.867)
		(end 188.722 -222.631)
		(width 0.127)
		(layer "B.Cu")
		(net "FP_PWR_BTN_N")
	)
	(segment
		(start 162.814 -177.419)
		(end 66.675 -177.419)
		(width 0.127)
		(layer "In2.Cu")
		(net "FP_PWR_BTN_N")
	)
	(segment
		(start 209.042 -142.7607)
		(end 207.7339 -142.7607)
		(width 0.127)
		(layer "In2.Cu")
		(net "FP_PWR_BTN_N")
	)
	(segment
		(start 66.675 -177.419)
		(end 64.643 -175.387)
		(width 0.127)
		(layer "In2.Cu")
		(net "FP_PWR_BTN_N")
	)
	(segment
		(start 284.990032 -132.9944)
		(end 274.872704 -143.111728)
		(width 0.127)
		(layer "In2.Cu")
		(net "FP_PWR_BTN_N")
	)
	(segment
		(start 191.77 -184.785)
		(end 191.643 -184.658)
		(width 0.127)
		(layer "In2.Cu")
		(net "FP_PWR_BTN_N")
	)
	(segment
		(start 52.324 -175.387)
		(end 47.117 -170.18)
		(width 0.127)
		(layer "In2.Cu")
		(net "FP_PWR_BTN_N")
	)
	(segment
		(start 209.393028 -143.111728)
		(end 209.042 -142.7607)
		(width 0.127)
		(layer "In2.Cu")
		(net "FP_PWR_BTN_N")
	)
	(segment
		(start 44.069 -170.18)
		(end 42.164 -168.275)
		(width 0.127)
		(layer "In2.Cu")
		(net "FP_PWR_BTN_N")
	)
	(segment
		(start 207.7339 -142.7607)
		(end 207.2386 -143.256)
		(width 0.127)
		(layer "In2.Cu")
		(net "FP_PWR_BTN_N")
	)
	(segment
		(start 286.127952 -132.9944)
		(end 284.990032 -132.9944)
		(width 0.127)
		(layer "In2.Cu")
		(net "FP_PWR_BTN_N")
	)
	(segment
		(start 274.872704 -143.111728)
		(end 209.393028 -143.111728)
		(width 0.127)
		(layer "In2.Cu")
		(net "FP_PWR_BTN_N")
	)
	(segment
		(start 47.117 -170.18)
		(end 44.069 -170.18)
		(width 0.127)
		(layer "In2.Cu")
		(net "FP_PWR_BTN_N")
	)
	(segment
		(start 191.643 -184.658)
		(end 170.053 -184.658)
		(width 0.127)
		(layer "In2.Cu")
		(net "FP_PWR_BTN_N")
	)
	(segment
		(start 170.053 -184.658)
		(end 162.814 -177.419)
		(width 0.127)
		(layer "In2.Cu")
		(net "FP_PWR_BTN_N")
	)
	(segment
		(start 64.643 -175.387)
		(end 52.324 -175.387)
		(width 0.127)
		(layer "In2.Cu")
		(net "FP_PWR_BTN_N")
	)
	(segment
		(start 286.549846 -133.416294)
		(end 286.127952 -132.9944)
		(width 0.127)
		(layer "In2.Cu")
		(net "FP_PWR_BTN_N")
	)
	(segment
		(start 91.567 -241.9985)
		(end 91.1225 -241.808)
		(width 0.1143)
		(layer "F.Cu")
		(net "SAS_FAULT_LED15")
	)
	(segment
		(start 93.853 -237.871)
		(end 93.853 -237.998)
		(width 0.1143)
		(layer "F.Cu")
		(net "SAS_FAULT_LED15")
	)
	(segment
		(start 93.599 -238.252)
		(end 91.44 -238.252)
		(width 0.1143)
		(layer "F.Cu")
		(net "SAS_FAULT_LED15")
	)
	(segment
		(start 91.3765 -231.3305)
		(end 92.71 -232.664)
		(width 0.1143)
		(layer "F.Cu")
		(net "SAS_FAULT_LED15")
	)
	(segment
		(start 96.999552 -251.773436)
		(end 98.313494 -250.459494)
		(width 0.1143)
		(layer "F.Cu")
		(net "SAS_FAULT_LED15")
	)
	(segment
		(start 92.71 -232.664)
		(end 92.837 -232.664)
		(width 0.1143)
		(layer "F.Cu")
		(net "SAS_FAULT_LED15")
	)
	(segment
		(start 91.313 -231.3305)
		(end 91.3765 -231.3305)
		(width 0.1143)
		(layer "F.Cu")
		(net "SAS_FAULT_LED15")
	)
	(segment
		(start 91.1225 -238.5695)
		(end 91.1225 -239.3442)
		(width 0.1143)
		(layer "F.Cu")
		(net "SAS_FAULT_LED15")
	)
	(segment
		(start 91.1225 -241.808)
		(end 91.1225 -239.3442)
		(width 0.1143)
		(layer "F.Cu")
		(net "SAS_FAULT_LED15")
	)
	(segment
		(start 91.44 -238.252)
		(end 91.1225 -238.5695)
		(width 0.1143)
		(layer "F.Cu")
		(net "SAS_FAULT_LED15")
	)
	(segment
		(start 93.853 -237.998)
		(end 93.599 -238.252)
		(width 0.1143)
		(layer "F.Cu")
		(net "SAS_FAULT_LED15")
	)
	(segment
		(start 96.999552 -256.25044)
		(end 96.999552 -251.773436)
		(width 0.1143)
		(layer "F.Cu")
		(net "SAS_FAULT_LED15")
	)
	(via
		(at 93.853 -237.871)
		(size 0.5588)
		(drill 0.3048)
		(layers "F.Cu" "B.Cu")
		(net "SAS_FAULT_LED15")
	)
	(via
		(at 92.837 -232.664)
		(size 0.5588)
		(drill 0.3048)
		(layers "F.Cu" "B.Cu")
		(net "SAS_FAULT_LED15")
	)
	(via
		(at 94.107 -239.141)
		(size 0.7112)
		(drill 0.3556)
		(layers "F.Cu" "B.Cu")
		(net "SAS_FAULT_LED15")
	)
	(via
		(at 98.313494 -250.459494)
		(size 0.508)
		(drill 0.254)
		(layers "F.Cu" "B.Cu")
		(net "SAS_FAULT_LED15")
	)
	(segment
		(start 98.425 -250.347988)
		(end 98.313494 -250.459494)
		(width 0.1143)
		(layer "B.Cu")
		(net "SAS_FAULT_LED15")
	)
	(segment
		(start 92.964 -236.911642)
		(end 92.964 -232.791)
		(width 0.1143)
		(layer "B.Cu")
		(net "SAS_FAULT_LED15")
	)
	(segment
		(start 93.853 -237.800642)
		(end 92.964 -236.911642)
		(width 0.1143)
		(layer "B.Cu")
		(net "SAS_FAULT_LED15")
	)
	(segment
		(start 97.2947 -242.3287)
		(end 97.2947 -245.630954)
		(width 0.1143)
		(layer "B.Cu")
		(net "SAS_FAULT_LED15")
	)
	(segment
		(start 93.853 -238.887)
		(end 94.107 -239.141)
		(width 0.1143)
		(layer "B.Cu")
		(net "SAS_FAULT_LED15")
	)
	(segment
		(start 92.964 -232.791)
		(end 92.837 -232.664)
		(width 0.1143)
		(layer "B.Cu")
		(net "SAS_FAULT_LED15")
	)
	(segment
		(start 98.425 -246.761254)
		(end 98.425 -250.347988)
		(width 0.1143)
		(layer "B.Cu")
		(net "SAS_FAULT_LED15")
	)
	(segment
		(start 97.2947 -245.630954)
		(end 98.425 -246.761254)
		(width 0.1143)
		(layer "B.Cu")
		(net "SAS_FAULT_LED15")
	)
	(segment
		(start 93.853 -237.871)
		(end 93.853 -238.887)
		(width 0.1143)
		(layer "B.Cu")
		(net "SAS_FAULT_LED15")
	)
	(segment
		(start 93.853 -237.871)
		(end 93.853 -237.800642)
		(width 0.1143)
		(layer "B.Cu")
		(net "SAS_FAULT_LED15")
	)
	(segment
		(start 94.107 -239.141)
		(end 97.2947 -242.3287)
		(width 0.1143)
		(layer "B.Cu")
		(net "SAS_FAULT_LED15")
	)
	(segment
		(start 131.407154 -229.456996)
		(end 133.631686 -227.232464)
		(width 0.1016)
		(layer "F.Cu")
		(net "SAS_EXP_GF_TX_DN4")
	)
	(segment
		(start 134.076948 -172.049948)
		(end 121.987818 -159.960818)
		(width 0.1016)
		(layer "F.Cu")
		(net "SAS_EXP_GF_TX_DN4")
	)
	(segment
		(start 121.44502 -158.649924)
		(end 121.44502 -114.931952)
		(width 0.1016)
		(layer "F.Cu")
		(net "SAS_EXP_GF_TX_DN4")
	)
	(segment
		(start 129.059178 -254.119634)
		(end 129.259076 -253.919736)
		(width 0.1016)
		(layer "F.Cu")
		(net "SAS_EXP_GF_TX_DN4")
	)
	(segment
		(start 135.360918 -223.05772)
		(end 135.360918 -175.149764)
		(width 0.1016)
		(layer "F.Cu")
		(net "SAS_EXP_GF_TX_DN4")
	)
	(segment
		(start 129.318512 -253.776226)
		(end 129.318512 -234.499404)
		(width 0.1016)
		(layer "F.Cu")
		(net "SAS_EXP_GF_TX_DN4")
	)
	(segment
		(start 128.999742 -256.25044)
		(end 128.999742 -254.263144)
		(width 0.1016)
		(layer "F.Cu")
		(net "SAS_EXP_GF_TX_DN4")
	)
	(arc
		(start 129.309368 -253.8349)
		(mid 129.316098 -253.805899)
		(end 129.318512 -253.776226)
		(width 0.1016)
		(layer "F.Cu")
		(net "SAS_EXP_GF_TX_DN4")
	)
	(arc
		(start 128.999742 -254.263144)
		(mid 129.01519 -254.18548)
		(end 129.059178 -254.119634)
		(width 0.1016)
		(layer "F.Cu")
		(net "SAS_EXP_GF_TX_DN4")
	)
	(arc
		(start 129.318512 -234.499404)
		(mid 129.861399 -231.770509)
		(end 131.407154 -229.456996)
		(width 0.1016)
		(layer "F.Cu")
		(net "SAS_EXP_GF_TX_DN4")
	)
	(arc
		(start 129.308606 -253.837948)
		(mid 129.308993 -253.836425)
		(end 129.309368 -253.8349)
		(width 0.1016)
		(layer "F.Cu")
		(net "SAS_EXP_GF_TX_DN4")
	)
	(arc
		(start 121.987818 -159.960818)
		(mid 121.586029 -159.35936)
		(end 121.44502 -158.649924)
		(width 0.1016)
		(layer "F.Cu")
		(net "SAS_EXP_GF_TX_DN4")
	)
	(arc
		(start 129.259076 -253.919736)
		(mid 129.28874 -253.881807)
		(end 129.308606 -253.837948)
		(width 0.1016)
		(layer "F.Cu")
		(net "SAS_EXP_GF_TX_DN4")
	)
	(arc
		(start 135.360918 -175.149764)
		(mid 135.027222 -173.472162)
		(end 134.076948 -172.049948)
		(width 0.1016)
		(layer "F.Cu")
		(net "SAS_EXP_GF_TX_DN4")
	)
	(arc
		(start 133.631686 -227.232464)
		(mid 134.911508 -225.317075)
		(end 135.360918 -223.05772)
		(width 0.1016)
		(layer "F.Cu")
		(net "SAS_EXP_GF_TX_DN4")
	)
	(arc
		(start 121.44502 -114.931952)
		(mid 121.407066 -114.741145)
		(end 121.29897 -114.5794)
		(width 0.1016)
		(layer "F.Cu")
		(net "SAS_EXP_GF_TX_DN4")
	)
	(segment
		(start 287.644332 -176.630838)
		(end 287.644332 -176.640236)
		(width 0.1143)
		(layer "F.Cu")
		(net "ROMA19")
	)
	(segment
		(start 288.034984 -176.240186)
		(end 287.644332 -176.630838)
		(width 0.1143)
		(layer "F.Cu")
		(net "ROMA19")
	)
	(segment
		(start 287.644332 -176.640236)
		(end 287.635442 -176.649126)
		(width 0.1143)
		(layer "F.Cu")
		(net "ROMA19")
	)
	(via
		(at 277.574248 -179.959)
		(size 0.7112)
		(drill 0.3556)
		(layers "F.Cu" "B.Cu")
		(net "ROMA19")
	)
	(via
		(at 287.635442 -176.649126)
		(size 0.508)
		(drill 0.254)
		(layers "F.Cu" "B.Cu")
		(net "ROMA19")
	)
	(segment
		(start 274.8915 -179.959)
		(end 274.6375 -179.705)
		(width 0.1143)
		(layer "B.Cu")
		(net "ROMA19")
	)
	(segment
		(start 286.34309 -177.34788)
		(end 280.185368 -177.34788)
		(width 0.1143)
		(layer "B.Cu")
		(net "ROMA19")
	)
	(segment
		(start 287.041844 -176.649126)
		(end 286.34309 -177.34788)
		(width 0.1143)
		(layer "B.Cu")
		(net "ROMA19")
	)
	(segment
		(start 287.635442 -176.649126)
		(end 287.041844 -176.649126)
		(width 0.1143)
		(layer "B.Cu")
		(net "ROMA19")
	)
	(segment
		(start 280.185368 -177.34788)
		(end 277.574248 -179.959)
		(width 0.1143)
		(layer "B.Cu")
		(net "ROMA19")
	)
	(segment
		(start 277.574248 -179.959)
		(end 274.8915 -179.959)
		(width 0.1143)
		(layer "B.Cu")
		(net "ROMA19")
	)
	(segment
		(start 93.580204 -248.984008)
		(end 93.7768 -248.984008)
		(width 0.1143)
		(layer "F.Cu")
		(net "SAS_I2C_B_BUF_SDA_R")
	)
	(segment
		(start 93.000322 -256.25044)
		(end 93.000322 -249.56389)
		(width 0.1143)
		(layer "F.Cu")
		(net "SAS_I2C_B_BUF_SDA_R")
	)
	(segment
		(start 93.000322 -249.56389)
		(end 93.580204 -248.984008)
		(width 0.1143)
		(layer "F.Cu")
		(net "SAS_I2C_B_BUF_SDA_R")
	)
	(segment
		(start 185.221372 -204.796136)
		(end 185.873136 -204.796136)
		(width 0.1143)
		(layer "F.Cu")
		(net "SAS_I2C_B_BUF_SDA_R")
	)
	(segment
		(start 185.873136 -204.796136)
		(end 186.944 -205.867)
		(width 0.1143)
		(layer "F.Cu")
		(net "SAS_I2C_B_BUF_SDA_R")
	)
	(via
		(at 186.182 -246.3038)
		(size 0.5588)
		(drill 0.3048)
		(layers "F.Cu" "B.Cu")
		(net "SAS_I2C_B_BUF_SDA_R")
	)
	(via
		(at 186.381136 -218.727274)
		(size 0.7112)
		(drill 0.3556)
		(layers "F.Cu" "B.Cu")
		(net "SAS_I2C_B_BUF_SDA_R")
	)
	(via
		(at 93.7768 -248.984008)
		(size 0.5588)
		(drill 0.3048)
		(layers "F.Cu" "B.Cu")
		(net "SAS_I2C_B_BUF_SDA_R")
	)
	(via
		(at 186.944 -205.867)
		(size 0.5588)
		(drill 0.3048)
		(layers "F.Cu" "B.Cu")
		(net "SAS_I2C_B_BUF_SDA_R")
	)
	(segment
		(start 185.801 -222.123)
		(end 186.381136 -221.542864)
		(width 0.1143)
		(layer "B.Cu")
		(net "SAS_I2C_B_BUF_SDA_R")
	)
	(segment
		(start 186.78271 -229.70871)
		(end 186.69 -229.616)
		(width 0.1143)
		(layer "B.Cu")
		(net "SAS_I2C_B_BUF_SDA_R")
	)
	(segment
		(start 186.3852 -246.3038)
		(end 186.78271 -245.90629)
		(width 0.1143)
		(layer "B.Cu")
		(net "SAS_I2C_B_BUF_SDA_R")
	)
	(segment
		(start 186.381136 -221.542864)
		(end 186.381136 -218.727274)
		(width 0.1143)
		(layer "B.Cu")
		(net "SAS_I2C_B_BUF_SDA_R")
	)
	(segment
		(start 186.381136 -218.727274)
		(end 186.381136 -206.429864)
		(width 0.1143)
		(layer "B.Cu")
		(net "SAS_I2C_B_BUF_SDA_R")
	)
	(segment
		(start 186.182 -246.3038)
		(end 186.3852 -246.3038)
		(width 0.1143)
		(layer "B.Cu")
		(net "SAS_I2C_B_BUF_SDA_R")
	)
	(segment
		(start 186.78271 -245.90629)
		(end 186.78271 -229.70871)
		(width 0.1143)
		(layer "B.Cu")
		(net "SAS_I2C_B_BUF_SDA_R")
	)
	(segment
		(start 186.69 -229.616)
		(end 186.69 -223.52)
		(width 0.1143)
		(layer "B.Cu")
		(net "SAS_I2C_B_BUF_SDA_R")
	)
	(segment
		(start 185.801 -222.631)
		(end 185.801 -222.123)
		(width 0.1143)
		(layer "B.Cu")
		(net "SAS_I2C_B_BUF_SDA_R")
	)
	(segment
		(start 186.381136 -206.429864)
		(end 186.944 -205.867)
		(width 0.1143)
		(layer "B.Cu")
		(net "SAS_I2C_B_BUF_SDA_R")
	)
	(segment
		(start 186.69 -223.52)
		(end 185.801 -222.631)
		(width 0.1143)
		(layer "B.Cu")
		(net "SAS_I2C_B_BUF_SDA_R")
	)
	(segment
		(start 122.217434 -246.507)
		(end 122.1994 -246.507)
		(width 0.127)
		(layer "In2.Cu")
		(net "SAS_I2C_B_BUF_SDA_R")
	)
	(segment
		(start 172.085 -246.38)
		(end 170.434 -246.38)
		(width 0.127)
		(layer "In2.Cu")
		(net "SAS_I2C_B_BUF_SDA_R")
	)
	(segment
		(start 172.1612 -246.3038)
		(end 172.085 -246.38)
		(width 0.127)
		(layer "In2.Cu")
		(net "SAS_I2C_B_BUF_SDA_R")
	)
	(segment
		(start 121.254774 -247.451626)
		(end 94.83598 -247.451626)
		(width 0.127)
		(layer "In2.Cu")
		(net "SAS_I2C_B_BUF_SDA_R")
	)
	(segment
		(start 186.182 -246.3038)
		(end 172.1612 -246.3038)
		(width 0.127)
		(layer "In2.Cu")
		(net "SAS_I2C_B_BUF_SDA_R")
	)
	(segment
		(start 122.1994 -246.507)
		(end 121.254774 -247.451626)
		(width 0.127)
		(layer "In2.Cu")
		(net "SAS_I2C_B_BUF_SDA_R")
	)
	(segment
		(start 93.7768 -248.510806)
		(end 93.7768 -248.984008)
		(width 0.127)
		(layer "In2.Cu")
		(net "SAS_I2C_B_BUF_SDA_R")
	)
	(segment
		(start 122.979434 -245.745)
		(end 122.217434 -246.507)
		(width 0.127)
		(layer "In2.Cu")
		(net "SAS_I2C_B_BUF_SDA_R")
	)
	(segment
		(start 170.434 -246.38)
		(end 169.799 -245.745)
		(width 0.127)
		(layer "In2.Cu")
		(net "SAS_I2C_B_BUF_SDA_R")
	)
	(segment
		(start 94.83598 -247.451626)
		(end 93.7768 -248.510806)
		(width 0.127)
		(layer "In2.Cu")
		(net "SAS_I2C_B_BUF_SDA_R")
	)
	(segment
		(start 169.799 -245.745)
		(end 122.979434 -245.745)
		(width 0.127)
		(layer "In2.Cu")
		(net "SAS_I2C_B_BUF_SDA_R")
	)
	(segment
		(start 92.192602 -173.755558)
		(end 96.496124 -169.452036)
		(width 0.1016)
		(layer "F.Cu")
		(net "SAS_EXP_GF_TX_DP15")
	)
	(segment
		(start 90.701876 -175.58385)
		(end 90.917268 -175.368458)
		(width 0.1016)
		(layer "F.Cu")
		(net "SAS_EXP_GF_TX_DP15")
	)
	(segment
		(start 91.8083 -174.47768)
		(end 92.023692 -174.262034)
		(width 0.1016)
		(layer "F.Cu")
		(net "SAS_EXP_GF_TX_DP15")
	)
	(segment
		(start 97.386902 -168.561258)
		(end 97.602294 -168.345866)
		(width 0.1016)
		(layer "F.Cu")
		(net "SAS_EXP_GF_TX_DP15")
	)
	(segment
		(start 71.999602 -256.25044)
		(end 71.999602 -254.28194)
		(width 0.1016)
		(layer "F.Cu")
		(net "SAS_EXP_GF_TX_DP15")
	)
	(segment
		(start 99.59975 -166.34841)
		(end 101.56952 -164.37864)
		(width 0.1016)
		(layer "F.Cu")
		(net "SAS_EXP_GF_TX_DP15")
	)
	(segment
		(start 99.215194 -167.070532)
		(end 99.43084 -166.85514)
		(width 0.1016)
		(layer "F.Cu")
		(net "SAS_EXP_GF_TX_DP15")
	)
	(segment
		(start 91.086178 -174.861982)
		(end 91.301824 -174.646336)
		(width 0.1016)
		(layer "F.Cu")
		(net "SAS_EXP_GF_TX_DP15")
	)
	(segment
		(start 72.192642 -245.597172)
		(end 72.74306 -245.046754)
		(width 0.1016)
		(layer "F.Cu")
		(net "SAS_EXP_GF_TX_DP15")
	)
	(segment
		(start 98.493326 -167.454834)
		(end 98.708718 -167.239442)
		(width 0.1016)
		(layer "F.Cu")
		(net "SAS_EXP_GF_TX_DP15")
	)
	(segment
		(start 84.039964 -182.246016)
		(end 84.255356 -182.03037)
		(width 0.1016)
		(layer "F.Cu")
		(net "SAS_EXP_GF_TX_DP15")
	)
	(segment
		(start 71.898002 -254.18034)
		(end 71.773034 -254.18034)
		(width 0.1016)
		(layer "F.Cu")
		(net "SAS_EXP_GF_TX_DP15")
	)
	(segment
		(start 82.93354 -183.35244)
		(end 83.148932 -183.136794)
		(width 0.1016)
		(layer "F.Cu")
		(net "SAS_EXP_GF_TX_DP15")
	)
	(segment
		(start 71.671434 -254.07874)
		(end 71.671434 -246.855488)
		(width 0.1016)
		(layer "F.Cu")
		(net "SAS_EXP_GF_TX_DP15")
	)
	(segment
		(start 98.109024 -168.176956)
		(end 98.324416 -167.96131)
		(width 0.1016)
		(layer "F.Cu")
		(net "SAS_EXP_GF_TX_DP15")
	)
	(segment
		(start 73.85304 -242.367054)
		(end 73.85304 -193.401188)
		(width 0.1016)
		(layer "F.Cu")
		(net "SAS_EXP_GF_TX_DP15")
	)
	(segment
		(start 74.776584 -191.171576)
		(end 82.427064 -183.521096)
		(width 0.1016)
		(layer "F.Cu")
		(net "SAS_EXP_GF_TX_DP15")
	)
	(segment
		(start 97.0026 -169.28338)
		(end 97.217992 -169.067734)
		(width 0.1016)
		(layer "F.Cu")
		(net "SAS_EXP_GF_TX_DP15")
	)
	(segment
		(start 84.424266 -181.523894)
		(end 90.1954 -175.75276)
		(width 0.1016)
		(layer "F.Cu")
		(net "SAS_EXP_GF_TX_DP15")
	)
	(segment
		(start 83.317842 -182.630318)
		(end 83.533488 -182.414672)
		(width 0.1016)
		(layer "F.Cu")
		(net "SAS_EXP_GF_TX_DP15")
	)
	(segment
		(start 102.22992 -162.784282)
		(end 102.22992 -115.02898)
		(width 0.1016)
		(layer "F.Cu")
		(net "SAS_EXP_GF_TX_DP15")
	)
	(arc
		(start 96.496124 -169.452036)
		(mid 96.612449 -169.378976)
		(end 96.749362 -169.367708)
		(width 0.1016)
		(layer "F.Cu")
		(net "SAS_EXP_GF_TX_DP15")
	)
	(arc
		(start 98.324416 -167.96131)
		(mid 98.397476 -167.844985)
		(end 98.408744 -167.708072)
		(width 0.1016)
		(layer "F.Cu")
		(net "SAS_EXP_GF_TX_DP15")
	)
	(arc
		(start 99.515168 -166.601902)
		(mid 99.526455 -166.464807)
		(end 99.59975 -166.34841)
		(width 0.1016)
		(layer "F.Cu")
		(net "SAS_EXP_GF_TX_DP15")
	)
	(arc
		(start 91.555062 -174.562008)
		(mid 91.691987 -174.550778)
		(end 91.8083 -174.47768)
		(width 0.1016)
		(layer "F.Cu")
		(net "SAS_EXP_GF_TX_DP15")
	)
	(arc
		(start 82.680302 -183.436768)
		(mid 82.817227 -183.425538)
		(end 82.93354 -183.35244)
		(width 0.1016)
		(layer "F.Cu")
		(net "SAS_EXP_GF_TX_DP15")
	)
	(arc
		(start 84.339684 -181.777132)
		(mid 84.351048 -181.640184)
		(end 84.424266 -181.523894)
		(width 0.1016)
		(layer "F.Cu")
		(net "SAS_EXP_GF_TX_DP15")
	)
	(arc
		(start 83.148932 -183.136794)
		(mid 83.222155 -183.020506)
		(end 83.233514 -182.883556)
		(width 0.1016)
		(layer "F.Cu")
		(net "SAS_EXP_GF_TX_DP15")
	)
	(arc
		(start 101.56952 -164.37864)
		(mid 102.058237 -163.647128)
		(end 102.22992 -162.784282)
		(width 0.1016)
		(layer "F.Cu")
		(net "SAS_EXP_GF_TX_DP15")
	)
	(arc
		(start 90.917268 -175.368458)
		(mid 90.990491 -175.25217)
		(end 91.00185 -175.11522)
		(width 0.1016)
		(layer "F.Cu")
		(net "SAS_EXP_GF_TX_DP15")
	)
	(arc
		(start 97.602294 -168.345866)
		(mid 97.718701 -168.272603)
		(end 97.855786 -168.261284)
		(width 0.1016)
		(layer "F.Cu")
		(net "SAS_EXP_GF_TX_DP15")
	)
	(arc
		(start 102.22992 -115.02898)
		(mid 102.267346 -114.792624)
		(end 102.37597 -114.5794)
		(width 0.1016)
		(layer "F.Cu")
		(net "SAS_EXP_GF_TX_DP15")
	)
	(arc
		(start 97.855786 -168.261284)
		(mid 97.992711 -168.250054)
		(end 98.109024 -168.176956)
		(width 0.1016)
		(layer "F.Cu")
		(net "SAS_EXP_GF_TX_DP15")
	)
	(arc
		(start 83.233514 -182.883556)
		(mid 83.244744 -182.746631)
		(end 83.317842 -182.630318)
		(width 0.1016)
		(layer "F.Cu")
		(net "SAS_EXP_GF_TX_DP15")
	)
	(arc
		(start 92.108274 -174.008796)
		(mid 92.119504 -173.871871)
		(end 92.192602 -173.755558)
		(width 0.1016)
		(layer "F.Cu")
		(net "SAS_EXP_GF_TX_DP15")
	)
	(arc
		(start 82.427064 -183.521096)
		(mid 82.543389 -183.448036)
		(end 82.680302 -183.436768)
		(width 0.1016)
		(layer "F.Cu")
		(net "SAS_EXP_GF_TX_DP15")
	)
	(arc
		(start 98.408744 -167.708072)
		(mid 98.420108 -167.571124)
		(end 98.493326 -167.454834)
		(width 0.1016)
		(layer "F.Cu")
		(net "SAS_EXP_GF_TX_DP15")
	)
	(arc
		(start 72.74306 -245.046754)
		(mid 73.564557 -243.817297)
		(end 73.85304 -242.367054)
		(width 0.1016)
		(layer "F.Cu")
		(net "SAS_EXP_GF_TX_DP15")
	)
	(arc
		(start 71.999602 -254.28194)
		(mid 71.969844 -254.210098)
		(end 71.898002 -254.18034)
		(width 0.1016)
		(layer "F.Cu")
		(net "SAS_EXP_GF_TX_DP15")
	)
	(arc
		(start 96.749362 -169.367708)
		(mid 96.886287 -169.356478)
		(end 97.0026 -169.28338)
		(width 0.1016)
		(layer "F.Cu")
		(net "SAS_EXP_GF_TX_DP15")
	)
	(arc
		(start 98.708718 -167.239442)
		(mid 98.825006 -167.166219)
		(end 98.961956 -167.15486)
		(width 0.1016)
		(layer "F.Cu")
		(net "SAS_EXP_GF_TX_DP15")
	)
	(arc
		(start 90.1954 -175.75276)
		(mid 90.311725 -175.6797)
		(end 90.448638 -175.668432)
		(width 0.1016)
		(layer "F.Cu")
		(net "SAS_EXP_GF_TX_DP15")
	)
	(arc
		(start 91.00185 -175.11522)
		(mid 91.01308 -174.978295)
		(end 91.086178 -174.861982)
		(width 0.1016)
		(layer "F.Cu")
		(net "SAS_EXP_GF_TX_DP15")
	)
	(arc
		(start 98.961956 -167.15486)
		(mid 99.098881 -167.14363)
		(end 99.215194 -167.070532)
		(width 0.1016)
		(layer "F.Cu")
		(net "SAS_EXP_GF_TX_DP15")
	)
	(arc
		(start 97.217992 -169.067734)
		(mid 97.291215 -168.951446)
		(end 97.302574 -168.814496)
		(width 0.1016)
		(layer "F.Cu")
		(net "SAS_EXP_GF_TX_DP15")
	)
	(arc
		(start 71.773034 -254.18034)
		(mid 71.701192 -254.150582)
		(end 71.671434 -254.07874)
		(width 0.1016)
		(layer "F.Cu")
		(net "SAS_EXP_GF_TX_DP15")
	)
	(arc
		(start 71.671434 -246.855488)
		(mid 71.806892 -246.174494)
		(end 72.192642 -245.597172)
		(width 0.1016)
		(layer "F.Cu")
		(net "SAS_EXP_GF_TX_DP15")
	)
	(arc
		(start 99.43084 -166.85514)
		(mid 99.5039 -166.738815)
		(end 99.515168 -166.601902)
		(width 0.1016)
		(layer "F.Cu")
		(net "SAS_EXP_GF_TX_DP15")
	)
	(arc
		(start 73.85304 -193.401188)
		(mid 74.09306 -192.194527)
		(end 74.776584 -191.171576)
		(width 0.1016)
		(layer "F.Cu")
		(net "SAS_EXP_GF_TX_DP15")
	)
	(arc
		(start 90.448638 -175.668432)
		(mid 90.585586 -175.657068)
		(end 90.701876 -175.58385)
		(width 0.1016)
		(layer "F.Cu")
		(net "SAS_EXP_GF_TX_DP15")
	)
	(arc
		(start 83.533488 -182.414672)
		(mid 83.649813 -182.341612)
		(end 83.786726 -182.330344)
		(width 0.1016)
		(layer "F.Cu")
		(net "SAS_EXP_GF_TX_DP15")
	)
	(arc
		(start 84.255356 -182.03037)
		(mid 84.328416 -181.914045)
		(end 84.339684 -181.777132)
		(width 0.1016)
		(layer "F.Cu")
		(net "SAS_EXP_GF_TX_DP15")
	)
	(arc
		(start 83.786726 -182.330344)
		(mid 83.923651 -182.319114)
		(end 84.039964 -182.246016)
		(width 0.1016)
		(layer "F.Cu")
		(net "SAS_EXP_GF_TX_DP15")
	)
	(arc
		(start 97.302574 -168.814496)
		(mid 97.313804 -168.677571)
		(end 97.386902 -168.561258)
		(width 0.1016)
		(layer "F.Cu")
		(net "SAS_EXP_GF_TX_DP15")
	)
	(arc
		(start 92.023692 -174.262034)
		(mid 92.096915 -174.145746)
		(end 92.108274 -174.008796)
		(width 0.1016)
		(layer "F.Cu")
		(net "SAS_EXP_GF_TX_DP15")
	)
	(arc
		(start 91.301824 -174.646336)
		(mid 91.418149 -174.573276)
		(end 91.555062 -174.562008)
		(width 0.1016)
		(layer "F.Cu")
		(net "SAS_EXP_GF_TX_DP15")
	)
	(segment
		(start 125.886972 -245.592092)
		(end 125.886972 -245.287292)
		(width 0.1016)
		(layer "F.Cu")
		(net "SAS_EXP_GF_TX_DP5")
	)
	(segment
		(start 128.77165 -230.152956)
		(end 128.988566 -229.935786)
		(width 0.1016)
		(layer "F.Cu")
		(net "SAS_EXP_GF_TX_DP5")
	)
	(segment
		(start 125.648212 -247.839738)
		(end 125.648212 -246.069612)
		(width 0.1016)
		(layer "F.Cu")
		(net "SAS_EXP_GF_TX_DP5")
	)
	(segment
		(start 125.886972 -242.462812)
		(end 125.886972 -242.158012)
		(width 0.1016)
		(layer "F.Cu")
		(net "SAS_EXP_GF_TX_DP5")
	)
	(segment
		(start 133.961124 -221.616778)
		(end 133.961124 -176.572926)
		(width 0.1016)
		(layer "F.Cu")
		(net "SAS_EXP_GF_TX_DP5")
	)
	(segment
		(start 125.648212 -243.245132)
		(end 125.648212 -242.940332)
		(width 0.1016)
		(layer "F.Cu")
		(net "SAS_EXP_GF_TX_DP5")
	)
	(segment
		(start 125.886972 -244.027452)
		(end 125.886972 -243.722652)
		(width 0.1016)
		(layer "F.Cu")
		(net "SAS_EXP_GF_TX_DP5")
	)
	(segment
		(start 126.000002 -256.25044)
		(end 126.000002 -254.258064)
		(width 0.1016)
		(layer "F.Cu")
		(net "SAS_EXP_GF_TX_DP5")
	)
	(segment
		(start 125.648212 -253.738126)
		(end 125.648212 -252.228858)
		(width 0.1016)
		(layer "F.Cu")
		(net "SAS_EXP_GF_TX_DP5")
	)
	(segment
		(start 120.00992 -160.086294)
		(end 120.00992 -114.772186)
		(width 0.1016)
		(layer "F.Cu")
		(net "SAS_EXP_GF_TX_DP5")
	)
	(segment
		(start 125.886972 -250.186698)
		(end 125.886972 -249.881898)
		(width 0.1016)
		(layer "F.Cu")
		(net "SAS_EXP_GF_TX_DP5")
	)
	(segment
		(start 125.648212 -241.680492)
		(end 125.648212 -237.6932)
		(width 0.1016)
		(layer "F.Cu")
		(net "SAS_EXP_GF_TX_DP5")
	)
	(segment
		(start 125.648212 -249.404378)
		(end 125.648212 -249.099578)
		(width 0.1016)
		(layer "F.Cu")
		(net "SAS_EXP_GF_TX_DP5")
	)
	(segment
		(start 125.940566 -254.114554)
		(end 125.707648 -253.881636)
		(width 0.1016)
		(layer "F.Cu")
		(net "SAS_EXP_GF_TX_DP5")
	)
	(segment
		(start 132.672836 -173.462696)
		(end 120.663208 -161.453068)
		(width 0.1016)
		(layer "F.Cu")
		(net "SAS_EXP_GF_TX_DP5")
	)
	(segment
		(start 120.663208 -161.453068)
		(end 120.514364 -161.304478)
		(width 0.1016)
		(layer "F.Cu")
		(net "SAS_EXP_GF_TX_DP5")
	)
	(segment
		(start 125.648212 -244.809772)
		(end 125.648212 -244.504972)
		(width 0.1016)
		(layer "F.Cu")
		(net "SAS_EXP_GF_TX_DP5")
	)
	(segment
		(start 125.886972 -248.622058)
		(end 125.886972 -248.317258)
		(width 0.1016)
		(layer "F.Cu")
		(net "SAS_EXP_GF_TX_DP5")
	)
	(segment
		(start 120.14073 -114.5794)
		(end 120.15597 -114.5794)
		(width 0.1016)
		(layer "F.Cu")
		(net "SAS_EXP_GF_TX_DP5")
	)
	(segment
		(start 120.025414 -114.694462)
		(end 120.047004 -114.642138)
		(width 0.1016)
		(layer "F.Cu")
		(net "SAS_EXP_GF_TX_DP5")
	)
	(segment
		(start 125.648212 -250.969018)
		(end 125.648212 -250.664218)
		(width 0.1016)
		(layer "F.Cu")
		(net "SAS_EXP_GF_TX_DP5")
	)
	(segment
		(start 128.988566 -229.935786)
		(end 131.59486 -227.329492)
		(width 0.1016)
		(layer "F.Cu")
		(net "SAS_EXP_GF_TX_DP5")
	)
	(segment
		(start 125.886972 -251.751338)
		(end 125.886972 -251.446538)
		(width 0.1016)
		(layer "F.Cu")
		(net "SAS_EXP_GF_TX_DP5")
	)
	(arc
		(start 125.648212 -242.940332)
		(mid 125.678704 -242.806339)
		(end 125.767592 -242.701572)
		(width 0.1016)
		(layer "F.Cu")
		(net "SAS_EXP_GF_TX_DP5")
	)
	(arc
		(start 125.767592 -245.048532)
		(mid 125.678798 -244.943718)
		(end 125.648212 -244.809772)
		(width 0.1016)
		(layer "F.Cu")
		(net "SAS_EXP_GF_TX_DP5")
	)
	(arc
		(start 125.767592 -249.643138)
		(mid 125.678798 -249.538324)
		(end 125.648212 -249.404378)
		(width 0.1016)
		(layer "F.Cu")
		(net "SAS_EXP_GF_TX_DP5")
	)
	(arc
		(start 125.767592 -244.266212)
		(mid 125.856386 -244.161398)
		(end 125.886972 -244.027452)
		(width 0.1016)
		(layer "F.Cu")
		(net "SAS_EXP_GF_TX_DP5")
	)
	(arc
		(start 125.648212 -237.6932)
		(mid 126.460019 -233.612439)
		(end 128.77165 -230.152956)
		(width 0.1016)
		(layer "F.Cu")
		(net "SAS_EXP_GF_TX_DP5")
	)
	(arc
		(start 125.648212 -252.228858)
		(mid 125.678704 -252.094865)
		(end 125.767592 -251.990098)
		(width 0.1016)
		(layer "F.Cu")
		(net "SAS_EXP_GF_TX_DP5")
	)
	(arc
		(start 120.514364 -161.304478)
		(mid 120.140997 -160.745555)
		(end 120.00992 -160.086294)
		(width 0.1016)
		(layer "F.Cu")
		(net "SAS_EXP_GF_TX_DP5")
	)
	(arc
		(start 125.767592 -243.483892)
		(mid 125.678798 -243.379078)
		(end 125.648212 -243.245132)
		(width 0.1016)
		(layer "F.Cu")
		(net "SAS_EXP_GF_TX_DP5")
	)
	(arc
		(start 125.767592 -248.078498)
		(mid 125.678798 -247.973684)
		(end 125.648212 -247.839738)
		(width 0.1016)
		(layer "F.Cu")
		(net "SAS_EXP_GF_TX_DP5")
	)
	(arc
		(start 125.886972 -249.881898)
		(mid 125.85648 -249.747905)
		(end 125.767592 -249.643138)
		(width 0.1016)
		(layer "F.Cu")
		(net "SAS_EXP_GF_TX_DP5")
	)
	(arc
		(start 125.886972 -245.287292)
		(mid 125.85648 -245.153299)
		(end 125.767592 -245.048532)
		(width 0.1016)
		(layer "F.Cu")
		(net "SAS_EXP_GF_TX_DP5")
	)
	(arc
		(start 125.767592 -245.830852)
		(mid 125.856386 -245.726038)
		(end 125.886972 -245.592092)
		(width 0.1016)
		(layer "F.Cu")
		(net "SAS_EXP_GF_TX_DP5")
	)
	(arc
		(start 125.886972 -242.158012)
		(mid 125.85648 -242.024019)
		(end 125.767592 -241.919252)
		(width 0.1016)
		(layer "F.Cu")
		(net "SAS_EXP_GF_TX_DP5")
	)
	(arc
		(start 120.00992 -114.772186)
		(mid 120.013822 -114.732556)
		(end 120.025414 -114.694462)
		(width 0.1016)
		(layer "F.Cu")
		(net "SAS_EXP_GF_TX_DP5")
	)
	(arc
		(start 125.707648 -253.881636)
		(mid 125.663653 -253.815793)
		(end 125.648212 -253.738126)
		(width 0.1016)
		(layer "F.Cu")
		(net "SAS_EXP_GF_TX_DP5")
	)
	(arc
		(start 125.767592 -248.860818)
		(mid 125.856386 -248.756004)
		(end 125.886972 -248.622058)
		(width 0.1016)
		(layer "F.Cu")
		(net "SAS_EXP_GF_TX_DP5")
	)
	(arc
		(start 133.961124 -176.572926)
		(mid 133.626322 -174.889672)
		(end 132.672836 -173.462696)
		(width 0.1016)
		(layer "F.Cu")
		(net "SAS_EXP_GF_TX_DP5")
	)
	(arc
		(start 126.000002 -254.258064)
		(mid 125.984554 -254.1804)
		(end 125.940566 -254.114554)
		(width 0.1016)
		(layer "F.Cu")
		(net "SAS_EXP_GF_TX_DP5")
	)
	(arc
		(start 120.047004 -114.642138)
		(mid 120.084353 -114.596529)
		(end 120.14073 -114.5794)
		(width 0.1016)
		(layer "F.Cu")
		(net "SAS_EXP_GF_TX_DP5")
	)
	(arc
		(start 125.648212 -250.664218)
		(mid 125.678704 -250.530225)
		(end 125.767592 -250.425458)
		(width 0.1016)
		(layer "F.Cu")
		(net "SAS_EXP_GF_TX_DP5")
	)
	(arc
		(start 125.767592 -250.425458)
		(mid 125.856386 -250.320644)
		(end 125.886972 -250.186698)
		(width 0.1016)
		(layer "F.Cu")
		(net "SAS_EXP_GF_TX_DP5")
	)
	(arc
		(start 125.648212 -244.504972)
		(mid 125.678704 -244.370979)
		(end 125.767592 -244.266212)
		(width 0.1016)
		(layer "F.Cu")
		(net "SAS_EXP_GF_TX_DP5")
	)
	(arc
		(start 125.767592 -251.990098)
		(mid 125.856386 -251.885284)
		(end 125.886972 -251.751338)
		(width 0.1016)
		(layer "F.Cu")
		(net "SAS_EXP_GF_TX_DP5")
	)
	(arc
		(start 131.59486 -227.329492)
		(mid 133.346113 -224.708462)
		(end 133.961124 -221.616778)
		(width 0.1016)
		(layer "F.Cu")
		(net "SAS_EXP_GF_TX_DP5")
	)
	(arc
		(start 125.886972 -243.722652)
		(mid 125.85648 -243.588659)
		(end 125.767592 -243.483892)
		(width 0.1016)
		(layer "F.Cu")
		(net "SAS_EXP_GF_TX_DP5")
	)
	(arc
		(start 125.886972 -248.317258)
		(mid 125.85648 -248.183265)
		(end 125.767592 -248.078498)
		(width 0.1016)
		(layer "F.Cu")
		(net "SAS_EXP_GF_TX_DP5")
	)
	(arc
		(start 125.648212 -246.069612)
		(mid 125.678704 -245.935619)
		(end 125.767592 -245.830852)
		(width 0.1016)
		(layer "F.Cu")
		(net "SAS_EXP_GF_TX_DP5")
	)
	(arc
		(start 125.648212 -249.099578)
		(mid 125.678704 -248.965585)
		(end 125.767592 -248.860818)
		(width 0.1016)
		(layer "F.Cu")
		(net "SAS_EXP_GF_TX_DP5")
	)
	(arc
		(start 125.767592 -241.919252)
		(mid 125.678798 -241.814438)
		(end 125.648212 -241.680492)
		(width 0.1016)
		(layer "F.Cu")
		(net "SAS_EXP_GF_TX_DP5")
	)
	(arc
		(start 125.767592 -251.207778)
		(mid 125.678798 -251.102964)
		(end 125.648212 -250.969018)
		(width 0.1016)
		(layer "F.Cu")
		(net "SAS_EXP_GF_TX_DP5")
	)
	(arc
		(start 125.886972 -251.446538)
		(mid 125.85648 -251.312545)
		(end 125.767592 -251.207778)
		(width 0.1016)
		(layer "F.Cu")
		(net "SAS_EXP_GF_TX_DP5")
	)
	(arc
		(start 125.767592 -242.701572)
		(mid 125.856386 -242.596758)
		(end 125.886972 -242.462812)
		(width 0.1016)
		(layer "F.Cu")
		(net "SAS_EXP_GF_TX_DP5")
	)
	(segment
		(start 117.350032 -103.35006)
		(end 117.850158 -103.850186)
		(width 0.1016)
		(layer "F.Cu")
		(net "SAS_GF_EXP_RX_DP5")
	)
	(via
		(at 117.850158 -103.850186)
		(size 0.508)
		(drill 0.254)
		(layers "F.Cu" "B.Cu")
		(net "SAS_GF_EXP_RX_DP5")
	)
	(segment
		(start 133.244844 -213.012782)
		(end 133.244844 -212.707982)
		(width 0.1016)
		(layer "B.Cu")
		(net "SAS_GF_EXP_RX_DP5")
	)
	(segment
		(start 133.006084 -209.101182)
		(end 133.006084 -170.433746)
		(width 0.1016)
		(layer "B.Cu")
		(net "SAS_GF_EXP_RX_DP5")
	)
	(segment
		(start 127.944372 -245.280942)
		(end 127.944372 -244.976142)
		(width 0.1016)
		(layer "B.Cu")
		(net "SAS_GF_EXP_RX_DP5")
	)
	(segment
		(start 133.006084 -213.795102)
		(end 133.006084 -213.490302)
		(width 0.1016)
		(layer "B.Cu")
		(net "SAS_GF_EXP_RX_DP5")
	)
	(segment
		(start 128.000252 -256.50444)
		(end 128.000252 -254.45212)
		(width 0.1016)
		(layer "B.Cu")
		(net "SAS_GF_EXP_RX_DP5")
	)
	(segment
		(start 127.944372 -248.410222)
		(end 127.944372 -248.105422)
		(width 0.1016)
		(layer "B.Cu")
		(net "SAS_GF_EXP_RX_DP5")
	)
	(segment
		(start 133.006084 -212.230462)
		(end 133.006084 -211.925662)
		(width 0.1016)
		(layer "B.Cu")
		(net "SAS_GF_EXP_RX_DP5")
	)
	(segment
		(start 133.244844 -214.577422)
		(end 133.244844 -214.272622)
		(width 0.1016)
		(layer "B.Cu")
		(net "SAS_GF_EXP_RX_DP5")
	)
	(segment
		(start 133.006084 -228.910388)
		(end 133.006084 -215.054942)
		(width 0.1016)
		(layer "B.Cu")
		(net "SAS_GF_EXP_RX_DP5")
	)
	(segment
		(start 128.854454 -234.676696)
		(end 131.864354 -231.666796)
		(width 0.1016)
		(layer "B.Cu")
		(net "SAS_GF_EXP_RX_DP5")
	)
	(segment
		(start 127.944372 -246.845582)
		(end 127.944372 -246.540782)
		(width 0.1016)
		(layer "B.Cu")
		(net "SAS_GF_EXP_RX_DP5")
	)
	(segment
		(start 127.705612 -244.498622)
		(end 127.705612 -237.450122)
		(width 0.1016)
		(layer "B.Cu")
		(net "SAS_GF_EXP_RX_DP5")
	)
	(segment
		(start 127.705612 -247.627902)
		(end 127.705612 -247.323102)
		(width 0.1016)
		(layer "B.Cu")
		(net "SAS_GF_EXP_RX_DP5")
	)
	(segment
		(start 132.341366 -168.903396)
		(end 123.15317 -159.7152)
		(width 0.1016)
		(layer "B.Cu")
		(net "SAS_GF_EXP_RX_DP5")
	)
	(segment
		(start 121.42597 -155.545282)
		(end 121.42597 -114.353594)
		(width 0.1016)
		(layer "B.Cu")
		(net "SAS_GF_EXP_RX_DP5")
	)
	(segment
		(start 117.738144 -109.48924)
		(end 117.738144 -104.120696)
		(width 0.1016)
		(layer "B.Cu")
		(net "SAS_GF_EXP_RX_DP5")
	)
	(segment
		(start 120.780556 -112.794796)
		(end 117.924072 -109.938058)
		(width 0.1016)
		(layer "B.Cu")
		(net "SAS_GF_EXP_RX_DP5")
	)
	(segment
		(start 132.394198 -168.956482)
		(end 132.341366 -168.903396)
		(width 0.1016)
		(layer "B.Cu")
		(net "SAS_GF_EXP_RX_DP5")
	)
	(segment
		(start 133.006084 -210.665822)
		(end 133.006084 -210.361022)
		(width 0.1016)
		(layer "B.Cu")
		(net "SAS_GF_EXP_RX_DP5")
	)
	(segment
		(start 133.244844 -211.448142)
		(end 133.244844 -211.143342)
		(width 0.1016)
		(layer "B.Cu")
		(net "SAS_GF_EXP_RX_DP5")
	)
	(segment
		(start 127.705612 -246.063262)
		(end 127.705612 -245.758462)
		(width 0.1016)
		(layer "B.Cu")
		(net "SAS_GF_EXP_RX_DP5")
	)
	(segment
		(start 127.705612 -253.74092)
		(end 127.705612 -248.887742)
		(width 0.1016)
		(layer "B.Cu")
		(net "SAS_GF_EXP_RX_DP5")
	)
	(segment
		(start 133.244844 -209.883502)
		(end 133.244844 -209.578702)
		(width 0.1016)
		(layer "B.Cu")
		(net "SAS_GF_EXP_RX_DP5")
	)
	(arc
		(start 127.705612 -237.450122)
		(mid 128.004177 -235.949135)
		(end 128.854454 -234.676696)
		(width 0.1016)
		(layer "B.Cu")
		(net "SAS_GF_EXP_RX_DP5")
	)
	(arc
		(start 133.244844 -214.272622)
		(mid 133.214352 -214.138629)
		(end 133.125464 -214.033862)
		(width 0.1016)
		(layer "B.Cu")
		(net "SAS_GF_EXP_RX_DP5")
	)
	(arc
		(start 127.705612 -245.758462)
		(mid 127.736198 -245.624544)
		(end 127.824992 -245.519702)
		(width 0.1016)
		(layer "B.Cu")
		(net "SAS_GF_EXP_RX_DP5")
	)
	(arc
		(start 117.738144 -104.120696)
		(mid 117.767262 -103.97431)
		(end 117.850158 -103.850186)
		(width 0.1016)
		(layer "B.Cu")
		(net "SAS_GF_EXP_RX_DP5")
	)
	(arc
		(start 121.42597 -114.353594)
		(mid 121.258335 -113.509985)
		(end 120.780556 -112.794796)
		(width 0.1016)
		(layer "B.Cu")
		(net "SAS_GF_EXP_RX_DP5")
	)
	(arc
		(start 127.824992 -244.737382)
		(mid 127.736198 -244.632568)
		(end 127.705612 -244.498622)
		(width 0.1016)
		(layer "B.Cu")
		(net "SAS_GF_EXP_RX_DP5")
	)
	(arc
		(start 133.125464 -212.469222)
		(mid 133.03667 -212.364408)
		(end 133.006084 -212.230462)
		(width 0.1016)
		(layer "B.Cu")
		(net "SAS_GF_EXP_RX_DP5")
	)
	(arc
		(start 133.244844 -209.578702)
		(mid 133.214352 -209.444709)
		(end 133.125464 -209.339942)
		(width 0.1016)
		(layer "B.Cu")
		(net "SAS_GF_EXP_RX_DP5")
	)
	(arc
		(start 133.006084 -210.361022)
		(mid 133.036576 -210.227029)
		(end 133.125464 -210.122262)
		(width 0.1016)
		(layer "B.Cu")
		(net "SAS_GF_EXP_RX_DP5")
	)
	(arc
		(start 133.125464 -209.339942)
		(mid 133.03667 -209.235128)
		(end 133.006084 -209.101182)
		(width 0.1016)
		(layer "B.Cu")
		(net "SAS_GF_EXP_RX_DP5")
	)
	(arc
		(start 117.924072 -109.938058)
		(mid 117.786452 -109.732139)
		(end 117.738144 -109.48924)
		(width 0.1016)
		(layer "B.Cu")
		(net "SAS_GF_EXP_RX_DP5")
	)
	(arc
		(start 127.944372 -248.105422)
		(mid 127.913786 -247.971504)
		(end 127.824992 -247.866662)
		(width 0.1016)
		(layer "B.Cu")
		(net "SAS_GF_EXP_RX_DP5")
	)
	(arc
		(start 133.244844 -212.707982)
		(mid 133.214352 -212.573989)
		(end 133.125464 -212.469222)
		(width 0.1016)
		(layer "B.Cu")
		(net "SAS_GF_EXP_RX_DP5")
	)
	(arc
		(start 133.244844 -211.143342)
		(mid 133.214352 -211.009349)
		(end 133.125464 -210.904582)
		(width 0.1016)
		(layer "B.Cu")
		(net "SAS_GF_EXP_RX_DP5")
	)
	(arc
		(start 133.125464 -214.816182)
		(mid 133.214258 -214.711368)
		(end 133.244844 -214.577422)
		(width 0.1016)
		(layer "B.Cu")
		(net "SAS_GF_EXP_RX_DP5")
	)
	(arc
		(start 133.125464 -213.251542)
		(mid 133.214258 -213.146728)
		(end 133.244844 -213.012782)
		(width 0.1016)
		(layer "B.Cu")
		(net "SAS_GF_EXP_RX_DP5")
	)
	(arc
		(start 133.125464 -210.122262)
		(mid 133.214258 -210.017448)
		(end 133.244844 -209.883502)
		(width 0.1016)
		(layer "B.Cu")
		(net "SAS_GF_EXP_RX_DP5")
	)
	(arc
		(start 127.852932 -254.09652)
		(mid 127.743918 -253.933369)
		(end 127.705612 -253.74092)
		(width 0.1016)
		(layer "B.Cu")
		(net "SAS_GF_EXP_RX_DP5")
	)
	(arc
		(start 133.125464 -214.033862)
		(mid 133.03667 -213.929048)
		(end 133.006084 -213.795102)
		(width 0.1016)
		(layer "B.Cu")
		(net "SAS_GF_EXP_RX_DP5")
	)
	(arc
		(start 127.705612 -248.887742)
		(mid 127.736198 -248.753824)
		(end 127.824992 -248.648982)
		(width 0.1016)
		(layer "B.Cu")
		(net "SAS_GF_EXP_RX_DP5")
	)
	(arc
		(start 123.15317 -159.7152)
		(mid 121.874828 -157.802025)
		(end 121.42597 -155.545282)
		(width 0.1016)
		(layer "B.Cu")
		(net "SAS_GF_EXP_RX_DP5")
	)
	(arc
		(start 127.944372 -246.540782)
		(mid 127.913786 -246.406864)
		(end 127.824992 -246.302022)
		(width 0.1016)
		(layer "B.Cu")
		(net "SAS_GF_EXP_RX_DP5")
	)
	(arc
		(start 133.006084 -211.925662)
		(mid 133.036576 -211.791669)
		(end 133.125464 -211.686902)
		(width 0.1016)
		(layer "B.Cu")
		(net "SAS_GF_EXP_RX_DP5")
	)
	(arc
		(start 133.006084 -215.054942)
		(mid 133.036576 -214.920949)
		(end 133.125464 -214.816182)
		(width 0.1016)
		(layer "B.Cu")
		(net "SAS_GF_EXP_RX_DP5")
	)
	(arc
		(start 127.824992 -245.519702)
		(mid 127.913786 -245.414888)
		(end 127.944372 -245.280942)
		(width 0.1016)
		(layer "B.Cu")
		(net "SAS_GF_EXP_RX_DP5")
	)
	(arc
		(start 133.006084 -213.490302)
		(mid 133.036576 -213.356309)
		(end 133.125464 -213.251542)
		(width 0.1016)
		(layer "B.Cu")
		(net "SAS_GF_EXP_RX_DP5")
	)
	(arc
		(start 133.125464 -210.904582)
		(mid 133.03667 -210.799768)
		(end 133.006084 -210.665822)
		(width 0.1016)
		(layer "B.Cu")
		(net "SAS_GF_EXP_RX_DP5")
	)
	(arc
		(start 131.864354 -231.666796)
		(mid 132.709313 -230.402131)
		(end 133.006084 -228.910388)
		(width 0.1016)
		(layer "B.Cu")
		(net "SAS_GF_EXP_RX_DP5")
	)
	(arc
		(start 127.824992 -246.302022)
		(mid 127.736198 -246.197208)
		(end 127.705612 -246.063262)
		(width 0.1016)
		(layer "B.Cu")
		(net "SAS_GF_EXP_RX_DP5")
	)
	(arc
		(start 127.944372 -244.976142)
		(mid 127.913786 -244.842224)
		(end 127.824992 -244.737382)
		(width 0.1016)
		(layer "B.Cu")
		(net "SAS_GF_EXP_RX_DP5")
	)
	(arc
		(start 127.824992 -248.648982)
		(mid 127.913786 -248.544168)
		(end 127.944372 -248.410222)
		(width 0.1016)
		(layer "B.Cu")
		(net "SAS_GF_EXP_RX_DP5")
	)
	(arc
		(start 133.125464 -211.686902)
		(mid 133.214258 -211.582088)
		(end 133.244844 -211.448142)
		(width 0.1016)
		(layer "B.Cu")
		(net "SAS_GF_EXP_RX_DP5")
	)
	(arc
		(start 127.824992 -247.866662)
		(mid 127.736198 -247.761848)
		(end 127.705612 -247.627902)
		(width 0.1016)
		(layer "B.Cu")
		(net "SAS_GF_EXP_RX_DP5")
	)
	(arc
		(start 127.705612 -247.323102)
		(mid 127.736198 -247.189184)
		(end 127.824992 -247.084342)
		(width 0.1016)
		(layer "B.Cu")
		(net "SAS_GF_EXP_RX_DP5")
	)
	(arc
		(start 127.824992 -247.084342)
		(mid 127.913786 -246.979528)
		(end 127.944372 -246.845582)
		(width 0.1016)
		(layer "B.Cu")
		(net "SAS_GF_EXP_RX_DP5")
	)
	(arc
		(start 128.000252 -254.45212)
		(mid 127.961969 -254.259661)
		(end 127.852932 -254.09652)
		(width 0.1016)
		(layer "B.Cu")
		(net "SAS_GF_EXP_RX_DP5")
	)
	(arc
		(start 133.006084 -170.433746)
		(mid 132.847019 -169.634274)
		(end 132.394198 -168.956482)
		(width 0.1016)
		(layer "B.Cu")
		(net "SAS_GF_EXP_RX_DP5")
	)
	(segment
		(start 292.443154 -169.44848)
		(end 292.433756 -169.44848)
		(width 0.1143)
		(layer "F.Cu")
		(net "RMII0_BMC_C_PHY_TXD1")
	)
	(segment
		(start 292.834822 -169.840148)
		(end 292.443154 -169.44848)
		(width 0.1143)
		(layer "F.Cu")
		(net "RMII0_BMC_C_PHY_TXD1")
	)
	(segment
		(start 292.433756 -169.44848)
		(end 292.425628 -169.440352)
		(width 0.1143)
		(layer "F.Cu")
		(net "RMII0_BMC_C_PHY_TXD1")
	)
	(via
		(at 292.425628 -169.440352)
		(size 0.508)
		(drill 0.254)
		(layers "F.Cu" "B.Cu")
		(net "RMII0_BMC_C_PHY_TXD1")
	)
	(via
		(at 292.354 -166.751)
		(size 0.7112)
		(drill 0.3556)
		(layers "F.Cu" "B.Cu")
		(net "RMII0_BMC_C_PHY_TXD1")
	)
	(segment
		(start 292.354 -166.751)
		(end 292.354 -167.132)
		(width 0.1143)
		(layer "B.Cu")
		(net "RMII0_BMC_C_PHY_TXD1")
	)
	(segment
		(start 292.56355 -169.104056)
		(end 292.56355 -169.30243)
		(width 0.1143)
		(layer "B.Cu")
		(net "RMII0_BMC_C_PHY_TXD1")
	)
	(segment
		(start 292.862 -167.64)
		(end 292.862 -168.805606)
		(width 0.1143)
		(layer "B.Cu")
		(net "RMII0_BMC_C_PHY_TXD1")
	)
	(segment
		(start 292.354 -167.132)
		(end 292.862 -167.64)
		(width 0.1143)
		(layer "B.Cu")
		(net "RMII0_BMC_C_PHY_TXD1")
	)
	(segment
		(start 292.354 -165.1635)
		(end 292.354 -166.751)
		(width 0.1143)
		(layer "B.Cu")
		(net "RMII0_BMC_C_PHY_TXD1")
	)
	(segment
		(start 292.862 -168.805606)
		(end 292.56355 -169.104056)
		(width 0.1143)
		(layer "B.Cu")
		(net "RMII0_BMC_C_PHY_TXD1")
	)
	(segment
		(start 292.56355 -169.30243)
		(end 292.425628 -169.440352)
		(width 0.1143)
		(layer "B.Cu")
		(net "RMII0_BMC_C_PHY_TXD1")
	)
	(segment
		(start 292.862 -164.6555)
		(end 292.354 -165.1635)
		(width 0.1143)
		(layer "B.Cu")
		(net "RMII0_BMC_C_PHY_TXD1")
	)
	(segment
		(start 91.524582 -137.209276)
		(end 91.524582 -138.260582)
		(width 0.1143)
		(layer "F.Cu")
		(net "PEER_1B_2B_HB")
	)
	(segment
		(start 91.524582 -138.260582)
		(end 92.075 -138.811)
		(width 0.1143)
		(layer "F.Cu")
		(net "PEER_1B_2B_HB")
	)
	(segment
		(start 92.075 -138.811)
		(end 92.075 -143.65097)
		(width 0.1143)
		(layer "F.Cu")
		(net "PEER_1B_2B_HB")
	)
	(segment
		(start 89.3826 -146.34337)
		(end 89.3826 -165.348412)
		(width 0.1143)
		(layer "F.Cu")
		(net "PEER_1B_2B_HB")
	)
	(segment
		(start 92.075 -143.65097)
		(end 89.3826 -146.34337)
		(width 0.1143)
		(layer "F.Cu")
		(net "PEER_1B_2B_HB")
	)
	(segment
		(start 89.3826 -165.348412)
		(end 88.9 -165.831012)
		(width 0.1143)
		(layer "F.Cu")
		(net "PEER_1B_2B_HB")
	)
	(via
		(at 88.9 -165.831012)
		(size 0.5588)
		(drill 0.3048)
		(layers "F.Cu" "B.Cu")
		(net "PEER_1B_2B_HB")
	)
	(via
		(at 312.293 -186.8678)
		(size 0.7112)
		(drill 0.3556)
		(layers "F.Cu" "B.Cu")
		(net "PEER_1B_2B_HB")
	)
	(via
		(at 312.928 -187.452)
		(size 0.5588)
		(drill 0.3048)
		(layers "F.Cu" "B.Cu")
		(net "PEER_1B_2B_HB")
	)
	(segment
		(start 71.755 -251.512324)
		(end 71.755 -220.98)
		(width 0.1143)
		(layer "B.Cu")
		(net "PEER_1B_2B_HB")
	)
	(segment
		(start 311.3405 -186.817)
		(end 312.2422 -186.817)
		(width 0.1143)
		(layer "B.Cu")
		(net "PEER_1B_2B_HB")
	)
	(segment
		(start 71.000112 -256.50444)
		(end 71.000112 -252.267212)
		(width 0.1143)
		(layer "B.Cu")
		(net "PEER_1B_2B_HB")
	)
	(segment
		(start 83.49615 -209.23885)
		(end 83.49615 -171.234862)
		(width 0.1143)
		(layer "B.Cu")
		(net "PEER_1B_2B_HB")
	)
	(segment
		(start 71.000112 -252.267212)
		(end 71.755 -251.512324)
		(width 0.1143)
		(layer "B.Cu")
		(net "PEER_1B_2B_HB")
	)
	(segment
		(start 312.2422 -186.817)
		(end 312.293 -186.8678)
		(width 0.1143)
		(layer "B.Cu")
		(net "PEER_1B_2B_HB")
	)
	(segment
		(start 83.49615 -171.234862)
		(end 88.9 -165.831012)
		(width 0.1143)
		(layer "B.Cu")
		(net "PEER_1B_2B_HB")
	)
	(segment
		(start 312.928 -187.452)
		(end 312.8772 -187.452)
		(width 0.1143)
		(layer "B.Cu")
		(net "PEER_1B_2B_HB")
	)
	(segment
		(start 312.8772 -187.452)
		(end 312.293 -186.8678)
		(width 0.1143)
		(layer "B.Cu")
		(net "PEER_1B_2B_HB")
	)
	(segment
		(start 71.755 -220.98)
		(end 83.49615 -209.23885)
		(width 0.1143)
		(layer "B.Cu")
		(net "PEER_1B_2B_HB")
	)
	(segment
		(start 99.251262 -171.165012)
		(end 164.74948 -171.165012)
		(width 0.127)
		(layer "In2.Cu")
		(net "PEER_1B_2B_HB")
	)
	(segment
		(start 207.391254 -175.8823)
		(end 220.042232 -175.8823)
		(width 0.127)
		(layer "In2.Cu")
		(net "PEER_1B_2B_HB")
	)
	(segment
		(start 250.707398 -176.784)
		(end 264.649712 -190.726314)
		(width 0.127)
		(layer "In2.Cu")
		(net "PEER_1B_2B_HB")
	)
	(segment
		(start 175.719232 -179.4383)
		(end 176.214532 -178.943)
		(width 0.127)
		(layer "In2.Cu")
		(net "PEER_1B_2B_HB")
	)
	(segment
		(start 91.917012 -165.831012)
		(end 95.2373 -169.1513)
		(width 0.127)
		(layer "In2.Cu")
		(net "PEER_1B_2B_HB")
	)
	(segment
		(start 203.073254 -180.2003)
		(end 207.391254 -175.8823)
		(width 0.127)
		(layer "In2.Cu")
		(net "PEER_1B_2B_HB")
	)
	(segment
		(start 164.74948 -171.165012)
		(end 173.022768 -179.4383)
		(width 0.127)
		(layer "In2.Cu")
		(net "PEER_1B_2B_HB")
	)
	(segment
		(start 264.649712 -190.726314)
		(end 264.649712 -197.33641)
		(width 0.127)
		(layer "In2.Cu")
		(net "PEER_1B_2B_HB")
	)
	(segment
		(start 197.104 -178.943)
		(end 198.3613 -180.2003)
		(width 0.127)
		(layer "In2.Cu")
		(net "PEER_1B_2B_HB")
	)
	(segment
		(start 264.649712 -197.33641)
		(end 274.564602 -207.2513)
		(width 0.127)
		(layer "In2.Cu")
		(net "PEER_1B_2B_HB")
	)
	(segment
		(start 313.9313 -188.4553)
		(end 312.928 -187.452)
		(width 0.127)
		(layer "In2.Cu")
		(net "PEER_1B_2B_HB")
	)
	(segment
		(start 224.114614 -175.7807)
		(end 225.117914 -176.784)
		(width 0.127)
		(layer "In2.Cu")
		(net "PEER_1B_2B_HB")
	)
	(segment
		(start 198.3613 -180.2003)
		(end 203.073254 -180.2003)
		(width 0.127)
		(layer "In2.Cu")
		(net "PEER_1B_2B_HB")
	)
	(segment
		(start 88.9 -165.831012)
		(end 91.917012 -165.831012)
		(width 0.127)
		(layer "In2.Cu")
		(net "PEER_1B_2B_HB")
	)
	(segment
		(start 297.829732 -207.2513)
		(end 313.9313 -191.149732)
		(width 0.127)
		(layer "In2.Cu")
		(net "PEER_1B_2B_HB")
	)
	(segment
		(start 173.022768 -179.4383)
		(end 175.719232 -179.4383)
		(width 0.127)
		(layer "In2.Cu")
		(net "PEER_1B_2B_HB")
	)
	(segment
		(start 176.214532 -178.943)
		(end 197.104 -178.943)
		(width 0.127)
		(layer "In2.Cu")
		(net "PEER_1B_2B_HB")
	)
	(segment
		(start 274.564602 -207.2513)
		(end 297.829732 -207.2513)
		(width 0.127)
		(layer "In2.Cu")
		(net "PEER_1B_2B_HB")
	)
	(segment
		(start 313.9313 -191.149732)
		(end 313.9313 -188.4553)
		(width 0.127)
		(layer "In2.Cu")
		(net "PEER_1B_2B_HB")
	)
	(segment
		(start 97.23755 -169.1513)
		(end 99.251262 -171.165012)
		(width 0.127)
		(layer "In2.Cu")
		(net "PEER_1B_2B_HB")
	)
	(segment
		(start 220.042232 -175.8823)
		(end 220.143832 -175.7807)
		(width 0.127)
		(layer "In2.Cu")
		(net "PEER_1B_2B_HB")
	)
	(segment
		(start 225.117914 -176.784)
		(end 250.707398 -176.784)
		(width 0.127)
		(layer "In2.Cu")
		(net "PEER_1B_2B_HB")
	)
	(segment
		(start 220.143832 -175.7807)
		(end 224.114614 -175.7807)
		(width 0.127)
		(layer "In2.Cu")
		(net "PEER_1B_2B_HB")
	)
	(segment
		(start 95.2373 -169.1513)
		(end 97.23755 -169.1513)
		(width 0.127)
		(layer "In2.Cu")
		(net "PEER_1B_2B_HB")
	)
	(segment
		(start 125.000512 -256.25044)
		(end 125.000512 -254.195326)
		(width 0.1016)
		(layer "F.Cu")
		(net "SAS_EXP_GF_TX_DN5")
	)
	(segment
		(start 120.420892 -161.695892)
		(end 120.271794 -161.547302)
		(width 0.1016)
		(layer "F.Cu")
		(net "SAS_EXP_GF_TX_DN5")
	)
	(segment
		(start 119.666766 -160.086294)
		(end 119.66702 -160.086294)
		(width 0.1016)
		(layer "F.Cu")
		(net "SAS_EXP_GF_TX_DN5")
	)
	(segment
		(start 128.52908 -229.910386)
		(end 128.962912 -229.4763)
		(width 0.1016)
		(layer "F.Cu")
		(net "SAS_EXP_GF_TX_DN5")
	)
	(segment
		(start 125.305312 -253.459488)
		(end 125.305312 -237.692946)
		(width 0.1016)
		(layer "F.Cu")
		(net "SAS_EXP_GF_TX_DN5")
	)
	(segment
		(start 128.962912 -229.4763)
		(end 131.35229 -227.086922)
		(width 0.1016)
		(layer "F.Cu")
		(net "SAS_EXP_GF_TX_DN5")
	)
	(segment
		(start 133.618224 -221.616524)
		(end 133.618224 -176.57318)
		(width 0.1016)
		(layer "F.Cu")
		(net "SAS_EXP_GF_TX_DN5")
	)
	(segment
		(start 132.430266 -173.705266)
		(end 120.420892 -161.695892)
		(width 0.1016)
		(layer "F.Cu")
		(net "SAS_EXP_GF_TX_DN5")
	)
	(segment
		(start 119.66702 -160.086294)
		(end 119.66702 -114.931952)
		(width 0.1016)
		(layer "F.Cu")
		(net "SAS_EXP_GF_TX_DN5")
	)
	(arc
		(start 125.305312 -237.692946)
		(mid 126.143187 -233.481046)
		(end 128.52908 -229.910386)
		(width 0.1016)
		(layer "F.Cu")
		(net "SAS_EXP_GF_TX_DN5")
	)
	(arc
		(start 119.66702 -114.931952)
		(mid 119.629066 -114.741145)
		(end 119.52097 -114.5794)
		(width 0.1016)
		(layer "F.Cu")
		(net "SAS_EXP_GF_TX_DN5")
	)
	(arc
		(start 120.271794 -161.547302)
		(mid 119.823932 -160.876985)
		(end 119.666766 -160.086294)
		(width 0.1016)
		(layer "F.Cu")
		(net "SAS_EXP_GF_TX_DN5")
	)
	(arc
		(start 125.000512 -254.195326)
		(mid 125.043415 -253.979636)
		(end 125.165612 -253.7968)
		(width 0.1016)
		(layer "F.Cu")
		(net "SAS_EXP_GF_TX_DN5")
	)
	(arc
		(start 131.35229 -227.086922)
		(mid 133.029311 -224.577082)
		(end 133.618224 -221.616524)
		(width 0.1016)
		(layer "F.Cu")
		(net "SAS_EXP_GF_TX_DN5")
	)
	(arc
		(start 125.165612 -253.7968)
		(mid 125.269019 -253.64204)
		(end 125.305312 -253.459488)
		(width 0.1016)
		(layer "F.Cu")
		(net "SAS_EXP_GF_TX_DN5")
	)
	(arc
		(start 133.618224 -176.57318)
		(mid 133.309489 -175.021065)
		(end 132.430266 -173.705266)
		(width 0.1016)
		(layer "F.Cu")
		(net "SAS_EXP_GF_TX_DN5")
	)
	(segment
		(start 21.7551 -242.8621)
		(end 12.279122 -242.8621)
		(width 0.1143)
		(layer "F.Cu")
		(net "PEER_TRAY")
	)
	(segment
		(start 28.194 -249.301)
		(end 21.7551 -242.8621)
		(width 0.1143)
		(layer "F.Cu")
		(net "PEER_TRAY")
	)
	(segment
		(start 7.570216 -238.153194)
		(end 7.570216 -229.67188)
		(width 0.1143)
		(layer "F.Cu")
		(net "PEER_TRAY")
	)
	(segment
		(start 12.279122 -242.8621)
		(end 7.570216 -238.153194)
		(width 0.1143)
		(layer "F.Cu")
		(net "PEER_TRAY")
	)
	(segment
		(start 7.570216 -229.67188)
		(end 7.570216 -227.06838)
		(width 0.1143)
		(layer "F.Cu")
		(net "PEER_TRAY")
	)
	(via
		(at 7.570216 -229.67188)
		(size 0.7112)
		(drill 0.3556)
		(layers "F.Cu" "B.Cu")
		(net "PEER_TRAY")
	)
	(via
		(at 28.194 -249.301)
		(size 0.508)
		(drill 0.254)
		(layers "F.Cu" "B.Cu")
		(net "PEER_TRAY")
	)
	(segment
		(start 29.36875 -253.20625)
		(end 29.36875 -250.85675)
		(width 0.1143)
		(layer "B.Cu")
		(net "PEER_TRAY")
	)
	(segment
		(start 28.194 -249.682)
		(end 28.194 -249.301)
		(width 0.1143)
		(layer "B.Cu")
		(net "PEER_TRAY")
	)
	(segment
		(start 29.000196 -253.574804)
		(end 29.36875 -253.20625)
		(width 0.1143)
		(layer "B.Cu")
		(net "PEER_TRAY")
	)
	(segment
		(start 29.000196 -256.50444)
		(end 29.000196 -253.574804)
		(width 0.1143)
		(layer "B.Cu")
		(net "PEER_TRAY")
	)
	(segment
		(start 29.36875 -250.85675)
		(end 28.194 -249.682)
		(width 0.1143)
		(layer "B.Cu")
		(net "PEER_TRAY")
	)
	(segment
		(start 8.713216 -228.02088)
		(end 8.713216 -227.06838)
		(width 0.1143)
		(layer "F.Cu")
		(net "SELF_TRAY")
	)
	(segment
		(start 8.713216 -230.968042)
		(end 8.713216 -228.02088)
		(width 0.1143)
		(layer "F.Cu")
		(net "SELF_TRAY")
	)
	(segment
		(start 81.16697 -147.193)
		(end 80.710532 -147.649438)
		(width 0.1143)
		(layer "F.Cu")
		(net "SELF_TRAY")
	)
	(segment
		(start 83.38947 -147.193)
		(end 81.16697 -147.193)
		(width 0.1143)
		(layer "F.Cu")
		(net "SELF_TRAY")
	)
	(segment
		(start 8.592566 -231.088692)
		(end 8.713216 -230.968042)
		(width 0.1143)
		(layer "F.Cu")
		(net "SELF_TRAY")
	)
	(segment
		(start 90.18397 -140.3985)
		(end 83.38947 -147.193)
		(width 0.1143)
		(layer "F.Cu")
		(net "SELF_TRAY")
	)
	(segment
		(start 29.337 -249.809)
		(end 29.337 -249.788426)
		(width 0.1143)
		(layer "F.Cu")
		(net "SELF_TRAY")
	)
	(segment
		(start 8.592566 -238.582708)
		(end 8.592566 -231.088692)
		(width 0.1143)
		(layer "F.Cu")
		(net "SELF_TRAY")
	)
	(segment
		(start 12.452858 -242.443)
		(end 8.592566 -238.582708)
		(width 0.1143)
		(layer "F.Cu")
		(net "SELF_TRAY")
	)
	(segment
		(start 21.991574 -242.443)
		(end 12.452858 -242.443)
		(width 0.1143)
		(layer "F.Cu")
		(net "SELF_TRAY")
	)
	(segment
		(start 29.337 -249.788426)
		(end 21.991574 -242.443)
		(width 0.1143)
		(layer "F.Cu")
		(net "SELF_TRAY")
	)
	(via
		(at 29.337 -249.809)
		(size 0.5588)
		(drill 0.3048)
		(layers "F.Cu" "B.Cu")
		(net "SELF_TRAY")
	)
	(via
		(at 9.779 -226.441)
		(size 0.7112)
		(drill 0.3556)
		(layers "F.Cu" "B.Cu")
		(net "SELF_TRAY")
	)
	(via
		(at 80.710532 -147.649438)
		(size 0.5588)
		(drill 0.3048)
		(layers "F.Cu" "B.Cu")
		(net "SELF_TRAY")
	)
	(via
		(at 8.713216 -228.02088)
		(size 0.5588)
		(drill 0.3048)
		(layers "F.Cu" "B.Cu")
		(net "SELF_TRAY")
	)
	(segment
		(start 10.4775 -222.34017)
		(end 10.726166 -222.588836)
		(width 0.1143)
		(layer "B.Cu")
		(net "SELF_TRAY")
	)
	(segment
		(start 11.86307 -219.422726)
		(end 10.4775 -220.808296)
		(width 0.1143)
		(layer "B.Cu")
		(net "SELF_TRAY")
	)
	(segment
		(start 18.219166 -211.921598)
		(end 18.219166 -213.1568)
		(width 0.1143)
		(layer "B.Cu")
		(net "SELF_TRAY")
	)
	(segment
		(start 80.710532 -149.562566)
		(end 64.6049 -165.668198)
		(width 0.1143)
		(layer "B.Cu")
		(net "SELF_TRAY")
	)
	(segment
		(start 51.175666 -175.6791)
		(end 51.175412 -175.6791)
		(width 0.1143)
		(layer "B.Cu")
		(net "SELF_TRAY")
	)
	(segment
		(start 50.015394 -176.839372)
		(end 39.192962 -187.661804)
		(width 0.1143)
		(layer "B.Cu")
		(net "SELF_TRAY")
	)
	(segment
		(start 30.46095 -253.429008)
		(end 30.46095 -250.93295)
		(width 0.1143)
		(layer "B.Cu")
		(net "SELF_TRAY")
	)
	(segment
		(start 39.192962 -187.661804)
		(end 39.192962 -188.892688)
		(width 0.1143)
		(layer "B.Cu")
		(net "SELF_TRAY")
	)
	(segment
		(start 39.192962 -188.892688)
		(end 39.193216 -188.892942)
		(width 0.1143)
		(layer "B.Cu")
		(net "SELF_TRAY")
	)
	(segment
		(start 51.188366 -175.6664)
		(end 51.175666 -175.6791)
		(width 0.1143)
		(layer "B.Cu")
		(net "SELF_TRAY")
	)
	(segment
		(start 10.4775 -220.808296)
		(end 10.4775 -222.34017)
		(width 0.1143)
		(layer "B.Cu")
		(net "SELF_TRAY")
	)
	(segment
		(start 10.726166 -222.588836)
		(end 10.726166 -225.570288)
		(width 0.1143)
		(layer "B.Cu")
		(net "SELF_TRAY")
	)
	(segment
		(start 50.015394 -176.839118)
		(end 50.015394 -176.839372)
		(width 0.1143)
		(layer "B.Cu")
		(net "SELF_TRAY")
	)
	(segment
		(start 14.486636 -216.88933)
		(end 14.486636 -217.669364)
		(width 0.1143)
		(layer "B.Cu")
		(net "SELF_TRAY")
	)
	(segment
		(start 10.726166 -225.570288)
		(end 10.3251 -225.971354)
		(width 0.1143)
		(layer "B.Cu")
		(net "SELF_TRAY")
	)
	(segment
		(start 39.193216 -188.892942)
		(end 39.193216 -190.947548)
		(width 0.1143)
		(layer "B.Cu")
		(net "SELF_TRAY")
	)
	(segment
		(start 10.248646 -225.971354)
		(end 9.779 -226.441)
		(width 0.1143)
		(layer "B.Cu")
		(net "SELF_TRAY")
	)
	(segment
		(start 14.486636 -217.669364)
		(end 12.733274 -219.422726)
		(width 0.1143)
		(layer "B.Cu")
		(net "SELF_TRAY")
	)
	(segment
		(start 8.713216 -228.02088)
		(end 8.713216 -227.506784)
		(width 0.1143)
		(layer "B.Cu")
		(net "SELF_TRAY")
	)
	(segment
		(start 59.08294 -175.6664)
		(end 51.188366 -175.6664)
		(width 0.1143)
		(layer "B.Cu")
		(net "SELF_TRAY")
	)
	(segment
		(start 51.175412 -175.6791)
		(end 50.015394 -176.839118)
		(width 0.1143)
		(layer "B.Cu")
		(net "SELF_TRAY")
	)
	(segment
		(start 8.713216 -227.506784)
		(end 9.779 -226.441)
		(width 0.1143)
		(layer "B.Cu")
		(net "SELF_TRAY")
	)
	(segment
		(start 18.219166 -213.1568)
		(end 14.486636 -216.88933)
		(width 0.1143)
		(layer "B.Cu")
		(net "SELF_TRAY")
	)
	(segment
		(start 29.999686 -253.890272)
		(end 30.46095 -253.429008)
		(width 0.1143)
		(layer "B.Cu")
		(net "SELF_TRAY")
	)
	(segment
		(start 12.733274 -219.422726)
		(end 11.86307 -219.422726)
		(width 0.1143)
		(layer "B.Cu")
		(net "SELF_TRAY")
	)
	(segment
		(start 29.999686 -256.50444)
		(end 29.999686 -253.890272)
		(width 0.1143)
		(layer "B.Cu")
		(net "SELF_TRAY")
	)
	(segment
		(start 64.6049 -170.14444)
		(end 59.08294 -175.6664)
		(width 0.1143)
		(layer "B.Cu")
		(net "SELF_TRAY")
	)
	(segment
		(start 64.6049 -165.668198)
		(end 64.6049 -170.14444)
		(width 0.1143)
		(layer "B.Cu")
		(net "SELF_TRAY")
	)
	(segment
		(start 30.46095 -250.93295)
		(end 29.337 -249.809)
		(width 0.1143)
		(layer "B.Cu")
		(net "SELF_TRAY")
	)
	(segment
		(start 10.3251 -225.971354)
		(end 10.248646 -225.971354)
		(width 0.1143)
		(layer "B.Cu")
		(net "SELF_TRAY")
	)
	(segment
		(start 39.193216 -190.947548)
		(end 18.219166 -211.921598)
		(width 0.1143)
		(layer "B.Cu")
		(net "SELF_TRAY")
	)
	(segment
		(start 80.710532 -147.649438)
		(end 80.710532 -149.562566)
		(width 0.1143)
		(layer "B.Cu")
		(net "SELF_TRAY")
	)
	(segment
		(start 91.694 -138.950954)
		(end 91.694 -143.14297)
		(width 0.1143)
		(layer "F.Cu")
		(net "PEER_1A_2A_HB")
	)
	(segment
		(start 91.124532 -138.381486)
		(end 91.694 -138.950954)
		(width 0.1143)
		(layer "F.Cu")
		(net "PEER_1A_2A_HB")
	)
	(segment
		(start 91.694 -143.14297)
		(end 87.986108 -146.850862)
		(width 0.1143)
		(layer "F.Cu")
		(net "PEER_1A_2A_HB")
	)
	(segment
		(start 90.162888 -248.23547)
		(end 91.631262 -246.767096)
		(width 0.1143)
		(layer "F.Cu")
		(net "PEER_1A_2A_HB")
	)
	(segment
		(start 91.124532 -137.209276)
		(end 91.124532 -138.381486)
		(width 0.1143)
		(layer "F.Cu")
		(net "PEER_1A_2A_HB")
	)
	(segment
		(start 91.631262 -246.767096)
		(end 92.357956 -246.767096)
		(width 0.1143)
		(layer "F.Cu")
		(net "PEER_1A_2A_HB")
	)
	(segment
		(start 90.000582 -248.6279)
		(end 90.162888 -248.23547)
		(width 0.1143)
		(layer "F.Cu")
		(net "PEER_1A_2A_HB")
	)
	(segment
		(start 90.000582 -256.25044)
		(end 90.000582 -248.6279)
		(width 0.1143)
		(layer "F.Cu")
		(net "PEER_1A_2A_HB")
	)
	(segment
		(start 87.986108 -146.850862)
		(end 87.986108 -165.863016)
		(width 0.1143)
		(layer "F.Cu")
		(net "PEER_1A_2A_HB")
	)
	(via
		(at 314.071 -187.43295)
		(size 0.5588)
		(drill 0.3048)
		(layers "F.Cu" "B.Cu")
		(net "PEER_1A_2A_HB")
	)
	(via
		(at 92.357956 -246.767096)
		(size 0.5588)
		(drill 0.3048)
		(layers "F.Cu" "B.Cu")
		(net "PEER_1A_2A_HB")
	)
	(via
		(at 87.986108 -165.863016)
		(size 0.5588)
		(drill 0.3048)
		(layers "F.Cu" "B.Cu")
		(net "PEER_1A_2A_HB")
	)
	(via
		(at 313.6138 -186.3598)
		(size 0.7112)
		(drill 0.3556)
		(layers "F.Cu" "B.Cu")
		(net "PEER_1A_2A_HB")
	)
	(via
		(at 71.247 -242.57)
		(size 0.5588)
		(drill 0.3048)
		(layers "F.Cu" "B.Cu")
		(net "PEER_1A_2A_HB")
	)
	(segment
		(start 83.12785 -208.71815)
		(end 71.3867 -220.4593)
		(width 0.1143)
		(layer "B.Cu")
		(net "PEER_1A_2A_HB")
	)
	(segment
		(start 71.3867 -220.4593)
		(end 71.3867 -242.4303)
		(width 0.1143)
		(layer "B.Cu")
		(net "PEER_1A_2A_HB")
	)
	(segment
		(start 87.986108 -165.863016)
		(end 87.986108 -165.886892)
		(width 0.1143)
		(layer "B.Cu")
		(net "PEER_1A_2A_HB")
	)
	(segment
		(start 311.912 -186.055)
		(end 313.309 -186.055)
		(width 0.1143)
		(layer "B.Cu")
		(net "PEER_1A_2A_HB")
	)
	(segment
		(start 311.3405 -185.674)
		(end 311.531 -185.674)
		(width 0.1143)
		(layer "B.Cu")
		(net "PEER_1A_2A_HB")
	)
	(segment
		(start 314.071 -187.43295)
		(end 314.071 -186.817)
		(width 0.1143)
		(layer "B.Cu")
		(net "PEER_1A_2A_HB")
	)
	(segment
		(start 314.071 -186.817)
		(end 313.6138 -186.3598)
		(width 0.1143)
		(layer "B.Cu")
		(net "PEER_1A_2A_HB")
	)
	(segment
		(start 71.3867 -242.4303)
		(end 71.247 -242.57)
		(width 0.1143)
		(layer "B.Cu")
		(net "PEER_1A_2A_HB")
	)
	(segment
		(start 87.986108 -165.886892)
		(end 83.12785 -170.74515)
		(width 0.1143)
		(layer "B.Cu")
		(net "PEER_1A_2A_HB")
	)
	(segment
		(start 83.12785 -170.74515)
		(end 83.12785 -208.71815)
		(width 0.1143)
		(layer "B.Cu")
		(net "PEER_1A_2A_HB")
	)
	(segment
		(start 313.309 -186.055)
		(end 313.6138 -186.3598)
		(width 0.1143)
		(layer "B.Cu")
		(net "PEER_1A_2A_HB")
	)
	(segment
		(start 311.531 -185.674)
		(end 311.912 -186.055)
		(width 0.1143)
		(layer "B.Cu")
		(net "PEER_1A_2A_HB")
	)
	(segment
		(start 196.946012 -179.324)
		(end 176.37252 -179.324)
		(width 0.127)
		(layer "In2.Cu")
		(net "PEER_1A_2A_HB")
	)
	(segment
		(start 288.4297 -207.7847)
		(end 274.559014 -207.7847)
		(width 0.127)
		(layer "In2.Cu")
		(net "PEER_1A_2A_HB")
	)
	(segment
		(start 223.956372 -176.1617)
		(end 220.30182 -176.1617)
		(width 0.127)
		(layer "In2.Cu")
		(net "PEER_1A_2A_HB")
	)
	(segment
		(start 288.8869 -208.2419)
		(end 288.4297 -207.7847)
		(width 0.127)
		(layer "In2.Cu")
		(net "PEER_1A_2A_HB")
	)
	(segment
		(start 220.20022 -176.2633)
		(end 207.549242 -176.2633)
		(width 0.127)
		(layer "In2.Cu")
		(net "PEER_1A_2A_HB")
	)
	(segment
		(start 176.37252 -179.324)
		(end 175.87722 -179.8193)
		(width 0.127)
		(layer "In2.Cu")
		(net "PEER_1A_2A_HB")
	)
	(segment
		(start 164.591492 -171.546012)
		(end 99.093274 -171.546012)
		(width 0.127)
		(layer "In2.Cu")
		(net "PEER_1A_2A_HB")
	)
	(segment
		(start 95.079312 -169.5323)
		(end 91.873324 -166.326312)
		(width 0.127)
		(layer "In2.Cu")
		(net "PEER_1A_2A_HB")
	)
	(segment
		(start 250.54941 -177.165)
		(end 224.959672 -177.165)
		(width 0.127)
		(layer "In2.Cu")
		(net "PEER_1A_2A_HB")
	)
	(segment
		(start 220.30182 -176.1617)
		(end 220.20022 -176.2633)
		(width 0.127)
		(layer "In2.Cu")
		(net "PEER_1A_2A_HB")
	)
	(segment
		(start 203.231242 -180.5813)
		(end 198.203312 -180.5813)
		(width 0.127)
		(layer "In2.Cu")
		(net "PEER_1A_2A_HB")
	)
	(segment
		(start 76.924662 -246.767096)
		(end 92.357956 -246.767096)
		(width 0.127)
		(layer "In2.Cu")
		(net "PEER_1A_2A_HB")
	)
	(segment
		(start 198.203312 -180.5813)
		(end 196.946012 -179.324)
		(width 0.127)
		(layer "In2.Cu")
		(net "PEER_1A_2A_HB")
	)
	(segment
		(start 175.87722 -179.8193)
		(end 172.86478 -179.8193)
		(width 0.127)
		(layer "In2.Cu")
		(net "PEER_1A_2A_HB")
	)
	(segment
		(start 314.3123 -187.67425)
		(end 314.3123 -191.30772)
		(width 0.127)
		(layer "In2.Cu")
		(net "PEER_1A_2A_HB")
	)
	(segment
		(start 264.268712 -197.494398)
		(end 264.268712 -190.884302)
		(width 0.127)
		(layer "In2.Cu")
		(net "PEER_1A_2A_HB")
	)
	(segment
		(start 72.517 -244.475)
		(end 74.632566 -244.475)
		(width 0.127)
		(layer "In2.Cu")
		(net "PEER_1A_2A_HB")
	)
	(segment
		(start 172.86478 -179.8193)
		(end 164.591492 -171.546012)
		(width 0.127)
		(layer "In2.Cu")
		(net "PEER_1A_2A_HB")
	)
	(segment
		(start 274.559014 -207.7847)
		(end 264.268712 -197.494398)
		(width 0.127)
		(layer "In2.Cu")
		(net "PEER_1A_2A_HB")
	)
	(segment
		(start 91.873324 -166.326312)
		(end 88.449404 -166.326312)
		(width 0.127)
		(layer "In2.Cu")
		(net "PEER_1A_2A_HB")
	)
	(segment
		(start 71.247 -243.205)
		(end 72.517 -244.475)
		(width 0.127)
		(layer "In2.Cu")
		(net "PEER_1A_2A_HB")
	)
	(segment
		(start 224.959672 -177.165)
		(end 223.956372 -176.1617)
		(width 0.127)
		(layer "In2.Cu")
		(net "PEER_1A_2A_HB")
	)
	(segment
		(start 99.093274 -171.546012)
		(end 97.079562 -169.5323)
		(width 0.127)
		(layer "In2.Cu")
		(net "PEER_1A_2A_HB")
	)
	(segment
		(start 71.247 -242.57)
		(end 71.247 -243.205)
		(width 0.127)
		(layer "In2.Cu")
		(net "PEER_1A_2A_HB")
	)
	(segment
		(start 88.449404 -166.326312)
		(end 87.986108 -165.863016)
		(width 0.127)
		(layer "In2.Cu")
		(net "PEER_1A_2A_HB")
	)
	(segment
		(start 74.632566 -244.475)
		(end 76.924662 -246.767096)
		(width 0.127)
		(layer "In2.Cu")
		(net "PEER_1A_2A_HB")
	)
	(segment
		(start 264.268712 -190.884302)
		(end 250.54941 -177.165)
		(width 0.127)
		(layer "In2.Cu")
		(net "PEER_1A_2A_HB")
	)
	(segment
		(start 297.37812 -208.2419)
		(end 288.8869 -208.2419)
		(width 0.127)
		(layer "In2.Cu")
		(net "PEER_1A_2A_HB")
	)
	(segment
		(start 314.3123 -191.30772)
		(end 297.37812 -208.2419)
		(width 0.127)
		(layer "In2.Cu")
		(net "PEER_1A_2A_HB")
	)
	(segment
		(start 314.071 -187.43295)
		(end 314.3123 -187.67425)
		(width 0.127)
		(layer "In2.Cu")
		(net "PEER_1A_2A_HB")
	)
	(segment
		(start 207.549242 -176.2633)
		(end 203.231242 -180.5813)
		(width 0.127)
		(layer "In2.Cu")
		(net "PEER_1A_2A_HB")
	)
	(segment
		(start 97.079562 -169.5323)
		(end 95.079312 -169.5323)
		(width 0.127)
		(layer "In2.Cu")
		(net "PEER_1A_2A_HB")
	)
	(segment
		(start 191.11468 -74.31532)
		(end 191.008 -74.422)
		(width 0.1397)
		(layer "B.Cu")
		(net "PCIE_SAS_CPU_RX_N3")
	)
	(segment
		(start 107.582208 -16.496792)
		(end 115.432078 -16.496792)
		(width 0.1397)
		(layer "B.Cu")
		(net "PCIE_SAS_CPU_RX_N3")
	)
	(segment
		(start 116.12372 -16.21028)
		(end 119.994172 -12.339828)
		(width 0.1397)
		(layer "B.Cu")
		(net "PCIE_SAS_CPU_RX_N3")
	)
	(segment
		(start 98.33356 -30.791658)
		(end 98.33356 -25.74544)
		(width 0.1397)
		(layer "B.Cu")
		(net "PCIE_SAS_CPU_RX_N3")
	)
	(segment
		(start 120.443244 -12.1539)
		(end 127.973328 -12.1539)
		(width 0.1397)
		(layer "B.Cu")
		(net "PCIE_SAS_CPU_RX_N3")
	)
	(segment
		(start 149.863302 -33.3756)
		(end 154.557984 -33.3756)
		(width 0.1397)
		(layer "B.Cu")
		(net "PCIE_SAS_CPU_RX_N3")
	)
	(segment
		(start 190.373 -73.827386)
		(end 190.450216 -73.75017)
		(width 0.1397)
		(layer "B.Cu")
		(net "PCIE_SAS_CPU_RX_N3")
	)
	(segment
		(start 155.007056 -33.561528)
		(end 191.123062 -69.677534)
		(width 0.1397)
		(layer "B.Cu")
		(net "PCIE_SAS_CPU_RX_N3")
	)
	(segment
		(start 128.4224 -12.339828)
		(end 149.17166 -33.089088)
		(width 0.1397)
		(layer "B.Cu")
		(net "PCIE_SAS_CPU_RX_N3")
	)
	(segment
		(start 191.30899 -70.126606)
		(end 191.30899 -73.846182)
		(width 0.1397)
		(layer "B.Cu")
		(net "PCIE_SAS_CPU_RX_N3")
	)
	(segment
		(start 98.519488 -25.296368)
		(end 107.133136 -16.68272)
		(width 0.1397)
		(layer "B.Cu")
		(net "PCIE_SAS_CPU_RX_N3")
	)
	(arc
		(start 98.56216 -31.3436)
		(mid 98.392955 -31.090367)
		(end 98.33356 -30.791658)
		(width 0.1397)
		(layer "B.Cu")
		(net "PCIE_SAS_CPU_RX_N3")
	)
	(arc
		(start 119.994172 -12.339828)
		(mid 120.200208 -12.202159)
		(end 120.443244 -12.1539)
		(width 0.1397)
		(layer "B.Cu")
		(net "PCIE_SAS_CPU_RX_N3")
	)
	(arc
		(start 191.008 -74.422)
		(mid 190.6905 -74.553513)
		(end 190.373 -74.422)
		(width 0.1397)
		(layer "B.Cu")
		(net "PCIE_SAS_CPU_RX_N3")
	)
	(arc
		(start 190.373 -74.422)
		(mid 190.249978 -74.12473)
		(end 190.373 -73.827386)
		(width 0.1397)
		(layer "B.Cu")
		(net "PCIE_SAS_CPU_RX_N3")
	)
	(arc
		(start 191.30899 -73.846182)
		(mid 191.258488 -74.100073)
		(end 191.11468 -74.31532)
		(width 0.1397)
		(layer "B.Cu")
		(net "PCIE_SAS_CPU_RX_N3")
	)
	(arc
		(start 149.17166 -33.089088)
		(mid 149.488974 -33.301174)
		(end 149.863302 -33.3756)
		(width 0.1397)
		(layer "B.Cu")
		(net "PCIE_SAS_CPU_RX_N3")
	)
	(arc
		(start 127.973328 -12.1539)
		(mid 128.216332 -12.202236)
		(end 128.4224 -12.339828)
		(width 0.1397)
		(layer "B.Cu")
		(net "PCIE_SAS_CPU_RX_N3")
	)
	(arc
		(start 115.432078 -16.496792)
		(mid 115.806387 -16.422319)
		(end 116.12372 -16.21028)
		(width 0.1397)
		(layer "B.Cu")
		(net "PCIE_SAS_CPU_RX_N3")
	)
	(arc
		(start 107.133136 -16.68272)
		(mid 107.339172 -16.545051)
		(end 107.582208 -16.496792)
		(width 0.1397)
		(layer "B.Cu")
		(net "PCIE_SAS_CPU_RX_N3")
	)
	(arc
		(start 191.123062 -69.677534)
		(mid 191.260731 -69.88357)
		(end 191.30899 -70.126606)
		(width 0.1397)
		(layer "B.Cu")
		(net "PCIE_SAS_CPU_RX_N3")
	)
	(arc
		(start 154.557984 -33.3756)
		(mid 154.800988 -33.423936)
		(end 155.007056 -33.561528)
		(width 0.1397)
		(layer "B.Cu")
		(net "PCIE_SAS_CPU_RX_N3")
	)
	(arc
		(start 98.33356 -25.74544)
		(mid 98.381896 -25.502436)
		(end 98.519488 -25.296368)
		(width 0.1397)
		(layer "B.Cu")
		(net "PCIE_SAS_CPU_RX_N3")
	)
	(segment
		(start 287.234884 -177.040032)
		(end 286.83966 -177.435256)
		(width 0.1143)
		(layer "F.Cu")
		(net "ROMA18")
	)
	(via
		(at 275.971 -181.102)
		(size 0.7112)
		(drill 0.3556)
		(layers "F.Cu" "B.Cu")
		(net "ROMA18")
	)
	(via
		(at 286.83966 -177.435256)
		(size 0.508)
		(drill 0.254)
		(layers "F.Cu" "B.Cu")
		(net "ROMA18")
	)
	(segment
		(start 275.463 -181.102)
		(end 275.971 -181.102)
		(width 0.1143)
		(layer "B.Cu")
		(net "ROMA18")
	)
	(segment
		(start 275.082 -180.721)
		(end 275.463 -181.102)
		(width 0.1143)
		(layer "B.Cu")
		(net "ROMA18")
	)
	(segment
		(start 275.971 -181.102)
		(end 277.480268 -181.102)
		(width 0.1143)
		(layer "B.Cu")
		(net "ROMA18")
	)
	(segment
		(start 277.480268 -181.102)
		(end 280.815288 -177.76698)
		(width 0.1143)
		(layer "B.Cu")
		(net "ROMA18")
	)
	(segment
		(start 286.3215 -177.76698)
		(end 286.653224 -177.435256)
		(width 0.1143)
		(layer "B.Cu")
		(net "ROMA18")
	)
	(segment
		(start 274.6375 -180.721)
		(end 275.082 -180.721)
		(width 0.1143)
		(layer "B.Cu")
		(net "ROMA18")
	)
	(segment
		(start 286.653224 -177.435256)
		(end 286.83966 -177.435256)
		(width 0.1143)
		(layer "B.Cu")
		(net "ROMA18")
	)
	(segment
		(start 280.815288 -177.76698)
		(end 286.3215 -177.76698)
		(width 0.1143)
		(layer "B.Cu")
		(net "ROMA18")
	)
	(segment
		(start 87.884 -26.10231)
		(end 87.884 -25.908)
		(width 0.1397)
		(layer "F.Cu")
		(net "CLK_100M_PCIE_SAS_C_N")
	)
	(via
		(at 87.884 -25.908)
		(size 0.5588)
		(drill 0.3048)
		(layers "F.Cu" "B.Cu")
		(net "CLK_100M_PCIE_SAS_C_N")
	)
	(arc
		(start 88.138 -26.715466)
		(mid 87.950029 -26.434148)
		(end 87.884 -26.10231)
		(width 0.1397)
		(layer "F.Cu")
		(net "CLK_100M_PCIE_SAS_C_N")
	)
	(segment
		(start 197.273164 -65.372488)
		(end 158.451804 -26.551128)
		(width 0.1397)
		(layer "B.Cu")
		(net "CLK_100M_PCIE_SAS_C_N")
	)
	(segment
		(start 207.106266 -72.740266)
		(end 200.210928 -65.844928)
		(width 0.1397)
		(layer "B.Cu")
		(net "CLK_100M_PCIE_SAS_C_N")
	)
	(segment
		(start 92.333572 -21.16201)
		(end 90.607134 -21.16201)
		(width 0.1397)
		(layer "B.Cu")
		(net "CLK_100M_PCIE_SAS_C_N")
	)
	(segment
		(start 158.002732 -26.3652)
		(end 152.873202 -26.3652)
		(width 0.1397)
		(layer "B.Cu")
		(net "CLK_100M_PCIE_SAS_C_N")
	)
	(segment
		(start 90.158062 -21.347938)
		(end 87.815928 -23.690072)
		(width 0.1397)
		(layer "B.Cu")
		(net "CLK_100M_PCIE_SAS_C_N")
	)
	(segment
		(start 104.228392 -9.67232)
		(end 93.025214 -20.875498)
		(width 0.1397)
		(layer "B.Cu")
		(net "CLK_100M_PCIE_SAS_C_N")
	)
	(segment
		(start 152.18156 -26.078688)
		(end 131.3307 -5.227828)
		(width 0.1397)
		(layer "B.Cu")
		(net "CLK_100M_PCIE_SAS_C_N")
	)
	(segment
		(start 87.63 -24.139144)
		(end 87.63 -25.294844)
		(width 0.1397)
		(layer "B.Cu")
		(net "CLK_100M_PCIE_SAS_C_N")
	)
	(segment
		(start 116.184172 -5.227828)
		(end 112.21212 -9.19988)
		(width 0.1397)
		(layer "B.Cu")
		(net "CLK_100M_PCIE_SAS_C_N")
	)
	(segment
		(start 206.449676 -73.75017)
		(end 206.274924 -73.925176)
		(width 0.1397)
		(layer "B.Cu")
		(net "CLK_100M_PCIE_SAS_C_N")
	)
	(segment
		(start 130.881628 -5.0419)
		(end 116.633244 -5.0419)
		(width 0.1397)
		(layer "B.Cu")
		(net "CLK_100M_PCIE_SAS_C_N")
	)
	(segment
		(start 207.292194 -74.219054)
		(end 207.292194 -73.189338)
		(width 0.1397)
		(layer "B.Cu")
		(net "CLK_100M_PCIE_SAS_C_N")
	)
	(segment
		(start 111.520478 -9.486392)
		(end 104.677464 -9.486392)
		(width 0.1397)
		(layer "B.Cu")
		(net "CLK_100M_PCIE_SAS_C_N")
	)
	(segment
		(start 199.761856 -65.659)
		(end 197.964806 -65.659)
		(width 0.1397)
		(layer "B.Cu")
		(net "CLK_100M_PCIE_SAS_C_N")
	)
	(arc
		(start 152.873202 -26.3652)
		(mid 152.498893 -26.290727)
		(end 152.18156 -26.078688)
		(width 0.1397)
		(layer "B.Cu")
		(net "CLK_100M_PCIE_SAS_C_N")
	)
	(arc
		(start 112.21212 -9.19988)
		(mid 111.894806 -9.411966)
		(end 111.520478 -9.486392)
		(width 0.1397)
		(layer "B.Cu")
		(net "CLK_100M_PCIE_SAS_C_N")
	)
	(arc
		(start 206.761334 -74.867516)
		(mid 207.119907 -74.619525)
		(end 207.292194 -74.219054)
		(width 0.1397)
		(layer "B.Cu")
		(net "CLK_100M_PCIE_SAS_C_N")
	)
	(arc
		(start 87.63 -25.294844)
		(mid 87.696008 -25.62669)
		(end 87.884 -25.908)
		(width 0.1397)
		(layer "B.Cu")
		(net "CLK_100M_PCIE_SAS_C_N")
	)
	(arc
		(start 206.017114 -74.547222)
		(mid 206.327874 -74.849896)
		(end 206.761334 -74.867516)
		(width 0.1397)
		(layer "B.Cu")
		(net "CLK_100M_PCIE_SAS_C_N")
	)
	(arc
		(start 131.3307 -5.227828)
		(mid 131.124664 -5.090159)
		(end 130.881628 -5.0419)
		(width 0.1397)
		(layer "B.Cu")
		(net "CLK_100M_PCIE_SAS_C_N")
	)
	(arc
		(start 206.274924 -73.925176)
		(mid 206.084145 -74.210558)
		(end 206.017114 -74.547222)
		(width 0.1397)
		(layer "B.Cu")
		(net "CLK_100M_PCIE_SAS_C_N")
	)
	(arc
		(start 90.607134 -21.16201)
		(mid 90.36413 -21.210346)
		(end 90.158062 -21.347938)
		(width 0.1397)
		(layer "B.Cu")
		(net "CLK_100M_PCIE_SAS_C_N")
	)
	(arc
		(start 87.815928 -23.690072)
		(mid 87.678259 -23.896108)
		(end 87.63 -24.139144)
		(width 0.1397)
		(layer "B.Cu")
		(net "CLK_100M_PCIE_SAS_C_N")
	)
	(arc
		(start 116.633244 -5.0419)
		(mid 116.39024 -5.090236)
		(end 116.184172 -5.227828)
		(width 0.1397)
		(layer "B.Cu")
		(net "CLK_100M_PCIE_SAS_C_N")
	)
	(arc
		(start 200.210928 -65.844928)
		(mid 200.004892 -65.707259)
		(end 199.761856 -65.659)
		(width 0.1397)
		(layer "B.Cu")
		(net "CLK_100M_PCIE_SAS_C_N")
	)
	(arc
		(start 158.451804 -26.551128)
		(mid 158.245768 -26.413459)
		(end 158.002732 -26.3652)
		(width 0.1397)
		(layer "B.Cu")
		(net "CLK_100M_PCIE_SAS_C_N")
	)
	(arc
		(start 104.677464 -9.486392)
		(mid 104.43446 -9.534728)
		(end 104.228392 -9.67232)
		(width 0.1397)
		(layer "B.Cu")
		(net "CLK_100M_PCIE_SAS_C_N")
	)
	(arc
		(start 197.964806 -65.659)
		(mid 197.590497 -65.584527)
		(end 197.273164 -65.372488)
		(width 0.1397)
		(layer "B.Cu")
		(net "CLK_100M_PCIE_SAS_C_N")
	)
	(arc
		(start 93.025214 -20.875498)
		(mid 92.7079 -21.087584)
		(end 92.333572 -21.16201)
		(width 0.1397)
		(layer "B.Cu")
		(net "CLK_100M_PCIE_SAS_C_N")
	)
	(arc
		(start 207.292194 -73.189338)
		(mid 207.243858 -72.946334)
		(end 207.106266 -72.740266)
		(width 0.1397)
		(layer "B.Cu")
		(net "CLK_100M_PCIE_SAS_C_N")
	)
	(via
		(at 138.221212 -247.269)
		(size 0.7112)
		(drill 0.3556)
		(layers "F.Cu" "B.Cu")
		(net "TRAY_ID")
	)
	(segment
		(start 138.221212 -248.793)
		(end 138.221212 -247.269)
		(width 0.127)
		(layer "B.Cu")
		(net "TRAY_ID")
	)
	(segment
		(start 138.000232 -256.50444)
		(end 138.000232 -249.01398)
		(width 0.127)
		(layer "B.Cu")
		(net "TRAY_ID")
	)
	(segment
		(start 138.000232 -249.01398)
		(end 138.221212 -248.793)
		(width 0.127)
		(layer "B.Cu")
		(net "TRAY_ID")
	)
	(segment
		(start 138.221212 -247.269)
		(end 138.221212 -245.9355)
		(width 0.127)
		(layer "B.Cu")
		(net "TRAY_ID")
	)
	(segment
		(start 142.1765 -64.135)
		(end 142.1765 -63.3095)
		(width 0.508)
		(layer "F.Cu")
		(net "P3V3")
	)
	(segment
		(start 202.184 -163.703)
		(end 202.946 -164.465)
		(width 0.508)
		(layer "F.Cu")
		(net "P3V3")
	)
	(segment
		(start 184.9755 -115.697)
		(end 186.055 -115.697)
		(width 0.508)
		(layer "F.Cu")
		(net "P3V3")
	)
	(segment
		(start 79.756 -25.908)
		(end 79.756 -26.035)
		(width 0.508)
		(layer "F.Cu")
		(net "P3V3")
	)
	(segment
		(start 203.073 -166.37)
		(end 204.089 -166.37)
		(width 0.508)
		(layer "F.Cu")
		(net "P3V3")
	)
	(segment
		(start 77.47 -23.1775)
		(end 77.47 -23.622)
		(width 0.508)
		(layer "F.Cu")
		(net "P3V3")
	)
	(segment
		(start 159.5755 -148.336)
		(end 159.5755 -149.479)
		(width 0.508)
		(layer "F.Cu")
		(net "P3V3")
	)
	(segment
		(start 142.1765 -67.183)
		(end 142.1765 -64.135)
		(width 0.508)
		(layer "F.Cu")
		(net "P3V3")
	)
	(segment
		(start 201.9554 -167.645588)
		(end 201.9554 -167.4876)
		(width 0.508)
		(layer "F.Cu")
		(net "P3V3")
	)
	(segment
		(start 158.369 -146.685)
		(end 158.369 -146.431)
		(width 0.508)
		(layer "F.Cu")
		(net "P3V3")
	)
	(segment
		(start 201.516488 -168.0845)
		(end 201.9554 -167.645588)
		(width 0.508)
		(layer "F.Cu")
		(net "P3V3")
	)
	(segment
		(start 142.1765 -63.3095)
		(end 142.113 -63.246)
		(width 0.508)
		(layer "F.Cu")
		(net "P3V3")
	)
	(segment
		(start 303.53 -107.315)
		(end 302.387 -108.458)
		(width 1.016)
		(layer "F.Cu")
		(net "P3V3")
	)
	(segment
		(start 202.946 -166.497)
		(end 203.073 -166.37)
		(width 0.508)
		(layer "F.Cu")
		(net "P3V3")
	)
	(segment
		(start 201.9554 -167.4876)
		(end 202.946 -166.497)
		(width 0.508)
		(layer "F.Cu")
		(net "P3V3")
	)
	(segment
		(start 302.387 -108.458)
		(end 302.387 -116.009928)
		(width 1.016)
		(layer "F.Cu")
		(net "P3V3")
	)
	(segment
		(start 159.5755 -150.292308)
		(end 159.645096 -150.361904)
		(width 0.508)
		(layer "F.Cu")
		(net "P3V3")
	)
	(segment
		(start 142.113 -63.246)
		(end 142.098776 -63.231776)
		(width 0.254)
		(layer "F.Cu")
		(net "P3V3")
	)
	(segment
		(start 159.5755 -149.479)
		(end 159.5755 -150.292308)
		(width 0.508)
		(layer "F.Cu")
		(net "P3V3")
	)
	(segment
		(start 158.75 -147.066)
		(end 158.369 -146.685)
		(width 0.508)
		(layer "F.Cu")
		(net "P3V3")
	)
	(segment
		(start 36.0045 -72.009)
		(end 36.957 -72.009)
		(width 0.508)
		(layer "F.Cu")
		(net "P3V3")
	)
	(segment
		(start 197.9295 -163.703)
		(end 202.184 -163.703)
		(width 0.508)
		(layer "F.Cu")
		(net "P3V3")
	)
	(segment
		(start 142.098776 -63.231776)
		(end 142.098776 -61.9379)
		(width 0.254)
		(layer "F.Cu")
		(net "P3V3")
	)
	(segment
		(start 302.387 -116.009928)
		(end 297.9674 -120.429528)
		(width 1.016)
		(layer "F.Cu")
		(net "P3V3")
	)
	(segment
		(start 201.295 -168.0845)
		(end 201.516488 -168.0845)
		(width 0.508)
		(layer "F.Cu")
		(net "P3V3")
	)
	(segment
		(start 297.9674 -120.429528)
		(end 297.9674 -126.7968)
		(width 1.016)
		(layer "F.Cu")
		(net "P3V3")
	)
	(segment
		(start 202.946 -164.465)
		(end 202.946 -166.497)
		(width 0.508)
		(layer "F.Cu")
		(net "P3V3")
	)
	(segment
		(start 159.5755 -147.066)
		(end 158.75 -147.066)
		(width 0.508)
		(layer "F.Cu")
		(net "P3V3")
	)
	(segment
		(start 77.47 -23.622)
		(end 79.756 -25.908)
		(width 0.508)
		(layer "F.Cu")
		(net "P3V3")
	)
	(via
		(at 304.5714 -57.5564)
		(size 0.7112)
		(drill 0.4064)
		(layers "F.Cu" "B.Cu")
		(net "P3V3")
	)
	(via
		(at 159.645096 -150.361904)
		(size 0.5588)
		(drill 0.3048)
		(layers "F.Cu" "B.Cu")
		(net "P3V3")
	)
	(via
		(at 294.767 -61.468)
		(size 0.7112)
		(drill 0.4064)
		(layers "F.Cu" "B.Cu")
		(net "P3V3")
	)
	(via
		(at 142.1765 -67.183)
		(size 0.508)
		(drill 0.254)
		(layers "F.Cu" "B.Cu")
		(net "P3V3")
	)
	(via
		(at 315.468 -56.769)
		(size 0.7112)
		(drill 0.4064)
		(layers "F.Cu" "B.Cu")
		(net "P3V3")
	)
	(via
		(at 204.089 -166.37)
		(size 0.5588)
		(drill 0.3048)
		(layers "F.Cu" "B.Cu")
		(net "P3V3")
	)
	(via
		(at 121.666 -29.591)
		(size 0.7112)
		(drill 0.3556)
		(layers "F.Cu" "B.Cu")
		(net "P3V3")
	)
	(via
		(at 314.833 -57.785)
		(size 0.7112)
		(drill 0.4064)
		(layers "F.Cu" "B.Cu")
		(net "P3V3")
	)
	(via
		(at 209.169 -141.351)
		(size 0.5588)
		(drill 0.3048)
		(layers "F.Cu" "B.Cu")
		(net "P3V3")
	)
	(via
		(at 130.302 -39.751)
		(size 0.5588)
		(drill 0.3048)
		(layers "F.Cu" "B.Cu")
		(net "P3V3")
	)
	(via
		(at 294.767 -62.611)
		(size 0.7112)
		(drill 0.4064)
		(layers "F.Cu" "B.Cu")
		(net "P3V3")
	)
	(via
		(at 303.5046 -57.5564)
		(size 0.7112)
		(drill 0.4064)
		(layers "F.Cu" "B.Cu")
		(net "P3V3")
	)
	(via
		(at 306.705 -57.15)
		(size 0.7112)
		(drill 0.4064)
		(layers "F.Cu" "B.Cu")
		(net "P3V3")
	)
	(via
		(at 158.369 -146.431)
		(size 0.5588)
		(drill 0.3048)
		(layers "F.Cu" "B.Cu")
		(net "P3V3")
	)
	(via
		(at 119.75592 -26.83764)
		(size 0.508)
		(drill 0.254)
		(layers "F.Cu" "B.Cu")
		(net "P3V3")
	)
	(via
		(at 305.6382 -57.5564)
		(size 0.7112)
		(drill 0.4064)
		(layers "F.Cu" "B.Cu")
		(net "P3V3")
	)
	(via
		(at 315.976 -57.785)
		(size 0.7112)
		(drill 0.4064)
		(layers "F.Cu" "B.Cu")
		(net "P3V3")
	)
	(via
		(at 295.91 -61.468)
		(size 0.7112)
		(drill 0.4064)
		(layers "F.Cu" "B.Cu")
		(net "P3V3")
	)
	(via
		(at 186.055 -115.697)
		(size 0.5588)
		(drill 0.3048)
		(layers "F.Cu" "B.Cu")
		(net "P3V3")
	)
	(via
		(at 159.131 -141.5669)
		(size 0.7112)
		(drill 0.4064)
		(layers "F.Cu" "B.Cu")
		(net "P3V3")
	)
	(via
		(at 36.957 -72.009)
		(size 0.5588)
		(drill 0.3048)
		(layers "F.Cu" "B.Cu")
		(net "P3V3")
	)
	(via
		(at 315.214 -55.626)
		(size 0.7112)
		(drill 0.4064)
		(layers "F.Cu" "B.Cu")
		(net "P3V3")
	)
	(via
		(at 303.53 -107.315)
		(size 0.7112)
		(drill 0.4064)
		(layers "F.Cu" "B.Cu")
		(net "P3V3")
	)
	(via
		(at 297.9674 -126.7968)
		(size 0.7112)
		(drill 0.4064)
		(layers "F.Cu" "B.Cu")
		(net "P3V3")
	)
	(via
		(at 130.3528 -30.8483)
		(size 0.5588)
		(drill 0.3048)
		(layers "F.Cu" "B.Cu")
		(net "P3V3")
	)
	(via
		(at 295.91 -62.611)
		(size 0.7112)
		(drill 0.4064)
		(layers "F.Cu" "B.Cu")
		(net "P3V3")
	)
	(via
		(at 79.756 -26.035)
		(size 0.5588)
		(drill 0.3048)
		(layers "F.Cu" "B.Cu")
		(net "P3V3")
	)
	(segment
		(start 130.728466 -39.324534)
		(end 130.302 -39.751)
		(width 0.508)
		(layer "B.Cu")
		(net "P3V3")
	)
	(segment
		(start 130.144266 -30.8483)
		(end 129.572766 -30.2768)
		(width 0.508)
		(layer "B.Cu")
		(net "P3V3")
	)
	(segment
		(start 151.511 -79.756)
		(end 151.511 -129.667)
		(width 0.508)
		(layer "B.Cu")
		(net "P3V3")
	)
	(segment
		(start 118.917466 -26.416)
		(end 119.265446 -26.76398)
		(width 0.508)
		(layer "B.Cu")
		(net "P3V3")
	)
	(segment
		(start 158.369 -142.3289)
		(end 159.131 -141.5669)
		(width 0.508)
		(layer "B.Cu")
		(net "P3V3")
	)
	(segment
		(start 192.181226 -114.6302)
		(end 187.1218 -114.6302)
		(width 0.508)
		(layer "B.Cu")
		(net "P3V3")
	)
	(segment
		(start 204.089 -166.37)
		(end 209.169 -161.29)
		(width 0.508)
		(layer "B.Cu")
		(net "P3V3")
	)
	(segment
		(start 147.447 -72.136)
		(end 147.447 -74.058272)
		(width 0.508)
		(layer "B.Cu")
		(net "P3V3")
	)
	(segment
		(start 67.3608 -53.5432)
		(end 74.422 -46.482)
		(width 0.508)
		(layer "B.Cu")
		(net "P3V3")
	)
	(segment
		(start 119.68226 -26.76398)
		(end 119.75592 -26.83764)
		(width 0.508)
		(layer "B.Cu")
		(net "P3V3")
	)
	(segment
		(start 122.460766 -30.2768)
		(end 121.774966 -29.591)
		(width 0.508)
		(layer "B.Cu")
		(net "P3V3")
	)
	(segment
		(start 187.1218 -114.6302)
		(end 186.055 -115.697)
		(width 0.508)
		(layer "B.Cu")
		(net "P3V3")
	)
	(segment
		(start 119.75592 -26.83764)
		(end 121.666 -28.74772)
		(width 0.508)
		(layer "B.Cu")
		(net "P3V3")
	)
	(segment
		(start 209.169 -141.351)
		(end 209.169 -135.162544)
		(width 0.508)
		(layer "B.Cu")
		(net "P3V3")
	)
	(segment
		(start 158.369 -146.685)
		(end 158.369 -146.431)
		(width 0.508)
		(layer "B.Cu")
		(net "P3V3")
	)
	(segment
		(start 67.3608 -67.033648)
		(end 67.3608 -53.5432)
		(width 0.508)
		(layer "B.Cu")
		(net "P3V3")
	)
	(segment
		(start 147.447 -74.058272)
		(end 148.191728 -74.803)
		(width 0.508)
		(layer "B.Cu")
		(net "P3V3")
	)
	(segment
		(start 159.645096 -150.361904)
		(end 159.645096 -147.961096)
		(width 0.508)
		(layer "B.Cu")
		(net "P3V3")
	)
	(segment
		(start 61.148214 -73.246234)
		(end 67.3608 -67.033648)
		(width 0.508)
		(layer "B.Cu")
		(net "P3V3")
	)
	(segment
		(start 119.265446 -26.76398)
		(end 119.68226 -26.76398)
		(width 0.508)
		(layer "B.Cu")
		(net "P3V3")
	)
	(segment
		(start 148.191728 -74.803)
		(end 149.813264 -74.803)
		(width 0.508)
		(layer "B.Cu")
		(net "P3V3")
	)
	(segment
		(start 194.945 -117.393974)
		(end 192.181226 -114.6302)
		(width 0.508)
		(layer "B.Cu")
		(net "P3V3")
	)
	(segment
		(start 197.196456 -123.19)
		(end 196.54647 -123.19)
		(width 0.508)
		(layer "B.Cu")
		(net "P3V3")
	)
	(segment
		(start 209.169 -161.29)
		(end 209.169 -141.351)
		(width 0.508)
		(layer "B.Cu")
		(net "P3V3")
	)
	(segment
		(start 36.957 -72.009)
		(end 38.194234 -73.246234)
		(width 0.508)
		(layer "B.Cu")
		(net "P3V3")
	)
	(segment
		(start 121.666 -28.74772)
		(end 121.666 -29.591)
		(width 0.508)
		(layer "B.Cu")
		(net "P3V3")
	)
	(segment
		(start 149.813264 -74.803)
		(end 150.495 -75.484736)
		(width 0.508)
		(layer "B.Cu")
		(net "P3V3")
	)
	(segment
		(start 196.54647 -123.19)
		(end 194.945 -121.58853)
		(width 0.508)
		(layer "B.Cu")
		(net "P3V3")
	)
	(segment
		(start 38.194234 -73.246234)
		(end 61.148214 -73.246234)
		(width 0.508)
		(layer "B.Cu")
		(net "P3V3")
	)
	(segment
		(start 150.495 -75.484736)
		(end 150.495 -78.74)
		(width 0.508)
		(layer "B.Cu")
		(net "P3V3")
	)
	(segment
		(start 209.169 -135.162544)
		(end 197.196456 -123.19)
		(width 0.508)
		(layer "B.Cu")
		(net "P3V3")
	)
	(segment
		(start 159.645096 -147.961096)
		(end 158.369 -146.685)
		(width 0.508)
		(layer "B.Cu")
		(net "P3V3")
	)
	(segment
		(start 194.945 -121.58853)
		(end 194.945 -117.393974)
		(width 0.508)
		(layer "B.Cu")
		(net "P3V3")
	)
	(segment
		(start 74.422 -33.782)
		(end 79.756 -28.448)
		(width 0.508)
		(layer "B.Cu")
		(net "P3V3")
	)
	(segment
		(start 142.1765 -67.183)
		(end 142.494 -67.183)
		(width 0.508)
		(layer "B.Cu")
		(net "P3V3")
	)
	(segment
		(start 121.774966 -29.591)
		(end 121.666 -29.591)
		(width 0.508)
		(layer "B.Cu")
		(net "P3V3")
	)
	(segment
		(start 159.131 -137.287)
		(end 159.131 -141.5669)
		(width 0.508)
		(layer "B.Cu")
		(net "P3V3")
	)
	(segment
		(start 74.422 -46.482)
		(end 74.422 -33.782)
		(width 0.508)
		(layer "B.Cu")
		(net "P3V3")
	)
	(segment
		(start 129.572766 -30.2768)
		(end 122.460766 -30.2768)
		(width 0.508)
		(layer "B.Cu")
		(net "P3V3")
	)
	(segment
		(start 79.756 -28.448)
		(end 79.756 -26.035)
		(width 0.508)
		(layer "B.Cu")
		(net "P3V3")
	)
	(segment
		(start 130.728466 -38.354)
		(end 130.728466 -39.324534)
		(width 0.508)
		(layer "B.Cu")
		(net "P3V3")
	)
	(segment
		(start 158.369 -146.431)
		(end 158.369 -142.3289)
		(width 0.508)
		(layer "B.Cu")
		(net "P3V3")
	)
	(segment
		(start 151.511 -129.667)
		(end 159.131 -137.287)
		(width 0.508)
		(layer "B.Cu")
		(net "P3V3")
	)
	(segment
		(start 142.494 -67.183)
		(end 147.447 -72.136)
		(width 0.508)
		(layer "B.Cu")
		(net "P3V3")
	)
	(segment
		(start 150.495 -78.74)
		(end 151.511 -79.756)
		(width 0.508)
		(layer "B.Cu")
		(net "P3V3")
	)
	(segment
		(start 130.3528 -30.8483)
		(end 130.144266 -30.8483)
		(width 0.508)
		(layer "B.Cu")
		(net "P3V3")
	)
	(segment
		(start 235.483908 -134.086092)
		(end 270.789908 -134.086092)
		(width 1.016)
		(layer "In2.Cu")
		(net "P3V3")
	)
	(segment
		(start 207.364584 -141.7828)
		(end 207.389984 -141.7574)
		(width 1.016)
		(layer "In2.Cu")
		(net "P3V3")
	)
	(segment
		(start 142.113 -63.375032)
		(end 131.807966 -53.069998)
		(width 0.508)
		(layer "In2.Cu")
		(net "P3V3")
	)
	(segment
		(start 308.102 -94.537784)
		(end 306.07 -96.569784)
		(width 1.016)
		(layer "In2.Cu")
		(net "P3V3")
	)
	(segment
		(start 306.07 -106.036872)
		(end 304.791872 -107.315)
		(width 1.016)
		(layer "In2.Cu")
		(net "P3V3")
	)
	(segment
		(start 306.07 -96.569784)
		(end 306.07 -106.036872)
		(width 1.016)
		(layer "In2.Cu")
		(net "P3V3")
	)
	(segment
		(start 184.640982 -141.7828)
		(end 207.364584 -141.7828)
		(width 1.016)
		(layer "In2.Cu")
		(net "P3V3")
	)
	(segment
		(start 209.169 -141.351)
		(end 228.219 -141.351)
		(width 1.016)
		(layer "In2.Cu")
		(net "P3V3")
	)
	(segment
		(start 297.7007 -127.0635)
		(end 297.9674 -126.7968)
		(width 1.016)
		(layer "In2.Cu")
		(net "P3V3")
	)
	(segment
		(start 142.113 -67.1195)
		(end 142.113 -63.375032)
		(width 0.508)
		(layer "In2.Cu")
		(net "P3V3")
	)
	(segment
		(start 296.2275 -127.0635)
		(end 297.7007 -127.0635)
		(width 1.016)
		(layer "In2.Cu")
		(net "P3V3")
	)
	(segment
		(start 270.789908 -134.086092)
		(end 273.812 -131.064)
		(width 1.016)
		(layer "In2.Cu")
		(net "P3V3")
	)
	(segment
		(start 142.1765 -67.183)
		(end 142.113 -67.1195)
		(width 0.508)
		(layer "In2.Cu")
		(net "P3V3")
	)
	(segment
		(start 131.807966 -53.069998)
		(end 131.807966 -41.256966)
		(width 0.508)
		(layer "In2.Cu")
		(net "P3V3")
	)
	(segment
		(start 281.6225 -130.1115)
		(end 293.1795 -130.1115)
		(width 1.016)
		(layer "In2.Cu")
		(net "P3V3")
	)
	(segment
		(start 273.812 -131.064)
		(end 280.67 -131.064)
		(width 1.016)
		(layer "In2.Cu")
		(net "P3V3")
	)
	(segment
		(start 293.1795 -130.1115)
		(end 296.2275 -127.0635)
		(width 1.016)
		(layer "In2.Cu")
		(net "P3V3")
	)
	(segment
		(start 306.578 -61.849)
		(end 308.102 -63.373)
		(width 1.016)
		(layer "In2.Cu")
		(net "P3V3")
	)
	(segment
		(start 308.102 -63.373)
		(end 308.102 -94.537784)
		(width 1.016)
		(layer "In2.Cu")
		(net "P3V3")
	)
	(segment
		(start 131.807966 -41.256966)
		(end 130.302 -39.751)
		(width 0.508)
		(layer "In2.Cu")
		(net "P3V3")
	)
	(segment
		(start 208.7626 -141.7574)
		(end 209.169 -141.351)
		(width 1.016)
		(layer "In2.Cu")
		(net "P3V3")
	)
	(segment
		(start 280.67 -131.064)
		(end 281.6225 -130.1115)
		(width 1.016)
		(layer "In2.Cu")
		(net "P3V3")
	)
	(segment
		(start 159.131 -141.5669)
		(end 184.425082 -141.5669)
		(width 1.016)
		(layer "In2.Cu")
		(net "P3V3")
	)
	(segment
		(start 228.219 -141.351)
		(end 235.483908 -134.086092)
		(width 1.016)
		(layer "In2.Cu")
		(net "P3V3")
	)
	(segment
		(start 304.791872 -107.315)
		(end 303.53 -107.315)
		(width 1.016)
		(layer "In2.Cu")
		(net "P3V3")
	)
	(segment
		(start 184.425082 -141.5669)
		(end 184.640982 -141.7828)
		(width 1.016)
		(layer "In2.Cu")
		(net "P3V3")
	)
	(segment
		(start 207.389984 -141.7574)
		(end 208.7626 -141.7574)
		(width 1.016)
		(layer "In2.Cu")
		(net "P3V3")
	)
	(segment
		(start 79.756 -26.162)
		(end 79.756 -26.035)
		(width 0.508)
		(layer "In5.Cu")
		(net "P3V3")
	)
	(segment
		(start 130.3528 -30.9372)
		(end 130.029966 -31.260034)
		(width 0.508)
		(layer "In5.Cu")
		(net "P3V3")
	)
	(segment
		(start 119.68226 -26.76398)
		(end 118.947946 -26.76398)
		(width 0.508)
		(layer "In5.Cu")
		(net "P3V3")
	)
	(segment
		(start 108.204 -26.15184)
		(end 106.79684 -27.559)
		(width 0.508)
		(layer "In5.Cu")
		(net "P3V3")
	)
	(segment
		(start 118.947946 -26.76398)
		(end 118.335806 -26.15184)
		(width 0.508)
		(layer "In5.Cu")
		(net "P3V3")
	)
	(segment
		(start 130.029966 -31.260034)
		(end 130.029966 -39.326566)
		(width 0.508)
		(layer "In5.Cu")
		(net "P3V3")
	)
	(segment
		(start 81.153 -27.559)
		(end 79.756 -26.162)
		(width 0.508)
		(layer "In5.Cu")
		(net "P3V3")
	)
	(segment
		(start 119.75592 -26.83764)
		(end 119.68226 -26.76398)
		(width 0.508)
		(layer "In5.Cu")
		(net "P3V3")
	)
	(segment
		(start 130.3528 -30.8483)
		(end 130.3528 -30.9372)
		(width 0.508)
		(layer "In5.Cu")
		(net "P3V3")
	)
	(segment
		(start 130.029966 -39.326566)
		(end 130.3782 -39.6748)
		(width 0.508)
		(layer "In5.Cu")
		(net "P3V3")
	)
	(segment
		(start 130.3782 -39.6748)
		(end 130.302 -39.751)
		(width 0.508)
		(layer "In5.Cu")
		(net "P3V3")
	)
	(segment
		(start 118.335806 -26.15184)
		(end 108.204 -26.15184)
		(width 0.508)
		(layer "In5.Cu")
		(net "P3V3")
	)
	(segment
		(start 106.79684 -27.559)
		(end 81.153 -27.559)
		(width 0.508)
		(layer "In5.Cu")
		(net "P3V3")
	)
	(segment
		(start 115.880896 -15.967964)
		(end 119.751348 -12.097512)
		(width 0.1397)
		(layer "B.Cu")
		(net "PCIE_SAS_CPU_RX_P3")
	)
	(segment
		(start 97.99066 -31.227522)
		(end 97.99066 -25.745186)
		(width 0.1397)
		(layer "B.Cu")
		(net "PCIE_SAS_CPU_RX_P3")
	)
	(segment
		(start 107.581954 -16.153892)
		(end 115.431824 -16.153892)
		(width 0.1397)
		(layer "B.Cu")
		(net "PCIE_SAS_CPU_RX_P3")
	)
	(segment
		(start 128.665224 -12.097512)
		(end 149.414484 -32.846772)
		(width 0.1397)
		(layer "B.Cu")
		(net "PCIE_SAS_CPU_RX_P3")
	)
	(segment
		(start 97.92716 -31.3436)
		(end 97.953576 -31.317184)
		(width 0.1397)
		(layer "B.Cu")
		(net "PCIE_SAS_CPU_RX_P3")
	)
	(segment
		(start 191.478662 -74.840592)
		(end 191.379602 -74.939398)
		(width 0.1397)
		(layer "B.Cu")
		(net "PCIE_SAS_CPU_RX_P3")
	)
	(segment
		(start 191.379602 -75.680316)
		(end 191.449706 -75.75042)
		(width 0.1397)
		(layer "B.Cu")
		(net "PCIE_SAS_CPU_RX_P3")
	)
	(segment
		(start 120.44299 -11.811)
		(end 127.973582 -11.811)
		(width 0.1397)
		(layer "B.Cu")
		(net "PCIE_SAS_CPU_RX_P3")
	)
	(segment
		(start 149.863556 -33.0327)
		(end 154.558238 -33.0327)
		(width 0.1397)
		(layer "B.Cu")
		(net "PCIE_SAS_CPU_RX_P3")
	)
	(segment
		(start 98.277172 -25.053544)
		(end 106.890312 -16.440404)
		(width 0.1397)
		(layer "B.Cu")
		(net "PCIE_SAS_CPU_RX_P3")
	)
	(segment
		(start 191.65189 -70.126352)
		(end 191.65189 -74.422)
		(width 0.1397)
		(layer "B.Cu")
		(net "PCIE_SAS_CPU_RX_P3")
	)
	(segment
		(start 155.24988 -33.319212)
		(end 191.365378 -69.43471)
		(width 0.1397)
		(layer "B.Cu")
		(net "PCIE_SAS_CPU_RX_P3")
	)
	(arc
		(start 191.365378 -69.43471)
		(mid 191.577464 -69.752024)
		(end 191.65189 -70.126352)
		(width 0.1397)
		(layer "B.Cu")
		(net "PCIE_SAS_CPU_RX_P3")
	)
	(arc
		(start 119.751348 -12.097512)
		(mid 120.068662 -11.885426)
		(end 120.44299 -11.811)
		(width 0.1397)
		(layer "B.Cu")
		(net "PCIE_SAS_CPU_RX_P3")
	)
	(arc
		(start 115.431824 -16.153892)
		(mid 115.674828 -16.105556)
		(end 115.880896 -15.967964)
		(width 0.1397)
		(layer "B.Cu")
		(net "PCIE_SAS_CPU_RX_P3")
	)
	(arc
		(start 106.890312 -16.440404)
		(mid 107.207626 -16.228318)
		(end 107.581954 -16.153892)
		(width 0.1397)
		(layer "B.Cu")
		(net "PCIE_SAS_CPU_RX_P3")
	)
	(arc
		(start 149.414484 -32.846772)
		(mid 149.62052 -32.984441)
		(end 149.863556 -33.0327)
		(width 0.1397)
		(layer "B.Cu")
		(net "PCIE_SAS_CPU_RX_P3")
	)
	(arc
		(start 191.65189 -74.422)
		(mid 191.606923 -74.648533)
		(end 191.478662 -74.840592)
		(width 0.1397)
		(layer "B.Cu")
		(net "PCIE_SAS_CPU_RX_P3")
	)
	(arc
		(start 97.953576 -31.317184)
		(mid 97.981009 -31.276033)
		(end 97.99066 -31.227522)
		(width 0.1397)
		(layer "B.Cu")
		(net "PCIE_SAS_CPU_RX_P3")
	)
	(arc
		(start 191.379602 -74.939398)
		(mid 191.2261 -75.309894)
		(end 191.379602 -75.680316)
		(width 0.1397)
		(layer "B.Cu")
		(net "PCIE_SAS_CPU_RX_P3")
	)
	(arc
		(start 154.558238 -33.0327)
		(mid 154.932547 -33.107173)
		(end 155.24988 -33.319212)
		(width 0.1397)
		(layer "B.Cu")
		(net "PCIE_SAS_CPU_RX_P3")
	)
	(arc
		(start 127.973582 -11.811)
		(mid 128.347891 -11.885473)
		(end 128.665224 -12.097512)
		(width 0.1397)
		(layer "B.Cu")
		(net "PCIE_SAS_CPU_RX_P3")
	)
	(arc
		(start 97.99066 -25.745186)
		(mid 98.065133 -25.370877)
		(end 98.277172 -25.053544)
		(width 0.1397)
		(layer "B.Cu")
		(net "PCIE_SAS_CPU_RX_P3")
	)
	(segment
		(start 340.614 -112.413288)
		(end 340.614 -113.157)
		(width 0.254)
		(layer "F.Cu")
		(net "P5V_STBY_SS")
	)
	(segment
		(start 340.36 -113.411)
		(end 340.36 -113.792)
		(width 0.254)
		(layer "F.Cu")
		(net "P5V_STBY_SS")
	)
	(segment
		(start 340.4235 -114.808)
		(end 340.4235 -113.9825)
		(width 0.254)
		(layer "F.Cu")
		(net "P5V_STBY_SS")
	)
	(segment
		(start 340.4235 -113.9825)
		(end 340.36 -113.919)
		(width 0.254)
		(layer "F.Cu")
		(net "P5V_STBY_SS")
	)
	(segment
		(start 340.36 -113.919)
		(end 340.36 -113.792)
		(width 0.254)
		(layer "F.Cu")
		(net "P5V_STBY_SS")
	)
	(segment
		(start 340.618064 -112.409224)
		(end 340.614 -112.413288)
		(width 0.254)
		(layer "F.Cu")
		(net "P5V_STBY_SS")
	)
	(segment
		(start 340.614 -113.157)
		(end 340.36 -113.411)
		(width 0.254)
		(layer "F.Cu")
		(net "P5V_STBY_SS")
	)
	(via
		(at 340.36 -113.792)
		(size 0.7112)
		(drill 0.3556)
		(layers "F.Cu" "B.Cu")
		(net "P5V_STBY_SS")
	)
	(segment
		(start 267.568426 -177.566574)
		(end 267.335 -177.8)
		(width 0.1143)
		(layer "F.Cu")
		(net "ROMA17")
	)
	(segment
		(start 266.5095 -178.054)
		(end 267.081 -178.054)
		(width 0.1143)
		(layer "F.Cu")
		(net "ROMA17")
	)
	(segment
		(start 267.081 -178.054)
		(end 267.335 -177.8)
		(width 0.1143)
		(layer "F.Cu")
		(net "ROMA17")
	)
	(segment
		(start 268.675104 -177.566574)
		(end 267.568426 -177.566574)
		(width 0.1143)
		(layer "F.Cu")
		(net "ROMA17")
	)
	(segment
		(start 288.034984 -177.040032)
		(end 287.63976 -177.435256)
		(width 0.1143)
		(layer "F.Cu")
		(net "ROMA17")
	)
	(via
		(at 268.675104 -177.566574)
		(size 0.7112)
		(drill 0.3556)
		(layers "F.Cu" "B.Cu")
		(net "ROMA17")
	)
	(via
		(at 287.63976 -177.435256)
		(size 0.508)
		(drill 0.254)
		(layers "F.Cu" "B.Cu")
		(net "ROMA17")
	)
	(via
		(at 267.335 -177.8)
		(size 0.5588)
		(drill 0.3048)
		(layers "F.Cu" "B.Cu")
		(net "ROMA17")
	)
	(segment
		(start 271.428464 -177.770536)
		(end 272.236184 -176.962816)
		(width 0.127)
		(layer "In2.Cu")
		(net "ROMA17")
	)
	(segment
		(start 277.436326 -176.962816)
		(end 277.5458 -177.07229)
		(width 0.127)
		(layer "In2.Cu")
		(net "ROMA17")
	)
	(segment
		(start 287.158176 -177.016156)
		(end 287.577276 -177.435256)
		(width 0.127)
		(layer "In2.Cu")
		(net "ROMA17")
	)
	(segment
		(start 287.577276 -177.435256)
		(end 287.63976 -177.435256)
		(width 0.127)
		(layer "In2.Cu")
		(net "ROMA17")
	)
	(segment
		(start 272.236184 -176.962816)
		(end 277.436326 -176.962816)
		(width 0.127)
		(layer "In2.Cu")
		(net "ROMA17")
	)
	(segment
		(start 286.60979 -177.07229)
		(end 286.665924 -177.016156)
		(width 0.127)
		(layer "In2.Cu")
		(net "ROMA17")
	)
	(segment
		(start 267.335 -177.8)
		(end 267.335 -177.795936)
		(width 0.127)
		(layer "In2.Cu")
		(net "ROMA17")
	)
	(segment
		(start 277.5458 -177.07229)
		(end 286.60979 -177.07229)
		(width 0.127)
		(layer "In2.Cu")
		(net "ROMA17")
	)
	(segment
		(start 267.3604 -177.770536)
		(end 271.428464 -177.770536)
		(width 0.127)
		(layer "In2.Cu")
		(net "ROMA17")
	)
	(segment
		(start 267.335 -177.795936)
		(end 267.3604 -177.770536)
		(width 0.127)
		(layer "In2.Cu")
		(net "ROMA17")
	)
	(segment
		(start 286.665924 -177.016156)
		(end 287.158176 -177.016156)
		(width 0.127)
		(layer "In2.Cu")
		(net "ROMA17")
	)
	(segment
		(start 21.2852 -243.2812)
		(end 12.105386 -243.2812)
		(width 0.1143)
		(layer "F.Cu")
		(net "SAS_SEB_PEER_PRSNT")
	)
	(segment
		(start 12.105386 -243.2812)
		(end 6.427216 -237.60303)
		(width 0.1143)
		(layer "F.Cu")
		(net "SAS_SEB_PEER_PRSNT")
	)
	(segment
		(start 6.427216 -228.40188)
		(end 6.427216 -227.06838)
		(width 0.1143)
		(layer "F.Cu")
		(net "SAS_SEB_PEER_PRSNT")
	)
	(segment
		(start 27.999436 -256.25044)
		(end 27.999436 -249.995436)
		(width 0.1143)
		(layer "F.Cu")
		(net "SAS_SEB_PEER_PRSNT")
	)
	(segment
		(start 6.427216 -237.60303)
		(end 6.427216 -228.40188)
		(width 0.1143)
		(layer "F.Cu")
		(net "SAS_SEB_PEER_PRSNT")
	)
	(segment
		(start 27.999436 -249.995436)
		(end 21.2852 -243.2812)
		(width 0.1143)
		(layer "F.Cu")
		(net "SAS_SEB_PEER_PRSNT")
	)
	(via
		(at 6.427216 -228.40188)
		(size 0.7112)
		(drill 0.3556)
		(layers "F.Cu" "B.Cu")
		(net "SAS_SEB_PEER_PRSNT")
	)
	(segment
		(start 200.28916 -75.55357)
		(end 200.28916 -76.198984)
		(width 0.1397)
		(layer "F.Cu")
		(net "PCIE_SAS_CPU_TX_N1")
	)
	(segment
		(start 200.288906 -75.553824)
		(end 200.28916 -75.55357)
		(width 0.1397)
		(layer "F.Cu")
		(net "PCIE_SAS_CPU_TX_N1")
	)
	(segment
		(start 96.350074 -34.19983)
		(end 96.547178 -34.002726)
		(width 0.1397)
		(layer "F.Cu")
		(net "PCIE_SAS_CPU_TX_N1")
	)
	(segment
		(start 199.482202 -74.493882)
		(end 200.11009 -75.12177)
		(width 0.1397)
		(layer "F.Cu")
		(net "PCIE_SAS_CPU_TX_N1")
	)
	(segment
		(start 96.324928 -31.8008)
		(end 95.432372 -30.90799)
		(width 0.1397)
		(layer "F.Cu")
		(net "PCIE_SAS_CPU_TX_N1")
	)
	(segment
		(start 95.060516 -30.0101)
		(end 95.060516 -23.702518)
		(width 0.1397)
		(layer "F.Cu")
		(net "PCIE_SAS_CPU_TX_N1")
	)
	(segment
		(start 105.292144 -13.208)
		(end 109.19587 -13.208)
		(width 0.1397)
		(layer "F.Cu")
		(net "PCIE_SAS_CPU_TX_N1")
	)
	(segment
		(start 199.29475 -73.406)
		(end 199.29475 -74.041)
		(width 0.1397)
		(layer "F.Cu")
		(net "PCIE_SAS_CPU_TX_N1")
	)
	(segment
		(start 141.1986 -11.310874)
		(end 141.1986 -16.45158)
		(width 0.1397)
		(layer "F.Cu")
		(net "PCIE_SAS_CPU_TX_N1")
	)
	(segment
		(start 95.432372 -22.804628)
		(end 104.843072 -13.393928)
		(width 0.1397)
		(layer "F.Cu")
		(net "PCIE_SAS_CPU_TX_N1")
	)
	(segment
		(start 109.887512 -12.921488)
		(end 117.200172 -5.608828)
		(width 0.1397)
		(layer "F.Cu")
		(net "PCIE_SAS_CPU_TX_N1")
	)
	(segment
		(start 141.670786 -17.591786)
		(end 185.349388 -61.270388)
		(width 0.1397)
		(layer "F.Cu")
		(net "PCIE_SAS_CPU_TX_N1")
	)
	(segment
		(start 136.162288 -5.608828)
		(end 140.72743 -10.17397)
		(width 0.1397)
		(layer "F.Cu")
		(net "PCIE_SAS_CPU_TX_N1")
	)
	(segment
		(start 186.04103 -61.5569)
		(end 187.554616 -61.5569)
		(width 0.1397)
		(layer "F.Cu")
		(net "PCIE_SAS_CPU_TX_N1")
	)
	(segment
		(start 117.649244 -5.4229)
		(end 135.713216 -5.4229)
		(width 0.1397)
		(layer "F.Cu")
		(net "PCIE_SAS_CPU_TX_N1")
	)
	(segment
		(start 96.724724 -33.574228)
		(end 96.724724 -32.765746)
		(width 0.1397)
		(layer "F.Cu")
		(net "PCIE_SAS_CPU_TX_N1")
	)
	(segment
		(start 188.003688 -61.742828)
		(end 199.031606 -72.770746)
		(width 0.1397)
		(layer "F.Cu")
		(net "PCIE_SAS_CPU_TX_N1")
	)
	(via
		(at 199.946768 -77.0255)
		(size 0.5588)
		(drill 0.3048)
		(layers "F.Cu" "B.Cu")
		(net "PCIE_SAS_CPU_TX_N1")
	)
	(arc
		(start 200.11009 -75.12177)
		(mid 200.242459 -75.320013)
		(end 200.288906 -75.553824)
		(width 0.1397)
		(layer "F.Cu")
		(net "PCIE_SAS_CPU_TX_N1")
	)
	(arc
		(start 187.554616 -61.5569)
		(mid 187.79762 -61.605236)
		(end 188.003688 -61.742828)
		(width 0.1397)
		(layer "F.Cu")
		(net "PCIE_SAS_CPU_TX_N1")
	)
	(arc
		(start 185.349388 -61.270388)
		(mid 185.666702 -61.482474)
		(end 186.04103 -61.5569)
		(width 0.1397)
		(layer "F.Cu")
		(net "PCIE_SAS_CPU_TX_N1")
	)
	(arc
		(start 199.031606 -72.770746)
		(mid 199.226351 -73.062203)
		(end 199.29475 -73.406)
		(width 0.1397)
		(layer "F.Cu")
		(net "PCIE_SAS_CPU_TX_N1")
	)
	(arc
		(start 95.432372 -30.90799)
		(mid 95.157166 -30.49602)
		(end 95.060516 -30.0101)
		(width 0.1397)
		(layer "F.Cu")
		(net "PCIE_SAS_CPU_TX_N1")
	)
	(arc
		(start 104.843072 -13.393928)
		(mid 105.049108 -13.256259)
		(end 105.292144 -13.208)
		(width 0.1397)
		(layer "F.Cu")
		(net "PCIE_SAS_CPU_TX_N1")
	)
	(arc
		(start 96.547178 -34.002726)
		(mid 96.678593 -33.806144)
		(end 96.724724 -33.574228)
		(width 0.1397)
		(layer "F.Cu")
		(net "PCIE_SAS_CPU_TX_N1")
	)
	(arc
		(start 109.19587 -13.208)
		(mid 109.570179 -13.133527)
		(end 109.887512 -12.921488)
		(width 0.1397)
		(layer "F.Cu")
		(net "PCIE_SAS_CPU_TX_N1")
	)
	(arc
		(start 135.713216 -5.4229)
		(mid 135.95622 -5.471236)
		(end 136.162288 -5.608828)
		(width 0.1397)
		(layer "F.Cu")
		(net "PCIE_SAS_CPU_TX_N1")
	)
	(arc
		(start 199.29475 -74.041)
		(mid 199.34341 -74.286099)
		(end 199.482202 -74.493882)
		(width 0.1397)
		(layer "F.Cu")
		(net "PCIE_SAS_CPU_TX_N1")
	)
	(arc
		(start 117.200172 -5.608828)
		(mid 117.406208 -5.471159)
		(end 117.649244 -5.4229)
		(width 0.1397)
		(layer "F.Cu")
		(net "PCIE_SAS_CPU_TX_N1")
	)
	(arc
		(start 200.28916 -76.198984)
		(mid 200.200182 -76.646306)
		(end 199.946768 -77.0255)
		(width 0.1397)
		(layer "F.Cu")
		(net "PCIE_SAS_CPU_TX_N1")
	)
	(arc
		(start 140.72743 -10.17397)
		(mid 141.076075 -10.69557)
		(end 141.1986 -11.310874)
		(width 0.1397)
		(layer "F.Cu")
		(net "PCIE_SAS_CPU_TX_N1")
	)
	(arc
		(start 95.060516 -23.702518)
		(mid 95.157155 -23.216593)
		(end 95.432372 -22.804628)
		(width 0.1397)
		(layer "F.Cu")
		(net "PCIE_SAS_CPU_TX_N1")
	)
	(arc
		(start 141.1986 -16.45158)
		(mid 141.321306 -17.068644)
		(end 141.670786 -17.591786)
		(width 0.1397)
		(layer "F.Cu")
		(net "PCIE_SAS_CPU_TX_N1")
	)
	(arc
		(start 96.724724 -32.765746)
		(mid 96.620771 -32.243521)
		(end 96.324928 -31.8008)
		(width 0.1397)
		(layer "F.Cu")
		(net "PCIE_SAS_CPU_TX_N1")
	)
	(segment
		(start 200.748646 -79.34071)
		(end 200.748646 -79.340964)
		(width 0.1397)
		(layer "B.Cu")
		(net "PCIE_SAS_CPU_TX_N1")
	)
	(segment
		(start 200.748138 -79.340202)
		(end 200.57999 -79.256128)
		(width 0.1397)
		(layer "B.Cu")
		(net "PCIE_SAS_CPU_TX_N1")
	)
	(segment
		(start 200.749154 -79.340964)
		(end 200.748646 -79.34071)
		(width 0.1397)
		(layer "B.Cu")
		(net "PCIE_SAS_CPU_TX_N1")
	)
	(segment
		(start 200.26122 -78.553564)
		(end 200.26122 -77.44206)
		(width 0.1397)
		(layer "B.Cu")
		(net "PCIE_SAS_CPU_TX_N1")
	)
	(segment
		(start 200.450196 -80.25003)
		(end 200.811638 -79.528416)
		(width 0.1397)
		(layer "B.Cu")
		(net "PCIE_SAS_CPU_TX_N1")
	)
	(segment
		(start 200.189084 -77.267562)
		(end 199.946768 -77.0255)
		(width 0.1397)
		(layer "B.Cu")
		(net "PCIE_SAS_CPU_TX_N1")
	)
	(segment
		(start 200.749408 -79.340964)
		(end 200.749154 -79.340964)
		(width 0.1397)
		(layer "B.Cu")
		(net "PCIE_SAS_CPU_TX_N1")
	)
	(arc
		(start 200.811638 -79.528416)
		(mid 200.819254 -79.421857)
		(end 200.749408 -79.340964)
		(width 0.1397)
		(layer "B.Cu")
		(net "PCIE_SAS_CPU_TX_N1")
	)
	(arc
		(start 200.57999 -79.256128)
		(mid 200.344701 -78.939287)
		(end 200.26122 -78.553564)
		(width 0.1397)
		(layer "B.Cu")
		(net "PCIE_SAS_CPU_TX_N1")
	)
	(arc
		(start 200.748646 -79.340964)
		(mid 200.748392 -79.340583)
		(end 200.748138 -79.340202)
		(width 0.1397)
		(layer "B.Cu")
		(net "PCIE_SAS_CPU_TX_N1")
	)
	(arc
		(start 200.26122 -77.44206)
		(mid 200.242529 -77.347624)
		(end 200.189084 -77.267562)
		(width 0.1397)
		(layer "B.Cu")
		(net "PCIE_SAS_CPU_TX_N1")
	)
	(segment
		(start 341.618062 -112.891062)
		(end 342.519 -113.792)
		(width 0.254)
		(layer "F.Cu")
		(net "P5V_STBY_VFB")
	)
	(segment
		(start 342.519508 -114.808)
		(end 342.256872 -115.070636)
		(width 0.254)
		(layer "F.Cu")
		(net "P5V_STBY_VFB")
	)
	(segment
		(start 343.9795 -115.824)
		(end 343.9795 -114.808)
		(width 0.254)
		(layer "F.Cu")
		(net "P5V_STBY_VFB")
	)
	(segment
		(start 342.519 -114.029744)
		(end 342.256872 -114.291872)
		(width 0.254)
		(layer "F.Cu")
		(net "P5V_STBY_VFB")
	)
	(segment
		(start 343.9795 -115.824)
		(end 343.2175 -115.824)
		(width 0.254)
		(layer "F.Cu")
		(net "P5V_STBY_VFB")
	)
	(segment
		(start 342.256872 -114.291872)
		(end 342.256872 -115.070636)
		(width 0.254)
		(layer "F.Cu")
		(net "P5V_STBY_VFB")
	)
	(segment
		(start 341.618062 -112.421924)
		(end 341.618062 -112.891062)
		(width 0.254)
		(layer "F.Cu")
		(net "P5V_STBY_VFB")
	)
	(segment
		(start 342.519 -113.792)
		(end 342.519 -114.029744)
		(width 0.254)
		(layer "F.Cu")
		(net "P5V_STBY_VFB")
	)
	(segment
		(start 343.2175 -115.824)
		(end 343.154 -115.7605)
		(width 0.254)
		(layer "F.Cu")
		(net "P5V_STBY_VFB")
	)
	(segment
		(start 343.9795 -114.808)
		(end 342.519508 -114.808)
		(width 0.254)
		(layer "F.Cu")
		(net "P5V_STBY_VFB")
	)
	(via
		(at 343.154 -115.7605)
		(size 0.5588)
		(drill 0.3048)
		(layers "F.Cu" "B.Cu")
		(net "P5V_STBY_VFB")
	)
	(via
		(at 343.154 -114.808)
		(size 0.7112)
		(drill 0.3556)
		(layers "F.Cu" "B.Cu")
		(net "P5V_STBY_VFB")
	)
	(segment
		(start 344.043 -115.7605)
		(end 343.154 -115.7605)
		(width 0.254)
		(layer "B.Cu")
		(net "P5V_STBY_VFB")
	)
	(segment
		(start 343.154 -114.808)
		(end 343.154 -115.7605)
		(width 0.254)
		(layer "B.Cu")
		(net "P5V_STBY_VFB")
	)
	(segment
		(start 344.1065 -115.824)
		(end 344.043 -115.7605)
		(width 0.254)
		(layer "B.Cu")
		(net "P5V_STBY_VFB")
	)
	(segment
		(start 332.976474 -172.905674)
		(end 333.1718 -173.101)
		(width 0.1143)
		(layer "F.Cu")
		(net "BMC_TXD5")
	)
	(segment
		(start 331.372972 -172.530516)
		(end 332.271116 -172.530516)
		(width 0.1143)
		(layer "F.Cu")
		(net "BMC_TXD5")
	)
	(segment
		(start 332.271116 -172.530516)
		(end 332.646274 -172.905674)
		(width 0.1143)
		(layer "F.Cu")
		(net "BMC_TXD5")
	)
	(segment
		(start 333.6798 -172.593)
		(end 333.1718 -173.101)
		(width 0.1143)
		(layer "F.Cu")
		(net "BMC_TXD5")
	)
	(segment
		(start 332.646274 -172.905674)
		(end 332.976474 -172.905674)
		(width 0.1143)
		(layer "F.Cu")
		(net "BMC_TXD5")
	)
	(segment
		(start 47.5742 -115.2017)
		(end 47.5742 -116.1542)
		(width 0.1143)
		(layer "F.Cu")
		(net "BMC_TXD5")
	)
	(segment
		(start 333.883 -172.593)
		(end 333.6798 -172.593)
		(width 0.1143)
		(layer "F.Cu")
		(net "BMC_TXD5")
	)
	(via
		(at 321.945 -173.959012)
		(size 0.5588)
		(drill 0.3048)
		(layers "F.Cu" "B.Cu")
		(net "BMC_TXD5")
	)
	(via
		(at 252.14326 -118.5545)
		(size 0.5588)
		(drill 0.3048)
		(layers "F.Cu" "B.Cu")
		(net "BMC_TXD5")
	)
	(via
		(at 333.883 -172.593)
		(size 0.7112)
		(drill 0.3556)
		(layers "F.Cu" "B.Cu")
		(net "BMC_TXD5")
	)
	(via
		(at 246.5705 -178.562)
		(size 0.5588)
		(drill 0.3048)
		(layers "F.Cu" "B.Cu")
		(net "BMC_TXD5")
	)
	(via
		(at 47.5742 -116.1542)
		(size 0.5588)
		(drill 0.3048)
		(layers "F.Cu" "B.Cu")
		(net "BMC_TXD5")
	)
	(via
		(at 333.1718 -173.101)
		(size 0.5588)
		(drill 0.3048)
		(layers "F.Cu" "B.Cu")
		(net "BMC_TXD5")
	)
	(via
		(at 321.691 -156.845)
		(size 0.5588)
		(drill 0.3048)
		(layers "F.Cu" "B.Cu")
		(net "BMC_TXD5")
	)
	(segment
		(start 318.819276 -131.56565)
		(end 321.98945 -134.735824)
		(width 0.1143)
		(layer "B.Cu")
		(net "BMC_TXD5")
	)
	(segment
		(start 321.691 -151.864822)
		(end 321.691 -156.845)
		(width 0.1143)
		(layer "B.Cu")
		(net "BMC_TXD5")
	)
	(segment
		(start 320.167 -175.641)
		(end 321.848988 -173.959012)
		(width 0.1143)
		(layer "B.Cu")
		(net "BMC_TXD5")
	)
	(segment
		(start 295.245282 -120.26265)
		(end 305.612292 -120.26265)
		(width 0.1143)
		(layer "B.Cu")
		(net "BMC_TXD5")
	)
	(segment
		(start 321.98945 -141.352778)
		(end 321.5005 -141.841728)
		(width 0.1143)
		(layer "B.Cu")
		(net "BMC_TXD5")
	)
	(segment
		(start 294.984932 -120.523)
		(end 295.245282 -120.26265)
		(width 0.1143)
		(layer "B.Cu")
		(net "BMC_TXD5")
	)
	(segment
		(start 325.674228 -173.99)
		(end 325.871078 -174.18685)
		(width 0.1143)
		(layer "B.Cu")
		(net "BMC_TXD5")
	)
	(segment
		(start 321.5005 -151.674322)
		(end 321.691 -151.864822)
		(width 0.1143)
		(layer "B.Cu")
		(net "BMC_TXD5")
	)
	(segment
		(start 252.70841 -119.11965)
		(end 272.194782 -119.11965)
		(width 0.1143)
		(layer "B.Cu")
		(net "BMC_TXD5")
	)
	(segment
		(start 321.98945 -134.735824)
		(end 321.98945 -141.352778)
		(width 0.1143)
		(layer "B.Cu")
		(net "BMC_TXD5")
	)
	(segment
		(start 273.598132 -120.523)
		(end 294.984932 -120.523)
		(width 0.1143)
		(layer "B.Cu")
		(net "BMC_TXD5")
	)
	(segment
		(start 324.594728 -173.99)
		(end 325.674228 -173.99)
		(width 0.1143)
		(layer "B.Cu")
		(net "BMC_TXD5")
	)
	(segment
		(start 321.848988 -173.959012)
		(end 321.945 -173.959012)
		(width 0.1143)
		(layer "B.Cu")
		(net "BMC_TXD5")
	)
	(segment
		(start 325.954898 -174.244)
		(end 332.0288 -174.244)
		(width 0.1143)
		(layer "B.Cu")
		(net "BMC_TXD5")
	)
	(segment
		(start 321.5005 -141.841728)
		(end 321.5005 -151.674322)
		(width 0.1143)
		(layer "B.Cu")
		(net "BMC_TXD5")
	)
	(segment
		(start 272.194782 -119.11965)
		(end 273.598132 -120.523)
		(width 0.1143)
		(layer "B.Cu")
		(net "BMC_TXD5")
	)
	(segment
		(start 305.612292 -120.26265)
		(end 316.915292 -131.56565)
		(width 0.1143)
		(layer "B.Cu")
		(net "BMC_TXD5")
	)
	(segment
		(start 318.4525 -175.641)
		(end 320.167 -175.641)
		(width 0.1143)
		(layer "B.Cu")
		(net "BMC_TXD5")
	)
	(segment
		(start 252.14326 -118.5545)
		(end 252.70841 -119.11965)
		(width 0.1143)
		(layer "B.Cu")
		(net "BMC_TXD5")
	)
	(segment
		(start 332.0288 -174.244)
		(end 333.1718 -173.101)
		(width 0.1143)
		(layer "B.Cu")
		(net "BMC_TXD5")
	)
	(segment
		(start 324.56374 -173.959012)
		(end 324.594728 -173.99)
		(width 0.1143)
		(layer "B.Cu")
		(net "BMC_TXD5")
	)
	(segment
		(start 325.897748 -174.18685)
		(end 325.954898 -174.244)
		(width 0.1143)
		(layer "B.Cu")
		(net "BMC_TXD5")
	)
	(segment
		(start 321.945 -173.959012)
		(end 324.56374 -173.959012)
		(width 0.1143)
		(layer "B.Cu")
		(net "BMC_TXD5")
	)
	(segment
		(start 316.915292 -131.56565)
		(end 318.819276 -131.56565)
		(width 0.1143)
		(layer "B.Cu")
		(net "BMC_TXD5")
	)
	(segment
		(start 325.871078 -174.18685)
		(end 325.897748 -174.18685)
		(width 0.1143)
		(layer "B.Cu")
		(net "BMC_TXD5")
	)
	(segment
		(start 69.6087 -170.7007)
		(end 72.136 -173.228)
		(width 0.127)
		(layer "In2.Cu")
		(net "BMC_TXD5")
	)
	(segment
		(start 322.072 -163.703)
		(end 322.77177 -164.40277)
		(width 0.127)
		(layer "In2.Cu")
		(net "BMC_TXD5")
	)
	(segment
		(start 322.77177 -167.132762)
		(end 321.375532 -168.529)
		(width 0.127)
		(layer "In2.Cu")
		(net "BMC_TXD5")
	)
	(segment
		(start 321.691 -156.845)
		(end 322.072 -157.226)
		(width 0.127)
		(layer "In2.Cu")
		(net "BMC_TXD5")
	)
	(segment
		(start 322.072 -157.226)
		(end 322.072 -163.703)
		(width 0.127)
		(layer "In2.Cu")
		(net "BMC_TXD5")
	)
	(segment
		(start 35.872928 -141.536928)
		(end 37.0713 -142.7353)
		(width 0.127)
		(layer "In2.Cu")
		(net "BMC_TXD5")
	)
	(segment
		(start 197.4977 -181.7497)
		(end 205.6003 -181.7497)
		(width 0.127)
		(layer "In2.Cu")
		(net "BMC_TXD5")
	)
	(segment
		(start 172.096938 -181.3052)
		(end 197.0532 -181.3052)
		(width 0.127)
		(layer "In2.Cu")
		(net "BMC_TXD5")
	)
	(segment
		(start 47.5742 -116.1542)
		(end 47.117 -115.697)
		(width 0.127)
		(layer "In2.Cu")
		(net "BMC_TXD5")
	)
	(segment
		(start 321.375532 -168.529)
		(end 321.280282 -168.529)
		(width 0.127)
		(layer "In2.Cu")
		(net "BMC_TXD5")
	)
	(segment
		(start 164.019738 -173.228)
		(end 172.096938 -181.3052)
		(width 0.127)
		(layer "In2.Cu")
		(net "BMC_TXD5")
	)
	(segment
		(start 37.0713 -153.724864)
		(end 54.047136 -170.7007)
		(width 0.127)
		(layer "In2.Cu")
		(net "BMC_TXD5")
	)
	(segment
		(start 37.0713 -142.7353)
		(end 37.0713 -153.724864)
		(width 0.127)
		(layer "In2.Cu")
		(net "BMC_TXD5")
	)
	(segment
		(start 320.59118 -173.959012)
		(end 321.945 -173.959012)
		(width 0.127)
		(layer "In2.Cu")
		(net "BMC_TXD5")
	)
	(segment
		(start 319.204848 -170.604434)
		(end 319.204848 -172.57268)
		(width 0.127)
		(layer "In2.Cu")
		(net "BMC_TXD5")
	)
	(segment
		(start 38.481 -115.697)
		(end 35.872928 -118.305072)
		(width 0.127)
		(layer "In2.Cu")
		(net "BMC_TXD5")
	)
	(segment
		(start 321.280282 -168.529)
		(end 319.204848 -170.604434)
		(width 0.127)
		(layer "In2.Cu")
		(net "BMC_TXD5")
	)
	(segment
		(start 72.136 -173.228)
		(end 164.019738 -173.228)
		(width 0.127)
		(layer "In2.Cu")
		(net "BMC_TXD5")
	)
	(segment
		(start 319.204848 -172.57268)
		(end 320.59118 -173.959012)
		(width 0.127)
		(layer "In2.Cu")
		(net "BMC_TXD5")
	)
	(segment
		(start 246.4562 -178.4477)
		(end 246.5705 -178.562)
		(width 0.127)
		(layer "In2.Cu")
		(net "BMC_TXD5")
	)
	(segment
		(start 54.047136 -170.7007)
		(end 69.6087 -170.7007)
		(width 0.127)
		(layer "In2.Cu")
		(net "BMC_TXD5")
	)
	(segment
		(start 208.9023 -178.4477)
		(end 246.4562 -178.4477)
		(width 0.127)
		(layer "In2.Cu")
		(net "BMC_TXD5")
	)
	(segment
		(start 322.77177 -164.40277)
		(end 322.77177 -167.132762)
		(width 0.127)
		(layer "In2.Cu")
		(net "BMC_TXD5")
	)
	(segment
		(start 47.117 -115.697)
		(end 38.481 -115.697)
		(width 0.127)
		(layer "In2.Cu")
		(net "BMC_TXD5")
	)
	(segment
		(start 205.6003 -181.7497)
		(end 208.9023 -178.4477)
		(width 0.127)
		(layer "In2.Cu")
		(net "BMC_TXD5")
	)
	(segment
		(start 35.872928 -118.305072)
		(end 35.872928 -141.536928)
		(width 0.127)
		(layer "In2.Cu")
		(net "BMC_TXD5")
	)
	(segment
		(start 197.0532 -181.3052)
		(end 197.4977 -181.7497)
		(width 0.127)
		(layer "In2.Cu")
		(net "BMC_TXD5")
	)
	(segment
		(start 247.6627 -123.74626)
		(end 247.6627 -140.667232)
		(width 0.127)
		(layer "In5.Cu")
		(net "BMC_TXD5")
	)
	(segment
		(start 252.14326 -118.5545)
		(end 252.14326 -119.2657)
		(width 0.127)
		(layer "In5.Cu")
		(net "BMC_TXD5")
	)
	(segment
		(start 246.5705 -177.545238)
		(end 246.5705 -178.562)
		(width 0.127)
		(layer "In5.Cu")
		(net "BMC_TXD5")
	)
	(segment
		(start 252.14326 -119.2657)
		(end 247.6627 -123.74626)
		(width 0.127)
		(layer "In5.Cu")
		(net "BMC_TXD5")
	)
	(segment
		(start 248.0945 -176.021238)
		(end 246.5705 -177.545238)
		(width 0.127)
		(layer "In5.Cu")
		(net "BMC_TXD5")
	)
	(segment
		(start 248.0945 -141.099032)
		(end 248.0945 -176.021238)
		(width 0.127)
		(layer "In5.Cu")
		(net "BMC_TXD5")
	)
	(segment
		(start 247.6627 -140.667232)
		(end 248.0945 -141.099032)
		(width 0.127)
		(layer "In5.Cu")
		(net "BMC_TXD5")
	)
	(segment
		(start 169.811446 -217.944446)
		(end 170.561 -218.694)
		(width 0.1143)
		(layer "F.Cu")
		(net "SAS_I2C_C_BUF_SCL_R")
	)
	(segment
		(start 170.8404 -196.240908)
		(end 170.8404 -204.169264)
		(width 0.1143)
		(layer "F.Cu")
		(net "SAS_I2C_C_BUF_SCL_R")
	)
	(segment
		(start 169.804842 -205.614778)
		(end 169.811446 -205.621382)
		(width 0.1143)
		(layer "F.Cu")
		(net "SAS_I2C_C_BUF_SCL_R")
	)
	(segment
		(start 170.8404 -204.169264)
		(end 169.804842 -205.204822)
		(width 0.1143)
		(layer "F.Cu")
		(net "SAS_I2C_C_BUF_SCL_R")
	)
	(segment
		(start 169.804842 -205.204822)
		(end 169.804842 -205.614778)
		(width 0.1143)
		(layer "F.Cu")
		(net "SAS_I2C_C_BUF_SCL_R")
	)
	(segment
		(start 171.3865 -195.199)
		(end 171.3865 -195.694808)
		(width 0.1143)
		(layer "F.Cu")
		(net "SAS_I2C_C_BUF_SCL_R")
	)
	(segment
		(start 169.811446 -205.621382)
		(end 169.811446 -217.944446)
		(width 0.1143)
		(layer "F.Cu")
		(net "SAS_I2C_C_BUF_SCL_R")
	)
	(segment
		(start 171.3865 -195.694808)
		(end 170.8404 -196.240908)
		(width 0.1143)
		(layer "F.Cu")
		(net "SAS_I2C_C_BUF_SCL_R")
	)
	(via
		(at 170.561 -218.694)
		(size 0.5588)
		(drill 0.3048)
		(layers "F.Cu" "B.Cu")
		(net "SAS_I2C_C_BUF_SCL_R")
	)
	(via
		(at 170.688 -245.8085)
		(size 0.5588)
		(drill 0.3048)
		(layers "F.Cu" "B.Cu")
		(net "SAS_I2C_C_BUF_SCL_R")
	)
	(via
		(at 170.561 -228.346)
		(size 0.7112)
		(drill 0.3556)
		(layers "F.Cu" "B.Cu")
		(net "SAS_I2C_C_BUF_SCL_R")
	)
	(via
		(at 93.187012 -248.285)
		(size 0.5588)
		(drill 0.3048)
		(layers "F.Cu" "B.Cu")
		(net "SAS_I2C_C_BUF_SCL_R")
	)
	(segment
		(start 170.561 -228.346)
		(end 170.561 -218.694)
		(width 0.1143)
		(layer "B.Cu")
		(net "SAS_I2C_C_BUF_SCL_R")
	)
	(segment
		(start 170.561 -245.6815)
		(end 170.561 -228.346)
		(width 0.1143)
		(layer "B.Cu")
		(net "SAS_I2C_C_BUF_SCL_R")
	)
	(segment
		(start 95.000572 -256.50444)
		(end 95.000572 -251.16536)
		(width 0.1143)
		(layer "B.Cu")
		(net "SAS_I2C_C_BUF_SCL_R")
	)
	(segment
		(start 95.000572 -251.16536)
		(end 93.187012 -249.3518)
		(width 0.1143)
		(layer "B.Cu")
		(net "SAS_I2C_C_BUF_SCL_R")
	)
	(segment
		(start 93.187012 -249.3518)
		(end 93.187012 -248.285)
		(width 0.1143)
		(layer "B.Cu")
		(net "SAS_I2C_C_BUF_SCL_R")
	)
	(segment
		(start 170.688 -245.8085)
		(end 170.561 -245.6815)
		(width 0.1143)
		(layer "B.Cu")
		(net "SAS_I2C_C_BUF_SCL_R")
	)
	(segment
		(start 170.1292 -245.237)
		(end 122.682 -245.237)
		(width 0.127)
		(layer "In2.Cu")
		(net "SAS_I2C_C_BUF_SCL_R")
	)
	(segment
		(start 170.688 -245.7958)
		(end 170.1292 -245.237)
		(width 0.127)
		(layer "In2.Cu")
		(net "SAS_I2C_C_BUF_SCL_R")
	)
	(segment
		(start 122.682 -245.237)
		(end 121.076974 -246.842026)
		(width 0.127)
		(layer "In2.Cu")
		(net "SAS_I2C_C_BUF_SCL_R")
	)
	(segment
		(start 121.076974 -246.842026)
		(end 94.629986 -246.842026)
		(width 0.127)
		(layer "In2.Cu")
		(net "SAS_I2C_C_BUF_SCL_R")
	)
	(segment
		(start 170.688 -245.8085)
		(end 170.688 -245.7958)
		(width 0.127)
		(layer "In2.Cu")
		(net "SAS_I2C_C_BUF_SCL_R")
	)
	(segment
		(start 94.629986 -246.842026)
		(end 93.187012 -248.285)
		(width 0.127)
		(layer "In2.Cu")
		(net "SAS_I2C_C_BUF_SCL_R")
	)
	(segment
		(start 71.101712 -254.18034)
		(end 71.226934 -254.18034)
		(width 0.1016)
		(layer "F.Cu")
		(net "SAS_EXP_GF_TX_DN15")
	)
	(segment
		(start 71.950072 -245.354602)
		(end 72.50049 -244.804184)
		(width 0.1016)
		(layer "F.Cu")
		(net "SAS_EXP_GF_TX_DN15")
	)
	(segment
		(start 73.51014 -242.3668)
		(end 73.51014 -193.400934)
		(width 0.1016)
		(layer "F.Cu")
		(net "SAS_EXP_GF_TX_DN15")
	)
	(segment
		(start 74.534014 -190.929006)
		(end 101.32695 -164.13607)
		(width 0.1016)
		(layer "F.Cu")
		(net "SAS_EXP_GF_TX_DN15")
	)
	(segment
		(start 71.000112 -256.25044)
		(end 71.000112 -254.28194)
		(width 0.1016)
		(layer "F.Cu")
		(net "SAS_EXP_GF_TX_DN15")
	)
	(segment
		(start 101.88702 -162.784028)
		(end 101.88702 -114.931952)
		(width 0.1016)
		(layer "F.Cu")
		(net "SAS_EXP_GF_TX_DN15")
	)
	(segment
		(start 71.328534 -254.07874)
		(end 71.328534 -246.855488)
		(width 0.1016)
		(layer "F.Cu")
		(net "SAS_EXP_GF_TX_DN15")
	)
	(arc
		(start 72.50049 -244.804184)
		(mid 73.247755 -243.685917)
		(end 73.51014 -242.3668)
		(width 0.1016)
		(layer "F.Cu")
		(net "SAS_EXP_GF_TX_DN15")
	)
	(arc
		(start 101.32695 -164.13607)
		(mid 101.741436 -163.515748)
		(end 101.88702 -162.784028)
		(width 0.1016)
		(layer "F.Cu")
		(net "SAS_EXP_GF_TX_DN15")
	)
	(arc
		(start 71.226934 -254.18034)
		(mid 71.298776 -254.150582)
		(end 71.328534 -254.07874)
		(width 0.1016)
		(layer "F.Cu")
		(net "SAS_EXP_GF_TX_DN15")
	)
	(arc
		(start 73.51014 -193.400934)
		(mid 73.776227 -192.063134)
		(end 74.534014 -190.929006)
		(width 0.1016)
		(layer "F.Cu")
		(net "SAS_EXP_GF_TX_DN15")
	)
	(arc
		(start 71.328534 -246.855488)
		(mid 71.490011 -246.043218)
		(end 71.950072 -245.354602)
		(width 0.1016)
		(layer "F.Cu")
		(net "SAS_EXP_GF_TX_DN15")
	)
	(arc
		(start 101.88702 -114.931952)
		(mid 101.849066 -114.741145)
		(end 101.74097 -114.5794)
		(width 0.1016)
		(layer "F.Cu")
		(net "SAS_EXP_GF_TX_DN15")
	)
	(arc
		(start 71.000112 -254.28194)
		(mid 71.02987 -254.210098)
		(end 71.101712 -254.18034)
		(width 0.1016)
		(layer "F.Cu")
		(net "SAS_EXP_GF_TX_DN15")
	)
	(segment
		(start 340.117938 -109.320076)
		(end 340.117938 -108.215938)
		(width 0.2032)
		(layer "F.Cu")
		(net "P5V_STBY_SW")
	)
	(segment
		(start 340.618064 -109.332776)
		(end 340.618064 -108.208064)
		(width 0.2032)
		(layer "F.Cu")
		(net "P5V_STBY_SW")
	)
	(segment
		(start 341.117936 -109.332776)
		(end 341.117936 -108.208064)
		(width 0.2032)
		(layer "F.Cu")
		(net "P5V_STBY_SW")
	)
	(via
		(at 343.662 -102.108)
		(size 0.5588)
		(drill 0.3048)
		(layers "F.Cu" "B.Cu")
		(net "P5V_STBY_SW")
	)
	(via
		(at 342.646 -101.473)
		(size 0.7112)
		(drill 0.3556)
		(layers "F.Cu" "B.Cu")
		(net "P5V_STBY_SW")
	)
	(segment
		(start 341.4395 -101.473)
		(end 342.646 -101.473)
		(width 0.508)
		(layer "B.Cu")
		(net "P5V_STBY_SW")
	)
	(segment
		(start 342.646 -101.473)
		(end 343.027 -101.473)
		(width 0.508)
		(layer "B.Cu")
		(net "P5V_STBY_SW")
	)
	(segment
		(start 343.027 -101.473)
		(end 343.662 -102.108)
		(width 0.508)
		(layer "B.Cu")
		(net "P5V_STBY_SW")
	)
	(segment
		(start 267.3604 -180.0606)
		(end 267.335 -180.086)
		(width 0.1143)
		(layer "F.Cu")
		(net "ROMA16")
	)
	(segment
		(start 288.034984 -179.440078)
		(end 288.025586 -179.440078)
		(width 0.1143)
		(layer "F.Cu")
		(net "ROMA16")
	)
	(segment
		(start 288.025586 -179.440078)
		(end 287.631124 -179.045616)
		(width 0.1143)
		(layer "F.Cu")
		(net "ROMA16")
	)
	(segment
		(start 268.224 -180.0606)
		(end 267.3604 -180.0606)
		(width 0.1143)
		(layer "F.Cu")
		(net "ROMA16")
	)
	(segment
		(start 266.5095 -180.086)
		(end 267.335 -180.086)
		(width 0.1143)
		(layer "F.Cu")
		(net "ROMA16")
	)
	(via
		(at 287.631124 -179.045616)
		(size 0.508)
		(drill 0.254)
		(layers "F.Cu" "B.Cu")
		(net "ROMA16")
	)
	(via
		(at 267.335 -180.086)
		(size 0.5588)
		(drill 0.3048)
		(layers "F.Cu" "B.Cu")
		(net "ROMA16")
	)
	(via
		(at 268.224 -180.0606)
		(size 0.7112)
		(drill 0.3556)
		(layers "F.Cu" "B.Cu")
		(net "ROMA16")
	)
	(segment
		(start 273.153632 -180.257196)
		(end 273.736308 -179.67452)
		(width 0.127)
		(layer "In2.Cu")
		(net "ROMA16")
	)
	(segment
		(start 284.87878 -179.67452)
		(end 285.05912 -179.49418)
		(width 0.127)
		(layer "In2.Cu")
		(net "ROMA16")
	)
	(segment
		(start 272.160492 -179.67452)
		(end 272.743168 -180.257196)
		(width 0.127)
		(layer "In2.Cu")
		(net "ROMA16")
	)
	(segment
		(start 267.85443 -179.67452)
		(end 272.160492 -179.67452)
		(width 0.127)
		(layer "In2.Cu")
		(net "ROMA16")
	)
	(segment
		(start 285.114238 -179.439062)
		(end 287.237678 -179.439062)
		(width 0.0889)
		(layer "In2.Cu")
		(net "ROMA16")
	)
	(segment
		(start 285.05912 -179.49418)
		(end 285.114238 -179.439062)
		(width 0.0889)
		(layer "In2.Cu")
		(net "ROMA16")
	)
	(segment
		(start 267.335 -180.086)
		(end 267.427456 -180.086)
		(width 0.127)
		(layer "In2.Cu")
		(net "ROMA16")
	)
	(segment
		(start 273.736308 -179.67452)
		(end 284.87878 -179.67452)
		(width 0.127)
		(layer "In2.Cu")
		(net "ROMA16")
	)
	(segment
		(start 267.64615 -179.8828)
		(end 267.85443 -179.67452)
		(width 0.127)
		(layer "In2.Cu")
		(net "ROMA16")
	)
	(segment
		(start 267.427456 -180.086)
		(end 267.630656 -179.8828)
		(width 0.127)
		(layer "In2.Cu")
		(net "ROMA16")
	)
	(segment
		(start 287.237678 -179.439062)
		(end 287.631124 -179.045616)
		(width 0.0889)
		(layer "In2.Cu")
		(net "ROMA16")
	)
	(segment
		(start 267.630656 -179.8828)
		(end 267.64615 -179.8828)
		(width 0.127)
		(layer "In2.Cu")
		(net "ROMA16")
	)
	(segment
		(start 272.743168 -180.257196)
		(end 273.153632 -180.257196)
		(width 0.127)
		(layer "In2.Cu")
		(net "ROMA16")
	)
	(segment
		(start 188.904372 -204.949552)
		(end 175.413924 -218.44)
		(width 0.1143)
		(layer "F.Cu")
		(net "SAS_I2C_C_BUF_SDA_R")
	)
	(segment
		(start 175.413924 -218.44)
		(end 172.085 -218.44)
		(width 0.1143)
		(layer "F.Cu")
		(net "SAS_I2C_C_BUF_SDA_R")
	)
	(segment
		(start 188.904372 -195.271136)
		(end 188.904372 -204.949552)
		(width 0.1143)
		(layer "F.Cu")
		(net "SAS_I2C_C_BUF_SDA_R")
	)
	(segment
		(start 172.085 -218.44)
		(end 171.069 -219.456)
		(width 0.1143)
		(layer "F.Cu")
		(net "SAS_I2C_C_BUF_SDA_R")
	)
	(via
		(at 171.196 -225.7806)
		(size 0.7112)
		(drill 0.3556)
		(layers "F.Cu" "B.Cu")
		(net "SAS_I2C_C_BUF_SDA_R")
	)
	(via
		(at 92.556584 -248.947686)
		(size 0.5588)
		(drill 0.3048)
		(layers "F.Cu" "B.Cu")
		(net "SAS_I2C_C_BUF_SDA_R")
	)
	(via
		(at 171.069 -219.456)
		(size 0.5588)
		(drill 0.3048)
		(layers "F.Cu" "B.Cu")
		(net "SAS_I2C_C_BUF_SDA_R")
	)
	(via
		(at 171.831 -245.8085)
		(size 0.5588)
		(drill 0.3048)
		(layers "F.Cu" "B.Cu")
		(net "SAS_I2C_C_BUF_SDA_R")
	)
	(segment
		(start 92.552012 -248.978674)
		(end 92.556584 -248.974102)
		(width 0.1143)
		(layer "B.Cu")
		(net "SAS_I2C_C_BUF_SDA_R")
	)
	(segment
		(start 93.999812 -250.9266)
		(end 92.552012 -249.4788)
		(width 0.1143)
		(layer "B.Cu")
		(net "SAS_I2C_C_BUF_SDA_R")
	)
	(segment
		(start 92.556584 -248.974102)
		(end 92.556584 -248.947686)
		(width 0.1143)
		(layer "B.Cu")
		(net "SAS_I2C_C_BUF_SDA_R")
	)
	(segment
		(start 171.196 -225.7806)
		(end 171.196 -245.1735)
		(width 0.1143)
		(layer "B.Cu")
		(net "SAS_I2C_C_BUF_SDA_R")
	)
	(segment
		(start 92.552012 -249.4788)
		(end 92.552012 -248.978674)
		(width 0.1143)
		(layer "B.Cu")
		(net "SAS_I2C_C_BUF_SDA_R")
	)
	(segment
		(start 171.069 -225.6536)
		(end 171.196 -225.7806)
		(width 0.1143)
		(layer "B.Cu")
		(net "SAS_I2C_C_BUF_SDA_R")
	)
	(segment
		(start 171.196 -245.1735)
		(end 171.831 -245.8085)
		(width 0.1143)
		(layer "B.Cu")
		(net "SAS_I2C_C_BUF_SDA_R")
	)
	(segment
		(start 171.069 -219.456)
		(end 171.069 -225.6536)
		(width 0.1143)
		(layer "B.Cu")
		(net "SAS_I2C_C_BUF_SDA_R")
	)
	(segment
		(start 93.999812 -256.50444)
		(end 93.999812 -250.9266)
		(width 0.1143)
		(layer "B.Cu")
		(net "SAS_I2C_C_BUF_SDA_R")
	)
	(segment
		(start 92.583 -248.92127)
		(end 92.556584 -248.947686)
		(width 0.127)
		(layer "In2.Cu")
		(net "SAS_I2C_C_BUF_SDA_R")
	)
	(segment
		(start 122.428 -244.729)
		(end 120.822974 -246.334026)
		(width 0.127)
		(layer "In2.Cu")
		(net "SAS_I2C_C_BUF_SDA_R")
	)
	(segment
		(start 94.41942 -246.334026)
		(end 92.583 -248.170446)
		(width 0.127)
		(layer "In2.Cu")
		(net "SAS_I2C_C_BUF_SDA_R")
	)
	(segment
		(start 171.831 -245.7958)
		(end 170.7642 -244.729)
		(width 0.127)
		(layer "In2.Cu")
		(net "SAS_I2C_C_BUF_SDA_R")
	)
	(segment
		(start 92.583 -248.170446)
		(end 92.583 -248.92127)
		(width 0.127)
		(layer "In2.Cu")
		(net "SAS_I2C_C_BUF_SDA_R")
	)
	(segment
		(start 171.831 -245.8085)
		(end 171.831 -245.7958)
		(width 0.127)
		(layer "In2.Cu")
		(net "SAS_I2C_C_BUF_SDA_R")
	)
	(segment
		(start 170.7642 -244.729)
		(end 122.428 -244.729)
		(width 0.127)
		(layer "In2.Cu")
		(net "SAS_I2C_C_BUF_SDA_R")
	)
	(segment
		(start 120.822974 -246.334026)
		(end 94.41942 -246.334026)
		(width 0.127)
		(layer "In2.Cu")
		(net "SAS_I2C_C_BUF_SDA_R")
	)
	(segment
		(start 344.805 -118.491)
		(end 343.789 -118.491)
		(width 0.254)
		(layer "F.Cu")
		(net "P5V_STBY_CC")
	)
	(segment
		(start 347.726 -90.551)
		(end 348.107 -90.551)
		(width 0.254)
		(layer "F.Cu")
		(net "P5V_STBY_CC")
	)
	(segment
		(start 347.4085 -90.551)
		(end 347.726 -90.551)
		(width 0.127)
		(layer "F.Cu")
		(net "P5V_STBY_CC")
	)
	(via
		(at 343.789 -118.491)
		(size 0.5588)
		(drill 0.3048)
		(layers "F.Cu" "B.Cu")
		(net "P5V_STBY_CC")
	)
	(via
		(at 349.25 -103.886)
		(size 0.7112)
		(drill 0.3556)
		(layers "F.Cu" "B.Cu")
		(net "P5V_STBY_CC")
	)
	(via
		(at 348.107 -90.551)
		(size 0.5588)
		(drill 0.3048)
		(layers "F.Cu" "B.Cu")
		(net "P5V_STBY_CC")
	)
	(segment
		(start 350.774 -105.41)
		(end 349.25 -103.886)
		(width 0.254)
		(layer "B.Cu")
		(net "P5V_STBY_CC")
	)
	(segment
		(start 349.758 -118.491)
		(end 350.774 -117.475)
		(width 0.254)
		(layer "B.Cu")
		(net "P5V_STBY_CC")
	)
	(segment
		(start 350.774 -117.475)
		(end 350.774 -105.41)
		(width 0.254)
		(layer "B.Cu")
		(net "P5V_STBY_CC")
	)
	(segment
		(start 343.789 -118.491)
		(end 349.758 -118.491)
		(width 0.254)
		(layer "B.Cu")
		(net "P5V_STBY_CC")
	)
	(segment
		(start 348.107 -102.743)
		(end 349.25 -103.886)
		(width 0.254)
		(layer "B.Cu")
		(net "P5V_STBY_CC")
	)
	(segment
		(start 348.107 -90.551)
		(end 348.107 -102.743)
		(width 0.254)
		(layer "B.Cu")
		(net "P5V_STBY_CC")
	)
	(via
		(at 344.9955 -113.2205)
		(size 0.7112)
		(drill 0.3556)
		(layers "F.Cu" "B.Cu")
		(net "P5V_STBY_VFB_R")
	)
	(segment
		(start 344.9955 -113.0935)
		(end 344.9955 -113.2205)
		(width 0.254)
		(layer "B.Cu")
		(net "P5V_STBY_VFB_R")
	)
	(segment
		(start 340.233 -100.203)
		(end 340.5505 -100.5205)
		(width 0.254)
		(layer "B.Cu")
		(net "P5V_STBY_VFB_R")
	)
	(segment
		(start 344.678 -112.776)
		(end 344.9955 -113.0935)
		(width 0.254)
		(layer "B.Cu")
		(net "P5V_STBY_VFB_R")
	)
	(segment
		(start 344.9955 -115.824)
		(end 344.9955 -113.2205)
		(width 0.254)
		(layer "B.Cu")
		(net "P5V_STBY_VFB_R")
	)
	(segment
		(start 340.5505 -100.5205)
		(end 340.5505 -101.473)
		(width 0.254)
		(layer "B.Cu")
		(net "P5V_STBY_VFB_R")
	)
	(segment
		(start 340.5505 -101.473)
		(end 344.678 -105.6005)
		(width 0.254)
		(layer "B.Cu")
		(net "P5V_STBY_VFB_R")
	)
	(segment
		(start 344.678 -105.6005)
		(end 344.678 -112.776)
		(width 0.254)
		(layer "B.Cu")
		(net "P5V_STBY_VFB_R")
	)
	(segment
		(start 292.80739 -162.67811)
		(end 292.80739 -164.1348)
		(width 0.1143)
		(layer "F.Cu")
		(net "RMII0_BMC_C_TX_EN")
	)
	(segment
		(start 292.834822 -165.56355)
		(end 292.834822 -167.440102)
		(width 0.1143)
		(layer "F.Cu")
		(net "RMII0_BMC_C_TX_EN")
	)
	(segment
		(start 292.80739 -164.1348)
		(end 292.80739 -165.536118)
		(width 0.1143)
		(layer "F.Cu")
		(net "RMII0_BMC_C_TX_EN")
	)
	(segment
		(start 293.497 -161.9885)
		(end 292.80739 -162.67811)
		(width 0.1143)
		(layer "F.Cu")
		(net "RMII0_BMC_C_TX_EN")
	)
	(segment
		(start 292.80739 -165.536118)
		(end 292.834822 -165.56355)
		(width 0.1143)
		(layer "F.Cu")
		(net "RMII0_BMC_C_TX_EN")
	)
	(via
		(at 292.80739 -164.1348)
		(size 0.7112)
		(drill 0.3556)
		(layers "F.Cu" "B.Cu")
		(net "RMII0_BMC_C_TX_EN")
	)
	(segment
		(start 107.349798 -103.35006)
		(end 106.849672 -103.850186)
		(width 0.1016)
		(layer "F.Cu")
		(net "SAS_GF_EXP_RX_DP15")
	)
	(via
		(at 106.849672 -103.850186)
		(size 0.508)
		(drill 0.254)
		(layers "F.Cu" "B.Cu")
		(net "SAS_GF_EXP_RX_DP15")
	)
	(segment
		(start 85.217 -209.794602)
		(end 85.217 -172.72)
		(width 0.1016)
		(layer "B.Cu")
		(net "SAS_GF_EXP_RX_DP15")
	)
	(segment
		(start 73.813924 -254.362712)
		(end 73.626472 -253.909576)
		(width 0.1016)
		(layer "B.Cu")
		(net "SAS_GF_EXP_RX_DP15")
	)
	(segment
		(start 73.816972 -245.72976)
		(end 73.816972 -245.42496)
		(width 0.1016)
		(layer "B.Cu")
		(net "SAS_GF_EXP_RX_DP15")
	)
	(segment
		(start 102.475792 -153.817574)
		(end 102.475792 -114.497358)
		(width 0.1016)
		(layer "B.Cu")
		(net "SAS_GF_EXP_RX_DP15")
	)
	(segment
		(start 73.578212 -253.666752)
		(end 73.578212 -246.20728)
		(width 0.1016)
		(layer "B.Cu")
		(net "SAS_GF_EXP_RX_DP15")
	)
	(segment
		(start 73.816972 -234.696)
		(end 73.816972 -234.3912)
		(width 0.1016)
		(layer "B.Cu")
		(net "SAS_GF_EXP_RX_DP15")
	)
	(segment
		(start 73.578212 -233.91368)
		(end 73.578212 -233.60888)
		(width 0.1016)
		(layer "B.Cu")
		(net "SAS_GF_EXP_RX_DP15")
	)
	(segment
		(start 73.999852 -256.50444)
		(end 73.999852 -254.811784)
		(width 0.1016)
		(layer "B.Cu")
		(net "SAS_GF_EXP_RX_DP15")
	)
	(segment
		(start 73.816972 -226.79152)
		(end 73.816972 -226.48672)
		(width 0.1016)
		(layer "B.Cu")
		(net "SAS_GF_EXP_RX_DP15")
	)
	(segment
		(start 105.424224 -110.78464)
		(end 105.42397 -110.78464)
		(width 0.1016)
		(layer "B.Cu")
		(net "SAS_GF_EXP_RX_DP15")
	)
	(segment
		(start 73.578212 -235.47832)
		(end 73.578212 -235.17352)
		(width 0.1016)
		(layer "B.Cu")
		(net "SAS_GF_EXP_RX_DP15")
	)
	(segment
		(start 105.03408 -111.614712)
		(end 105.113074 -111.536226)
		(width 0.1016)
		(layer "B.Cu")
		(net "SAS_GF_EXP_RX_DP15")
	)
	(segment
		(start 73.578212 -241.81816)
		(end 73.578212 -236.73816)
		(width 0.1016)
		(layer "B.Cu")
		(net "SAS_GF_EXP_RX_DP15")
	)
	(segment
		(start 73.578212 -232.34904)
		(end 73.578212 -227.26904)
		(width 0.1016)
		(layer "B.Cu")
		(net "SAS_GF_EXP_RX_DP15")
	)
	(segment
		(start 105.649776 -109.44352)
		(end 106.361738 -108.731558)
		(width 0.1016)
		(layer "B.Cu")
		(net "SAS_GF_EXP_RX_DP15")
	)
	(segment
		(start 73.816972 -233.13136)
		(end 73.816972 -232.82656)
		(width 0.1016)
		(layer "B.Cu")
		(net "SAS_GF_EXP_RX_DP15")
	)
	(segment
		(start 102.705154 -113.943638)
		(end 105.03408 -111.614712)
		(width 0.1016)
		(layer "B.Cu")
		(net "SAS_GF_EXP_RX_DP15")
	)
	(segment
		(start 73.578212 -243.3828)
		(end 73.578212 -243.078)
		(width 0.1016)
		(layer "B.Cu")
		(net "SAS_GF_EXP_RX_DP15")
	)
	(segment
		(start 106.647742 -108.039916)
		(end 106.647742 -104.31526)
		(width 0.1016)
		(layer "B.Cu")
		(net "SAS_GF_EXP_RX_DP15")
	)
	(segment
		(start 73.816972 -244.16512)
		(end 73.816972 -243.86032)
		(width 0.1016)
		(layer "B.Cu")
		(net "SAS_GF_EXP_RX_DP15")
	)
	(segment
		(start 74.295 -221.615)
		(end 84.582 -211.328)
		(width 0.1016)
		(layer "B.Cu")
		(net "SAS_GF_EXP_RX_DP15")
	)
	(segment
		(start 102.475538 -153.82875)
		(end 102.475792 -153.817574)
		(width 0.1016)
		(layer "B.Cu")
		(net "SAS_GF_EXP_RX_DP15")
	)
	(segment
		(start 73.578212 -226.0092)
		(end 73.578212 -223.345502)
		(width 0.1016)
		(layer "B.Cu")
		(net "SAS_GF_EXP_RX_DP15")
	)
	(segment
		(start 105.42397 -110.78464)
		(end 105.42397 -109.988604)
		(width 0.1016)
		(layer "B.Cu")
		(net "SAS_GF_EXP_RX_DP15")
	)
	(segment
		(start 73.816972 -236.26064)
		(end 73.816972 -235.95584)
		(width 0.1016)
		(layer "B.Cu")
		(net "SAS_GF_EXP_RX_DP15")
	)
	(segment
		(start 85.745828 -171.443142)
		(end 101.847904 -155.341066)
		(width 0.1016)
		(layer "B.Cu")
		(net "SAS_GF_EXP_RX_DP15")
	)
	(segment
		(start 73.578212 -244.94744)
		(end 73.578212 -244.64264)
		(width 0.1016)
		(layer "B.Cu")
		(net "SAS_GF_EXP_RX_DP15")
	)
	(segment
		(start 106.83367 -103.866188)
		(end 106.849672 -103.850186)
		(width 0.1016)
		(layer "B.Cu")
		(net "SAS_GF_EXP_RX_DP15")
	)
	(segment
		(start 73.816972 -242.60048)
		(end 73.816972 -242.29568)
		(width 0.1016)
		(layer "B.Cu")
		(net "SAS_GF_EXP_RX_DP15")
	)
	(arc
		(start 73.578212 -227.26904)
		(mid 73.608704 -227.135047)
		(end 73.697592 -227.03028)
		(width 0.1016)
		(layer "B.Cu")
		(net "SAS_GF_EXP_RX_DP15")
	)
	(arc
		(start 105.113074 -111.536226)
		(mid 105.343453 -111.191395)
		(end 105.424224 -110.78464)
		(width 0.1016)
		(layer "B.Cu")
		(net "SAS_GF_EXP_RX_DP15")
	)
	(arc
		(start 73.697592 -236.4994)
		(mid 73.786386 -236.394586)
		(end 73.816972 -236.26064)
		(width 0.1016)
		(layer "B.Cu")
		(net "SAS_GF_EXP_RX_DP15")
	)
	(arc
		(start 73.697592 -234.15244)
		(mid 73.608798 -234.047626)
		(end 73.578212 -233.91368)
		(width 0.1016)
		(layer "B.Cu")
		(net "SAS_GF_EXP_RX_DP15")
	)
	(arc
		(start 73.816972 -245.42496)
		(mid 73.78648 -245.290967)
		(end 73.697592 -245.1862)
		(width 0.1016)
		(layer "B.Cu")
		(net "SAS_GF_EXP_RX_DP15")
	)
	(arc
		(start 73.697592 -226.24796)
		(mid 73.608798 -226.143146)
		(end 73.578212 -226.0092)
		(width 0.1016)
		(layer "B.Cu")
		(net "SAS_GF_EXP_RX_DP15")
	)
	(arc
		(start 102.475792 -114.497358)
		(mid 102.535401 -114.197685)
		(end 102.705154 -113.943638)
		(width 0.1016)
		(layer "B.Cu")
		(net "SAS_GF_EXP_RX_DP15")
	)
	(arc
		(start 73.578212 -244.64264)
		(mid 73.608704 -244.508647)
		(end 73.697592 -244.40388)
		(width 0.1016)
		(layer "B.Cu")
		(net "SAS_GF_EXP_RX_DP15")
	)
	(arc
		(start 84.582 -211.328)
		(mid 85.052 -210.624456)
		(end 85.217 -209.794602)
		(width 0.1016)
		(layer "B.Cu")
		(net "SAS_GF_EXP_RX_DP15")
	)
	(arc
		(start 73.816972 -232.82656)
		(mid 73.78648 -232.692567)
		(end 73.697592 -232.5878)
		(width 0.1016)
		(layer "B.Cu")
		(net "SAS_GF_EXP_RX_DP15")
	)
	(arc
		(start 73.697592 -244.40388)
		(mid 73.786386 -244.299066)
		(end 73.816972 -244.16512)
		(width 0.1016)
		(layer "B.Cu")
		(net "SAS_GF_EXP_RX_DP15")
	)
	(arc
		(start 73.816972 -243.86032)
		(mid 73.78648 -243.726327)
		(end 73.697592 -243.62156)
		(width 0.1016)
		(layer "B.Cu")
		(net "SAS_GF_EXP_RX_DP15")
	)
	(arc
		(start 73.999852 -254.811784)
		(mid 73.951531 -254.568766)
		(end 73.813924 -254.362712)
		(width 0.1016)
		(layer "B.Cu")
		(net "SAS_GF_EXP_RX_DP15")
	)
	(arc
		(start 73.697592 -245.96852)
		(mid 73.786386 -245.863706)
		(end 73.816972 -245.72976)
		(width 0.1016)
		(layer "B.Cu")
		(net "SAS_GF_EXP_RX_DP15")
	)
	(arc
		(start 85.217 -172.72)
		(mid 85.354435 -172.02898)
		(end 85.745828 -171.443142)
		(width 0.1016)
		(layer "B.Cu")
		(net "SAS_GF_EXP_RX_DP15")
	)
	(arc
		(start 73.626472 -253.909576)
		(mid 73.590392 -253.790539)
		(end 73.578212 -253.666752)
		(width 0.1016)
		(layer "B.Cu")
		(net "SAS_GF_EXP_RX_DP15")
	)
	(arc
		(start 106.647742 -104.31526)
		(mid 106.696063 -104.072242)
		(end 106.83367 -103.866188)
		(width 0.1016)
		(layer "B.Cu")
		(net "SAS_GF_EXP_RX_DP15")
	)
	(arc
		(start 73.816972 -234.3912)
		(mid 73.78648 -234.257207)
		(end 73.697592 -234.15244)
		(width 0.1016)
		(layer "B.Cu")
		(net "SAS_GF_EXP_RX_DP15")
	)
	(arc
		(start 73.578212 -235.17352)
		(mid 73.608704 -235.039527)
		(end 73.697592 -234.93476)
		(width 0.1016)
		(layer "B.Cu")
		(net "SAS_GF_EXP_RX_DP15")
	)
	(arc
		(start 73.578212 -243.078)
		(mid 73.608704 -242.944007)
		(end 73.697592 -242.83924)
		(width 0.1016)
		(layer "B.Cu")
		(net "SAS_GF_EXP_RX_DP15")
	)
	(arc
		(start 73.578212 -236.73816)
		(mid 73.608704 -236.604167)
		(end 73.697592 -236.4994)
		(width 0.1016)
		(layer "B.Cu")
		(net "SAS_GF_EXP_RX_DP15")
	)
	(arc
		(start 73.697592 -232.5878)
		(mid 73.608798 -232.482986)
		(end 73.578212 -232.34904)
		(width 0.1016)
		(layer "B.Cu")
		(net "SAS_GF_EXP_RX_DP15")
	)
	(arc
		(start 73.697592 -234.93476)
		(mid 73.786386 -234.829946)
		(end 73.816972 -234.696)
		(width 0.1016)
		(layer "B.Cu")
		(net "SAS_GF_EXP_RX_DP15")
	)
	(arc
		(start 101.847904 -155.341066)
		(mid 102.311797 -154.647191)
		(end 102.475538 -153.82875)
		(width 0.1016)
		(layer "B.Cu")
		(net "SAS_GF_EXP_RX_DP15")
	)
	(arc
		(start 73.578212 -233.60888)
		(mid 73.608704 -233.474887)
		(end 73.697592 -233.37012)
		(width 0.1016)
		(layer "B.Cu")
		(net "SAS_GF_EXP_RX_DP15")
	)
	(arc
		(start 73.697592 -245.1862)
		(mid 73.608798 -245.081386)
		(end 73.578212 -244.94744)
		(width 0.1016)
		(layer "B.Cu")
		(net "SAS_GF_EXP_RX_DP15")
	)
	(arc
		(start 73.816972 -242.29568)
		(mid 73.78648 -242.161687)
		(end 73.697592 -242.05692)
		(width 0.1016)
		(layer "B.Cu")
		(net "SAS_GF_EXP_RX_DP15")
	)
	(arc
		(start 73.697592 -227.03028)
		(mid 73.786386 -226.925466)
		(end 73.816972 -226.79152)
		(width 0.1016)
		(layer "B.Cu")
		(net "SAS_GF_EXP_RX_DP15")
	)
	(arc
		(start 73.816972 -226.48672)
		(mid 73.78648 -226.352727)
		(end 73.697592 -226.24796)
		(width 0.1016)
		(layer "B.Cu")
		(net "SAS_GF_EXP_RX_DP15")
	)
	(arc
		(start 105.42397 -109.988604)
		(mid 105.482651 -109.693597)
		(end 105.649776 -109.44352)
		(width 0.1016)
		(layer "B.Cu")
		(net "SAS_GF_EXP_RX_DP15")
	)
	(arc
		(start 106.361738 -108.731558)
		(mid 106.573443 -108.414157)
		(end 106.647742 -108.039916)
		(width 0.1016)
		(layer "B.Cu")
		(net "SAS_GF_EXP_RX_DP15")
	)
	(arc
		(start 73.697592 -233.37012)
		(mid 73.786386 -233.265306)
		(end 73.816972 -233.13136)
		(width 0.1016)
		(layer "B.Cu")
		(net "SAS_GF_EXP_RX_DP15")
	)
	(arc
		(start 73.578212 -223.345502)
		(mid 73.764501 -222.408965)
		(end 74.295 -221.615)
		(width 0.1016)
		(layer "B.Cu")
		(net "SAS_GF_EXP_RX_DP15")
	)
	(arc
		(start 73.578212 -246.20728)
		(mid 73.608704 -246.073287)
		(end 73.697592 -245.96852)
		(width 0.1016)
		(layer "B.Cu")
		(net "SAS_GF_EXP_RX_DP15")
	)
	(arc
		(start 73.697592 -242.83924)
		(mid 73.786386 -242.734426)
		(end 73.816972 -242.60048)
		(width 0.1016)
		(layer "B.Cu")
		(net "SAS_GF_EXP_RX_DP15")
	)
	(arc
		(start 73.816972 -235.95584)
		(mid 73.78648 -235.821847)
		(end 73.697592 -235.71708)
		(width 0.1016)
		(layer "B.Cu")
		(net "SAS_GF_EXP_RX_DP15")
	)
	(arc
		(start 73.697592 -243.62156)
		(mid 73.608798 -243.516746)
		(end 73.578212 -243.3828)
		(width 0.1016)
		(layer "B.Cu")
		(net "SAS_GF_EXP_RX_DP15")
	)
	(arc
		(start 73.697592 -242.05692)
		(mid 73.608798 -241.952106)
		(end 73.578212 -241.81816)
		(width 0.1016)
		(layer "B.Cu")
		(net "SAS_GF_EXP_RX_DP15")
	)
	(arc
		(start 73.697592 -235.71708)
		(mid 73.608798 -235.612266)
		(end 73.578212 -235.47832)
		(width 0.1016)
		(layer "B.Cu")
		(net "SAS_GF_EXP_RX_DP15")
	)
	(segment
		(start 286.425386 -178.640232)
		(end 286.027622 -179.037996)
		(width 0.1143)
		(layer "F.Cu")
		(net "ROMA0")
	)
	(segment
		(start 286.434784 -178.640232)
		(end 286.425386 -178.640232)
		(width 0.1143)
		(layer "F.Cu")
		(net "ROMA0")
	)
	(via
		(at 263.779 -179.451)
		(size 0.5588)
		(drill 0.3048)
		(layers "F.Cu" "B.Cu")
		(net "ROMA0")
	)
	(via
		(at 286.027622 -179.037996)
		(size 0.508)
		(drill 0.254)
		(layers "F.Cu" "B.Cu")
		(net "ROMA0")
	)
	(via
		(at 287.02 -91.821)
		(size 0.5588)
		(drill 0.3048)
		(layers "F.Cu" "B.Cu")
		(net "ROMA0")
	)
	(via
		(at 287.655 -84.582)
		(size 0.508)
		(drill 0.254)
		(layers "F.Cu" "B.Cu")
		(net "ROMA0")
	)
	(segment
		(start 287.909 -84.836)
		(end 287.655 -84.582)
		(width 0.1143)
		(layer "B.Cu")
		(net "ROMA0")
	)
	(segment
		(start 329.184 -83.693)
		(end 328.041 -84.836)
		(width 0.1143)
		(layer "B.Cu")
		(net "ROMA0")
	)
	(segment
		(start 328.041 -84.836)
		(end 287.909 -84.836)
		(width 0.1143)
		(layer "B.Cu")
		(net "ROMA0")
	)
	(segment
		(start 267.46708 -179.451)
		(end 267.72108 -179.197)
		(width 0.127)
		(layer "In2.Cu")
		(net "ROMA0")
	)
	(segment
		(start 267.72108 -179.197)
		(end 285.868618 -179.197)
		(width 0.127)
		(layer "In2.Cu")
		(net "ROMA0")
	)
	(segment
		(start 287.02 -91.821)
		(end 287.02 -85.217)
		(width 0.127)
		(layer "In2.Cu")
		(net "ROMA0")
	)
	(segment
		(start 285.868618 -179.197)
		(end 286.027622 -179.037996)
		(width 0.127)
		(layer "In2.Cu")
		(net "ROMA0")
	)
	(segment
		(start 263.779 -179.451)
		(end 267.46708 -179.451)
		(width 0.127)
		(layer "In2.Cu")
		(net "ROMA0")
	)
	(segment
		(start 287.02 -85.217)
		(end 287.655 -84.582)
		(width 0.127)
		(layer "In2.Cu")
		(net "ROMA0")
	)
	(segment
		(start 267.335 -148.336)
		(end 267.335 -132.715)
		(width 0.127)
		(layer "In5.Cu")
		(net "ROMA0")
	)
	(segment
		(start 263.779 -168.188132)
		(end 263.525 -167.934132)
		(width 0.127)
		(layer "In5.Cu")
		(net "ROMA0")
	)
	(segment
		(start 287.02 -113.03)
		(end 287.02 -91.821)
		(width 0.127)
		(layer "In5.Cu")
		(net "ROMA0")
	)
	(segment
		(start 263.525 -167.934132)
		(end 263.525 -162.179)
		(width 0.127)
		(layer "In5.Cu")
		(net "ROMA0")
	)
	(segment
		(start 263.525 -162.179)
		(end 263.1567 -161.8107)
		(width 0.127)
		(layer "In5.Cu")
		(net "ROMA0")
	)
	(segment
		(start 263.779 -179.451)
		(end 263.779 -168.188132)
		(width 0.127)
		(layer "In5.Cu")
		(net "ROMA0")
	)
	(segment
		(start 263.1567 -152.5143)
		(end 267.335 -148.336)
		(width 0.127)
		(layer "In5.Cu")
		(net "ROMA0")
	)
	(segment
		(start 267.335 -132.715)
		(end 287.02 -113.03)
		(width 0.127)
		(layer "In5.Cu")
		(net "ROMA0")
	)
	(segment
		(start 263.1567 -161.8107)
		(end 263.1567 -152.5143)
		(width 0.127)
		(layer "In5.Cu")
		(net "ROMA0")
	)
	(segment
		(start 12.205716 -214.05088)
		(end 12.205716 -211.76488)
		(width 0.1143)
		(layer "F.Cu")
		(net "PCIE_MATED#")
	)
	(segment
		(start 99.568 -242.6335)
		(end 98.679 -242.6335)
		(width 0.1143)
		(layer "F.Cu")
		(net "PCIE_MATED#")
	)
	(segment
		(start 11.380216 -212.65388)
		(end 11.380216 -212.20938)
		(width 0.1143)
		(layer "F.Cu")
		(net "PCIE_MATED#")
	)
	(segment
		(start 11.951716 -211.63788)
		(end 12.078716 -211.63788)
		(width 0.1143)
		(layer "F.Cu")
		(net "PCIE_MATED#")
	)
	(segment
		(start 12.142216 -238.30788)
		(end 13.412216 -239.57788)
		(width 0.1143)
		(layer "F.Cu")
		(net "PCIE_MATED#")
	)
	(segment
		(start 12.205716 -211.76488)
		(end 12.078716 -211.63788)
		(width 0.1143)
		(layer "F.Cu")
		(net "PCIE_MATED#")
	)
	(segment
		(start 12.142216 -237.73638)
		(end 12.142216 -238.30788)
		(width 0.1143)
		(layer "F.Cu")
		(net "PCIE_MATED#")
	)
	(segment
		(start 11.380216 -212.20938)
		(end 11.951716 -211.63788)
		(width 0.1143)
		(layer "F.Cu")
		(net "PCIE_MATED#")
	)
	(via
		(at 26.874216 -239.57788)
		(size 0.5588)
		(drill 0.3048)
		(layers "F.Cu" "B.Cu")
		(net "PCIE_MATED#")
	)
	(via
		(at 11.380216 -212.65388)
		(size 0.5588)
		(drill 0.3048)
		(layers "F.Cu" "B.Cu")
		(net "PCIE_MATED#")
	)
	(via
		(at 9.856216 -214.20328)
		(size 0.7112)
		(drill 0.3556)
		(layers "F.Cu" "B.Cu")
		(net "PCIE_MATED#")
	)
	(via
		(at 98.679 -242.6335)
		(size 0.5588)
		(drill 0.3048)
		(layers "F.Cu" "B.Cu")
		(net "PCIE_MATED#")
	)
	(via
		(at 13.412216 -239.57788)
		(size 0.5588)
		(drill 0.3048)
		(layers "F.Cu" "B.Cu")
		(net "PCIE_MATED#")
	)
	(segment
		(start 13.412216 -239.57788)
		(end 8.224266 -234.38993)
		(width 0.1143)
		(layer "B.Cu")
		(net "PCIE_MATED#")
	)
	(segment
		(start 8.224266 -215.83523)
		(end 9.856216 -214.20328)
		(width 0.1143)
		(layer "B.Cu")
		(net "PCIE_MATED#")
	)
	(segment
		(start 11.380216 -212.65388)
		(end 11.380216 -212.67928)
		(width 0.1143)
		(layer "B.Cu")
		(net "PCIE_MATED#")
	)
	(segment
		(start 13.412216 -239.57788)
		(end 26.874216 -239.57788)
		(width 0.1143)
		(layer "B.Cu")
		(net "PCIE_MATED#")
	)
	(segment
		(start 8.224266 -234.38993)
		(end 8.224266 -215.83523)
		(width 0.1143)
		(layer "B.Cu")
		(net "PCIE_MATED#")
	)
	(segment
		(start 11.380216 -212.67928)
		(end 9.856216 -214.20328)
		(width 0.1143)
		(layer "B.Cu")
		(net "PCIE_MATED#")
	)
	(segment
		(start 84.836 -243.332)
		(end 73.66 -243.332)
		(width 0.127)
		(layer "In2.Cu")
		(net "PCIE_MATED#")
	)
	(segment
		(start 85.5345 -242.6335)
		(end 84.836 -243.332)
		(width 0.127)
		(layer "In2.Cu")
		(net "PCIE_MATED#")
	)
	(segment
		(start 28.723336 -241.427)
		(end 26.874216 -239.57788)
		(width 0.127)
		(layer "In2.Cu")
		(net "PCIE_MATED#")
	)
	(segment
		(start 73.66 -243.332)
		(end 71.755 -241.427)
		(width 0.127)
		(layer "In2.Cu")
		(net "PCIE_MATED#")
	)
	(segment
		(start 71.755 -241.427)
		(end 28.723336 -241.427)
		(width 0.127)
		(layer "In2.Cu")
		(net "PCIE_MATED#")
	)
	(segment
		(start 98.679 -242.6335)
		(end 85.5345 -242.6335)
		(width 0.127)
		(layer "In2.Cu")
		(net "PCIE_MATED#")
	)
	(segment
		(start 199.061578 -68.124578)
		(end 202.656694 -71.719694)
		(width 0.1397)
		(layer "B.Cu")
		(net "PCIE_SAS_CPU_RX_N0")
	)
	(segment
		(start 113.060734 -10.95248)
		(end 117.007386 -7.005828)
		(width 0.1397)
		(layer "B.Cu")
		(net "PCIE_SAS_CPU_RX_N0")
	)
	(segment
		(start 157.725872 -28.303982)
		(end 196.677788 -67.255898)
		(width 0.1397)
		(layer "B.Cu")
		(net "PCIE_SAS_CPU_RX_N0")
	)
	(segment
		(start 117.456458 -6.8199)
		(end 130.180842 -6.8199)
		(width 0.1397)
		(layer "B.Cu")
		(net "PCIE_SAS_CPU_RX_N0")
	)
	(segment
		(start 105.40365 -11.238992)
		(end 112.369092 -11.238992)
		(width 0.1397)
		(layer "B.Cu")
		(net "PCIE_SAS_CPU_RX_N0")
	)
	(segment
		(start 202.145646 -74.05497)
		(end 202.450446 -73.75017)
		(width 0.1397)
		(layer "B.Cu")
		(net "PCIE_SAS_CPU_RX_N0")
	)
	(segment
		(start 203.165456 -74.495914)
		(end 202.9587 -74.70267)
		(width 0.1397)
		(layer "B.Cu")
		(net "PCIE_SAS_CPU_RX_N0")
	)
	(segment
		(start 202.813412 -74.783696)
		(end 202.526392 -74.783696)
		(width 0.1397)
		(layer "B.Cu")
		(net "PCIE_SAS_CPU_RX_N0")
	)
	(segment
		(start 93.84411 -30.991048)
		(end 93.84411 -29.96311)
		(width 0.1397)
		(layer "B.Cu")
		(net "PCIE_SAS_CPU_RX_N0")
	)
	(segment
		(start 152.147016 -28.1178)
		(end 157.277054 -28.1178)
		(width 0.1397)
		(layer "B.Cu")
		(net "PCIE_SAS_CPU_RX_N0")
	)
	(segment
		(start 93.074998 -28.757372)
		(end 93.074998 -23.567644)
		(width 0.1397)
		(layer "B.Cu")
		(net "PCIE_SAS_CPU_RX_N0")
	)
	(segment
		(start 93.639386 -29.46908)
		(end 93.179392 -29.009086)
		(width 0.1397)
		(layer "B.Cu")
		(net "PCIE_SAS_CPU_RX_N0")
	)
	(segment
		(start 130.629914 -7.005828)
		(end 151.455374 -27.831288)
		(width 0.1397)
		(layer "B.Cu")
		(net "PCIE_SAS_CPU_RX_N0")
	)
	(segment
		(start 203.302616 -73.279)
		(end 203.302616 -74.164698)
		(width 0.1397)
		(layer "B.Cu")
		(net "PCIE_SAS_CPU_RX_N0")
	)
	(segment
		(start 198.341488 -67.945)
		(end 198.628 -67.945)
		(width 0.1397)
		(layer "B.Cu")
		(net "PCIE_SAS_CPU_RX_N0")
	)
	(segment
		(start 93.260926 -23.118572)
		(end 104.954578 -11.42492)
		(width 0.1397)
		(layer "B.Cu")
		(net "PCIE_SAS_CPU_RX_N0")
	)
	(arc
		(start 202.656694 -71.719694)
		(mid 203.134719 -72.43511)
		(end 203.302616 -73.279)
		(width 0.1397)
		(layer "B.Cu")
		(net "PCIE_SAS_CPU_RX_N0")
	)
	(arc
		(start 93.074998 -23.567644)
		(mid 93.123334 -23.32464)
		(end 93.260926 -23.118572)
		(width 0.1397)
		(layer "B.Cu")
		(net "PCIE_SAS_CPU_RX_N0")
	)
	(arc
		(start 151.455374 -27.831288)
		(mid 151.772688 -28.043374)
		(end 152.147016 -28.1178)
		(width 0.1397)
		(layer "B.Cu")
		(net "PCIE_SAS_CPU_RX_N0")
	)
	(arc
		(start 202.9587 -74.70267)
		(mid 202.891697 -74.753301)
		(end 202.813412 -74.783696)
		(width 0.1397)
		(layer "B.Cu")
		(net "PCIE_SAS_CPU_RX_N0")
	)
	(arc
		(start 202.145646 -74.625962)
		(mid 202.02739 -74.340466)
		(end 202.145646 -74.05497)
		(width 0.1397)
		(layer "B.Cu")
		(net "PCIE_SAS_CPU_RX_N0")
	)
	(arc
		(start 198.628 -67.945)
		(mid 198.862645 -67.991674)
		(end 199.061578 -68.124578)
		(width 0.1397)
		(layer "B.Cu")
		(net "PCIE_SAS_CPU_RX_N0")
	)
	(arc
		(start 196.677788 -67.255898)
		(mid 197.4411 -67.765927)
		(end 198.341488 -67.945)
		(width 0.1397)
		(layer "B.Cu")
		(net "PCIE_SAS_CPU_RX_N0")
	)
	(arc
		(start 93.99016 -31.3436)
		(mid 93.882081 -31.181848)
		(end 93.84411 -30.991048)
		(width 0.1397)
		(layer "B.Cu")
		(net "PCIE_SAS_CPU_RX_N0")
	)
	(arc
		(start 104.954578 -11.42492)
		(mid 105.160614 -11.287251)
		(end 105.40365 -11.238992)
		(width 0.1397)
		(layer "B.Cu")
		(net "PCIE_SAS_CPU_RX_N0")
	)
	(arc
		(start 93.84411 -29.96311)
		(mid 93.790853 -29.695748)
		(end 93.639386 -29.46908)
		(width 0.1397)
		(layer "B.Cu")
		(net "PCIE_SAS_CPU_RX_N0")
	)
	(arc
		(start 93.179392 -29.009086)
		(mid 93.102143 -28.893614)
		(end 93.074998 -28.757372)
		(width 0.1397)
		(layer "B.Cu")
		(net "PCIE_SAS_CPU_RX_N0")
	)
	(arc
		(start 117.007386 -7.005828)
		(mid 117.213422 -6.868159)
		(end 117.456458 -6.8199)
		(width 0.1397)
		(layer "B.Cu")
		(net "PCIE_SAS_CPU_RX_N0")
	)
	(arc
		(start 203.302616 -74.164698)
		(mid 203.266963 -74.343938)
		(end 203.165456 -74.495914)
		(width 0.1397)
		(layer "B.Cu")
		(net "PCIE_SAS_CPU_RX_N0")
	)
	(arc
		(start 130.180842 -6.8199)
		(mid 130.423846 -6.868236)
		(end 130.629914 -7.005828)
		(width 0.1397)
		(layer "B.Cu")
		(net "PCIE_SAS_CPU_RX_N0")
	)
	(arc
		(start 202.526392 -74.783696)
		(mid 202.320325 -74.742707)
		(end 202.145646 -74.625962)
		(width 0.1397)
		(layer "B.Cu")
		(net "PCIE_SAS_CPU_RX_N0")
	)
	(arc
		(start 112.369092 -11.238992)
		(mid 112.743401 -11.164519)
		(end 113.060734 -10.95248)
		(width 0.1397)
		(layer "B.Cu")
		(net "PCIE_SAS_CPU_RX_N0")
	)
	(arc
		(start 157.277054 -28.1178)
		(mid 157.520004 -28.166219)
		(end 157.725872 -28.303982)
		(width 0.1397)
		(layer "B.Cu")
		(net "PCIE_SAS_CPU_RX_N0")
	)
	(segment
		(start 344.297 -106.6165)
		(end 344.17 -106.7435)
		(width 0.508)
		(layer "F.Cu")
		(net "P5V_STBY_VBST_RR")
	)
	(segment
		(start 344.297 -105.791)
		(end 344.297 -106.6165)
		(width 0.508)
		(layer "F.Cu")
		(net "P5V_STBY_VBST_RR")
	)
	(segment
		(start 344.1065 -106.68)
		(end 344.17 -106.7435)
		(width 0.508)
		(layer "F.Cu")
		(net "P5V_STBY_VBST_RR")
	)
	(segment
		(start 343.027 -106.68)
		(end 344.1065 -106.68)
		(width 0.508)
		(layer "F.Cu")
		(net "P5V_STBY_VBST_RR")
	)
	(via
		(at 344.297 -105.791)
		(size 0.7112)
		(drill 0.3556)
		(layers "F.Cu" "B.Cu")
		(net "P5V_STBY_VBST_RR")
	)
	(segment
		(start 280.761948 -176.317656)
		(end 283.372052 -176.317656)
		(width 0.1143)
		(layer "F.Cu")
		(net "ROMA10")
	)
	(segment
		(start 274.6375 -175.641)
		(end 274.867624 -175.410876)
		(width 0.1143)
		(layer "F.Cu")
		(net "ROMA10")
	)
	(segment
		(start 276.071076 -175.410876)
		(end 276.437852 -175.0441)
		(width 0.1143)
		(layer "F.Cu")
		(net "ROMA10")
	)
	(segment
		(start 283.631132 -176.576736)
		(end 285.010352 -176.576736)
		(width 0.1143)
		(layer "F.Cu")
		(net "ROMA10")
	)
	(segment
		(start 274.867624 -175.410876)
		(end 275.5646 -175.410876)
		(width 0.1143)
		(layer "F.Cu")
		(net "ROMA10")
	)
	(segment
		(start 279.488392 -175.0441)
		(end 280.761948 -176.317656)
		(width 0.1143)
		(layer "F.Cu")
		(net "ROMA10")
	)
	(segment
		(start 285.010352 -176.576736)
		(end 285.346902 -176.240186)
		(width 0.1143)
		(layer "F.Cu")
		(net "ROMA10")
	)
	(segment
		(start 285.346902 -176.240186)
		(end 285.634938 -176.240186)
		(width 0.1143)
		(layer "F.Cu")
		(net "ROMA10")
	)
	(segment
		(start 275.5646 -175.410876)
		(end 276.071076 -175.410876)
		(width 0.1143)
		(layer "F.Cu")
		(net "ROMA10")
	)
	(segment
		(start 276.437852 -175.0441)
		(end 279.488392 -175.0441)
		(width 0.1143)
		(layer "F.Cu")
		(net "ROMA10")
	)
	(segment
		(start 283.372052 -176.317656)
		(end 283.631132 -176.576736)
		(width 0.1143)
		(layer "F.Cu")
		(net "ROMA10")
	)
	(via
		(at 275.5646 -175.410876)
		(size 0.7112)
		(drill 0.3556)
		(layers "F.Cu" "B.Cu")
		(net "ROMA10")
	)
	(segment
		(start 227.6094 -117.2464)
		(end 237.5916 -127.2286)
		(width 0.1143)
		(layer "F.Cu")
		(net "JTAG_BMC_TDI")
	)
	(segment
		(start 312.7883 -172.085)
		(end 314.16371 -172.085)
		(width 0.1143)
		(layer "F.Cu")
		(net "JTAG_BMC_TDI")
	)
	(segment
		(start 218.1225 -168.92524)
		(end 218.1225 -169.2275)
		(width 0.1143)
		(layer "F.Cu")
		(net "JTAG_BMC_TDI")
	)
	(segment
		(start 314.54471 -172.466)
		(end 315.849 -172.466)
		(width 0.1143)
		(layer "F.Cu")
		(net "JTAG_BMC_TDI")
	)
	(segment
		(start 227.6094 -109.1184)
		(end 227.6094 -117.2464)
		(width 0.1143)
		(layer "F.Cu")
		(net "JTAG_BMC_TDI")
	)
	(segment
		(start 226.949 -108.458)
		(end 227.6094 -109.1184)
		(width 0.1143)
		(layer "F.Cu")
		(net "JTAG_BMC_TDI")
	)
	(segment
		(start 301.898812 -171.704)
		(end 301.634906 -171.440094)
		(width 0.1143)
		(layer "F.Cu")
		(net "JTAG_BMC_TDI")
	)
	(segment
		(start 239.08004 -98.67011)
		(end 234.81411 -98.67011)
		(width 0.1143)
		(layer "F.Cu")
		(net "JTAG_BMC_TDI")
	)
	(segment
		(start 233.7054 -163.0934)
		(end 227.4316 -163.0934)
		(width 0.1143)
		(layer "F.Cu")
		(net "JTAG_BMC_TDI")
	)
	(segment
		(start 314.16371 -172.085)
		(end 314.54471 -172.466)
		(width 0.1143)
		(layer "F.Cu")
		(net "JTAG_BMC_TDI")
	)
	(segment
		(start 223.52 -168.402)
		(end 223.52 -167.005)
		(width 0.1143)
		(layer "F.Cu")
		(net "JTAG_BMC_TDI")
	)
	(segment
		(start 219.373196 -170.47845)
		(end 221.44355 -170.47845)
		(width 0.1143)
		(layer "F.Cu")
		(net "JTAG_BMC_TDI")
	)
	(segment
		(start 303.020476 -171.704)
		(end 301.898812 -171.704)
		(width 0.1143)
		(layer "F.Cu")
		(net "JTAG_BMC_TDI")
	)
	(segment
		(start 303.619154 -171.105322)
		(end 303.020476 -171.704)
		(width 0.1143)
		(layer "F.Cu")
		(net "JTAG_BMC_TDI")
	)
	(segment
		(start 227.4316 -163.0934)
		(end 223.52 -167.005)
		(width 0.1143)
		(layer "F.Cu")
		(net "JTAG_BMC_TDI")
	)
	(segment
		(start 237.5916 -151.7142)
		(end 237.5916 -159.2072)
		(width 0.1143)
		(layer "F.Cu")
		(net "JTAG_BMC_TDI")
	)
	(segment
		(start 309.852822 -171.105322)
		(end 303.619154 -171.105322)
		(width 0.1143)
		(layer "F.Cu")
		(net "JTAG_BMC_TDI")
	)
	(segment
		(start 312.7883 -172.085)
		(end 310.8325 -172.085)
		(width 0.1143)
		(layer "F.Cu")
		(net "JTAG_BMC_TDI")
	)
	(segment
		(start 310.8325 -172.085)
		(end 309.852822 -171.105322)
		(width 0.1143)
		(layer "F.Cu")
		(net "JTAG_BMC_TDI")
	)
	(segment
		(start 221.44355 -170.47845)
		(end 223.52 -168.402)
		(width 0.1143)
		(layer "F.Cu")
		(net "JTAG_BMC_TDI")
	)
	(segment
		(start 315.849 -172.466)
		(end 317.3095 -172.466)
		(width 0.1143)
		(layer "F.Cu")
		(net "JTAG_BMC_TDI")
	)
	(segment
		(start 237.5916 -127.2286)
		(end 237.5916 -151.7142)
		(width 0.1143)
		(layer "F.Cu")
		(net "JTAG_BMC_TDI")
	)
	(segment
		(start 218.1225 -169.2275)
		(end 219.373196 -170.47845)
		(width 0.1143)
		(layer "F.Cu")
		(net "JTAG_BMC_TDI")
	)
	(segment
		(start 237.5916 -159.2072)
		(end 233.7054 -163.0934)
		(width 0.1143)
		(layer "F.Cu")
		(net "JTAG_BMC_TDI")
	)
	(segment
		(start 317.3095 -172.466)
		(end 317.5635 -172.72)
		(width 0.1143)
		(layer "F.Cu")
		(net "JTAG_BMC_TDI")
	)
	(via
		(at 320.167 -138.7856)
		(size 0.5588)
		(drill 0.3048)
		(layers "F.Cu" "B.Cu")
		(net "JTAG_BMC_TDI")
	)
	(via
		(at 237.5916 -151.7142)
		(size 0.5588)
		(drill 0.3048)
		(layers "F.Cu" "B.Cu")
		(net "JTAG_BMC_TDI")
	)
	(via
		(at 226.949 -108.458)
		(size 0.5588)
		(drill 0.3048)
		(layers "F.Cu" "B.Cu")
		(net "JTAG_BMC_TDI")
	)
	(via
		(at 312.7883 -172.085)
		(size 0.5588)
		(drill 0.3048)
		(layers "F.Cu" "B.Cu")
		(net "JTAG_BMC_TDI")
	)
	(via
		(at 234.81411 -98.67011)
		(size 0.5588)
		(drill 0.3048)
		(layers "F.Cu" "B.Cu")
		(net "JTAG_BMC_TDI")
	)
	(via
		(at 223.52 -167.005)
		(size 0.7112)
		(drill 0.3556)
		(layers "F.Cu" "B.Cu")
		(net "JTAG_BMC_TDI")
	)
	(segment
		(start 292.738302 -136.652)
		(end 286.598868 -136.652)
		(width 0.127)
		(layer "In2.Cu")
		(net "JTAG_BMC_TDI")
	)
	(segment
		(start 313.252612 -132.155946)
		(end 304.594514 -132.155946)
		(width 0.127)
		(layer "In2.Cu")
		(net "JTAG_BMC_TDI")
	)
	(segment
		(start 269.332202 -151.7015)
		(end 269.319502 -151.7142)
		(width 0.127)
		(layer "In2.Cu")
		(net "JTAG_BMC_TDI")
	)
	(segment
		(start 286.598868 -136.652)
		(end 271.549368 -151.7015)
		(width 0.127)
		(layer "In2.Cu")
		(net "JTAG_BMC_TDI")
	)
	(segment
		(start 234.81411 -98.67011)
		(end 234.81411 -98.96729)
		(width 0.127)
		(layer "In2.Cu")
		(net "JTAG_BMC_TDI")
	)
	(segment
		(start 315.793628 -135.051292)
		(end 315.793628 -134.696962)
		(width 0.127)
		(layer "In2.Cu")
		(net "JTAG_BMC_TDI")
	)
	(segment
		(start 226.822 -106.9594)
		(end 226.822 -108.331)
		(width 0.127)
		(layer "In2.Cu")
		(net "JTAG_BMC_TDI")
	)
	(segment
		(start 319.527936 -138.7856)
		(end 315.793628 -135.051292)
		(width 0.127)
		(layer "In2.Cu")
		(net "JTAG_BMC_TDI")
	)
	(segment
		(start 226.822 -108.331)
		(end 226.949 -108.458)
		(width 0.127)
		(layer "In2.Cu")
		(net "JTAG_BMC_TDI")
	)
	(segment
		(start 304.086768 -131.6482)
		(end 297.742102 -131.6482)
		(width 0.127)
		(layer "In2.Cu")
		(net "JTAG_BMC_TDI")
	)
	(segment
		(start 234.81411 -98.96729)
		(end 226.822 -106.9594)
		(width 0.127)
		(layer "In2.Cu")
		(net "JTAG_BMC_TDI")
	)
	(segment
		(start 320.167 -138.7856)
		(end 319.527936 -138.7856)
		(width 0.127)
		(layer "In2.Cu")
		(net "JTAG_BMC_TDI")
	)
	(segment
		(start 315.793628 -134.696962)
		(end 313.252612 -132.155946)
		(width 0.127)
		(layer "In2.Cu")
		(net "JTAG_BMC_TDI")
	)
	(segment
		(start 304.594514 -132.155946)
		(end 304.086768 -131.6482)
		(width 0.127)
		(layer "In2.Cu")
		(net "JTAG_BMC_TDI")
	)
	(segment
		(start 271.549368 -151.7015)
		(end 269.332202 -151.7015)
		(width 0.127)
		(layer "In2.Cu")
		(net "JTAG_BMC_TDI")
	)
	(segment
		(start 297.742102 -131.6482)
		(end 292.738302 -136.652)
		(width 0.127)
		(layer "In2.Cu")
		(net "JTAG_BMC_TDI")
	)
	(segment
		(start 269.319502 -151.7142)
		(end 237.5916 -151.7142)
		(width 0.127)
		(layer "In2.Cu")
		(net "JTAG_BMC_TDI")
	)
	(segment
		(start 333.7433 -160.38322)
		(end 333.7433 -150.390098)
		(width 0.127)
		(layer "In5.Cu")
		(net "JTAG_BMC_TDI")
	)
	(segment
		(start 315.0616 -172.085)
		(end 319.7479 -167.3987)
		(width 0.127)
		(layer "In5.Cu")
		(net "JTAG_BMC_TDI")
	)
	(segment
		(start 333.7433 -150.390098)
		(end 327.055734 -143.702532)
		(width 0.127)
		(layer "In5.Cu")
		(net "JTAG_BMC_TDI")
	)
	(segment
		(start 327.055734 -143.702532)
		(end 324.231 -143.702532)
		(width 0.127)
		(layer "In5.Cu")
		(net "JTAG_BMC_TDI")
	)
	(segment
		(start 319.7479 -167.3987)
		(end 326.72782 -167.3987)
		(width 0.127)
		(layer "In5.Cu")
		(net "JTAG_BMC_TDI")
	)
	(segment
		(start 312.7883 -172.085)
		(end 315.0616 -172.085)
		(width 0.127)
		(layer "In5.Cu")
		(net "JTAG_BMC_TDI")
	)
	(segment
		(start 326.72782 -167.3987)
		(end 333.7433 -160.38322)
		(width 0.127)
		(layer "In5.Cu")
		(net "JTAG_BMC_TDI")
	)
	(segment
		(start 320.167 -139.638532)
		(end 320.167 -138.7856)
		(width 0.127)
		(layer "In5.Cu")
		(net "JTAG_BMC_TDI")
	)
	(segment
		(start 324.231 -143.702532)
		(end 320.167 -139.638532)
		(width 0.127)
		(layer "In5.Cu")
		(net "JTAG_BMC_TDI")
	)
	(segment
		(start 339.253576 -112.421924)
		(end 339.09 -112.5855)
		(width 0.254)
		(layer "F.Cu")
		(net "AGND_P5V_STBY")
	)
	(segment
		(start 345.28252 -119.126)
		(end 346.075 -118.33352)
		(width 0.254)
		(layer "F.Cu")
		(net "AGND_P5V_STBY")
	)
	(segment
		(start 342.256872 -115.959636)
		(end 342.637872 -116.340636)
		(width 0.254)
		(layer "F.Cu")
		(net "AGND_P5V_STBY")
	)
	(segment
		(start 342.637872 -118.482872)
		(end 343.281 -119.126)
		(width 0.254)
		(layer "F.Cu")
		(net "AGND_P5V_STBY")
	)
	(segment
		(start 339.5345 -114.808)
		(end 339.5345 -113.03)
		(width 0.254)
		(layer "F.Cu")
		(net "AGND_P5V_STBY")
	)
	(segment
		(start 340.117938 -112.421924)
		(end 339.253576 -112.421924)
		(width 0.254)
		(layer "F.Cu")
		(net "AGND_P5V_STBY")
	)
	(segment
		(start 346.075 -115.57)
		(end 346.075 -116.586)
		(width 0.254)
		(layer "F.Cu")
		(net "AGND_P5V_STBY")
	)
	(segment
		(start 343.281 -119.126)
		(end 345.28252 -119.126)
		(width 0.254)
		(layer "F.Cu")
		(net "AGND_P5V_STBY")
	)
	(segment
		(start 342.637872 -116.340636)
		(end 342.637872 -118.482872)
		(width 0.254)
		(layer "F.Cu")
		(net "AGND_P5V_STBY")
	)
	(segment
		(start 346.075 -118.33352)
		(end 346.075 -116.586)
		(width 0.254)
		(layer "F.Cu")
		(net "AGND_P5V_STBY")
	)
	(segment
		(start 339.5345 -113.03)
		(end 339.09 -112.5855)
		(width 0.254)
		(layer "F.Cu")
		(net "AGND_P5V_STBY")
	)
	(via
		(at 339.09 -112.5855)
		(size 0.5588)
		(drill 0.3048)
		(layers "F.Cu" "B.Cu")
		(net "AGND_P5V_STBY")
	)
	(via
		(at 340.995 -114.935)
		(size 0.7112)
		(drill 0.3556)
		(layers "F.Cu" "B.Cu")
		(net "AGND_P5V_STBY")
	)
	(via
		(at 346.075 -116.586)
		(size 0.5588)
		(drill 0.3048)
		(layers "F.Cu" "B.Cu")
		(net "AGND_P5V_STBY")
	)
	(segment
		(start 346.1766 -116.4844)
		(end 346.075 -116.586)
		(width 0.254)
		(layer "B.Cu")
		(net "AGND_P5V_STBY")
	)
	(segment
		(start 346.075 -116.586)
		(end 342.646 -116.586)
		(width 0.254)
		(layer "B.Cu")
		(net "AGND_P5V_STBY")
	)
	(segment
		(start 342.646 -116.586)
		(end 340.995 -114.935)
		(width 0.254)
		(layer "B.Cu")
		(net "AGND_P5V_STBY")
	)
	(segment
		(start 347.472 -116.4844)
		(end 346.1766 -116.4844)
		(width 0.254)
		(layer "B.Cu")
		(net "AGND_P5V_STBY")
	)
	(segment
		(start 339.09 -113.03)
		(end 339.09 -112.5855)
		(width 0.254)
		(layer "B.Cu")
		(net "AGND_P5V_STBY")
	)
	(segment
		(start 340.995 -114.935)
		(end 339.09 -113.03)
		(width 0.254)
		(layer "B.Cu")
		(net "AGND_P5V_STBY")
	)
	(segment
		(start 350.033336 -71.641462)
		(end 350.033336 -70.231)
		(width 0.1143)
		(layer "F.Cu")
		(net "ROMD1_R")
	)
	(segment
		(start 342.824308 -69.61505)
		(end 350.28505 -69.61505)
		(width 0.1143)
		(layer "F.Cu")
		(net "ROMD1_R")
	)
	(segment
		(start 350.393 -69.765672)
		(end 350.393 -69.723)
		(width 0.1143)
		(layer "F.Cu")
		(net "ROMD1_R")
	)
	(segment
		(start 338.0105 -75.692)
		(end 338.709 -74.9935)
		(width 0.1143)
		(layer "F.Cu")
		(net "ROMD1_R")
	)
	(segment
		(start 338.709 -73.730358)
		(end 342.824308 -69.61505)
		(width 0.1143)
		(layer "F.Cu")
		(net "ROMD1_R")
	)
	(segment
		(start 338.709 -74.9935)
		(end 338.709 -73.730358)
		(width 0.1143)
		(layer "F.Cu")
		(net "ROMD1_R")
	)
	(segment
		(start 350.033336 -70.231)
		(end 350.060006 -70.098666)
		(width 0.1143)
		(layer "F.Cu")
		(net "ROMD1_R")
	)
	(segment
		(start 350.28505 -69.61505)
		(end 350.393 -69.723)
		(width 0.1143)
		(layer "F.Cu")
		(net "ROMD1_R")
	)
	(segment
		(start 350.060006 -70.098666)
		(end 350.393 -69.765672)
		(width 0.1143)
		(layer "F.Cu")
		(net "ROMD1_R")
	)
	(via
		(at 349.758 -70.358)
		(size 0.7112)
		(drill 0.3556)
		(layers "F.Cu" "B.Cu")
		(net "ROMD1_R")
	)
	(via
		(at 350.393 -69.723)
		(size 0.5588)
		(drill 0.3048)
		(layers "F.Cu" "B.Cu")
		(net "ROMD1_R")
	)
	(segment
		(start 349.5802 -71.3613)
		(end 349.5802 -70.5358)
		(width 0.1143)
		(layer "B.Cu")
		(net "ROMD1_R")
	)
	(segment
		(start 349.5802 -70.5358)
		(end 349.758 -70.358)
		(width 0.1143)
		(layer "B.Cu")
		(net "ROMD1_R")
	)
	(segment
		(start 350.393 -69.723)
		(end 349.758 -70.358)
		(width 0.1143)
		(layer "B.Cu")
		(net "ROMD1_R")
	)
	(segment
		(start 348.5642 -71.3613)
		(end 349.5802 -71.3613)
		(width 0.1143)
		(layer "B.Cu")
		(net "ROMD1_R")
	)
	(segment
		(start 302.26 -172.248322)
		(end 301.931578 -172.576744)
		(width 0.1143)
		(layer "F.Cu")
		(net "JTAG_BMC_TMS")
	)
	(segment
		(start 308.646322 -172.248322)
		(end 302.26 -172.248322)
		(width 0.1143)
		(layer "F.Cu")
		(net "JTAG_BMC_TMS")
	)
	(segment
		(start 314.964064 -193.298064)
		(end 314.071 -192.405)
		(width 0.1143)
		(layer "F.Cu")
		(net "JTAG_BMC_TMS")
	)
	(segment
		(start 246.253 -116.868702)
		(end 246.253 -137.16)
		(width 0.1143)
		(layer "F.Cu")
		(net "JTAG_BMC_TMS")
	)
	(segment
		(start 243.080032 -98.67011)
		(end 243.080032 -100.078032)
		(width 0.1143)
		(layer "F.Cu")
		(net "JTAG_BMC_TMS")
	)
	(segment
		(start 314.071 -192.405)
		(end 312.9915 -192.405)
		(width 0.1143)
		(layer "F.Cu")
		(net "JTAG_BMC_TMS")
	)
	(segment
		(start 314.964064 -193.421)
		(end 314.964064 -193.298064)
		(width 0.1143)
		(layer "F.Cu")
		(net "JTAG_BMC_TMS")
	)
	(segment
		(start 248.77649 -111.39551)
		(end 247.717564 -112.454436)
		(width 0.1143)
		(layer "F.Cu")
		(net "JTAG_BMC_TMS")
	)
	(segment
		(start 313.69 -173.228)
		(end 309.626 -173.228)
		(width 0.1143)
		(layer "F.Cu")
		(net "JTAG_BMC_TMS")
	)
	(segment
		(start 301.171356 -172.576744)
		(end 300.834806 -172.240194)
		(width 0.1143)
		(layer "F.Cu")
		(net "JTAG_BMC_TMS")
	)
	(segment
		(start 301.931578 -172.576744)
		(end 301.171356 -172.576744)
		(width 0.1143)
		(layer "F.Cu")
		(net "JTAG_BMC_TMS")
	)
	(segment
		(start 309.626 -173.228)
		(end 308.646322 -172.248322)
		(width 0.1143)
		(layer "F.Cu")
		(net "JTAG_BMC_TMS")
	)
	(segment
		(start 314.964064 -195.199)
		(end 314.964064 -193.421)
		(width 0.1143)
		(layer "F.Cu")
		(net "JTAG_BMC_TMS")
	)
	(segment
		(start 248.77649 -105.77449)
		(end 248.77649 -111.39551)
		(width 0.1143)
		(layer "F.Cu")
		(net "JTAG_BMC_TMS")
	)
	(segment
		(start 247.717564 -115.404138)
		(end 246.253 -116.868702)
		(width 0.1143)
		(layer "F.Cu")
		(net "JTAG_BMC_TMS")
	)
	(segment
		(start 247.717564 -112.454436)
		(end 247.717564 -115.404138)
		(width 0.1143)
		(layer "F.Cu")
		(net "JTAG_BMC_TMS")
	)
	(segment
		(start 243.080032 -100.078032)
		(end 248.77649 -105.77449)
		(width 0.1143)
		(layer "F.Cu")
		(net "JTAG_BMC_TMS")
	)
	(segment
		(start 246.253 -137.16)
		(end 248.158 -139.065)
		(width 0.1143)
		(layer "F.Cu")
		(net "JTAG_BMC_TMS")
	)
	(via
		(at 314.964064 -193.421)
		(size 0.5588)
		(drill 0.3048)
		(layers "F.Cu" "B.Cu")
		(net "JTAG_BMC_TMS")
	)
	(via
		(at 313.69 -173.228)
		(size 0.5588)
		(drill 0.3048)
		(layers "F.Cu" "B.Cu")
		(net "JTAG_BMC_TMS")
	)
	(via
		(at 274.574 -138.2776)
		(size 0.5588)
		(drill 0.3048)
		(layers "F.Cu" "B.Cu")
		(net "JTAG_BMC_TMS")
	)
	(via
		(at 248.158 -139.065)
		(size 0.5588)
		(drill 0.3048)
		(layers "F.Cu" "B.Cu")
		(net "JTAG_BMC_TMS")
	)
	(segment
		(start 316.357 -185.42)
		(end 316.357 -182.098696)
		(width 0.127)
		(layer "In2.Cu")
		(net "JTAG_BMC_TMS")
	)
	(segment
		(start 317.119 -191.135)
		(end 317.119 -186.182)
		(width 0.127)
		(layer "In2.Cu")
		(net "JTAG_BMC_TMS")
	)
	(segment
		(start 262.347456 -138.2776)
		(end 260.556756 -140.0683)
		(width 0.127)
		(layer "In2.Cu")
		(net "JTAG_BMC_TMS")
	)
	(segment
		(start 317.119 -186.182)
		(end 316.357 -185.42)
		(width 0.127)
		(layer "In2.Cu")
		(net "JTAG_BMC_TMS")
	)
	(segment
		(start 274.574 -138.2776)
		(end 262.347456 -138.2776)
		(width 0.127)
		(layer "In2.Cu")
		(net "JTAG_BMC_TMS")
	)
	(segment
		(start 260.556756 -140.0683)
		(end 249.1613 -140.0683)
		(width 0.127)
		(layer "In2.Cu")
		(net "JTAG_BMC_TMS")
	)
	(segment
		(start 315.849 -181.590696)
		(end 315.849 -175.387)
		(width 0.127)
		(layer "In2.Cu")
		(net "JTAG_BMC_TMS")
	)
	(segment
		(start 249.1613 -140.0683)
		(end 248.158 -139.065)
		(width 0.127)
		(layer "In2.Cu")
		(net "JTAG_BMC_TMS")
	)
	(segment
		(start 316.357 -182.098696)
		(end 315.849 -181.590696)
		(width 0.127)
		(layer "In2.Cu")
		(net "JTAG_BMC_TMS")
	)
	(segment
		(start 314.964064 -193.289936)
		(end 317.119 -191.135)
		(width 0.127)
		(layer "In2.Cu")
		(net "JTAG_BMC_TMS")
	)
	(segment
		(start 315.849 -175.387)
		(end 313.69 -173.228)
		(width 0.127)
		(layer "In2.Cu")
		(net "JTAG_BMC_TMS")
	)
	(segment
		(start 314.964064 -193.421)
		(end 314.964064 -193.289936)
		(width 0.127)
		(layer "In2.Cu")
		(net "JTAG_BMC_TMS")
	)
	(segment
		(start 275.0693 -138.7729)
		(end 275.0693 -140.081762)
		(width 0.127)
		(layer "In5.Cu")
		(net "JTAG_BMC_TMS")
	)
	(segment
		(start 274.9169 -140.234162)
		(end 274.9169 -144.546828)
		(width 0.127)
		(layer "In5.Cu")
		(net "JTAG_BMC_TMS")
	)
	(segment
		(start 289.501072 -154.753818)
		(end 290.517072 -155.769818)
		(width 0.127)
		(layer "In5.Cu")
		(net "JTAG_BMC_TMS")
	)
	(segment
		(start 312.039 -173.228)
		(end 313.69 -173.228)
		(width 0.127)
		(layer "In5.Cu")
		(net "JTAG_BMC_TMS")
	)
	(segment
		(start 275.0693 -140.081762)
		(end 274.9169 -140.234162)
		(width 0.127)
		(layer "In5.Cu")
		(net "JTAG_BMC_TMS")
	)
	(segment
		(start 274.9169 -144.546828)
		(end 285.12389 -154.753818)
		(width 0.127)
		(layer "In5.Cu")
		(net "JTAG_BMC_TMS")
	)
	(segment
		(start 285.12389 -154.753818)
		(end 289.501072 -154.753818)
		(width 0.127)
		(layer "In5.Cu")
		(net "JTAG_BMC_TMS")
	)
	(segment
		(start 293.310818 -155.769818)
		(end 309.499 -171.958)
		(width 0.127)
		(layer "In5.Cu")
		(net "JTAG_BMC_TMS")
	)
	(segment
		(start 310.769 -171.958)
		(end 312.039 -173.228)
		(width 0.127)
		(layer "In5.Cu")
		(net "JTAG_BMC_TMS")
	)
	(segment
		(start 274.574 -138.2776)
		(end 275.0693 -138.7729)
		(width 0.127)
		(layer "In5.Cu")
		(net "JTAG_BMC_TMS")
	)
	(segment
		(start 309.499 -171.958)
		(end 310.769 -171.958)
		(width 0.127)
		(layer "In5.Cu")
		(net "JTAG_BMC_TMS")
	)
	(segment
		(start 290.517072 -155.769818)
		(end 293.310818 -155.769818)
		(width 0.127)
		(layer "In5.Cu")
		(net "JTAG_BMC_TMS")
	)
	(segment
		(start 341.122 -115.443)
		(end 341.122 -115.824)
		(width 0.3048)
		(layer "F.Cu")
		(net "P5V_STBY_VRG5")
	)
	(segment
		(start 341.117936 -113.533936)
		(end 341.503 -113.919)
		(width 0.3048)
		(layer "F.Cu")
		(net "P5V_STBY_VRG5")
	)
	(segment
		(start 341.503 -114.554)
		(end 341.117936 -114.939064)
		(width 0.3048)
		(layer "F.Cu")
		(net "P5V_STBY_VRG5")
	)
	(segment
		(start 341.117936 -115.438936)
		(end 341.122 -115.443)
		(width 0.3048)
		(layer "F.Cu")
		(net "P5V_STBY_VRG5")
	)
	(segment
		(start 341.503 -113.919)
		(end 341.503 -114.427)
		(width 0.3048)
		(layer "F.Cu")
		(net "P5V_STBY_VRG5")
	)
	(segment
		(start 341.503 -114.427)
		(end 341.503 -114.554)
		(width 0.3048)
		(layer "F.Cu")
		(net "P5V_STBY_VRG5")
	)
	(segment
		(start 340.026752 -115.824)
		(end 339.979 -115.8875)
		(width 0.508)
		(layer "F.Cu")
		(net "P5V_STBY_VRG5")
	)
	(segment
		(start 341.117936 -114.939064)
		(end 341.117936 -115.438936)
		(width 0.3048)
		(layer "F.Cu")
		(net "P5V_STBY_VRG5")
	)
	(segment
		(start 341.122 -115.824)
		(end 340.026752 -115.824)
		(width 0.508)
		(layer "F.Cu")
		(net "P5V_STBY_VRG5")
	)
	(segment
		(start 341.117936 -112.409224)
		(end 341.117936 -113.533936)
		(width 0.3048)
		(layer "F.Cu")
		(net "P5V_STBY_VRG5")
	)
	(via
		(at 341.503 -114.427)
		(size 0.7112)
		(drill 0.3556)
		(layers "F.Cu" "B.Cu")
		(net "P5V_STBY_VRG5")
	)
	(segment
		(start 123.867164 -115.550696)
		(end 130.656838 -108.761022)
		(width 0.1016)
		(layer "F.Cu")
		(net "SAS_EXP_GF_TX_DN3")
	)
	(segment
		(start 133.306312 -253.75997)
		(end 133.306312 -231.290876)
		(width 0.1016)
		(layer "F.Cu")
		(net "SAS_EXP_GF_TX_DN3")
	)
	(segment
		(start 133.000242 -256.25044)
		(end 133.000242 -254.4064)
		(width 0.1016)
		(layer "F.Cu")
		(net "SAS_EXP_GF_TX_DN3")
	)
	(segment
		(start 123.15952 -156.327348)
		(end 123.15952 -117.2591)
		(width 0.1016)
		(layer "F.Cu")
		(net "SAS_EXP_GF_TX_DN3")
	)
	(segment
		(start 134.015988 -229.577138)
		(end 136.436354 -227.156772)
		(width 0.1016)
		(layer "F.Cu")
		(net "SAS_EXP_GF_TX_DN3")
	)
	(segment
		(start 135.6233 -169.9133)
		(end 123.952762 -158.242762)
		(width 0.1016)
		(layer "F.Cu")
		(net "SAS_EXP_GF_TX_DN3")
	)
	(segment
		(start 133.152134 -254.040132)
		(end 133.217412 -253.9746)
		(width 0.1016)
		(layer "F.Cu")
		(net "SAS_EXP_GF_TX_DN3")
	)
	(segment
		(start 137.181336 -225.358198)
		(end 137.181336 -173.674786)
		(width 0.1016)
		(layer "F.Cu")
		(net "SAS_EXP_GF_TX_DN3")
	)
	(segment
		(start 131.15417 -107.560364)
		(end 131.15417 -99.502722)
		(width 0.1016)
		(layer "F.Cu")
		(net "SAS_EXP_GF_TX_DN3")
	)
	(arc
		(start 123.15952 -117.2591)
		(mid 123.343416 -116.334504)
		(end 123.867164 -115.550696)
		(width 0.1016)
		(layer "F.Cu")
		(net "SAS_EXP_GF_TX_DN3")
	)
	(arc
		(start 131.15417 -99.502722)
		(mid 131.121823 -99.340104)
		(end 131.02971 -99.20224)
		(width 0.1016)
		(layer "F.Cu")
		(net "SAS_EXP_GF_TX_DN3")
	)
	(arc
		(start 130.656838 -108.761022)
		(mid 131.024915 -108.210155)
		(end 131.15417 -107.560364)
		(width 0.1016)
		(layer "F.Cu")
		(net "SAS_EXP_GF_TX_DN3")
	)
	(arc
		(start 123.952762 -158.242762)
		(mid 123.36565 -157.363948)
		(end 123.15952 -156.327348)
		(width 0.1016)
		(layer "F.Cu")
		(net "SAS_EXP_GF_TX_DN3")
	)
	(arc
		(start 136.436354 -227.156772)
		(mid 136.98773 -226.331579)
		(end 137.181336 -225.358198)
		(width 0.1016)
		(layer "F.Cu")
		(net "SAS_EXP_GF_TX_DN3")
	)
	(arc
		(start 133.217412 -253.9746)
		(mid 133.247423 -253.939459)
		(end 133.271768 -253.900178)
		(width 0.1016)
		(layer "F.Cu")
		(net "SAS_EXP_GF_TX_DN3")
	)
	(arc
		(start 133.000242 -254.4064)
		(mid 133.039768 -254.208162)
		(end 133.152134 -254.040132)
		(width 0.1016)
		(layer "F.Cu")
		(net "SAS_EXP_GF_TX_DN3")
	)
	(arc
		(start 133.306312 -231.290876)
		(mid 133.490685 -230.363408)
		(end 134.015988 -229.577138)
		(width 0.1016)
		(layer "F.Cu")
		(net "SAS_EXP_GF_TX_DN3")
	)
	(arc
		(start 137.181336 -173.674786)
		(mid 136.776411 -171.639093)
		(end 135.6233 -169.9133)
		(width 0.1016)
		(layer "F.Cu")
		(net "SAS_EXP_GF_TX_DN3")
	)
	(arc
		(start 133.295898 -253.837948)
		(mid 133.303637 -253.799298)
		(end 133.306312 -253.75997)
		(width 0.1016)
		(layer "F.Cu")
		(net "SAS_EXP_GF_TX_DN3")
	)
	(arc
		(start 133.271768 -253.900178)
		(mid 133.285561 -253.869732)
		(end 133.295898 -253.837948)
		(width 0.1016)
		(layer "F.Cu")
		(net "SAS_EXP_GF_TX_DN3")
	)
	(segment
		(start 160.63214 -75.553824)
		(end 160.63214 -76.30922)
		(width 0.1397)
		(layer "F.Cu")
		(net "PCIE_SAS_CPU_TX_P6")
	)
	(segment
		(start 103.085646 -30.760924)
		(end 103.439722 -30.406848)
		(width 0.1397)
		(layer "F.Cu")
		(net "PCIE_SAS_CPU_TX_P6")
	)
	(segment
		(start 104.016556 -26.633678)
		(end 108.59897 -22.051264)
		(width 0.1397)
		(layer "F.Cu")
		(net "PCIE_SAS_CPU_TX_P6")
	)
	(segment
		(start 132.1689 -16.58747)
		(end 132.1689 -19.778726)
		(width 0.1397)
		(layer "F.Cu")
		(net "PCIE_SAS_CPU_TX_P6")
	)
	(segment
		(start 118.89613 -14.224)
		(end 130.326384 -14.224)
		(width 0.1397)
		(layer "F.Cu")
		(net "PCIE_SAS_CPU_TX_P6")
	)
	(segment
		(start 102.880922 -32.81934)
		(end 102.880922 -31.255208)
		(width 0.1397)
		(layer "F.Cu")
		(net "PCIE_SAS_CPU_TX_P6")
	)
	(segment
		(start 111.131858 -21.582888)
		(end 118.204488 -14.510512)
		(width 0.1397)
		(layer "F.Cu")
		(net "PCIE_SAS_CPU_TX_P6")
	)
	(segment
		(start 159.796734 -74.323194)
		(end 160.35274 -74.8792)
		(width 0.1397)
		(layer "F.Cu")
		(net "PCIE_SAS_CPU_TX_P6")
	)
	(segment
		(start 102.750112 -33.399984)
		(end 102.781862 -33.368234)
		(width 0.1397)
		(layer "F.Cu")
		(net "PCIE_SAS_CPU_TX_P6")
	)
	(segment
		(start 109.290612 -21.764752)
		(end 110.6932 -21.764752)
		(width 0.1397)
		(layer "F.Cu")
		(net "PCIE_SAS_CPU_TX_P6")
	)
	(segment
		(start 103.544116 -30.155134)
		(end 103.544116 -27.774138)
		(width 0.1397)
		(layer "F.Cu")
		(net "PCIE_SAS_CPU_TX_P6")
	)
	(segment
		(start 102.781862 -33.368234)
		(end 102.781862 -33.058608)
		(width 0.1397)
		(layer "F.Cu")
		(net "PCIE_SAS_CPU_TX_P6")
	)
	(segment
		(start 132.540756 -20.676616)
		(end 159.16529 -47.30115)
		(width 0.1397)
		(layer "F.Cu")
		(net "PCIE_SAS_CPU_TX_P6")
	)
	(segment
		(start 159.63773 -48.44161)
		(end 159.63773 -73.9394)
		(width 0.1397)
		(layer "F.Cu")
		(net "PCIE_SAS_CPU_TX_P6")
	)
	(via
		(at 160.928812 -77.0255)
		(size 0.5588)
		(drill 0.3048)
		(layers "F.Cu" "B.Cu")
		(net "PCIE_SAS_CPU_TX_P6")
	)
	(arc
		(start 159.16529 -47.30115)
		(mid 159.514913 -47.824397)
		(end 159.63773 -48.44161)
		(width 0.1397)
		(layer "F.Cu")
		(net "PCIE_SAS_CPU_TX_P6")
	)
	(arc
		(start 102.880922 -31.255208)
		(mid 102.934131 -30.987709)
		(end 103.085646 -30.760924)
		(width 0.1397)
		(layer "F.Cu")
		(net "PCIE_SAS_CPU_TX_P6")
	)
	(arc
		(start 103.544116 -27.774138)
		(mid 103.666891 -27.156908)
		(end 104.016556 -26.633678)
		(width 0.1397)
		(layer "F.Cu")
		(net "PCIE_SAS_CPU_TX_P6")
	)
	(arc
		(start 110.6932 -21.764752)
		(mid 110.93061 -21.717435)
		(end 111.131858 -21.582888)
		(width 0.1397)
		(layer "F.Cu")
		(net "PCIE_SAS_CPU_TX_P6")
	)
	(arc
		(start 132.1689 -19.778726)
		(mid 132.265539 -20.264651)
		(end 132.540756 -20.676616)
		(width 0.1397)
		(layer "F.Cu")
		(net "PCIE_SAS_CPU_TX_P6")
	)
	(arc
		(start 130.326384 -14.224)
		(mid 130.890542 -14.336218)
		(end 131.3688 -14.6558)
		(width 0.1397)
		(layer "F.Cu")
		(net "PCIE_SAS_CPU_TX_P6")
	)
	(arc
		(start 160.35274 -74.8792)
		(mid 160.559555 -75.18872)
		(end 160.63214 -75.553824)
		(width 0.1397)
		(layer "F.Cu")
		(net "PCIE_SAS_CPU_TX_P6")
	)
	(arc
		(start 118.204488 -14.510512)
		(mid 118.521802 -14.298426)
		(end 118.89613 -14.224)
		(width 0.1397)
		(layer "F.Cu")
		(net "PCIE_SAS_CPU_TX_P6")
	)
	(arc
		(start 103.439722 -30.406848)
		(mid 103.516971 -30.291376)
		(end 103.544116 -30.155134)
		(width 0.1397)
		(layer "F.Cu")
		(net "PCIE_SAS_CPU_TX_P6")
	)
	(arc
		(start 160.63214 -76.30922)
		(mid 160.709246 -76.69686)
		(end 160.928812 -77.0255)
		(width 0.1397)
		(layer "F.Cu")
		(net "PCIE_SAS_CPU_TX_P6")
	)
	(arc
		(start 108.59897 -22.051264)
		(mid 108.916284 -21.839178)
		(end 109.290612 -21.764752)
		(width 0.1397)
		(layer "F.Cu")
		(net "PCIE_SAS_CPU_TX_P6")
	)
	(arc
		(start 159.63773 -73.9394)
		(mid 159.679048 -74.14712)
		(end 159.796734 -74.323194)
		(width 0.1397)
		(layer "F.Cu")
		(net "PCIE_SAS_CPU_TX_P6")
	)
	(arc
		(start 131.3688 -14.6558)
		(mid 131.960978 -15.542058)
		(end 132.1689 -16.58747)
		(width 0.1397)
		(layer "F.Cu")
		(net "PCIE_SAS_CPU_TX_P6")
	)
	(arc
		(start 102.831392 -32.938974)
		(mid 102.868067 -32.884085)
		(end 102.880922 -32.81934)
		(width 0.1397)
		(layer "F.Cu")
		(net "PCIE_SAS_CPU_TX_P6")
	)
	(arc
		(start 102.781862 -33.058608)
		(mid 102.794739 -32.993872)
		(end 102.831392 -32.938974)
		(width 0.1397)
		(layer "F.Cu")
		(net "PCIE_SAS_CPU_TX_P6")
	)
	(segment
		(start 160.938972 -79.052928)
		(end 160.776666 -78.971648)
		(width 0.1397)
		(layer "B.Cu")
		(net "PCIE_SAS_CPU_TX_P6")
	)
	(segment
		(start 161.449766 -78.24978)
		(end 161.449766 -78.641956)
		(width 0.1397)
		(layer "B.Cu")
		(net "PCIE_SAS_CPU_TX_P6")
	)
	(segment
		(start 160.61055 -78.570582)
		(end 160.61055 -77.56144)
		(width 0.1397)
		(layer "B.Cu")
		(net "PCIE_SAS_CPU_TX_P6")
	)
	(segment
		(start 160.764474 -77.189838)
		(end 160.928812 -77.0255)
		(width 0.1397)
		(layer "B.Cu")
		(net "PCIE_SAS_CPU_TX_P6")
	)
	(arc
		(start 160.776666 -78.971648)
		(mid 160.653714 -78.787637)
		(end 160.61055 -78.570582)
		(width 0.1397)
		(layer "B.Cu")
		(net "PCIE_SAS_CPU_TX_P6")
	)
	(arc
		(start 160.61055 -77.56144)
		(mid 160.650553 -77.36033)
		(end 160.764474 -77.189838)
		(width 0.1397)
		(layer "B.Cu")
		(net "PCIE_SAS_CPU_TX_P6")
	)
	(arc
		(start 161.449766 -78.641956)
		(mid 161.41187 -78.832471)
		(end 161.30397 -78.994)
		(width 0.1397)
		(layer "B.Cu")
		(net "PCIE_SAS_CPU_TX_P6")
	)
	(arc
		(start 161.30397 -78.994)
		(mid 161.130997 -79.082377)
		(end 160.938972 -79.052928)
		(width 0.1397)
		(layer "B.Cu")
		(net "PCIE_SAS_CPU_TX_P6")
	)
	(segment
		(start 344.8685 -114.808)
		(end 344.8685 -113.792)
		(width 0.254)
		(layer "F.Cu")
		(net "P5V_STBY_CC_R")
	)
	(segment
		(start 343.535 -116.967)
		(end 344.805 -116.967)
		(width 0.254)
		(layer "F.Cu")
		(net "P5V_STBY_CC_R")
	)
	(segment
		(start 344.8685 -115.824)
		(end 344.8685 -114.808)
		(width 0.254)
		(layer "F.Cu")
		(net "P5V_STBY_CC_R")
	)
	(segment
		(start 344.8685 -115.824)
		(end 344.8685 -116.9035)
		(width 0.254)
		(layer "F.Cu")
		(net "P5V_STBY_CC_R")
	)
	(segment
		(start 344.8685 -116.9035)
		(end 344.805 -116.967)
		(width 0.254)
		(layer "F.Cu")
		(net "P5V_STBY_CC_R")
	)
	(via
		(at 343.535 -116.967)
		(size 0.7112)
		(drill 0.3556)
		(layers "F.Cu" "B.Cu")
		(net "P5V_STBY_CC_R")
	)
	(segment
		(start 286.434784 -176.240186)
		(end 286.033464 -175.838866)
		(width 0.1143)
		(layer "F.Cu")
		(net "ROMA9")
	)
	(via
		(at 276.1234 -176.53)
		(size 0.7112)
		(drill 0.3556)
		(layers "F.Cu" "B.Cu")
		(net "ROMA9")
	)
	(via
		(at 286.033464 -175.838866)
		(size 0.508)
		(drill 0.254)
		(layers "F.Cu" "B.Cu")
		(net "ROMA9")
	)
	(segment
		(start 278.872188 -175.78324)
		(end 283.51353 -175.78324)
		(width 0.1143)
		(layer "B.Cu")
		(net "ROMA9")
	)
	(segment
		(start 278.125428 -176.53)
		(end 278.872188 -175.78324)
		(width 0.1143)
		(layer "B.Cu")
		(net "ROMA9")
	)
	(segment
		(start 283.51353 -175.78324)
		(end 283.569156 -175.838866)
		(width 0.1143)
		(layer "B.Cu")
		(net "ROMA9")
	)
	(segment
		(start 274.6375 -176.657)
		(end 274.7645 -176.53)
		(width 0.1143)
		(layer "B.Cu")
		(net "ROMA9")
	)
	(segment
		(start 283.569156 -175.838866)
		(end 286.033464 -175.838866)
		(width 0.1143)
		(layer "B.Cu")
		(net "ROMA9")
	)
	(segment
		(start 276.1234 -176.53)
		(end 278.125428 -176.53)
		(width 0.1143)
		(layer "B.Cu")
		(net "ROMA9")
	)
	(segment
		(start 274.7645 -176.53)
		(end 276.1234 -176.53)
		(width 0.1143)
		(layer "B.Cu")
		(net "ROMA9")
	)
	(segment
		(start 314.55868 -191.49568)
		(end 315.341 -192.278)
		(width 0.1143)
		(layer "F.Cu")
		(net "JTAG_BMC_TCK")
	)
	(segment
		(start 248.085864 -115.556792)
		(end 248.085864 -113.737136)
		(width 0.1143)
		(layer "F.Cu")
		(net "JTAG_BMC_TCK")
	)
	(segment
		(start 248.412 -139.8016)
		(end 249.0343 -139.1793)
		(width 0.1143)
		(layer "F.Cu")
		(net "JTAG_BMC_TCK")
	)
	(segment
		(start 312.475626 -189.857126)
		(end 312.475626 -189.86373)
		(width 0.1143)
		(layer "F.Cu")
		(net "JTAG_BMC_TCK")
	)
	(segment
		(start 246.634 -136.144)
		(end 246.634 -117.008656)
		(width 0.1143)
		(layer "F.Cu")
		(net "JTAG_BMC_TCK")
	)
	(segment
		(start 312.9915 -191.262)
		(end 313.22518 -191.49568)
		(width 0.1143)
		(layer "F.Cu")
		(net "JTAG_BMC_TCK")
	)
	(segment
		(start 249.936 -111.887)
		(end 249.936 -103.693976)
		(width 0.1143)
		(layer "F.Cu")
		(net "JTAG_BMC_TCK")
	)
	(segment
		(start 315.341 -192.278)
		(end 315.463936 -192.400936)
		(width 0.1143)
		(layer "F.Cu")
		(net "JTAG_BMC_TCK")
	)
	(segment
		(start 300.834806 -171.440094)
		(end 300.834806 -171.449238)
		(width 0.1143)
		(layer "F.Cu")
		(net "JTAG_BMC_TCK")
	)
	(segment
		(start 312.475626 -189.86373)
		(end 312.9915 -190.379604)
		(width 0.1143)
		(layer "F.Cu")
		(net "JTAG_BMC_TCK")
	)
	(segment
		(start 249.0343 -139.1793)
		(end 249.0343 -138.5443)
		(width 0.1143)
		(layer "F.Cu")
		(net "JTAG_BMC_TCK")
	)
	(segment
		(start 246.634 -117.008656)
		(end 248.085864 -115.556792)
		(width 0.1143)
		(layer "F.Cu")
		(net "JTAG_BMC_TCK")
	)
	(segment
		(start 300.834806 -171.449238)
		(end 301.23511 -171.849542)
		(width 0.1143)
		(layer "F.Cu")
		(net "JTAG_BMC_TCK")
	)
	(segment
		(start 315.463936 -192.400936)
		(end 315.463936 -195.199)
		(width 0.1143)
		(layer "F.Cu")
		(net "JTAG_BMC_TCK")
	)
	(segment
		(start 248.085864 -113.737136)
		(end 249.936 -111.887)
		(width 0.1143)
		(layer "F.Cu")
		(net "JTAG_BMC_TCK")
	)
	(segment
		(start 249.936 -103.693976)
		(end 247.080024 -100.838)
		(width 0.1143)
		(layer "F.Cu")
		(net "JTAG_BMC_TCK")
	)
	(segment
		(start 313.22518 -191.49568)
		(end 314.55868 -191.49568)
		(width 0.1143)
		(layer "F.Cu")
		(net "JTAG_BMC_TCK")
	)
	(segment
		(start 247.080024 -100.838)
		(end 247.080024 -98.67011)
		(width 0.1143)
		(layer "F.Cu")
		(net "JTAG_BMC_TCK")
	)
	(segment
		(start 248.412 -140.716)
		(end 248.412 -139.8016)
		(width 0.1143)
		(layer "F.Cu")
		(net "JTAG_BMC_TCK")
	)
	(segment
		(start 312.9915 -190.379604)
		(end 312.9915 -191.262)
		(width 0.1143)
		(layer "F.Cu")
		(net "JTAG_BMC_TCK")
	)
	(segment
		(start 249.0343 -138.5443)
		(end 246.634 -136.144)
		(width 0.1143)
		(layer "F.Cu")
		(net "JTAG_BMC_TCK")
	)
	(via
		(at 301.23511 -171.849542)
		(size 0.508)
		(drill 0.254)
		(layers "F.Cu" "B.Cu")
		(net "JTAG_BMC_TCK")
	)
	(via
		(at 274.574 -139.192)
		(size 0.5588)
		(drill 0.3048)
		(layers "F.Cu" "B.Cu")
		(net "JTAG_BMC_TCK")
	)
	(via
		(at 248.412 -140.716)
		(size 0.5588)
		(drill 0.3048)
		(layers "F.Cu" "B.Cu")
		(net "JTAG_BMC_TCK")
	)
	(via
		(at 312.475626 -189.857126)
		(size 0.5588)
		(drill 0.3048)
		(layers "F.Cu" "B.Cu")
		(net "JTAG_BMC_TCK")
	)
	(segment
		(start 262.168132 -139.192)
		(end 260.771132 -140.589)
		(width 0.127)
		(layer "In2.Cu")
		(net "JTAG_BMC_TCK")
	)
	(segment
		(start 312.52922 -183.6547)
		(end 313.0423 -183.14162)
		(width 0.127)
		(layer "In2.Cu")
		(net "JTAG_BMC_TCK")
	)
	(segment
		(start 312.475626 -189.857126)
		(end 311.6707 -189.0522)
		(width 0.127)
		(layer "In2.Cu")
		(net "JTAG_BMC_TCK")
	)
	(segment
		(start 305.874674 -171.849542)
		(end 301.23511 -171.849542)
		(width 0.127)
		(layer "In2.Cu")
		(net "JTAG_BMC_TCK")
	)
	(segment
		(start 260.771132 -140.589)
		(end 248.539 -140.589)
		(width 0.127)
		(layer "In2.Cu")
		(net "JTAG_BMC_TCK")
	)
	(segment
		(start 313.0423 -179.017168)
		(end 305.874674 -171.849542)
		(width 0.127)
		(layer "In2.Cu")
		(net "JTAG_BMC_TCK")
	)
	(segment
		(start 311.6707 -189.0522)
		(end 311.6707 -184.325768)
		(width 0.127)
		(layer "In2.Cu")
		(net "JTAG_BMC_TCK")
	)
	(segment
		(start 248.539 -140.589)
		(end 248.412 -140.716)
		(width 0.127)
		(layer "In2.Cu")
		(net "JTAG_BMC_TCK")
	)
	(segment
		(start 311.6707 -184.325768)
		(end 312.341768 -183.6547)
		(width 0.127)
		(layer "In2.Cu")
		(net "JTAG_BMC_TCK")
	)
	(segment
		(start 312.341768 -183.6547)
		(end 312.52922 -183.6547)
		(width 0.127)
		(layer "In2.Cu")
		(net "JTAG_BMC_TCK")
	)
	(segment
		(start 313.0423 -183.14162)
		(end 313.0423 -179.017168)
		(width 0.127)
		(layer "In2.Cu")
		(net "JTAG_BMC_TCK")
	)
	(segment
		(start 274.574 -139.192)
		(end 262.168132 -139.192)
		(width 0.127)
		(layer "In2.Cu")
		(net "JTAG_BMC_TCK")
	)
	(segment
		(start 301.23511 -164.44722)
		(end 301.23511 -171.849542)
		(width 0.127)
		(layer "In5.Cu")
		(net "JTAG_BMC_TCK")
	)
	(segment
		(start 274.574 -139.954)
		(end 274.5359 -139.9921)
		(width 0.127)
		(layer "In5.Cu")
		(net "JTAG_BMC_TCK")
	)
	(segment
		(start 285.03372 -155.202636)
		(end 289.315144 -155.202636)
		(width 0.127)
		(layer "In5.Cu")
		(net "JTAG_BMC_TCK")
	)
	(segment
		(start 289.315144 -155.202636)
		(end 290.331144 -156.218636)
		(width 0.127)
		(layer "In5.Cu")
		(net "JTAG_BMC_TCK")
	)
	(segment
		(start 274.5359 -144.704816)
		(end 285.03372 -155.202636)
		(width 0.127)
		(layer "In5.Cu")
		(net "JTAG_BMC_TCK")
	)
	(segment
		(start 290.331144 -156.218636)
		(end 293.006526 -156.218636)
		(width 0.127)
		(layer "In5.Cu")
		(net "JTAG_BMC_TCK")
	)
	(segment
		(start 293.006526 -156.218636)
		(end 301.23511 -164.44722)
		(width 0.127)
		(layer "In5.Cu")
		(net "JTAG_BMC_TCK")
	)
	(segment
		(start 274.5359 -139.9921)
		(end 274.5359 -144.704816)
		(width 0.127)
		(layer "In5.Cu")
		(net "JTAG_BMC_TCK")
	)
	(segment
		(start 274.574 -139.192)
		(end 274.574 -139.954)
		(width 0.127)
		(layer "In5.Cu")
		(net "JTAG_BMC_TCK")
	)
	(segment
		(start 109.349794 -103.35006)
		(end 108.849668 -103.850186)
		(width 0.1016)
		(layer "F.Cu")
		(net "SAS_GF_EXP_RX_DP13")
	)
	(via
		(at 108.849668 -103.850186)
		(size 0.508)
		(drill 0.254)
		(layers "F.Cu" "B.Cu")
		(net "SAS_GF_EXP_RX_DP13")
	)
	(segment
		(start 107.27944 -113.20907)
		(end 107.52074 -112.96777)
		(width 0.1016)
		(layer "B.Cu")
		(net "SAS_GF_EXP_RX_DP13")
	)
	(segment
		(start 88.9 -211.353908)
		(end 88.9 -175.637698)
		(width 0.1016)
		(layer "B.Cu")
		(net "SAS_GF_EXP_RX_DP13")
	)
	(segment
		(start 81.680812 -253.491746)
		(end 81.680812 -252.3744)
		(width 0.1016)
		(layer "B.Cu")
		(net "SAS_GF_EXP_RX_DP13")
	)
	(segment
		(start 80.645 -234.606592)
		(end 80.645 -229.526592)
		(width 0.1016)
		(layer "B.Cu")
		(net "SAS_GF_EXP_RX_DP13")
	)
	(segment
		(start 107.155234 -113.333022)
		(end 107.27944 -113.20907)
		(width 0.1016)
		(layer "B.Cu")
		(net "SAS_GF_EXP_RX_DP13")
	)
	(segment
		(start 80.645 -236.171232)
		(end 80.645 -235.866432)
		(width 0.1016)
		(layer "B.Cu")
		(net "SAS_GF_EXP_RX_DP13")
	)
	(segment
		(start 80.88376 -238.518192)
		(end 80.88376 -238.213392)
		(width 0.1016)
		(layer "B.Cu")
		(net "SAS_GF_EXP_RX_DP13")
	)
	(segment
		(start 80.645 -245.640352)
		(end 80.645 -245.335552)
		(width 0.1016)
		(layer "B.Cu")
		(net "SAS_GF_EXP_RX_DP13")
	)
	(segment
		(start 80.88376 -236.953552)
		(end 80.88376 -236.648752)
		(width 0.1016)
		(layer "B.Cu")
		(net "SAS_GF_EXP_RX_DP13")
	)
	(segment
		(start 80.88376 -235.388912)
		(end 80.88376 -235.084112)
		(width 0.1016)
		(layer "B.Cu")
		(net "SAS_GF_EXP_RX_DP13")
	)
	(segment
		(start 108.486448 -105.500932)
		(end 108.486448 -105.500678)
		(width 0.1016)
		(layer "B.Cu")
		(net "SAS_GF_EXP_RX_DP13")
	)
	(segment
		(start 80.645 -250.218194)
		(end 80.645 -248.464832)
		(width 0.1016)
		(layer "B.Cu")
		(net "SAS_GF_EXP_RX_DP13")
	)
	(segment
		(start 80.645 -244.075712)
		(end 80.645 -238.995712)
		(width 0.1016)
		(layer "B.Cu")
		(net "SAS_GF_EXP_RX_DP13")
	)
	(segment
		(start 80.88376 -244.858032)
		(end 80.88376 -244.553232)
		(width 0.1016)
		(layer "B.Cu")
		(net "SAS_GF_EXP_RX_DP13")
	)
	(segment
		(start 81.177892 -251.16028)
		(end 80.934306 -250.916694)
		(width 0.1016)
		(layer "B.Cu")
		(net "SAS_GF_EXP_RX_DP13")
	)
	(segment
		(start 80.645 -247.204992)
		(end 80.645 -246.900192)
		(width 0.1016)
		(layer "B.Cu")
		(net "SAS_GF_EXP_RX_DP13")
	)
	(segment
		(start 80.88376 -247.987312)
		(end 80.88376 -247.682512)
		(width 0.1016)
		(layer "B.Cu")
		(net "SAS_GF_EXP_RX_DP13")
	)
	(segment
		(start 81.01457 -220.33357)
		(end 88.12657 -213.22157)
		(width 0.1016)
		(layer "B.Cu")
		(net "SAS_GF_EXP_RX_DP13")
	)
	(segment
		(start 82.040222 -256.406396)
		(end 82.040222 -254.359664)
		(width 0.1016)
		(layer "B.Cu")
		(net "SAS_GF_EXP_RX_DP13")
	)
	(segment
		(start 89.568528 -174.023782)
		(end 104.54894 -159.04337)
		(width 0.1016)
		(layer "B.Cu")
		(net "SAS_GF_EXP_RX_DP13")
	)
	(segment
		(start 106.31297 -154.784552)
		(end 106.31297 -115.3668)
		(width 0.1016)
		(layer "B.Cu")
		(net "SAS_GF_EXP_RX_DP13")
	)
	(segment
		(start 80.645 -237.735872)
		(end 80.645 -237.431072)
		(width 0.1016)
		(layer "B.Cu")
		(net "SAS_GF_EXP_RX_DP13")
	)
	(segment
		(start 108.760768 -104.838754)
		(end 108.760768 -103.939086)
		(width 0.1016)
		(layer "B.Cu")
		(net "SAS_GF_EXP_RX_DP13")
	)
	(segment
		(start 80.88376 -229.049072)
		(end 80.88376 -228.744272)
		(width 0.1016)
		(layer "B.Cu")
		(net "SAS_GF_EXP_RX_DP13")
	)
	(segment
		(start 108.413042 -110.813088)
		(end 108.413042 -105.677716)
		(width 0.1016)
		(layer "B.Cu")
		(net "SAS_GF_EXP_RX_DP13")
	)
	(segment
		(start 80.645 -228.266752)
		(end 80.645 -221.225872)
		(width 0.1016)
		(layer "B.Cu")
		(net "SAS_GF_EXP_RX_DP13")
	)
	(segment
		(start 80.88376 -246.422672)
		(end 80.88376 -246.117872)
		(width 0.1016)
		(layer "B.Cu")
		(net "SAS_GF_EXP_RX_DP13")
	)
	(arc
		(start 104.54894 -159.04337)
		(mid 105.854482 -157.089393)
		(end 106.31297 -154.784552)
		(width 0.1016)
		(layer "B.Cu")
		(net "SAS_GF_EXP_RX_DP13")
	)
	(arc
		(start 107.52074 -112.96777)
		(mid 108.181203 -111.979178)
		(end 108.413042 -110.813088)
		(width 0.1016)
		(layer "B.Cu")
		(net "SAS_GF_EXP_RX_DP13")
	)
	(arc
		(start 80.76438 -237.974632)
		(mid 80.675492 -237.869837)
		(end 80.645 -237.735872)
		(width 0.1016)
		(layer "B.Cu")
		(net "SAS_GF_EXP_RX_DP13")
	)
	(arc
		(start 108.760768 -103.939086)
		(mid 108.786806 -103.876224)
		(end 108.849668 -103.850186)
		(width 0.1016)
		(layer "B.Cu")
		(net "SAS_GF_EXP_RX_DP13")
	)
	(arc
		(start 80.88376 -228.744272)
		(mid 80.853268 -228.610279)
		(end 80.76438 -228.505512)
		(width 0.1016)
		(layer "B.Cu")
		(net "SAS_GF_EXP_RX_DP13")
	)
	(arc
		(start 108.413042 -105.677716)
		(mid 108.432237 -105.582066)
		(end 108.486448 -105.500932)
		(width 0.1016)
		(layer "B.Cu")
		(net "SAS_GF_EXP_RX_DP13")
	)
	(arc
		(start 80.645 -221.225872)
		(mid 80.741054 -220.742974)
		(end 81.01457 -220.33357)
		(width 0.1016)
		(layer "B.Cu")
		(net "SAS_GF_EXP_RX_DP13")
	)
	(arc
		(start 80.76438 -247.443752)
		(mid 80.675492 -247.338957)
		(end 80.645 -247.204992)
		(width 0.1016)
		(layer "B.Cu")
		(net "SAS_GF_EXP_RX_DP13")
	)
	(arc
		(start 80.76438 -237.192312)
		(mid 80.853268 -237.087517)
		(end 80.88376 -236.953552)
		(width 0.1016)
		(layer "B.Cu")
		(net "SAS_GF_EXP_RX_DP13")
	)
	(arc
		(start 80.645 -229.526592)
		(mid 80.675492 -229.392599)
		(end 80.76438 -229.287832)
		(width 0.1016)
		(layer "B.Cu")
		(net "SAS_GF_EXP_RX_DP13")
	)
	(arc
		(start 106.31297 -115.3668)
		(mid 106.531813 -114.266133)
		(end 107.155234 -113.333022)
		(width 0.1016)
		(layer "B.Cu")
		(net "SAS_GF_EXP_RX_DP13")
	)
	(arc
		(start 80.76438 -248.226072)
		(mid 80.853268 -248.121277)
		(end 80.88376 -247.987312)
		(width 0.1016)
		(layer "B.Cu")
		(net "SAS_GF_EXP_RX_DP13")
	)
	(arc
		(start 80.76438 -236.409992)
		(mid 80.675492 -236.305197)
		(end 80.645 -236.171232)
		(width 0.1016)
		(layer "B.Cu")
		(net "SAS_GF_EXP_RX_DP13")
	)
	(arc
		(start 80.88376 -236.648752)
		(mid 80.853268 -236.514759)
		(end 80.76438 -236.409992)
		(width 0.1016)
		(layer "B.Cu")
		(net "SAS_GF_EXP_RX_DP13")
	)
	(arc
		(start 80.645 -245.335552)
		(mid 80.675492 -245.201559)
		(end 80.76438 -245.096792)
		(width 0.1016)
		(layer "B.Cu")
		(net "SAS_GF_EXP_RX_DP13")
	)
	(arc
		(start 88.12657 -213.22157)
		(mid 88.699043 -212.364664)
		(end 88.9 -211.353908)
		(width 0.1016)
		(layer "B.Cu")
		(net "SAS_GF_EXP_RX_DP13")
	)
	(arc
		(start 81.999582 -256.50444)
		(mid 82.029639 -256.459457)
		(end 82.040222 -256.406396)
		(width 0.1016)
		(layer "B.Cu")
		(net "SAS_GF_EXP_RX_DP13")
	)
	(arc
		(start 80.645 -248.464832)
		(mid 80.675492 -248.330839)
		(end 80.76438 -248.226072)
		(width 0.1016)
		(layer "B.Cu")
		(net "SAS_GF_EXP_RX_DP13")
	)
	(arc
		(start 80.88376 -247.682512)
		(mid 80.853268 -247.548519)
		(end 80.76438 -247.443752)
		(width 0.1016)
		(layer "B.Cu")
		(net "SAS_GF_EXP_RX_DP13")
	)
	(arc
		(start 80.88376 -238.213392)
		(mid 80.853268 -238.079399)
		(end 80.76438 -237.974632)
		(width 0.1016)
		(layer "B.Cu")
		(net "SAS_GF_EXP_RX_DP13")
	)
	(arc
		(start 82.040222 -254.359664)
		(mid 81.993559 -254.124894)
		(end 81.860644 -253.925832)
		(width 0.1016)
		(layer "B.Cu")
		(net "SAS_GF_EXP_RX_DP13")
	)
	(arc
		(start 81.860644 -253.925832)
		(mid 81.727569 -253.726672)
		(end 81.680812 -253.491746)
		(width 0.1016)
		(layer "B.Cu")
		(net "SAS_GF_EXP_RX_DP13")
	)
	(arc
		(start 80.645 -237.431072)
		(mid 80.675492 -237.297079)
		(end 80.76438 -237.192312)
		(width 0.1016)
		(layer "B.Cu")
		(net "SAS_GF_EXP_RX_DP13")
	)
	(arc
		(start 80.76438 -228.505512)
		(mid 80.675492 -228.400717)
		(end 80.645 -228.266752)
		(width 0.1016)
		(layer "B.Cu")
		(net "SAS_GF_EXP_RX_DP13")
	)
	(arc
		(start 80.645 -238.995712)
		(mid 80.675492 -238.861719)
		(end 80.76438 -238.756952)
		(width 0.1016)
		(layer "B.Cu")
		(net "SAS_GF_EXP_RX_DP13")
	)
	(arc
		(start 80.76438 -238.756952)
		(mid 80.853268 -238.652157)
		(end 80.88376 -238.518192)
		(width 0.1016)
		(layer "B.Cu")
		(net "SAS_GF_EXP_RX_DP13")
	)
	(arc
		(start 80.76438 -245.879112)
		(mid 80.675492 -245.774317)
		(end 80.645 -245.640352)
		(width 0.1016)
		(layer "B.Cu")
		(net "SAS_GF_EXP_RX_DP13")
	)
	(arc
		(start 108.486448 -105.500678)
		(mid 108.689399 -105.196985)
		(end 108.760768 -104.838754)
		(width 0.1016)
		(layer "B.Cu")
		(net "SAS_GF_EXP_RX_DP13")
	)
	(arc
		(start 80.934306 -250.916694)
		(mid 80.720172 -250.596219)
		(end 80.645 -250.218194)
		(width 0.1016)
		(layer "B.Cu")
		(net "SAS_GF_EXP_RX_DP13")
	)
	(arc
		(start 88.9 -175.637698)
		(mid 89.073741 -174.764244)
		(end 89.568528 -174.023782)
		(width 0.1016)
		(layer "B.Cu")
		(net "SAS_GF_EXP_RX_DP13")
	)
	(arc
		(start 80.76438 -245.096792)
		(mid 80.853268 -244.991997)
		(end 80.88376 -244.858032)
		(width 0.1016)
		(layer "B.Cu")
		(net "SAS_GF_EXP_RX_DP13")
	)
	(arc
		(start 80.645 -235.866432)
		(mid 80.675492 -235.732439)
		(end 80.76438 -235.627672)
		(width 0.1016)
		(layer "B.Cu")
		(net "SAS_GF_EXP_RX_DP13")
	)
	(arc
		(start 80.76438 -229.287832)
		(mid 80.853268 -229.183037)
		(end 80.88376 -229.049072)
		(width 0.1016)
		(layer "B.Cu")
		(net "SAS_GF_EXP_RX_DP13")
	)
	(arc
		(start 81.680812 -252.3744)
		(mid 81.55011 -251.717317)
		(end 81.177892 -251.16028)
		(width 0.1016)
		(layer "B.Cu")
		(net "SAS_GF_EXP_RX_DP13")
	)
	(arc
		(start 80.88376 -235.084112)
		(mid 80.853268 -234.950119)
		(end 80.76438 -234.845352)
		(width 0.1016)
		(layer "B.Cu")
		(net "SAS_GF_EXP_RX_DP13")
	)
	(arc
		(start 80.88376 -244.553232)
		(mid 80.853268 -244.419239)
		(end 80.76438 -244.314472)
		(width 0.1016)
		(layer "B.Cu")
		(net "SAS_GF_EXP_RX_DP13")
	)
	(arc
		(start 80.88376 -246.117872)
		(mid 80.853268 -245.983879)
		(end 80.76438 -245.879112)
		(width 0.1016)
		(layer "B.Cu")
		(net "SAS_GF_EXP_RX_DP13")
	)
	(arc
		(start 80.645 -246.900192)
		(mid 80.675492 -246.766199)
		(end 80.76438 -246.661432)
		(width 0.1016)
		(layer "B.Cu")
		(net "SAS_GF_EXP_RX_DP13")
	)
	(arc
		(start 80.76438 -235.627672)
		(mid 80.853268 -235.522877)
		(end 80.88376 -235.388912)
		(width 0.1016)
		(layer "B.Cu")
		(net "SAS_GF_EXP_RX_DP13")
	)
	(arc
		(start 80.76438 -244.314472)
		(mid 80.675492 -244.209677)
		(end 80.645 -244.075712)
		(width 0.1016)
		(layer "B.Cu")
		(net "SAS_GF_EXP_RX_DP13")
	)
	(arc
		(start 80.76438 -246.661432)
		(mid 80.853268 -246.556637)
		(end 80.88376 -246.422672)
		(width 0.1016)
		(layer "B.Cu")
		(net "SAS_GF_EXP_RX_DP13")
	)
	(arc
		(start 80.76438 -234.845352)
		(mid 80.675492 -234.740557)
		(end 80.645 -234.606592)
		(width 0.1016)
		(layer "B.Cu")
		(net "SAS_GF_EXP_RX_DP13")
	)
	(segment
		(start 343.607136 -111.120936)
		(end 343.916 -111.4298)
		(width 0.3048)
		(layer "F.Cu")
		(net "P5V_STBY_VCC")
	)
	(segment
		(start 342.406224 -111.120936)
		(end 343.607136 -111.120936)
		(width 0.3048)
		(layer "F.Cu")
		(net "P5V_STBY_VCC")
	)
	(segment
		(start 343.916 -111.4298)
		(end 345.2622 -112.776)
		(width 0.508)
		(layer "F.Cu")
		(net "P5V_STBY_VCC")
	)
	(segment
		(start 345.2622 -112.776)
		(end 346.075 -112.776)
		(width 0.508)
		(layer "F.Cu")
		(net "P5V_STBY_VCC")
	)
	(segment
		(start 346.075 -112.776)
		(end 346.075 -114.046)
		(width 0.508)
		(layer "F.Cu")
		(net "P5V_STBY_VCC")
	)
	(via
		(at 343.916 -111.4298)
		(size 0.7112)
		(drill 0.3556)
		(layers "F.Cu" "B.Cu")
		(net "P5V_STBY_VCC")
	)
	(segment
		(start 261.71525 -90.90025)
		(end 262.3439 -91.5289)
		(width 0.1143)
		(layer "F.Cu")
		(net "RMII_BMC_MDIO")
	)
	(segment
		(start 304.6349 -159.085026)
		(end 304.6349 -159.822896)
		(width 0.1143)
		(layer "F.Cu")
		(net "RMII_BMC_MDIO")
	)
	(segment
		(start 311.16143 -144.201388)
		(end 311.16143 -154.06116)
		(width 0.1143)
		(layer "F.Cu")
		(net "RMII_BMC_MDIO")
	)
	(segment
		(start 300.651418 -163.880546)
		(end 300.04639 -163.880546)
		(width 0.1143)
		(layer "F.Cu")
		(net "RMII_BMC_MDIO")
	)
	(segment
		(start 304.6349 -159.822896)
		(end 304.59045 -159.867346)
		(width 0.1143)
		(layer "F.Cu")
		(net "RMII_BMC_MDIO")
	)
	(segment
		(start 269.4686 -119.701564)
		(end 269.4686 -125.0696)
		(width 0.1143)
		(layer "F.Cu")
		(net "RMII_BMC_MDIO")
	)
	(segment
		(start 291.667692 -137.17905)
		(end 296.074592 -141.58595)
		(width 0.1143)
		(layer "F.Cu")
		(net "RMII_BMC_MDIO")
	)
	(segment
		(start 262.3439 -91.5289)
		(end 262.3439 -93.176598)
		(width 0.1143)
		(layer "F.Cu")
		(net "RMII_BMC_MDIO")
	)
	(segment
		(start 300.04639 -163.880546)
		(end 299.055282 -164.871654)
		(width 0.1143)
		(layer "F.Cu")
		(net "RMII_BMC_MDIO")
	)
	(segment
		(start 299.055282 -165.08476)
		(end 298.53636 -165.603682)
		(width 0.1143)
		(layer "F.Cu")
		(net "RMII_BMC_MDIO")
	)
	(segment
		(start 196.6214 -25.8064)
		(end 261.38505 -90.57005)
		(width 0.1143)
		(layer "F.Cu")
		(net "RMII_BMC_MDIO")
	)
	(segment
		(start 268.47165 -118.704614)
		(end 269.4686 -119.701564)
		(width 0.1143)
		(layer "F.Cu")
		(net "RMII_BMC_MDIO")
	)
	(segment
		(start 194.437 -21.209)
		(end 196.6214 -23.3934)
		(width 0.1143)
		(layer "F.Cu")
		(net "RMII_BMC_MDIO")
	)
	(segment
		(start 299.055282 -164.871654)
		(end 299.055282 -165.08476)
		(width 0.1143)
		(layer "F.Cu")
		(net "RMII_BMC_MDIO")
	)
	(segment
		(start 193.421 -20.193)
		(end 192.2145 -20.193)
		(width 0.1143)
		(layer "F.Cu")
		(net "RMII_BMC_MDIO")
	)
	(segment
		(start 261.38505 -90.613992)
		(end 261.671308 -90.90025)
		(width 0.1143)
		(layer "F.Cu")
		(net "RMII_BMC_MDIO")
	)
	(segment
		(start 303.40935 -161.28365)
		(end 303.041812 -161.28365)
		(width 0.1143)
		(layer "F.Cu")
		(net "RMII_BMC_MDIO")
	)
	(segment
		(start 307.916326 -155.8036)
		(end 304.6349 -159.085026)
		(width 0.1143)
		(layer "F.Cu")
		(net "RMII_BMC_MDIO")
	)
	(segment
		(start 268.4653 -99.308412)
		(end 268.47165 -99.314762)
		(width 0.1143)
		(layer "F.Cu")
		(net "RMII_BMC_MDIO")
	)
	(segment
		(start 268.47165 -99.314762)
		(end 268.47165 -118.704614)
		(width 0.1143)
		(layer "F.Cu")
		(net "RMII_BMC_MDIO")
	)
	(segment
		(start 261.671308 -90.90025)
		(end 261.71525 -90.90025)
		(width 0.1143)
		(layer "F.Cu")
		(net "RMII_BMC_MDIO")
	)
	(segment
		(start 262.3439 -93.176598)
		(end 268.4653 -99.297998)
		(width 0.1143)
		(layer "F.Cu")
		(net "RMII_BMC_MDIO")
	)
	(segment
		(start 269.4686 -125.0696)
		(end 274.32 -129.921)
		(width 0.1143)
		(layer "F.Cu")
		(net "RMII_BMC_MDIO")
	)
	(segment
		(start 304.59045 -159.867346)
		(end 304.59045 -160.10255)
		(width 0.1143)
		(layer "F.Cu")
		(net "RMII_BMC_MDIO")
	)
	(segment
		(start 302.71085 -161.821114)
		(end 300.651418 -163.880546)
		(width 0.1143)
		(layer "F.Cu")
		(net "RMII_BMC_MDIO")
	)
	(segment
		(start 274.32 -129.921)
		(end 274.32 -132.08)
		(width 0.1143)
		(layer "F.Cu")
		(net "RMII_BMC_MDIO")
	)
	(segment
		(start 311.16143 -154.06116)
		(end 309.41899 -155.8036)
		(width 0.1143)
		(layer "F.Cu")
		(net "RMII_BMC_MDIO")
	)
	(segment
		(start 196.6214 -23.3934)
		(end 196.6214 -25.8064)
		(width 0.1143)
		(layer "F.Cu")
		(net "RMII_BMC_MDIO")
	)
	(segment
		(start 298.43476 -166.38524)
		(end 298.43476 -167.440102)
		(width 0.1143)
		(layer "F.Cu")
		(net "RMII_BMC_MDIO")
	)
	(segment
		(start 309.41899 -155.8036)
		(end 307.916326 -155.8036)
		(width 0.1143)
		(layer "F.Cu")
		(net "RMII_BMC_MDIO")
	)
	(segment
		(start 298.53636 -166.28364)
		(end 298.43476 -166.38524)
		(width 0.1143)
		(layer "F.Cu")
		(net "RMII_BMC_MDIO")
	)
	(segment
		(start 191.4525 -20.955)
		(end 190.3095 -20.955)
		(width 0.1143)
		(layer "F.Cu")
		(net "RMII_BMC_MDIO")
	)
	(segment
		(start 285.369 -132.461)
		(end 285.369 -133.2357)
		(width 0.1143)
		(layer "F.Cu")
		(net "RMII_BMC_MDIO")
	)
	(segment
		(start 308.545992 -141.58595)
		(end 311.16143 -144.201388)
		(width 0.1143)
		(layer "F.Cu")
		(net "RMII_BMC_MDIO")
	)
	(segment
		(start 285.369 -133.2357)
		(end 289.31235 -137.17905)
		(width 0.1143)
		(layer "F.Cu")
		(net "RMII_BMC_MDIO")
	)
	(segment
		(start 268.4653 -99.297998)
		(end 268.4653 -99.308412)
		(width 0.1143)
		(layer "F.Cu")
		(net "RMII_BMC_MDIO")
	)
	(segment
		(start 296.074592 -141.58595)
		(end 308.545992 -141.58595)
		(width 0.1143)
		(layer "F.Cu")
		(net "RMII_BMC_MDIO")
	)
	(segment
		(start 302.71085 -161.614612)
		(end 302.71085 -161.821114)
		(width 0.1143)
		(layer "F.Cu")
		(net "RMII_BMC_MDIO")
	)
	(segment
		(start 192.2145 -20.193)
		(end 191.4525 -20.955)
		(width 0.1143)
		(layer "F.Cu")
		(net "RMII_BMC_MDIO")
	)
	(segment
		(start 303.041812 -161.28365)
		(end 302.71085 -161.614612)
		(width 0.1143)
		(layer "F.Cu")
		(net "RMII_BMC_MDIO")
	)
	(segment
		(start 261.38505 -90.57005)
		(end 261.38505 -90.613992)
		(width 0.1143)
		(layer "F.Cu")
		(net "RMII_BMC_MDIO")
	)
	(segment
		(start 194.437 -21.209)
		(end 193.421 -20.193)
		(width 0.1143)
		(layer "F.Cu")
		(net "RMII_BMC_MDIO")
	)
	(segment
		(start 289.31235 -137.17905)
		(end 291.667692 -137.17905)
		(width 0.1143)
		(layer "F.Cu")
		(net "RMII_BMC_MDIO")
	)
	(segment
		(start 298.53636 -165.603682)
		(end 298.53636 -166.28364)
		(width 0.1143)
		(layer "F.Cu")
		(net "RMII_BMC_MDIO")
	)
	(segment
		(start 304.59045 -160.10255)
		(end 303.40935 -161.28365)
		(width 0.1143)
		(layer "F.Cu")
		(net "RMII_BMC_MDIO")
	)
	(via
		(at 274.32 -132.08)
		(size 0.5588)
		(drill 0.3048)
		(layers "F.Cu" "B.Cu")
		(net "RMII_BMC_MDIO")
	)
	(via
		(at 285.369 -132.461)
		(size 0.5588)
		(drill 0.3048)
		(layers "F.Cu" "B.Cu")
		(net "RMII_BMC_MDIO")
	)
	(via
		(at 194.437 -21.209)
		(size 0.7112)
		(drill 0.3556)
		(layers "F.Cu" "B.Cu")
		(net "RMII_BMC_MDIO")
	)
	(segment
		(start 284.988 -132.08)
		(end 285.369 -132.461)
		(width 0.127)
		(layer "In2.Cu")
		(net "RMII_BMC_MDIO")
	)
	(segment
		(start 274.32 -132.08)
		(end 284.988 -132.08)
		(width 0.127)
		(layer "In2.Cu")
		(net "RMII_BMC_MDIO")
	)
	(segment
		(start 342.9 -112.649)
		(end 343.916 -112.649)
		(width 0.254)
		(layer "F.Cu")
		(net "P5V_STBY_VO")
	)
	(segment
		(start 343.916 -112.649)
		(end 344.1446 -112.8776)
		(width 0.254)
		(layer "F.Cu")
		(net "P5V_STBY_VO")
	)
	(segment
		(start 343.9795 -113.792)
		(end 343.9795 -113.0935)
		(width 0.254)
		(layer "F.Cu")
		(net "P5V_STBY_VO")
	)
	(segment
		(start 342.418924 -111.621062)
		(end 342.418924 -112.167924)
		(width 0.254)
		(layer "F.Cu")
		(net "P5V_STBY_VO")
	)
	(segment
		(start 344.15603 -112.91697)
		(end 344.15603 -112.8776)
		(width 0.254)
		(layer "F.Cu")
		(net "P5V_STBY_VO")
	)
	(segment
		(start 342.418924 -112.167924)
		(end 342.9 -112.649)
		(width 0.254)
		(layer "F.Cu")
		(net "P5V_STBY_VO")
	)
	(segment
		(start 344.1446 -112.8776)
		(end 344.15603 -112.8776)
		(width 0.254)
		(layer "F.Cu")
		(net "P5V_STBY_VO")
	)
	(segment
		(start 343.9795 -113.0935)
		(end 344.15603 -112.91697)
		(width 0.254)
		(layer "F.Cu")
		(net "P5V_STBY_VO")
	)
	(via
		(at 344.15603 -112.8776)
		(size 0.7112)
		(drill 0.3556)
		(layers "F.Cu" "B.Cu")
		(net "P5V_STBY_VO")
	)
	(segment
		(start 287.234884 -176.240186)
		(end 286.83966 -175.844962)
		(width 0.1143)
		(layer "F.Cu")
		(net "ROMA8")
	)
	(via
		(at 286.83966 -175.844962)
		(size 0.508)
		(drill 0.254)
		(layers "F.Cu" "B.Cu")
		(net "ROMA8")
	)
	(via
		(at 277.876 -177.673)
		(size 0.7112)
		(drill 0.3556)
		(layers "F.Cu" "B.Cu")
		(net "ROMA8")
	)
	(segment
		(start 286.199326 -176.238916)
		(end 283.556456 -176.238916)
		(width 0.0889)
		(layer "B.Cu")
		(net "ROMA8")
	)
	(segment
		(start 286.83966 -175.844962)
		(end 286.59328 -175.844962)
		(width 0.0889)
		(layer "B.Cu")
		(net "ROMA8")
	)
	(segment
		(start 286.59328 -175.844962)
		(end 286.199326 -176.238916)
		(width 0.0889)
		(layer "B.Cu")
		(net "ROMA8")
	)
	(segment
		(start 283.556456 -176.238916)
		(end 283.51988 -176.20234)
		(width 0.0889)
		(layer "B.Cu")
		(net "ROMA8")
	)
	(segment
		(start 279.629108 -176.20234)
		(end 278.158448 -177.673)
		(width 0.1143)
		(layer "B.Cu")
		(net "ROMA8")
	)
	(segment
		(start 278.158448 -177.673)
		(end 277.876 -177.673)
		(width 0.1143)
		(layer "B.Cu")
		(net "ROMA8")
	)
	(segment
		(start 283.51988 -176.20234)
		(end 279.629108 -176.20234)
		(width 0.1143)
		(layer "B.Cu")
		(net "ROMA8")
	)
	(segment
		(start 277.876 -177.673)
		(end 274.6375 -177.673)
		(width 0.1143)
		(layer "B.Cu")
		(net "ROMA8")
	)
	(segment
		(start 338.201 -111.125)
		(end 339.325712 -111.125)
		(width 0.254)
		(layer "F.Cu")
		(net "P5V_STBY_EN_R")
	)
	(segment
		(start 338.0105 -110.9345)
		(end 338.201 -111.125)
		(width 0.254)
		(layer "F.Cu")
		(net "P5V_STBY_EN_R")
	)
	(segment
		(start 336.169 -112.141)
		(end 336.169 -113.0935)
		(width 0.254)
		(layer "F.Cu")
		(net "P5V_STBY_EN_R")
	)
	(segment
		(start 336.169 -110.9345)
		(end 336.169 -112.141)
		(width 0.254)
		(layer "F.Cu")
		(net "P5V_STBY_EN_R")
	)
	(segment
		(start 339.325712 -111.125)
		(end 339.329776 -111.120936)
		(width 0.254)
		(layer "F.Cu")
		(net "P5V_STBY_EN_R")
	)
	(segment
		(start 336.169 -113.0935)
		(end 334.899 -113.0935)
		(width 0.254)
		(layer "F.Cu")
		(net "P5V_STBY_EN_R")
	)
	(segment
		(start 336.169 -110.9345)
		(end 337.185 -110.9345)
		(width 0.254)
		(layer "F.Cu")
		(net "P5V_STBY_EN_R")
	)
	(segment
		(start 337.185 -110.9345)
		(end 338.0105 -110.9345)
		(width 0.254)
		(layer "F.Cu")
		(net "P5V_STBY_EN_R")
	)
	(via
		(at 336.169 -112.141)
		(size 0.7112)
		(drill 0.3556)
		(layers "F.Cu" "B.Cu")
		(net "P5V_STBY_EN_R")
	)
	(segment
		(start 308.2925 -112.776)
		(end 306.578 -112.776)
		(width 0.254)
		(layer "F.Cu")
		(net "P5V_STBY_PG")
	)
	(segment
		(start 339.979 -116.7765)
		(end 338.455 -116.7765)
		(width 0.254)
		(layer "F.Cu")
		(net "P5V_STBY_PG")
	)
	(segment
		(start 306.451 -108.712)
		(end 311.531 -108.712)
		(width 0.254)
		(layer "F.Cu")
		(net "P5V_STBY_PG")
	)
	(segment
		(start 338.339938 -111.621062)
		(end 337.947 -112.014)
		(width 0.254)
		(layer "F.Cu")
		(net "P5V_STBY_PG")
	)
	(segment
		(start 314.96 -105.283)
		(end 321.084702 -105.283)
		(width 0.254)
		(layer "F.Cu")
		(net "P5V_STBY_PG")
	)
	(segment
		(start 305.689 -109.474)
		(end 306.451 -108.712)
		(width 0.254)
		(layer "F.Cu")
		(net "P5V_STBY_PG")
	)
	(segment
		(start 325.236332 -102.766368)
		(end 325.247 -102.7557)
		(width 0.254)
		(layer "F.Cu")
		(net "P5V_STBY_PG")
	)
	(segment
		(start 323.601334 -102.766368)
		(end 325.236332 -102.766368)
		(width 0.254)
		(layer "F.Cu")
		(net "P5V_STBY_PG")
	)
	(segment
		(start 305.689 -111.887)
		(end 305.689 -109.474)
		(width 0.254)
		(layer "F.Cu")
		(net "P5V_STBY_PG")
	)
	(segment
		(start 339.317076 -111.621062)
		(end 338.339938 -111.621062)
		(width 0.254)
		(layer "F.Cu")
		(net "P5V_STBY_PG")
	)
	(segment
		(start 321.084702 -105.283)
		(end 323.601334 -102.766368)
		(width 0.254)
		(layer "F.Cu")
		(net "P5V_STBY_PG")
	)
	(segment
		(start 311.531 -108.712)
		(end 314.96 -105.283)
		(width 0.254)
		(layer "F.Cu")
		(net "P5V_STBY_PG")
	)
	(segment
		(start 306.578 -112.776)
		(end 305.689 -111.887)
		(width 0.254)
		(layer "F.Cu")
		(net "P5V_STBY_PG")
	)
	(segment
		(start 338.455 -116.7765)
		(end 338.328 -116.6495)
		(width 0.254)
		(layer "F.Cu")
		(net "P5V_STBY_PG")
	)
	(via
		(at 338.328 -116.6495)
		(size 0.5588)
		(drill 0.3048)
		(layers "F.Cu" "B.Cu")
		(net "P5V_STBY_PG")
	)
	(via
		(at 325.247 -102.7557)
		(size 0.5588)
		(drill 0.3048)
		(layers "F.Cu" "B.Cu")
		(net "P5V_STBY_PG")
	)
	(via
		(at 337.947 -112.014)
		(size 0.5588)
		(drill 0.3048)
		(layers "F.Cu" "B.Cu")
		(net "P5V_STBY_PG")
	)
	(via
		(at 337.947 -114.935)
		(size 0.7112)
		(drill 0.3556)
		(layers "F.Cu" "B.Cu")
		(net "P5V_STBY_PG")
	)
	(segment
		(start 337.947 -112.014)
		(end 337.947 -114.935)
		(width 0.254)
		(layer "B.Cu")
		(net "P5V_STBY_PG")
	)
	(segment
		(start 337.947 -114.935)
		(end 337.947 -116.2685)
		(width 0.254)
		(layer "B.Cu")
		(net "P5V_STBY_PG")
	)
	(segment
		(start 337.947 -116.2685)
		(end 338.328 -116.6495)
		(width 0.254)
		(layer "B.Cu")
		(net "P5V_STBY_PG")
	)
	(segment
		(start 325.374 -104.394)
		(end 325.374 -102.8827)
		(width 0.254)
		(layer "In5.Cu")
		(net "P5V_STBY_PG")
	)
	(segment
		(start 325.374 -102.8827)
		(end 325.247 -102.7557)
		(width 0.254)
		(layer "In5.Cu")
		(net "P5V_STBY_PG")
	)
	(segment
		(start 332.994 -112.014)
		(end 325.374 -104.394)
		(width 0.254)
		(layer "In5.Cu")
		(net "P5V_STBY_PG")
	)
	(segment
		(start 337.947 -112.014)
		(end 332.994 -112.014)
		(width 0.254)
		(layer "In5.Cu")
		(net "P5V_STBY_PG")
	)
	(segment
		(start 312.547 -171.577)
		(end 311.912 -170.942)
		(width 0.1143)
		(layer "F.Cu")
		(net "JTAG_BMC_TRST_N")
	)
	(segment
		(start 314.463938 -195.199)
		(end 314.452 -195.187062)
		(width 0.1143)
		(layer "F.Cu")
		(net "JTAG_BMC_TRST_N")
	)
	(segment
		(start 317.246 -171.577)
		(end 317.5635 -171.2595)
		(width 0.1143)
		(layer "F.Cu")
		(net "JTAG_BMC_TRST_N")
	)
	(segment
		(start 241.080036 -94.36989)
		(end 241.078004 -94.367858)
		(width 0.1143)
		(layer "F.Cu")
		(net "JTAG_BMC_TRST_N")
	)
	(segment
		(start 241.078004 -91.853004)
		(end 238.633 -89.408)
		(width 0.1143)
		(layer "F.Cu")
		(net "JTAG_BMC_TRST_N")
	)
	(segment
		(start 312.9915 -193.548)
		(end 313.817 -193.548)
		(width 0.1143)
		(layer "F.Cu")
		(net "JTAG_BMC_TRST_N")
	)
	(segment
		(start 314.325 -171.577)
		(end 317.246 -171.577)
		(width 0.1143)
		(layer "F.Cu")
		(net "JTAG_BMC_TRST_N")
	)
	(segment
		(start 317.5635 -171.2595)
		(end 317.5635 -170.434)
		(width 0.1143)
		(layer "F.Cu")
		(net "JTAG_BMC_TRST_N")
	)
	(segment
		(start 311.531 -194.945)
		(end 311.5945 -194.945)
		(width 0.1143)
		(layer "F.Cu")
		(net "JTAG_BMC_TRST_N")
	)
	(segment
		(start 311.5945 -194.945)
		(end 312.9915 -193.548)
		(width 0.1143)
		(layer "F.Cu")
		(net "JTAG_BMC_TRST_N")
	)
	(segment
		(start 314.452 -195.187062)
		(end 314.452 -194.183)
		(width 0.1143)
		(layer "F.Cu")
		(net "JTAG_BMC_TRST_N")
	)
	(segment
		(start 311.610248 -170.640248)
		(end 311.912 -170.942)
		(width 0.1143)
		(layer "F.Cu")
		(net "JTAG_BMC_TRST_N")
	)
	(segment
		(start 301.634906 -170.640248)
		(end 311.610248 -170.640248)
		(width 0.1143)
		(layer "F.Cu")
		(net "JTAG_BMC_TRST_N")
	)
	(segment
		(start 314.325 -171.577)
		(end 312.547 -171.577)
		(width 0.1143)
		(layer "F.Cu")
		(net "JTAG_BMC_TRST_N")
	)
	(segment
		(start 241.078004 -94.367858)
		(end 241.078004 -91.853004)
		(width 0.1143)
		(layer "F.Cu")
		(net "JTAG_BMC_TRST_N")
	)
	(segment
		(start 313.817 -193.548)
		(end 314.452 -194.183)
		(width 0.1143)
		(layer "F.Cu")
		(net "JTAG_BMC_TRST_N")
	)
	(via
		(at 331.724 -85.979)
		(size 0.5588)
		(drill 0.3048)
		(layers "F.Cu" "B.Cu")
		(net "JTAG_BMC_TRST_N")
	)
	(via
		(at 311.912 -170.942)
		(size 0.7112)
		(drill 0.3556)
		(layers "F.Cu" "B.Cu")
		(net "JTAG_BMC_TRST_N")
	)
	(via
		(at 238.633 -89.408)
		(size 0.5588)
		(drill 0.3048)
		(layers "F.Cu" "B.Cu")
		(net "JTAG_BMC_TRST_N")
	)
	(via
		(at 314.325 -171.577)
		(size 0.5588)
		(drill 0.3048)
		(layers "F.Cu" "B.Cu")
		(net "JTAG_BMC_TRST_N")
	)
	(via
		(at 314.452 -194.183)
		(size 0.5588)
		(drill 0.3048)
		(layers "F.Cu" "B.Cu")
		(net "JTAG_BMC_TRST_N")
	)
	(segment
		(start 239.776 -89.408)
		(end 238.633 -89.408)
		(width 0.1143)
		(layer "B.Cu")
		(net "JTAG_BMC_TRST_N")
	)
	(segment
		(start 318.971676 -82.729324)
		(end 318.290448 -83.410552)
		(width 0.1143)
		(layer "B.Cu")
		(net "JTAG_BMC_TRST_N")
	)
	(segment
		(start 256.30505 -90.40495)
		(end 240.77295 -90.40495)
		(width 0.1143)
		(layer "B.Cu")
		(net "JTAG_BMC_TRST_N")
	)
	(segment
		(start 263.144 -83.566)
		(end 256.30505 -90.40495)
		(width 0.1143)
		(layer "B.Cu")
		(net "JTAG_BMC_TRST_N")
	)
	(segment
		(start 240.77295 -90.40495)
		(end 239.776 -89.408)
		(width 0.1143)
		(layer "B.Cu")
		(net "JTAG_BMC_TRST_N")
	)
	(segment
		(start 306.733194 -83.410552)
		(end 306.653692 -83.33105)
		(width 0.1143)
		(layer "B.Cu")
		(net "JTAG_BMC_TRST_N")
	)
	(segment
		(start 306.653692 -83.33105)
		(end 306.248308 -83.33105)
		(width 0.1143)
		(layer "B.Cu")
		(net "JTAG_BMC_TRST_N")
	)
	(segment
		(start 306.013358 -83.566)
		(end 263.144 -83.566)
		(width 0.1143)
		(layer "B.Cu")
		(net "JTAG_BMC_TRST_N")
	)
	(segment
		(start 330.454 -83.696556)
		(end 329.486768 -82.729324)
		(width 0.1143)
		(layer "B.Cu")
		(net "JTAG_BMC_TRST_N")
	)
	(segment
		(start 330.454 -84.709)
		(end 330.454 -83.696556)
		(width 0.1143)
		(layer "B.Cu")
		(net "JTAG_BMC_TRST_N")
	)
	(segment
		(start 329.486768 -82.729324)
		(end 318.971676 -82.729324)
		(width 0.1143)
		(layer "B.Cu")
		(net "JTAG_BMC_TRST_N")
	)
	(segment
		(start 331.724 -85.979)
		(end 330.454 -84.709)
		(width 0.1143)
		(layer "B.Cu")
		(net "JTAG_BMC_TRST_N")
	)
	(segment
		(start 318.290448 -83.410552)
		(end 306.733194 -83.410552)
		(width 0.1143)
		(layer "B.Cu")
		(net "JTAG_BMC_TRST_N")
	)
	(segment
		(start 306.248308 -83.33105)
		(end 306.013358 -83.566)
		(width 0.1143)
		(layer "B.Cu")
		(net "JTAG_BMC_TRST_N")
	)
	(segment
		(start 314.325 -171.577)
		(end 315.722 -171.577)
		(width 0.127)
		(layer "In2.Cu")
		(net "JTAG_BMC_TRST_N")
	)
	(segment
		(start 316.738 -181.40172)
		(end 316.738 -185.039)
		(width 0.127)
		(layer "In2.Cu")
		(net "JTAG_BMC_TRST_N")
	)
	(segment
		(start 317.5 -185.801)
		(end 317.5 -192.024)
		(width 0.127)
		(layer "In2.Cu")
		(net "JTAG_BMC_TRST_N")
	)
	(segment
		(start 315.341 -194.183)
		(end 314.452 -194.183)
		(width 0.127)
		(layer "In2.Cu")
		(net "JTAG_BMC_TRST_N")
	)
	(segment
		(start 315.722 -171.577)
		(end 316.484 -172.339)
		(width 0.127)
		(layer "In2.Cu")
		(net "JTAG_BMC_TRST_N")
	)
	(segment
		(start 317.5 -192.024)
		(end 315.341 -194.183)
		(width 0.127)
		(layer "In2.Cu")
		(net "JTAG_BMC_TRST_N")
	)
	(segment
		(start 316.484 -181.14772)
		(end 316.738 -181.40172)
		(width 0.127)
		(layer "In2.Cu")
		(net "JTAG_BMC_TRST_N")
	)
	(segment
		(start 316.738 -185.039)
		(end 317.5 -185.801)
		(width 0.127)
		(layer "In2.Cu")
		(net "JTAG_BMC_TRST_N")
	)
	(segment
		(start 316.484 -172.339)
		(end 316.484 -181.14772)
		(width 0.127)
		(layer "In2.Cu")
		(net "JTAG_BMC_TRST_N")
	)
	(segment
		(start 313.7535 -122.9995)
		(end 313.7535 -114.104166)
		(width 0.127)
		(layer "In5.Cu")
		(net "JTAG_BMC_TRST_N")
	)
	(segment
		(start 322.071238 -166.96817)
		(end 326.619362 -166.96817)
		(width 0.127)
		(layer "In5.Cu")
		(net "JTAG_BMC_TRST_N")
	)
	(segment
		(start 321.515232 -166.3827)
		(end 321.8307 -166.698168)
		(width 0.127)
		(layer "In5.Cu")
		(net "JTAG_BMC_TRST_N")
	)
	(segment
		(start 331.724 -89.027)
		(end 331.724 -85.979)
		(width 0.127)
		(layer "In5.Cu")
		(net "JTAG_BMC_TRST_N")
	)
	(segment
		(start 313.7535 -114.104166)
		(end 314.472066 -113.3856)
		(width 0.127)
		(layer "In5.Cu")
		(net "JTAG_BMC_TRST_N")
	)
	(segment
		(start 318.897 -128.143)
		(end 313.7535 -122.9995)
		(width 0.127)
		(layer "In5.Cu")
		(net "JTAG_BMC_TRST_N")
	)
	(segment
		(start 326.619362 -166.96817)
		(end 333.3623 -160.225232)
		(width 0.127)
		(layer "In5.Cu")
		(net "JTAG_BMC_TRST_N")
	)
	(segment
		(start 320.167 -100.584)
		(end 331.724 -89.027)
		(width 0.127)
		(layer "In5.Cu")
		(net "JTAG_BMC_TRST_N")
	)
	(segment
		(start 333.3623 -151.202898)
		(end 331.88275 -149.723348)
		(width 0.127)
		(layer "In5.Cu")
		(net "JTAG_BMC_TRST_N")
	)
	(segment
		(start 320.167 -107.315)
		(end 320.167 -100.584)
		(width 0.127)
		(layer "In5.Cu")
		(net "JTAG_BMC_TRST_N")
	)
	(segment
		(start 314.325 -171.577)
		(end 314.833 -171.577)
		(width 0.127)
		(layer "In5.Cu")
		(net "JTAG_BMC_TRST_N")
	)
	(segment
		(start 323.137784 -147.212304)
		(end 318.897 -142.97152)
		(width 0.127)
		(layer "In5.Cu")
		(net "JTAG_BMC_TRST_N")
	)
	(segment
		(start 333.3623 -160.225232)
		(end 333.3623 -151.202898)
		(width 0.127)
		(layer "In5.Cu")
		(net "JTAG_BMC_TRST_N")
	)
	(segment
		(start 317.5 -110.363)
		(end 317.5 -109.982)
		(width 0.127)
		(layer "In5.Cu")
		(net "JTAG_BMC_TRST_N")
	)
	(segment
		(start 317.5 -109.982)
		(end 320.167 -107.315)
		(width 0.127)
		(layer "In5.Cu")
		(net "JTAG_BMC_TRST_N")
	)
	(segment
		(start 318.897 -142.97152)
		(end 318.897 -128.143)
		(width 0.127)
		(layer "In5.Cu")
		(net "JTAG_BMC_TRST_N")
	)
	(segment
		(start 314.472066 -113.3856)
		(end 314.4774 -113.3856)
		(width 0.127)
		(layer "In5.Cu")
		(net "JTAG_BMC_TRST_N")
	)
	(segment
		(start 320.0273 -166.3827)
		(end 321.515232 -166.3827)
		(width 0.127)
		(layer "In5.Cu")
		(net "JTAG_BMC_TRST_N")
	)
	(segment
		(start 321.8307 -166.727632)
		(end 322.071238 -166.96817)
		(width 0.127)
		(layer "In5.Cu")
		(net "JTAG_BMC_TRST_N")
	)
	(segment
		(start 321.8307 -166.698168)
		(end 321.8307 -166.727632)
		(width 0.127)
		(layer "In5.Cu")
		(net "JTAG_BMC_TRST_N")
	)
	(segment
		(start 314.4774 -113.3856)
		(end 317.5 -110.363)
		(width 0.127)
		(layer "In5.Cu")
		(net "JTAG_BMC_TRST_N")
	)
	(segment
		(start 329.164442 -147.212304)
		(end 323.137784 -147.212304)
		(width 0.127)
		(layer "In5.Cu")
		(net "JTAG_BMC_TRST_N")
	)
	(segment
		(start 331.88275 -149.723348)
		(end 331.675486 -149.723348)
		(width 0.127)
		(layer "In5.Cu")
		(net "JTAG_BMC_TRST_N")
	)
	(segment
		(start 314.833 -171.577)
		(end 320.0273 -166.3827)
		(width 0.127)
		(layer "In5.Cu")
		(net "JTAG_BMC_TRST_N")
	)
	(segment
		(start 331.675486 -149.723348)
		(end 329.164442 -147.212304)
		(width 0.127)
		(layer "In5.Cu")
		(net "JTAG_BMC_TRST_N")
	)
	(segment
		(start 129.2479 -148.903436)
		(end 129.2479 -119.248174)
		(width 0.1016)
		(layer "F.Cu")
		(net "SAS_EXP_GF_TX_DP0")
	)
	(segment
		(start 146.191732 -166.901368)
		(end 139.81684 -160.526476)
		(width 0.1016)
		(layer "F.Cu")
		(net "SAS_EXP_GF_TX_DP0")
	)
	(segment
		(start 147.682712 -240.519458)
		(end 147.682712 -170.50131)
		(width 0.1016)
		(layer "F.Cu")
		(net "SAS_EXP_GF_TX_DP0")
	)
	(segment
		(start 147.682712 -243.648738)
		(end 147.682712 -243.343938)
		(width 0.1016)
		(layer "F.Cu")
		(net "SAS_EXP_GF_TX_DP0")
	)
	(segment
		(start 148.000212 -256.25044)
		(end 148.000212 -254.37846)
		(width 0.1016)
		(layer "F.Cu")
		(net "SAS_EXP_GF_TX_DP0")
	)
	(segment
		(start 147.921472 -249.809762)
		(end 147.921472 -249.504962)
		(width 0.1016)
		(layer "F.Cu")
		(net "SAS_EXP_GF_TX_DP0")
	)
	(segment
		(start 136.906 -99.369118)
		(end 136.906 -99.0854)
		(width 0.1016)
		(layer "F.Cu")
		(net "SAS_EXP_GF_TX_DP0")
	)
	(segment
		(start 139.32154 -160.03143)
		(end 129.99339 -150.70328)
		(width 0.1016)
		(layer "F.Cu")
		(net "SAS_EXP_GF_TX_DP0")
	)
	(segment
		(start 139.81684 -160.526476)
		(end 139.32154 -160.03143)
		(width 0.1016)
		(layer "F.Cu")
		(net "SAS_EXP_GF_TX_DP0")
	)
	(segment
		(start 147.682712 -247.462802)
		(end 147.682712 -244.908578)
		(width 0.1016)
		(layer "F.Cu")
		(net "SAS_EXP_GF_TX_DP0")
	)
	(segment
		(start 147.921472 -248.245122)
		(end 147.921472 -247.940322)
		(width 0.1016)
		(layer "F.Cu")
		(net "SAS_EXP_GF_TX_DP0")
	)
	(segment
		(start 136.789668 -99.527614)
		(end 136.876282 -99.441)
		(width 0.1016)
		(layer "F.Cu")
		(net "SAS_EXP_GF_TX_DP0")
	)
	(segment
		(start 129.682748 -118.198392)
		(end 136.00557 -111.87557)
		(width 0.1016)
		(layer "F.Cu")
		(net "SAS_EXP_GF_TX_DP0")
	)
	(segment
		(start 147.682712 -242.084098)
		(end 147.682712 -241.779298)
		(width 0.1016)
		(layer "F.Cu")
		(net "SAS_EXP_GF_TX_DP0")
	)
	(segment
		(start 136.75995 -110.05439)
		(end 136.75995 -99.599496)
		(width 0.1016)
		(layer "F.Cu")
		(net "SAS_EXP_GF_TX_DP0")
	)
	(segment
		(start 147.682712 -253.611888)
		(end 147.682712 -250.287282)
		(width 0.1016)
		(layer "F.Cu")
		(net "SAS_EXP_GF_TX_DP0")
	)
	(segment
		(start 147.921472 -242.866418)
		(end 147.921472 -242.561618)
		(width 0.1016)
		(layer "F.Cu")
		(net "SAS_EXP_GF_TX_DP0")
	)
	(segment
		(start 147.682712 -249.027442)
		(end 147.682712 -248.722642)
		(width 0.1016)
		(layer "F.Cu")
		(net "SAS_EXP_GF_TX_DP0")
	)
	(segment
		(start 147.921472 -244.431058)
		(end 147.921472 -244.126258)
		(width 0.1016)
		(layer "F.Cu")
		(net "SAS_EXP_GF_TX_DP0")
	)
	(segment
		(start 147.921472 -241.301778)
		(end 147.921472 -240.996978)
		(width 0.1016)
		(layer "F.Cu")
		(net "SAS_EXP_GF_TX_DP0")
	)
	(arc
		(start 148.000212 -254.37846)
		(mid 147.954002 -254.146148)
		(end 147.822412 -253.9492)
		(width 0.1016)
		(layer "F.Cu")
		(net "SAS_EXP_GF_TX_DP0")
	)
	(arc
		(start 147.802092 -243.887498)
		(mid 147.713298 -243.782684)
		(end 147.682712 -243.648738)
		(width 0.1016)
		(layer "F.Cu")
		(net "SAS_EXP_GF_TX_DP0")
	)
	(arc
		(start 147.921472 -244.126258)
		(mid 147.89098 -243.992265)
		(end 147.802092 -243.887498)
		(width 0.1016)
		(layer "F.Cu")
		(net "SAS_EXP_GF_TX_DP0")
	)
	(arc
		(start 129.2479 -119.248174)
		(mid 129.360911 -118.680031)
		(end 129.682748 -118.198392)
		(width 0.1016)
		(layer "F.Cu")
		(net "SAS_EXP_GF_TX_DP0")
	)
	(arc
		(start 147.921472 -249.504962)
		(mid 147.89098 -249.370969)
		(end 147.802092 -249.266202)
		(width 0.1016)
		(layer "F.Cu")
		(net "SAS_EXP_GF_TX_DP0")
	)
	(arc
		(start 147.802092 -247.701562)
		(mid 147.713298 -247.596748)
		(end 147.682712 -247.462802)
		(width 0.1016)
		(layer "F.Cu")
		(net "SAS_EXP_GF_TX_DP0")
	)
	(arc
		(start 147.682712 -243.343938)
		(mid 147.713204 -243.209945)
		(end 147.802092 -243.105178)
		(width 0.1016)
		(layer "F.Cu")
		(net "SAS_EXP_GF_TX_DP0")
	)
	(arc
		(start 147.802092 -249.266202)
		(mid 147.713298 -249.161388)
		(end 147.682712 -249.027442)
		(width 0.1016)
		(layer "F.Cu")
		(net "SAS_EXP_GF_TX_DP0")
	)
	(arc
		(start 147.682712 -244.908578)
		(mid 147.713204 -244.774585)
		(end 147.802092 -244.669818)
		(width 0.1016)
		(layer "F.Cu")
		(net "SAS_EXP_GF_TX_DP0")
	)
	(arc
		(start 147.921472 -247.940322)
		(mid 147.89098 -247.806329)
		(end 147.802092 -247.701562)
		(width 0.1016)
		(layer "F.Cu")
		(net "SAS_EXP_GF_TX_DP0")
	)
	(arc
		(start 136.876282 -99.441)
		(mid 136.898265 -99.408006)
		(end 136.906 -99.369118)
		(width 0.1016)
		(layer "F.Cu")
		(net "SAS_EXP_GF_TX_DP0")
	)
	(arc
		(start 147.802092 -244.669818)
		(mid 147.890886 -244.565004)
		(end 147.921472 -244.431058)
		(width 0.1016)
		(layer "F.Cu")
		(net "SAS_EXP_GF_TX_DP0")
	)
	(arc
		(start 136.75995 -99.599496)
		(mid 136.767669 -99.560601)
		(end 136.789668 -99.527614)
		(width 0.1016)
		(layer "F.Cu")
		(net "SAS_EXP_GF_TX_DP0")
	)
	(arc
		(start 147.682712 -248.722642)
		(mid 147.713204 -248.588649)
		(end 147.802092 -248.483882)
		(width 0.1016)
		(layer "F.Cu")
		(net "SAS_EXP_GF_TX_DP0")
	)
	(arc
		(start 147.802092 -250.048522)
		(mid 147.890886 -249.943708)
		(end 147.921472 -249.809762)
		(width 0.1016)
		(layer "F.Cu")
		(net "SAS_EXP_GF_TX_DP0")
	)
	(arc
		(start 147.802092 -241.540538)
		(mid 147.890886 -241.435724)
		(end 147.921472 -241.301778)
		(width 0.1016)
		(layer "F.Cu")
		(net "SAS_EXP_GF_TX_DP0")
	)
	(arc
		(start 147.802092 -243.105178)
		(mid 147.890886 -243.000364)
		(end 147.921472 -242.866418)
		(width 0.1016)
		(layer "F.Cu")
		(net "SAS_EXP_GF_TX_DP0")
	)
	(arc
		(start 147.682712 -241.779298)
		(mid 147.713204 -241.645305)
		(end 147.802092 -241.540538)
		(width 0.1016)
		(layer "F.Cu")
		(net "SAS_EXP_GF_TX_DP0")
	)
	(arc
		(start 147.802092 -242.322858)
		(mid 147.713298 -242.218044)
		(end 147.682712 -242.084098)
		(width 0.1016)
		(layer "F.Cu")
		(net "SAS_EXP_GF_TX_DP0")
	)
	(arc
		(start 147.802092 -248.483882)
		(mid 147.890886 -248.379068)
		(end 147.921472 -248.245122)
		(width 0.1016)
		(layer "F.Cu")
		(net "SAS_EXP_GF_TX_DP0")
	)
	(arc
		(start 136.00557 -111.87557)
		(mid 136.563876 -111.040006)
		(end 136.75995 -110.05439)
		(width 0.1016)
		(layer "F.Cu")
		(net "SAS_EXP_GF_TX_DP0")
	)
	(arc
		(start 147.682712 -170.50131)
		(mid 147.295272 -168.553045)
		(end 146.191732 -166.901368)
		(width 0.1016)
		(layer "F.Cu")
		(net "SAS_EXP_GF_TX_DP0")
	)
	(arc
		(start 147.682712 -250.287282)
		(mid 147.713204 -250.153289)
		(end 147.802092 -250.048522)
		(width 0.1016)
		(layer "F.Cu")
		(net "SAS_EXP_GF_TX_DP0")
	)
	(arc
		(start 147.802092 -240.758218)
		(mid 147.713298 -240.653404)
		(end 147.682712 -240.519458)
		(width 0.1016)
		(layer "F.Cu")
		(net "SAS_EXP_GF_TX_DP0")
	)
	(arc
		(start 129.99339 -150.70328)
		(mid 129.441624 -149.877505)
		(end 129.2479 -148.903436)
		(width 0.1016)
		(layer "F.Cu")
		(net "SAS_EXP_GF_TX_DP0")
	)
	(arc
		(start 147.921472 -242.561618)
		(mid 147.89098 -242.427625)
		(end 147.802092 -242.322858)
		(width 0.1016)
		(layer "F.Cu")
		(net "SAS_EXP_GF_TX_DP0")
	)
	(arc
		(start 147.921472 -240.996978)
		(mid 147.89098 -240.862985)
		(end 147.802092 -240.758218)
		(width 0.1016)
		(layer "F.Cu")
		(net "SAS_EXP_GF_TX_DP0")
	)
	(arc
		(start 147.822412 -253.9492)
		(mid 147.719005 -253.79444)
		(end 147.682712 -253.611888)
		(width 0.1016)
		(layer "F.Cu")
		(net "SAS_EXP_GF_TX_DP0")
	)
	(segment
		(start 196.28993 -75.55357)
		(end 196.28993 -76.198984)
		(width 0.1397)
		(layer "F.Cu")
		(net "PCIE_SAS_CPU_TX_N2")
	)
	(segment
		(start 139.445746 -12.340844)
		(end 139.446 -12.34059)
		(width 0.1397)
		(layer "F.Cu")
		(net "PCIE_SAS_CPU_TX_N2")
	)
	(segment
		(start 195.29552 -73.66)
		(end 195.29552 -73.9394)
		(width 0.1397)
		(layer "F.Cu")
		(net "PCIE_SAS_CPU_TX_N2")
	)
	(segment
		(start 110.141512 -14.699488)
		(end 117.479572 -7.361428)
		(width 0.1397)
		(layer "F.Cu")
		(net "PCIE_SAS_CPU_TX_N2")
	)
	(segment
		(start 195.554854 -74.565764)
		(end 196.11086 -75.12177)
		(width 0.1397)
		(layer "F.Cu")
		(net "PCIE_SAS_CPU_TX_N2")
	)
	(segment
		(start 98.32467 -33.46323)
		(end 98.32467 -32.18307)
		(width 0.1397)
		(layer "F.Cu")
		(net "PCIE_SAS_CPU_TX_N2")
	)
	(segment
		(start 139.446 -12.34059)
		(end 139.446 -17.361408)
		(width 0.1397)
		(layer "F.Cu")
		(net "PCIE_SAS_CPU_TX_N2")
	)
	(segment
		(start 186.12993 -64.06007)
		(end 194.988434 -72.918574)
		(width 0.1397)
		(layer "F.Cu")
		(net "PCIE_SAS_CPU_TX_N2")
	)
	(segment
		(start 96.813116 -29.855922)
		(end 96.813116 -24.528018)
		(width 0.1397)
		(layer "F.Cu")
		(net "PCIE_SAS_CPU_TX_N2")
	)
	(segment
		(start 139.81811 -18.391378)
		(end 139.81811 -18.401538)
		(width 0.1397)
		(layer "F.Cu")
		(net "PCIE_SAS_CPU_TX_N2")
	)
	(segment
		(start 106.092244 -14.986)
		(end 109.44987 -14.986)
		(width 0.1397)
		(layer "F.Cu")
		(net "PCIE_SAS_CPU_TX_N2")
	)
	(segment
		(start 97.95002 -34.19983)
		(end 98.068638 -34.080958)
		(width 0.1397)
		(layer "F.Cu")
		(net "PCIE_SAS_CPU_TX_N2")
	)
	(segment
		(start 139.81811 -18.401538)
		(end 184.77738 -63.360808)
		(width 0.1397)
		(layer "F.Cu")
		(net "PCIE_SAS_CPU_TX_N2")
	)
	(segment
		(start 185.89244 -63.822834)
		(end 186.12993 -64.06007)
		(width 0.1397)
		(layer "F.Cu")
		(net "PCIE_SAS_CPU_TX_N2")
	)
	(segment
		(start 196.289676 -75.553824)
		(end 196.28993 -75.55357)
		(width 0.1397)
		(layer "F.Cu")
		(net "PCIE_SAS_CPU_TX_N2")
	)
	(segment
		(start 98.119946 -31.688786)
		(end 97.184972 -30.753812)
		(width 0.1397)
		(layer "F.Cu")
		(net "PCIE_SAS_CPU_TX_N2")
	)
	(segment
		(start 117.928644 -7.1755)
		(end 134.773416 -7.1755)
		(width 0.1397)
		(layer "F.Cu")
		(net "PCIE_SAS_CPU_TX_N2")
	)
	(segment
		(start 135.222488 -7.361428)
		(end 138.91133 -11.05027)
		(width 0.1397)
		(layer "F.Cu")
		(net "PCIE_SAS_CPU_TX_N2")
	)
	(segment
		(start 97.184972 -23.630128)
		(end 105.643172 -15.171928)
		(width 0.1397)
		(layer "F.Cu")
		(net "PCIE_SAS_CPU_TX_N2")
	)
	(via
		(at 195.947538 -77.0255)
		(size 0.5588)
		(drill 0.3048)
		(layers "F.Cu" "B.Cu")
		(net "PCIE_SAS_CPU_TX_N2")
	)
	(arc
		(start 109.44987 -14.986)
		(mid 109.824179 -14.911527)
		(end 110.141512 -14.699488)
		(width 0.1397)
		(layer "F.Cu")
		(net "PCIE_SAS_CPU_TX_N2")
	)
	(arc
		(start 139.446 -17.361408)
		(mid 139.541963 -17.908942)
		(end 139.81811 -18.391378)
		(width 0.1397)
		(layer "F.Cu")
		(net "PCIE_SAS_CPU_TX_N2")
	)
	(arc
		(start 97.184972 -30.753812)
		(mid 96.909766 -30.341842)
		(end 96.813116 -29.855922)
		(width 0.1397)
		(layer "F.Cu")
		(net "PCIE_SAS_CPU_TX_N2")
	)
	(arc
		(start 138.91133 -11.05027)
		(mid 139.306889 -11.642405)
		(end 139.445746 -12.340844)
		(width 0.1397)
		(layer "F.Cu")
		(net "PCIE_SAS_CPU_TX_N2")
	)
	(arc
		(start 105.643172 -15.171928)
		(mid 105.849208 -15.034259)
		(end 106.092244 -14.986)
		(width 0.1397)
		(layer "F.Cu")
		(net "PCIE_SAS_CPU_TX_N2")
	)
	(arc
		(start 195.29552 -73.9394)
		(mid 195.362857 -74.278396)
		(end 195.554854 -74.565764)
		(width 0.1397)
		(layer "F.Cu")
		(net "PCIE_SAS_CPU_TX_N2")
	)
	(arc
		(start 185.42 -63.627)
		(mid 185.675684 -63.677952)
		(end 185.89244 -63.822834)
		(width 0.1397)
		(layer "F.Cu")
		(net "PCIE_SAS_CPU_TX_N2")
	)
	(arc
		(start 196.28993 -76.198984)
		(mid 196.200952 -76.646306)
		(end 195.947538 -77.0255)
		(width 0.1397)
		(layer "F.Cu")
		(net "PCIE_SAS_CPU_TX_N2")
	)
	(arc
		(start 196.11086 -75.12177)
		(mid 196.243229 -75.320013)
		(end 196.289676 -75.553824)
		(width 0.1397)
		(layer "F.Cu")
		(net "PCIE_SAS_CPU_TX_N2")
	)
	(arc
		(start 184.77738 -63.360808)
		(mid 185.072217 -63.557811)
		(end 185.42 -63.627)
		(width 0.1397)
		(layer "F.Cu")
		(net "PCIE_SAS_CPU_TX_N2")
	)
	(arc
		(start 98.068638 -34.080958)
		(mid 98.258093 -33.797557)
		(end 98.32467 -33.46323)
		(width 0.1397)
		(layer "F.Cu")
		(net "PCIE_SAS_CPU_TX_N2")
	)
	(arc
		(start 96.813116 -24.528018)
		(mid 96.909755 -24.042093)
		(end 97.184972 -23.630128)
		(width 0.1397)
		(layer "F.Cu")
		(net "PCIE_SAS_CPU_TX_N2")
	)
	(arc
		(start 98.32467 -32.18307)
		(mid 98.271461 -31.915571)
		(end 98.119946 -31.688786)
		(width 0.1397)
		(layer "F.Cu")
		(net "PCIE_SAS_CPU_TX_N2")
	)
	(arc
		(start 134.773416 -7.1755)
		(mid 135.01642 -7.223836)
		(end 135.222488 -7.361428)
		(width 0.1397)
		(layer "F.Cu")
		(net "PCIE_SAS_CPU_TX_N2")
	)
	(arc
		(start 194.988434 -72.918574)
		(mid 195.215728 -73.258743)
		(end 195.29552 -73.66)
		(width 0.1397)
		(layer "F.Cu")
		(net "PCIE_SAS_CPU_TX_N2")
	)
	(arc
		(start 117.479572 -7.361428)
		(mid 117.685608 -7.223759)
		(end 117.928644 -7.1755)
		(width 0.1397)
		(layer "F.Cu")
		(net "PCIE_SAS_CPU_TX_N2")
	)
	(segment
		(start 196.449696 -80.25003)
		(end 196.449696 -80.249776)
		(width 0.1397)
		(layer "B.Cu")
		(net "PCIE_SAS_CPU_TX_N2")
	)
	(segment
		(start 196.449696 -80.249776)
		(end 196.717666 -79.981806)
		(width 0.1397)
		(layer "B.Cu")
		(net "PCIE_SAS_CPU_TX_N2")
	)
	(segment
		(start 196.76999 -79.421736)
		(end 196.58076 -79.256128)
		(width 0.1397)
		(layer "B.Cu")
		(net "PCIE_SAS_CPU_TX_N2")
	)
	(segment
		(start 196.26199 -78.553564)
		(end 196.26199 -77.44206)
		(width 0.1397)
		(layer "B.Cu")
		(net "PCIE_SAS_CPU_TX_N2")
	)
	(segment
		(start 196.189854 -77.267562)
		(end 195.947538 -77.0255)
		(width 0.1397)
		(layer "B.Cu")
		(net "PCIE_SAS_CPU_TX_N2")
	)
	(arc
		(start 196.86397 -79.629)
		(mid 196.839364 -79.515227)
		(end 196.76999 -79.421736)
		(width 0.1397)
		(layer "B.Cu")
		(net "PCIE_SAS_CPU_TX_N2")
	)
	(arc
		(start 196.58076 -79.256128)
		(mid 196.557802 -79.235423)
		(end 196.535548 -79.213964)
		(width 0.1397)
		(layer "B.Cu")
		(net "PCIE_SAS_CPU_TX_N2")
	)
	(arc
		(start 196.535548 -79.213964)
		(mid 196.333065 -78.910971)
		(end 196.26199 -78.553564)
		(width 0.1397)
		(layer "B.Cu")
		(net "PCIE_SAS_CPU_TX_N2")
	)
	(arc
		(start 196.26199 -77.44206)
		(mid 196.243299 -77.347624)
		(end 196.189854 -77.267562)
		(width 0.1397)
		(layer "B.Cu")
		(net "PCIE_SAS_CPU_TX_N2")
	)
	(arc
		(start 196.717666 -79.981806)
		(mid 196.825906 -79.819952)
		(end 196.86397 -79.629)
		(width 0.1397)
		(layer "B.Cu")
		(net "PCIE_SAS_CPU_TX_N2")
	)
	(segment
		(start 341.618062 -109.320076)
		(end 341.618062 -109.231938)
		(width 0.3048)
		(layer "F.Cu")
		(net "P5V_STBY_VBST")
	)
	(segment
		(start 342.138 -108.712)
		(end 343.027 -107.823)
		(width 0.508)
		(layer "F.Cu")
		(net "P5V_STBY_VBST")
	)
	(segment
		(start 341.618062 -109.231938)
		(end 342.138 -108.712)
		(width 0.3048)
		(layer "F.Cu")
		(net "P5V_STBY_VBST")
	)
	(segment
		(start 343.027 -107.823)
		(end 343.2175 -107.823)
		(width 0.508)
		(layer "F.Cu")
		(net "P5V_STBY_VBST")
	)
	(segment
		(start 344.17 -107.6325)
		(end 343.408 -107.6325)
		(width 0.508)
		(layer "F.Cu")
		(net "P5V_STBY_VBST")
	)
	(segment
		(start 343.408 -107.6325)
		(end 343.2175 -107.823)
		(width 0.508)
		(layer "F.Cu")
		(net "P5V_STBY_VBST")
	)
	(via
		(at 343.2175 -107.823)
		(size 0.7112)
		(drill 0.3556)
		(layers "F.Cu" "B.Cu")
		(net "P5V_STBY_VBST")
	)
	(segment
		(start 222.5675 -25.781)
		(end 225.90252 -25.781)
		(width 0.127)
		(layer "F.Cu")
		(net "BMC_ID_LED")
	)
	(segment
		(start 296.834814 -169.03065)
		(end 296.442892 -168.638728)
		(width 0.127)
		(layer "F.Cu")
		(net "BMC_ID_LED")
	)
	(segment
		(start 263.18845 -87.515192)
		(end 263.18845 -92.70365)
		(width 0.127)
		(layer "F.Cu")
		(net "BMC_ID_LED")
	)
	(segment
		(start 263.18845 -92.70365)
		(end 269.434564 -98.949764)
		(width 0.127)
		(layer "F.Cu")
		(net "BMC_ID_LED")
	)
	(segment
		(start 239.268 -63.594742)
		(end 263.18845 -87.515192)
		(width 0.127)
		(layer "F.Cu")
		(net "BMC_ID_LED")
	)
	(segment
		(start 239.268 -39.14648)
		(end 239.268 -63.594742)
		(width 0.127)
		(layer "F.Cu")
		(net "BMC_ID_LED")
	)
	(segment
		(start 296.834814 -169.040048)
		(end 296.834814 -169.03065)
		(width 0.127)
		(layer "F.Cu")
		(net "BMC_ID_LED")
	)
	(segment
		(start 269.434564 -98.949764)
		(end 269.434564 -100.438204)
		(width 0.127)
		(layer "F.Cu")
		(net "BMC_ID_LED")
	)
	(segment
		(start 225.90252 -25.781)
		(end 239.268 -39.14648)
		(width 0.127)
		(layer "F.Cu")
		(net "BMC_ID_LED")
	)
	(via
		(at 295.656 -100.838)
		(size 0.5588)
		(drill 0.3048)
		(layers "F.Cu" "B.Cu")
		(net "BMC_ID_LED")
	)
	(via
		(at 294.386 -100.711)
		(size 0.7112)
		(drill 0.3556)
		(layers "F.Cu" "B.Cu")
		(net "BMC_ID_LED")
	)
	(via
		(at 296.442892 -168.638728)
		(size 0.508)
		(drill 0.254)
		(layers "F.Cu" "B.Cu")
		(net "BMC_ID_LED")
	)
	(via
		(at 301.117 -139.21105)
		(size 0.5588)
		(drill 0.3048)
		(layers "F.Cu" "B.Cu")
		(net "BMC_ID_LED")
	)
	(via
		(at 269.434564 -100.438204)
		(size 0.5588)
		(drill 0.3048)
		(layers "F.Cu" "B.Cu")
		(net "BMC_ID_LED")
	)
	(segment
		(start 295.529 -100.711)
		(end 294.386 -100.711)
		(width 0.127)
		(layer "B.Cu")
		(net "BMC_ID_LED")
	)
	(segment
		(start 269.785592 -100.711)
		(end 269.512796 -100.438204)
		(width 0.127)
		(layer "B.Cu")
		(net "BMC_ID_LED")
	)
	(segment
		(start 269.512796 -100.438204)
		(end 269.434564 -100.438204)
		(width 0.127)
		(layer "B.Cu")
		(net "BMC_ID_LED")
	)
	(segment
		(start 295.656 -100.838)
		(end 295.529 -100.711)
		(width 0.127)
		(layer "B.Cu")
		(net "BMC_ID_LED")
	)
	(segment
		(start 294.386 -100.711)
		(end 269.785592 -100.711)
		(width 0.127)
		(layer "B.Cu")
		(net "BMC_ID_LED")
	)
	(segment
		(start 302.2727 -140.36675)
		(end 301.117 -139.21105)
		(width 0.127)
		(layer "In2.Cu")
		(net "BMC_ID_LED")
	)
	(segment
		(start 296.442892 -168.638728)
		(end 296.442892 -165.710108)
		(width 0.127)
		(layer "In2.Cu")
		(net "BMC_ID_LED")
	)
	(segment
		(start 300.271434 -159.004)
		(end 300.858936 -159.004)
		(width 0.127)
		(layer "In2.Cu")
		(net "BMC_ID_LED")
	)
	(segment
		(start 299.593 -160.952434)
		(end 299.974 -160.571434)
		(width 0.127)
		(layer "In2.Cu")
		(net "BMC_ID_LED")
	)
	(segment
		(start 299.593 -162.56)
		(end 299.593 -160.952434)
		(width 0.127)
		(layer "In2.Cu")
		(net "BMC_ID_LED")
	)
	(segment
		(start 296.442892 -165.710108)
		(end 299.593 -162.56)
		(width 0.127)
		(layer "In2.Cu")
		(net "BMC_ID_LED")
	)
	(segment
		(start 302.2727 -157.590236)
		(end 302.2727 -140.36675)
		(width 0.127)
		(layer "In2.Cu")
		(net "BMC_ID_LED")
	)
	(segment
		(start 299.974 -159.301434)
		(end 300.271434 -159.004)
		(width 0.127)
		(layer "In2.Cu")
		(net "BMC_ID_LED")
	)
	(segment
		(start 300.858936 -159.004)
		(end 302.2727 -157.590236)
		(width 0.127)
		(layer "In2.Cu")
		(net "BMC_ID_LED")
	)
	(segment
		(start 299.974 -160.571434)
		(end 299.974 -159.301434)
		(width 0.127)
		(layer "In2.Cu")
		(net "BMC_ID_LED")
	)
	(segment
		(start 301.117 -139.21105)
		(end 296.672 -134.76605)
		(width 0.127)
		(layer "In5.Cu")
		(net "BMC_ID_LED")
	)
	(segment
		(start 296.672 -105.856532)
		(end 296.7863 -105.742232)
		(width 0.127)
		(layer "In5.Cu")
		(net "BMC_ID_LED")
	)
	(segment
		(start 296.672 -134.76605)
		(end 296.672 -105.856532)
		(width 0.127)
		(layer "In5.Cu")
		(net "BMC_ID_LED")
	)
	(segment
		(start 296.7863 -105.742232)
		(end 296.7863 -101.9683)
		(width 0.127)
		(layer "In5.Cu")
		(net "BMC_ID_LED")
	)
	(segment
		(start 296.7863 -101.9683)
		(end 295.656 -100.838)
		(width 0.127)
		(layer "In5.Cu")
		(net "BMC_ID_LED")
	)
	(segment
		(start 107.349798 -102.350062)
		(end 106.849672 -102.850188)
		(width 0.1016)
		(layer "F.Cu")
		(net "SAS_GF_EXP_RX_DN15")
	)
	(via
		(at 106.849672 -102.850188)
		(size 0.508)
		(drill 0.254)
		(layers "F.Cu" "B.Cu")
		(net "SAS_GF_EXP_RX_DN15")
	)
	(segment
		(start 73.235312 -254.087376)
		(end 73.235312 -223.345756)
		(width 0.1016)
		(layer "B.Cu")
		(net "SAS_GF_EXP_RX_DN15")
	)
	(segment
		(start 102.132892 -153.8097)
		(end 102.132892 -114.497104)
		(width 0.1016)
		(layer "B.Cu")
		(net "SAS_GF_EXP_RX_DN15")
	)
	(segment
		(start 105.08107 -110.78464)
		(end 105.08107 -109.98835)
		(width 0.1016)
		(layer "B.Cu")
		(net "SAS_GF_EXP_RX_DN15")
	)
	(segment
		(start 105.407206 -109.20095)
		(end 105.406952 -109.200696)
		(width 0.1016)
		(layer "B.Cu")
		(net "SAS_GF_EXP_RX_DN15")
	)
	(segment
		(start 106.849672 -102.865174)
		(end 106.849672 -102.850188)
		(width 0.1016)
		(layer "B.Cu")
		(net "SAS_GF_EXP_RX_DN15")
	)
	(segment
		(start 102.132638 -153.825194)
		(end 102.132892 -153.8097)
		(width 0.1016)
		(layer "B.Cu")
		(net "SAS_GF_EXP_RX_DN15")
	)
	(segment
		(start 74.05243 -221.37243)
		(end 84.33943 -211.08543)
		(width 0.1016)
		(layer "B.Cu")
		(net "SAS_GF_EXP_RX_DN15")
	)
	(segment
		(start 73.000362 -256.50444)
		(end 73.000362 -254.679958)
		(width 0.1016)
		(layer "B.Cu")
		(net "SAS_GF_EXP_RX_DN15")
	)
	(segment
		(start 104.791764 -111.371888)
		(end 104.870504 -111.293402)
		(width 0.1016)
		(layer "B.Cu")
		(net "SAS_GF_EXP_RX_DN15")
	)
	(segment
		(start 106.756962 -103.088948)
		(end 106.849672 -102.865174)
		(width 0.1016)
		(layer "B.Cu")
		(net "SAS_GF_EXP_RX_DN15")
	)
	(segment
		(start 106.49077 -103.42372)
		(end 106.619294 -103.295196)
		(width 0.1016)
		(layer "B.Cu")
		(net "SAS_GF_EXP_RX_DN15")
	)
	(segment
		(start 85.503258 -171.200572)
		(end 101.605334 -155.098496)
		(width 0.1016)
		(layer "B.Cu")
		(net "SAS_GF_EXP_RX_DN15")
	)
	(segment
		(start 73.22439 -254.124206)
		(end 73.230486 -254.1143)
		(width 0.1016)
		(layer "B.Cu")
		(net "SAS_GF_EXP_RX_DN15")
	)
	(segment
		(start 84.8741 -209.794602)
		(end 84.8741 -172.719746)
		(width 0.1016)
		(layer "B.Cu")
		(net "SAS_GF_EXP_RX_DN15")
	)
	(segment
		(start 106.304842 -108.039916)
		(end 106.304842 -103.872792)
		(width 0.1016)
		(layer "B.Cu")
		(net "SAS_GF_EXP_RX_DN15")
	)
	(segment
		(start 102.462584 -113.701068)
		(end 104.791764 -111.371888)
		(width 0.1016)
		(layer "B.Cu")
		(net "SAS_GF_EXP_RX_DN15")
	)
	(segment
		(start 105.406952 -109.200696)
		(end 106.118914 -108.488988)
		(width 0.1016)
		(layer "B.Cu")
		(net "SAS_GF_EXP_RX_DN15")
	)
	(arc
		(start 101.605334 -155.098496)
		(mid 101.995681 -154.5143)
		(end 102.132638 -153.825194)
		(width 0.1016)
		(layer "B.Cu")
		(net "SAS_GF_EXP_RX_DN15")
	)
	(arc
		(start 105.08107 -109.98835)
		(mid 105.165818 -109.562204)
		(end 105.407206 -109.20095)
		(width 0.1016)
		(layer "B.Cu")
		(net "SAS_GF_EXP_RX_DN15")
	)
	(arc
		(start 73.162414 -254.288798)
		(mid 73.198155 -254.235308)
		(end 73.210674 -254.172212)
		(width 0.1016)
		(layer "B.Cu")
		(net "SAS_GF_EXP_RX_DN15")
	)
	(arc
		(start 73.210674 -254.172212)
		(mid 73.214168 -254.147247)
		(end 73.22439 -254.124206)
		(width 0.1016)
		(layer "B.Cu")
		(net "SAS_GF_EXP_RX_DN15")
	)
	(arc
		(start 73.230486 -254.1143)
		(mid 73.234008 -254.101037)
		(end 73.235312 -254.087376)
		(width 0.1016)
		(layer "B.Cu")
		(net "SAS_GF_EXP_RX_DN15")
	)
	(arc
		(start 102.132892 -114.497104)
		(mid 102.218568 -114.066292)
		(end 102.462584 -113.701068)
		(width 0.1016)
		(layer "B.Cu")
		(net "SAS_GF_EXP_RX_DN15")
	)
	(arc
		(start 106.304842 -103.872792)
		(mid 106.353163 -103.629774)
		(end 106.49077 -103.42372)
		(width 0.1016)
		(layer "B.Cu")
		(net "SAS_GF_EXP_RX_DN15")
	)
	(arc
		(start 104.870504 -111.293402)
		(mid 105.026389 -111.059965)
		(end 105.08107 -110.78464)
		(width 0.1016)
		(layer "B.Cu")
		(net "SAS_GF_EXP_RX_DN15")
	)
	(arc
		(start 73.235312 -223.345756)
		(mid 73.447571 -222.277806)
		(end 74.05243 -221.37243)
		(width 0.1016)
		(layer "B.Cu")
		(net "SAS_GF_EXP_RX_DN15")
	)
	(arc
		(start 106.118914 -108.488988)
		(mid 106.256529 -108.282938)
		(end 106.304842 -108.039916)
		(width 0.1016)
		(layer "B.Cu")
		(net "SAS_GF_EXP_RX_DN15")
	)
	(arc
		(start 84.33943 -211.08543)
		(mid 84.73515 -210.493193)
		(end 84.8741 -209.794602)
		(width 0.1016)
		(layer "B.Cu")
		(net "SAS_GF_EXP_RX_DN15")
	)
	(arc
		(start 106.619294 -103.295196)
		(mid 106.698295 -103.198858)
		(end 106.756962 -103.088948)
		(width 0.1016)
		(layer "B.Cu")
		(net "SAS_GF_EXP_RX_DN15")
	)
	(arc
		(start 73.000362 -254.679958)
		(mid 73.042473 -254.468253)
		(end 73.162414 -254.288798)
		(width 0.1016)
		(layer "B.Cu")
		(net "SAS_GF_EXP_RX_DN15")
	)
	(arc
		(start 84.8741 -172.719746)
		(mid 85.037602 -171.897586)
		(end 85.503258 -171.200572)
		(width 0.1016)
		(layer "B.Cu")
		(net "SAS_GF_EXP_RX_DN15")
	)
	(via
		(at 345.44 -110.109)
		(size 0.7112)
		(drill 0.3556)
		(layers "F.Cu" "B.Cu")
		(net "P5V_STBY_VIN")
	)
	(segment
		(start 279.315164 -177.634646)
		(end 279.099518 -177.419)
		(width 0.1143)
		(layer "F.Cu")
		(net "ROMA7")
	)
	(segment
		(start 283.392372 -177.617882)
		(end 283.375608 -177.634646)
		(width 0.1143)
		(layer "F.Cu")
		(net "ROMA7")
	)
	(segment
		(start 274.6375 -178.689)
		(end 275.014944 -178.502056)
		(width 0.1143)
		(layer "F.Cu")
		(net "ROMA7")
	)
	(segment
		(start 279.099518 -177.419)
		(end 277.990046 -177.419)
		(width 0.1143)
		(layer "F.Cu")
		(net "ROMA7")
	)
	(segment
		(start 275.952204 -177.564796)
		(end 276.281388 -177.564796)
		(width 0.1143)
		(layer "F.Cu")
		(net "ROMA7")
	)
	(segment
		(start 276.427184 -177.419)
		(end 277.990046 -177.419)
		(width 0.1143)
		(layer "F.Cu")
		(net "ROMA7")
	)
	(segment
		(start 276.281388 -177.564796)
		(end 276.427184 -177.419)
		(width 0.1143)
		(layer "F.Cu")
		(net "ROMA7")
	)
	(segment
		(start 275.014944 -178.502056)
		(end 275.952204 -177.564796)
		(width 0.1143)
		(layer "F.Cu")
		(net "ROMA7")
	)
	(segment
		(start 284.612588 -177.617882)
		(end 283.392372 -177.617882)
		(width 0.1143)
		(layer "F.Cu")
		(net "ROMA7")
	)
	(segment
		(start 283.375608 -177.634646)
		(end 279.315164 -177.634646)
		(width 0.1143)
		(layer "F.Cu")
		(net "ROMA7")
	)
	(segment
		(start 284.834838 -177.840132)
		(end 284.612588 -177.617882)
		(width 0.1143)
		(layer "F.Cu")
		(net "ROMA7")
	)
	(via
		(at 277.990046 -177.419)
		(size 0.7112)
		(drill 0.3556)
		(layers "F.Cu" "B.Cu")
		(net "ROMA7")
	)
	(segment
		(start 111.34979 -103.35006)
		(end 110.849664 -103.850186)
		(width 0.1016)
		(layer "F.Cu")
		(net "SAS_GF_EXP_RX_DP11")
	)
	(via
		(at 110.849664 -103.850186)
		(size 0.508)
		(drill 0.254)
		(layers "F.Cu" "B.Cu")
		(net "SAS_GF_EXP_RX_DP11")
	)
	(segment
		(start 93.492828 -177.158142)
		(end 107.96397 -162.687)
		(width 0.1016)
		(layer "B.Cu")
		(net "SAS_GF_EXP_RX_DP11")
	)
	(segment
		(start 110.381542 -105.97515)
		(end 110.635542 -105.274618)
		(width 0.1016)
		(layer "B.Cu")
		(net "SAS_GF_EXP_RX_DP11")
	)
	(segment
		(start 87.99957 -219.31757)
		(end 92.31757 -214.99957)
		(width 0.1016)
		(layer "B.Cu")
		(net "SAS_GF_EXP_RX_DP11")
	)
	(segment
		(start 87.870284 -227.029772)
		(end 87.870284 -226.724972)
		(width 0.1016)
		(layer "B.Cu")
		(net "SAS_GF_EXP_RX_DP11")
	)
	(segment
		(start 87.631524 -229.376732)
		(end 87.631524 -229.071932)
		(width 0.1016)
		(layer "B.Cu")
		(net "SAS_GF_EXP_RX_DP11")
	)
	(segment
		(start 87.631524 -226.247452)
		(end 87.631524 -222.360998)
		(width 0.1016)
		(layer "B.Cu")
		(net "SAS_GF_EXP_RX_DP11")
	)
	(segment
		(start 87.631524 -227.812092)
		(end 87.631524 -227.507292)
		(width 0.1016)
		(layer "B.Cu")
		(net "SAS_GF_EXP_RX_DP11")
	)
	(segment
		(start 88.894412 -244.5512)
		(end 88.606376 -244.263164)
		(width 0.1016)
		(layer "B.Cu")
		(net "SAS_GF_EXP_RX_DP11")
	)
	(segment
		(start 87.870284 -228.594412)
		(end 87.870284 -228.289612)
		(width 0.1016)
		(layer "B.Cu")
		(net "SAS_GF_EXP_RX_DP11")
	)
	(segment
		(start 92.964 -213.438486)
		(end 92.964 -178.435)
		(width 0.1016)
		(layer "B.Cu")
		(net "SAS_GF_EXP_RX_DP11")
	)
	(segment
		(start 87.631524 -238.845852)
		(end 87.631524 -238.541052)
		(width 0.1016)
		(layer "B.Cu")
		(net "SAS_GF_EXP_RX_DP11")
	)
	(segment
		(start 110.849664 -103.876856)
		(end 110.849664 -103.850186)
		(width 0.1016)
		(layer "B.Cu")
		(net "SAS_GF_EXP_RX_DP11")
	)
	(segment
		(start 87.631524 -237.281212)
		(end 87.631524 -236.976412)
		(width 0.1016)
		(layer "B.Cu")
		(net "SAS_GF_EXP_RX_DP11")
	)
	(segment
		(start 87.631524 -241.9096)
		(end 87.631524 -240.105692)
		(width 0.1016)
		(layer "B.Cu")
		(net "SAS_GF_EXP_RX_DP11")
	)
	(segment
		(start 89.671652 -253.952756)
		(end 89.671652 -246.42826)
		(width 0.1016)
		(layer "B.Cu")
		(net "SAS_GF_EXP_RX_DP11")
	)
	(segment
		(start 110.343442 -107.307888)
		(end 110.343442 -106.191558)
		(width 0.1016)
		(layer "B.Cu")
		(net "SAS_GF_EXP_RX_DP11")
	)
	(segment
		(start 87.870284 -230.159052)
		(end 87.870284 -229.854252)
		(width 0.1016)
		(layer "B.Cu")
		(net "SAS_GF_EXP_RX_DP11")
	)
	(segment
		(start 110.673642 -105.05821)
		(end 110.673642 -104.18064)
		(width 0.1016)
		(layer "B.Cu")
		(net "SAS_GF_EXP_RX_DP11")
	)
	(segment
		(start 87.870284 -239.628172)
		(end 87.870284 -239.323372)
		(width 0.1016)
		(layer "B.Cu")
		(net "SAS_GF_EXP_RX_DP11")
	)
	(segment
		(start 87.631524 -235.716572)
		(end 87.631524 -230.636572)
		(width 0.1016)
		(layer "B.Cu")
		(net "SAS_GF_EXP_RX_DP11")
	)
	(segment
		(start 110.716314 -104.047544)
		(end 110.72876 -104.030018)
		(width 0.1016)
		(layer "B.Cu")
		(net "SAS_GF_EXP_RX_DP11")
	)
	(segment
		(start 109.987842 -157.800548)
		(end 109.987842 -108.166408)
		(width 0.1016)
		(layer "B.Cu")
		(net "SAS_GF_EXP_RX_DP11")
	)
	(segment
		(start 90.000582 -256.50444)
		(end 90.000582 -254.28194)
		(width 0.1016)
		(layer "B.Cu")
		(net "SAS_GF_EXP_RX_DP11")
	)
	(segment
		(start 87.870284 -236.498892)
		(end 87.870284 -236.194092)
		(width 0.1016)
		(layer "B.Cu")
		(net "SAS_GF_EXP_RX_DP11")
	)
	(segment
		(start 87.631524 -221.101158)
		(end 87.631524 -220.206062)
		(width 0.1016)
		(layer "B.Cu")
		(net "SAS_GF_EXP_RX_DP11")
	)
	(segment
		(start 87.870284 -221.883478)
		(end 87.870284 -221.578678)
		(width 0.1016)
		(layer "B.Cu")
		(net "SAS_GF_EXP_RX_DP11")
	)
	(segment
		(start 87.870284 -238.063532)
		(end 87.870284 -237.758732)
		(width 0.1016)
		(layer "B.Cu")
		(net "SAS_GF_EXP_RX_DP11")
	)
	(segment
		(start 110.761526 -103.99141)
		(end 110.830614 -103.922322)
		(width 0.1016)
		(layer "B.Cu")
		(net "SAS_GF_EXP_RX_DP11")
	)
	(arc
		(start 107.96397 -162.687)
		(mid 109.461892 -160.445062)
		(end 109.987842 -157.800548)
		(width 0.1016)
		(layer "B.Cu")
		(net "SAS_GF_EXP_RX_DP11")
	)
	(arc
		(start 87.750904 -236.737652)
		(mid 87.839698 -236.632838)
		(end 87.870284 -236.498892)
		(width 0.1016)
		(layer "B.Cu")
		(net "SAS_GF_EXP_RX_DP11")
	)
	(arc
		(start 87.750904 -227.268532)
		(mid 87.839698 -227.163718)
		(end 87.870284 -227.029772)
		(width 0.1016)
		(layer "B.Cu")
		(net "SAS_GF_EXP_RX_DP11")
	)
	(arc
		(start 110.635542 -105.274618)
		(mid 110.664027 -105.168075)
		(end 110.673642 -105.05821)
		(width 0.1016)
		(layer "B.Cu")
		(net "SAS_GF_EXP_RX_DP11")
	)
	(arc
		(start 87.750904 -229.615492)
		(mid 87.66211 -229.510678)
		(end 87.631524 -229.376732)
		(width 0.1016)
		(layer "B.Cu")
		(net "SAS_GF_EXP_RX_DP11")
	)
	(arc
		(start 110.673642 -104.18064)
		(mid 110.684573 -104.110757)
		(end 110.716314 -104.047544)
		(width 0.1016)
		(layer "B.Cu")
		(net "SAS_GF_EXP_RX_DP11")
	)
	(arc
		(start 87.750904 -221.339918)
		(mid 87.662016 -221.235123)
		(end 87.631524 -221.101158)
		(width 0.1016)
		(layer "B.Cu")
		(net "SAS_GF_EXP_RX_DP11")
	)
	(arc
		(start 87.750904 -228.050852)
		(mid 87.66211 -227.946038)
		(end 87.631524 -227.812092)
		(width 0.1016)
		(layer "B.Cu")
		(net "SAS_GF_EXP_RX_DP11")
	)
	(arc
		(start 87.750904 -239.866932)
		(mid 87.839698 -239.762118)
		(end 87.870284 -239.628172)
		(width 0.1016)
		(layer "B.Cu")
		(net "SAS_GF_EXP_RX_DP11")
	)
	(arc
		(start 87.750904 -230.397812)
		(mid 87.839698 -230.292998)
		(end 87.870284 -230.159052)
		(width 0.1016)
		(layer "B.Cu")
		(net "SAS_GF_EXP_RX_DP11")
	)
	(arc
		(start 87.870284 -228.289612)
		(mid 87.839792 -228.155619)
		(end 87.750904 -228.050852)
		(width 0.1016)
		(layer "B.Cu")
		(net "SAS_GF_EXP_RX_DP11")
	)
	(arc
		(start 87.870284 -221.578678)
		(mid 87.839792 -221.444685)
		(end 87.750904 -221.339918)
		(width 0.1016)
		(layer "B.Cu")
		(net "SAS_GF_EXP_RX_DP11")
	)
	(arc
		(start 92.964 -178.435)
		(mid 93.101435 -177.74398)
		(end 93.492828 -177.158142)
		(width 0.1016)
		(layer "B.Cu")
		(net "SAS_GF_EXP_RX_DP11")
	)
	(arc
		(start 92.31757 -214.99957)
		(mid 92.796058 -214.283324)
		(end 92.964 -213.438486)
		(width 0.1016)
		(layer "B.Cu")
		(net "SAS_GF_EXP_RX_DP11")
	)
	(arc
		(start 89.671652 -246.42826)
		(mid 89.469756 -245.41241)
		(end 88.894412 -244.5512)
		(width 0.1016)
		(layer "B.Cu")
		(net "SAS_GF_EXP_RX_DP11")
	)
	(arc
		(start 87.870284 -229.854252)
		(mid 87.839792 -229.720259)
		(end 87.750904 -229.615492)
		(width 0.1016)
		(layer "B.Cu")
		(net "SAS_GF_EXP_RX_DP11")
	)
	(arc
		(start 89.836244 -254.117348)
		(mid 89.71986 -254.06914)
		(end 89.671652 -253.952756)
		(width 0.1016)
		(layer "B.Cu")
		(net "SAS_GF_EXP_RX_DP11")
	)
	(arc
		(start 87.631524 -238.541052)
		(mid 87.662016 -238.407059)
		(end 87.750904 -238.302292)
		(width 0.1016)
		(layer "B.Cu")
		(net "SAS_GF_EXP_RX_DP11")
	)
	(arc
		(start 110.830614 -103.922322)
		(mid 110.844689 -103.901491)
		(end 110.849664 -103.876856)
		(width 0.1016)
		(layer "B.Cu")
		(net "SAS_GF_EXP_RX_DP11")
	)
	(arc
		(start 88.606376 -244.263164)
		(mid 87.88486 -243.18334)
		(end 87.631524 -241.9096)
		(width 0.1016)
		(layer "B.Cu")
		(net "SAS_GF_EXP_RX_DP11")
	)
	(arc
		(start 87.750904 -239.084612)
		(mid 87.66211 -238.979798)
		(end 87.631524 -238.845852)
		(width 0.1016)
		(layer "B.Cu")
		(net "SAS_GF_EXP_RX_DP11")
	)
	(arc
		(start 87.631524 -240.105692)
		(mid 87.662016 -239.971699)
		(end 87.750904 -239.866932)
		(width 0.1016)
		(layer "B.Cu")
		(net "SAS_GF_EXP_RX_DP11")
	)
	(arc
		(start 87.631524 -236.976412)
		(mid 87.662016 -236.842419)
		(end 87.750904 -236.737652)
		(width 0.1016)
		(layer "B.Cu")
		(net "SAS_GF_EXP_RX_DP11")
	)
	(arc
		(start 90.000582 -254.28194)
		(mid 89.952464 -254.165646)
		(end 89.836244 -254.117348)
		(width 0.1016)
		(layer "B.Cu")
		(net "SAS_GF_EXP_RX_DP11")
	)
	(arc
		(start 87.750904 -238.302292)
		(mid 87.839698 -238.197478)
		(end 87.870284 -238.063532)
		(width 0.1016)
		(layer "B.Cu")
		(net "SAS_GF_EXP_RX_DP11")
	)
	(arc
		(start 87.631524 -229.071932)
		(mid 87.662016 -228.937939)
		(end 87.750904 -228.833172)
		(width 0.1016)
		(layer "B.Cu")
		(net "SAS_GF_EXP_RX_DP11")
	)
	(arc
		(start 87.750904 -235.955332)
		(mid 87.66211 -235.850518)
		(end 87.631524 -235.716572)
		(width 0.1016)
		(layer "B.Cu")
		(net "SAS_GF_EXP_RX_DP11")
	)
	(arc
		(start 110.165642 -107.737148)
		(mid 110.297237 -107.540202)
		(end 110.343442 -107.307888)
		(width 0.1016)
		(layer "B.Cu")
		(net "SAS_GF_EXP_RX_DP11")
	)
	(arc
		(start 87.631524 -227.507292)
		(mid 87.662016 -227.373299)
		(end 87.750904 -227.268532)
		(width 0.1016)
		(layer "B.Cu")
		(net "SAS_GF_EXP_RX_DP11")
	)
	(arc
		(start 87.631524 -222.360998)
		(mid 87.662016 -222.227005)
		(end 87.750904 -222.122238)
		(width 0.1016)
		(layer "B.Cu")
		(net "SAS_GF_EXP_RX_DP11")
	)
	(arc
		(start 87.870284 -239.323372)
		(mid 87.839792 -239.189379)
		(end 87.750904 -239.084612)
		(width 0.1016)
		(layer "B.Cu")
		(net "SAS_GF_EXP_RX_DP11")
	)
	(arc
		(start 87.750904 -226.486212)
		(mid 87.66211 -226.381398)
		(end 87.631524 -226.247452)
		(width 0.1016)
		(layer "B.Cu")
		(net "SAS_GF_EXP_RX_DP11")
	)
	(arc
		(start 110.72876 -104.030018)
		(mid 110.744334 -104.010028)
		(end 110.761526 -103.99141)
		(width 0.1016)
		(layer "B.Cu")
		(net "SAS_GF_EXP_RX_DP11")
	)
	(arc
		(start 87.870284 -237.758732)
		(mid 87.839792 -237.624739)
		(end 87.750904 -237.519972)
		(width 0.1016)
		(layer "B.Cu")
		(net "SAS_GF_EXP_RX_DP11")
	)
	(arc
		(start 87.750904 -228.833172)
		(mid 87.839698 -228.728358)
		(end 87.870284 -228.594412)
		(width 0.1016)
		(layer "B.Cu")
		(net "SAS_GF_EXP_RX_DP11")
	)
	(arc
		(start 110.343442 -106.191558)
		(mid 110.353063 -106.081694)
		(end 110.381542 -105.97515)
		(width 0.1016)
		(layer "B.Cu")
		(net "SAS_GF_EXP_RX_DP11")
	)
	(arc
		(start 87.870284 -226.724972)
		(mid 87.839792 -226.590979)
		(end 87.750904 -226.486212)
		(width 0.1016)
		(layer "B.Cu")
		(net "SAS_GF_EXP_RX_DP11")
	)
	(arc
		(start 87.870284 -236.194092)
		(mid 87.839792 -236.060099)
		(end 87.750904 -235.955332)
		(width 0.1016)
		(layer "B.Cu")
		(net "SAS_GF_EXP_RX_DP11")
	)
	(arc
		(start 87.631524 -220.206062)
		(mid 87.727172 -219.725206)
		(end 87.99957 -219.31757)
		(width 0.1016)
		(layer "B.Cu")
		(net "SAS_GF_EXP_RX_DP11")
	)
	(arc
		(start 87.750904 -237.519972)
		(mid 87.66211 -237.415158)
		(end 87.631524 -237.281212)
		(width 0.1016)
		(layer "B.Cu")
		(net "SAS_GF_EXP_RX_DP11")
	)
	(arc
		(start 87.750904 -222.122238)
		(mid 87.839792 -222.017443)
		(end 87.870284 -221.883478)
		(width 0.1016)
		(layer "B.Cu")
		(net "SAS_GF_EXP_RX_DP11")
	)
	(arc
		(start 109.987842 -108.166408)
		(mid 110.034052 -107.934096)
		(end 110.165642 -107.737148)
		(width 0.1016)
		(layer "B.Cu")
		(net "SAS_GF_EXP_RX_DP11")
	)
	(arc
		(start 87.631524 -230.636572)
		(mid 87.662016 -230.502579)
		(end 87.750904 -230.397812)
		(width 0.1016)
		(layer "B.Cu")
		(net "SAS_GF_EXP_RX_DP11")
	)
	(segment
		(start 336.55 -106.68)
		(end 334.9498 -106.68)
		(width 0.508)
		(layer "F.Cu")
		(net "P5V_STBY__SNB")
	)
	(segment
		(start 334.6958 -106.934)
		(end 334.6958 -108.458)
		(width 0.508)
		(layer "F.Cu")
		(net "P5V_STBY__SNB")
	)
	(segment
		(start 334.9498 -106.68)
		(end 334.6958 -106.934)
		(width 0.508)
		(layer "F.Cu")
		(net "P5V_STBY__SNB")
	)
	(via
		(at 334.6958 -106.934)
		(size 0.7112)
		(drill 0.3556)
		(layers "F.Cu" "B.Cu")
		(net "P5V_STBY__SNB")
	)
	(segment
		(start 285.634938 -177.840132)
		(end 285.298388 -178.176682)
		(width 0.1143)
		(layer "F.Cu")
		(net "ROMA6")
	)
	(segment
		(start 274.6375 -179.705)
		(end 274.819872 -179.49672)
		(width 0.1143)
		(layer "F.Cu")
		(net "ROMA6")
	)
	(segment
		(start 276.254464 -178.062128)
		(end 275.926296 -178.390296)
		(width 0.1143)
		(layer "F.Cu")
		(net "ROMA6")
	)
	(segment
		(start 274.819872 -179.49672)
		(end 275.926296 -178.390296)
		(width 0.1143)
		(layer "F.Cu")
		(net "ROMA6")
	)
	(segment
		(start 285.298388 -178.176682)
		(end 284.659324 -178.176682)
		(width 0.1143)
		(layer "F.Cu")
		(net "ROMA6")
	)
	(segment
		(start 284.54477 -178.062128)
		(end 276.254464 -178.062128)
		(width 0.1143)
		(layer "F.Cu")
		(net "ROMA6")
	)
	(segment
		(start 284.659324 -178.176682)
		(end 284.54477 -178.062128)
		(width 0.1143)
		(layer "F.Cu")
		(net "ROMA6")
	)
	(via
		(at 275.926296 -178.390296)
		(size 0.7112)
		(drill 0.3556)
		(layers "F.Cu" "B.Cu")
		(net "ROMA6")
	)
	(segment
		(start 116.350034 -102.350062)
		(end 116.350034 -102.37089)
		(width 0.1016)
		(layer "F.Cu")
		(net "SAS_GF_EXP_RX_DN6")
	)
	(segment
		(start 116.350034 -102.37089)
		(end 115.880642 -102.840282)
		(width 0.1016)
		(layer "F.Cu")
		(net "SAS_GF_EXP_RX_DN6")
	)
	(via
		(at 115.880642 -102.840282)
		(size 0.508)
		(drill 0.254)
		(layers "F.Cu" "B.Cu")
		(net "SAS_GF_EXP_RX_DN6")
	)
	(segment
		(start 123.298712 -253.826772)
		(end 123.298712 -238.97336)
		(width 0.1016)
		(layer "B.Cu")
		(net "SAS_GF_EXP_RX_DN6")
	)
	(segment
		(start 123.000262 -256.50444)
		(end 123.000262 -254.547624)
		(width 0.1016)
		(layer "B.Cu")
		(net "SAS_GF_EXP_RX_DN6")
	)
	(segment
		(start 124.465842 -236.15523)
		(end 129.139442 -231.48163)
		(width 0.1016)
		(layer "B.Cu")
		(net "SAS_GF_EXP_RX_DN6")
	)
	(segment
		(start 119.30507 -157.358334)
		(end 119.30507 -114.144044)
		(width 0.1016)
		(layer "B.Cu")
		(net "SAS_GF_EXP_RX_DN6")
	)
	(segment
		(start 115.66017 -103.29164)
		(end 115.71732 -103.23449)
		(width 0.1016)
		(layer "B.Cu")
		(net "SAS_GF_EXP_RX_DN6")
	)
	(segment
		(start 115.645692 -105.859072)
		(end 115.32616 -105.53954)
		(width 0.1016)
		(layer "B.Cu")
		(net "SAS_GF_EXP_RX_DN6")
	)
	(segment
		(start 115.474242 -103.916226)
		(end 115.474242 -103.740712)
		(width 0.1016)
		(layer "B.Cu")
		(net "SAS_GF_EXP_RX_DN6")
	)
	(segment
		(start 115.325906 -104.169464)
		(end 115.400074 -104.095296)
		(width 0.1016)
		(layer "B.Cu")
		(net "SAS_GF_EXP_RX_DN6")
	)
	(segment
		(start 130.631184 -227.880164)
		(end 130.631184 -171.726606)
		(width 0.1016)
		(layer "B.Cu")
		(net "SAS_GF_EXP_RX_DN6")
	)
	(segment
		(start 115.73129 -108.768134)
		(end 115.73129 -106.065574)
		(width 0.1016)
		(layer "B.Cu")
		(net "SAS_GF_EXP_RX_DN6")
	)
	(segment
		(start 118.57482 -112.38103)
		(end 116.275104 -110.081314)
		(width 0.1016)
		(layer "B.Cu")
		(net "SAS_GF_EXP_RX_DN6")
	)
	(segment
		(start 130.193288 -170.669458)
		(end 121.0183 -161.49447)
		(width 0.1016)
		(layer "B.Cu")
		(net "SAS_GF_EXP_RX_DN6")
	)
	(arc
		(start 123.14936 -254.187452)
		(mid 123.259877 -254.021956)
		(end 123.298712 -253.826772)
		(width 0.1016)
		(layer "B.Cu")
		(net "SAS_GF_EXP_RX_DN6")
	)
	(arc
		(start 115.042188 -104.854248)
		(mid 115.115994 -104.483672)
		(end 115.325906 -104.169464)
		(width 0.1016)
		(layer "B.Cu")
		(net "SAS_GF_EXP_RX_DN6")
	)
	(arc
		(start 123.298712 -238.97336)
		(mid 123.601989 -237.448213)
		(end 124.465842 -236.15523)
		(width 0.1016)
		(layer "B.Cu")
		(net "SAS_GF_EXP_RX_DN6")
	)
	(arc
		(start 116.275104 -110.081314)
		(mid 115.872639 -109.478793)
		(end 115.73129 -108.768134)
		(width 0.1016)
		(layer "B.Cu")
		(net "SAS_GF_EXP_RX_DN6")
	)
	(arc
		(start 115.474242 -103.740712)
		(mid 115.522563 -103.497694)
		(end 115.66017 -103.29164)
		(width 0.1016)
		(layer "B.Cu")
		(net "SAS_GF_EXP_RX_DN6")
	)
	(arc
		(start 115.73129 -106.065574)
		(mid 115.708987 -105.953832)
		(end 115.645692 -105.859072)
		(width 0.1016)
		(layer "B.Cu")
		(net "SAS_GF_EXP_RX_DN6")
	)
	(arc
		(start 115.32616 -105.53954)
		(mid 115.115967 -105.225154)
		(end 115.042188 -104.854248)
		(width 0.1016)
		(layer "B.Cu")
		(net "SAS_GF_EXP_RX_DN6")
	)
	(arc
		(start 119.30507 -114.144044)
		(mid 119.115282 -113.189913)
		(end 118.57482 -112.38103)
		(width 0.1016)
		(layer "B.Cu")
		(net "SAS_GF_EXP_RX_DN6")
	)
	(arc
		(start 115.400074 -104.095296)
		(mid 115.45497 -104.013138)
		(end 115.474242 -103.916226)
		(width 0.1016)
		(layer "B.Cu")
		(net "SAS_GF_EXP_RX_DN6")
	)
	(arc
		(start 123.000262 -254.547624)
		(mid 123.039013 -254.352721)
		(end 123.14936 -254.187452)
		(width 0.1016)
		(layer "B.Cu")
		(net "SAS_GF_EXP_RX_DN6")
	)
	(arc
		(start 121.0183 -161.49447)
		(mid 119.750368 -159.59678)
		(end 119.30507 -157.358334)
		(width 0.1016)
		(layer "B.Cu")
		(net "SAS_GF_EXP_RX_DN6")
	)
	(arc
		(start 130.631184 -171.726606)
		(mid 130.517381 -171.154477)
		(end 130.193288 -170.669458)
		(width 0.1016)
		(layer "B.Cu")
		(net "SAS_GF_EXP_RX_DN6")
	)
	(arc
		(start 129.139442 -231.48163)
		(mid 130.243518 -229.829263)
		(end 130.631184 -227.880164)
		(width 0.1016)
		(layer "B.Cu")
		(net "SAS_GF_EXP_RX_DN6")
	)
	(arc
		(start 115.71732 -103.23449)
		(mid 115.83817 -103.053626)
		(end 115.880642 -102.840282)
		(width 0.1016)
		(layer "B.Cu")
		(net "SAS_GF_EXP_RX_DN6")
	)
	(segment
		(start 329.734672 -110.435136)
		(end 329.946 -110.223808)
		(width 0.508)
		(layer "F.Cu")
		(net "P3V3_STBY_SNB")
	)
	(segment
		(start 328.145648 -110.416848)
		(end 329.716384 -110.416848)
		(width 0.508)
		(layer "F.Cu")
		(net "P3V3_STBY_SNB")
	)
	(segment
		(start 329.716384 -110.416848)
		(end 329.734672 -110.435136)
		(width 0.508)
		(layer "F.Cu")
		(net "P3V3_STBY_SNB")
	)
	(segment
		(start 329.946 -110.223808)
		(end 329.946 -108.966)
		(width 0.508)
		(layer "F.Cu")
		(net "P3V3_STBY_SNB")
	)
	(via
		(at 329.946 -108.966)
		(size 0.7112)
		(drill 0.3556)
		(layers "F.Cu" "B.Cu")
		(net "P3V3_STBY_SNB")
	)
	(segment
		(start 105.34396 -28.758388)
		(end 105.34396 -28.570174)
		(width 0.1397)
		(layer "B.Cu")
		(net "PCIE_SAS_CPU_RX_N7")
	)
	(segment
		(start 147.609052 -41.656)
		(end 152.63114 -41.656)
		(width 0.1397)
		(layer "B.Cu")
		(net "PCIE_SAS_CPU_RX_N7")
	)
	(segment
		(start 133.940042 -28.39212)
		(end 146.91741 -41.369488)
		(width 0.1397)
		(layer "B.Cu")
		(net "PCIE_SAS_CPU_RX_N7")
	)
	(segment
		(start 158.369 -73.831196)
		(end 158.450026 -73.75017)
		(width 0.1397)
		(layer "B.Cu")
		(net "PCIE_SAS_CPU_RX_N7")
	)
	(segment
		(start 153.080212 -41.841928)
		(end 159.124142 -47.885858)
		(width 0.1397)
		(layer "B.Cu")
		(net "PCIE_SAS_CPU_RX_N7")
	)
	(segment
		(start 104.65816 -31.3436)
		(end 104.65816 -29.880814)
		(width 0.1397)
		(layer "B.Cu")
		(net "PCIE_SAS_CPU_RX_N7")
	)
	(segment
		(start 118.925594 -23.693628)
		(end 121.430542 -26.198576)
		(width 0.1397)
		(layer "B.Cu")
		(net "PCIE_SAS_CPU_RX_N7")
	)
	(segment
		(start 158.836868 -74.676)
		(end 158.75 -74.676)
		(width 0.1397)
		(layer "B.Cu")
		(net "PCIE_SAS_CPU_RX_N7")
	)
	(segment
		(start 123.6726 -27.1272)
		(end 130.8862 -27.1272)
		(width 0.1397)
		(layer "B.Cu")
		(net "PCIE_SAS_CPU_RX_N7")
	)
	(segment
		(start 104.762554 -29.6291)
		(end 105.139236 -29.252418)
		(width 0.1397)
		(layer "B.Cu")
		(net "PCIE_SAS_CPU_RX_N7")
	)
	(segment
		(start 159.27451 -48.248824)
		(end 159.27451 -74.238358)
		(width 0.1397)
		(layer "B.Cu")
		(net "PCIE_SAS_CPU_RX_N7")
	)
	(segment
		(start 158.533338 -74.586084)
		(end 158.369 -74.422)
		(width 0.1397)
		(layer "B.Cu")
		(net "PCIE_SAS_CPU_RX_N7")
	)
	(segment
		(start 110.486444 -23.5077)
		(end 118.476522 -23.5077)
		(width 0.1397)
		(layer "B.Cu")
		(net "PCIE_SAS_CPU_RX_N7")
	)
	(segment
		(start 105.4735 -28.2575)
		(end 110.037372 -23.693628)
		(width 0.1397)
		(layer "B.Cu")
		(net "PCIE_SAS_CPU_RX_N7")
	)
	(arc
		(start 158.369 -74.422)
		(mid 158.24664 -74.126598)
		(end 158.369 -73.831196)
		(width 0.1397)
		(layer "B.Cu")
		(net "PCIE_SAS_CPU_RX_N7")
	)
	(arc
		(start 146.91741 -41.369488)
		(mid 147.234724 -41.581574)
		(end 147.609052 -41.656)
		(width 0.1397)
		(layer "B.Cu")
		(net "PCIE_SAS_CPU_RX_N7")
	)
	(arc
		(start 105.34396 -28.570174)
		(mid 105.377622 -28.400946)
		(end 105.4735 -28.2575)
		(width 0.1397)
		(layer "B.Cu")
		(net "PCIE_SAS_CPU_RX_N7")
	)
	(arc
		(start 118.476522 -23.5077)
		(mid 118.719526 -23.556036)
		(end 118.925594 -23.693628)
		(width 0.1397)
		(layer "B.Cu")
		(net "PCIE_SAS_CPU_RX_N7")
	)
	(arc
		(start 159.27451 -74.238358)
		(mid 159.146328 -74.547818)
		(end 158.836868 -74.676)
		(width 0.1397)
		(layer "B.Cu")
		(net "PCIE_SAS_CPU_RX_N7")
	)
	(arc
		(start 152.63114 -41.656)
		(mid 152.874144 -41.704336)
		(end 153.080212 -41.841928)
		(width 0.1397)
		(layer "B.Cu")
		(net "PCIE_SAS_CPU_RX_N7")
	)
	(arc
		(start 110.037372 -23.693628)
		(mid 110.243408 -23.555959)
		(end 110.486444 -23.5077)
		(width 0.1397)
		(layer "B.Cu")
		(net "PCIE_SAS_CPU_RX_N7")
	)
	(arc
		(start 130.8862 -27.1272)
		(mid 132.538919 -27.455946)
		(end 133.940042 -28.39212)
		(width 0.1397)
		(layer "B.Cu")
		(net "PCIE_SAS_CPU_RX_N7")
	)
	(arc
		(start 121.430542 -26.198576)
		(mid 122.459221 -26.885854)
		(end 123.6726 -27.1272)
		(width 0.1397)
		(layer "B.Cu")
		(net "PCIE_SAS_CPU_RX_N7")
	)
	(arc
		(start 104.65816 -29.880814)
		(mid 104.68535 -29.744591)
		(end 104.762554 -29.6291)
		(width 0.1397)
		(layer "B.Cu")
		(net "PCIE_SAS_CPU_RX_N7")
	)
	(arc
		(start 159.124142 -47.885858)
		(mid 159.235414 -48.052388)
		(end 159.27451 -48.248824)
		(width 0.1397)
		(layer "B.Cu")
		(net "PCIE_SAS_CPU_RX_N7")
	)
	(arc
		(start 105.139236 -29.252418)
		(mid 105.290717 -29.025756)
		(end 105.34396 -28.758388)
		(width 0.1397)
		(layer "B.Cu")
		(net "PCIE_SAS_CPU_RX_N7")
	)
	(arc
		(start 158.75 -74.676)
		(mid 158.632731 -74.65258)
		(end 158.533338 -74.586084)
		(width 0.1397)
		(layer "B.Cu")
		(net "PCIE_SAS_CPU_RX_N7")
	)
	(segment
		(start 314.833 -109.22)
		(end 314.833 -113.03)
		(width 0.254)
		(layer "F.Cu")
		(net "P3V3_STBY_VFB_R")
	)
	(segment
		(start 317.0555 -108.585)
		(end 315.468 -108.585)
		(width 0.254)
		(layer "F.Cu")
		(net "P3V3_STBY_VFB_R")
	)
	(segment
		(start 311.912 -114.935)
		(end 312.928 -114.935)
		(width 0.254)
		(layer "F.Cu")
		(net "P3V3_STBY_VFB_R")
	)
	(segment
		(start 312.928 -114.935)
		(end 313.817 -114.046)
		(width 0.254)
		(layer "F.Cu")
		(net "P3V3_STBY_VFB_R")
	)
	(segment
		(start 315.468 -108.585)
		(end 314.833 -109.22)
		(width 0.254)
		(layer "F.Cu")
		(net "P3V3_STBY_VFB_R")
	)
	(segment
		(start 314.833 -113.03)
		(end 313.817 -114.046)
		(width 0.254)
		(layer "F.Cu")
		(net "P3V3_STBY_VFB_R")
	)
	(via
		(at 313.817 -114.046)
		(size 0.7112)
		(drill 0.3556)
		(layers "F.Cu" "B.Cu")
		(net "P3V3_STBY_VFB_R")
	)
	(segment
		(start 342.650572 -69.19595)
		(end 351.13595 -69.19595)
		(width 0.1143)
		(layer "F.Cu")
		(net "ROMD0_R")
	)
	(segment
		(start 351.13595 -69.19595)
		(end 351.663 -69.723)
		(width 0.1143)
		(layer "F.Cu")
		(net "ROMD0_R")
	)
	(segment
		(start 351.303336 -69.998336)
		(end 351.557336 -69.744336)
		(width 0.1143)
		(layer "F.Cu")
		(net "ROMD0_R")
	)
	(segment
		(start 351.303336 -71.641462)
		(end 351.303336 -69.998336)
		(width 0.1143)
		(layer "F.Cu")
		(net "ROMD0_R")
	)
	(segment
		(start 338.0105 -73.836022)
		(end 342.650572 -69.19595)
		(width 0.1143)
		(layer "F.Cu")
		(net "ROMD0_R")
	)
	(segment
		(start 338.0105 -74.422)
		(end 338.0105 -73.836022)
		(width 0.1143)
		(layer "F.Cu")
		(net "ROMD0_R")
	)
	(segment
		(start 351.641664 -69.744336)
		(end 351.663 -69.723)
		(width 0.1143)
		(layer "F.Cu")
		(net "ROMD0_R")
	)
	(segment
		(start 351.557336 -69.744336)
		(end 351.641664 -69.744336)
		(width 0.1143)
		(layer "F.Cu")
		(net "ROMD0_R")
	)
	(via
		(at 351.663 -68.834)
		(size 0.7112)
		(drill 0.3556)
		(layers "F.Cu" "B.Cu")
		(net "ROMD0_R")
	)
	(via
		(at 351.663 -69.723)
		(size 0.5588)
		(drill 0.3048)
		(layers "F.Cu" "B.Cu")
		(net "ROMD0_R")
	)
	(segment
		(start 351.663 -68.834)
		(end 351.663 -69.723)
		(width 0.1143)
		(layer "B.Cu")
		(net "ROMD0_R")
	)
	(segment
		(start 351.6122 -71.3613)
		(end 351.663 -71.3105)
		(width 0.1143)
		(layer "B.Cu")
		(net "ROMD0_R")
	)
	(segment
		(start 350.5962 -71.3613)
		(end 351.6122 -71.3613)
		(width 0.1143)
		(layer "B.Cu")
		(net "ROMD0_R")
	)
	(segment
		(start 351.663 -71.3105)
		(end 351.663 -69.723)
		(width 0.1143)
		(layer "B.Cu")
		(net "ROMD0_R")
	)
	(segment
		(start 178.8795 -18.415)
		(end 177.546 -18.415)
		(width 0.1143)
		(layer "F.Cu")
		(net "TEMP_SENSOR_DXP_R")
	)
	(segment
		(start 177.546 -18.415)
		(end 176.911 -18.415)
		(width 0.1143)
		(layer "F.Cu")
		(net "TEMP_SENSOR_DXP_R")
	)
	(segment
		(start 176.911 -18.415)
		(end 174.244 -15.748)
		(width 0.1143)
		(layer "F.Cu")
		(net "TEMP_SENSOR_DXP_R")
	)
	(via
		(at 174.244 -15.748)
		(size 0.5588)
		(drill 0.3048)
		(layers "F.Cu" "B.Cu")
		(net "TEMP_SENSOR_DXP_R")
	)
	(via
		(at 177.546 -18.415)
		(size 0.7112)
		(drill 0.3556)
		(layers "F.Cu" "B.Cu")
		(net "TEMP_SENSOR_DXP_R")
	)
	(segment
		(start 119.741188 -16.891)
		(end 136.398 -16.891)
		(width 0.127)
		(layer "In2.Cu")
		(net "TEMP_SENSOR_DXP_R")
	)
	(segment
		(start 145.6563 -26.1493)
		(end 165.432232 -26.1493)
		(width 0.127)
		(layer "In2.Cu")
		(net "TEMP_SENSOR_DXP_R")
	)
	(segment
		(start 102.350062 -5.999988)
		(end 104.55148 -8.201406)
		(width 0.127)
		(layer "In2.Cu")
		(net "TEMP_SENSOR_DXP_R")
	)
	(segment
		(start 174.244 -16.764)
		(end 174.244 -15.748)
		(width 0.127)
		(layer "In2.Cu")
		(net "TEMP_SENSOR_DXP_R")
	)
	(segment
		(start 136.398 -16.891)
		(end 145.6563 -26.1493)
		(width 0.127)
		(layer "In2.Cu")
		(net "TEMP_SENSOR_DXP_R")
	)
	(segment
		(start 168.858692 -22.72284)
		(end 168.858692 -22.149308)
		(width 0.127)
		(layer "In2.Cu")
		(net "TEMP_SENSOR_DXP_R")
	)
	(segment
		(start 168.858692 -22.149308)
		(end 174.244 -16.764)
		(width 0.127)
		(layer "In2.Cu")
		(net "TEMP_SENSOR_DXP_R")
	)
	(segment
		(start 111.051594 -8.201406)
		(end 119.741188 -16.891)
		(width 0.127)
		(layer "In2.Cu")
		(net "TEMP_SENSOR_DXP_R")
	)
	(segment
		(start 104.55148 -8.201406)
		(end 111.051594 -8.201406)
		(width 0.127)
		(layer "In2.Cu")
		(net "TEMP_SENSOR_DXP_R")
	)
	(segment
		(start 165.432232 -26.1493)
		(end 168.858692 -22.72284)
		(width 0.127)
		(layer "In2.Cu")
		(net "TEMP_SENSOR_DXP_R")
	)
	(segment
		(start 318.008 -110.6805)
		(end 318.008 -111.633)
		(width 0.254)
		(layer "F.Cu")
		(net "P3V3_STBY_VFB")
	)
	(segment
		(start 317.9445 -110.617)
		(end 318.008 -110.6805)
		(width 0.254)
		(layer "F.Cu")
		(net "P3V3_STBY_VFB")
	)
	(segment
		(start 317.9445 -110.617)
		(end 317.9445 -109.601)
		(width 0.254)
		(layer "F.Cu")
		(net "P3V3_STBY_VFB")
	)
	(segment
		(start 318.77 -110.617)
		(end 317.9445 -110.617)
		(width 0.254)
		(layer "F.Cu")
		(net "P3V3_STBY_VFB")
	)
	(segment
		(start 319.94475 -110.398814)
		(end 318.988186 -110.398814)
		(width 0.254)
		(layer "F.Cu")
		(net "P3V3_STBY_VFB")
	)
	(segment
		(start 318.988186 -110.398814)
		(end 318.77 -110.617)
		(width 0.254)
		(layer "F.Cu")
		(net "P3V3_STBY_VFB")
	)
	(segment
		(start 317.9445 -109.601)
		(end 317.9445 -108.585)
		(width 0.254)
		(layer "F.Cu")
		(net "P3V3_STBY_VFB")
	)
	(via
		(at 318.008 -111.633)
		(size 0.7112)
		(drill 0.3556)
		(layers "F.Cu" "B.Cu")
		(net "P3V3_STBY_VFB")
	)
	(segment
		(start 286.04591 -175.060356)
		(end 286.034988 -175.049434)
		(width 0.1143)
		(layer "F.Cu")
		(net "ROMA14")
	)
	(segment
		(start 286.055054 -175.060356)
		(end 286.04591 -175.060356)
		(width 0.1143)
		(layer "F.Cu")
		(net "ROMA14")
	)
	(segment
		(start 286.434784 -175.440086)
		(end 286.055054 -175.060356)
		(width 0.1143)
		(layer "F.Cu")
		(net "ROMA14")
	)
	(via
		(at 286.034988 -175.049434)
		(size 0.508)
		(drill 0.254)
		(layers "F.Cu" "B.Cu")
		(net "ROMA14")
	)
	(via
		(at 277.9395 -175.2727)
		(size 0.7112)
		(drill 0.3556)
		(layers "F.Cu" "B.Cu")
		(net "ROMA14")
	)
	(segment
		(start 286.034988 -175.049434)
		(end 284.894782 -175.049434)
		(width 0.1143)
		(layer "B.Cu")
		(net "ROMA14")
	)
	(segment
		(start 274.6375 -175.641)
		(end 275.0058 -175.2727)
		(width 0.1143)
		(layer "B.Cu")
		(net "ROMA14")
	)
	(segment
		(start 284.894782 -175.049434)
		(end 284.671516 -175.2727)
		(width 0.1143)
		(layer "B.Cu")
		(net "ROMA14")
	)
	(segment
		(start 275.0058 -175.2727)
		(end 277.9395 -175.2727)
		(width 0.1143)
		(layer "B.Cu")
		(net "ROMA14")
	)
	(segment
		(start 284.671516 -175.2727)
		(end 277.9395 -175.2727)
		(width 0.1143)
		(layer "B.Cu")
		(net "ROMA14")
	)
	(segment
		(start 111.34979 -102.350062)
		(end 110.849664 -102.850188)
		(width 0.1016)
		(layer "F.Cu")
		(net "SAS_GF_EXP_RX_DN11")
	)
	(via
		(at 110.849664 -102.850188)
		(size 0.508)
		(drill 0.254)
		(layers "F.Cu" "B.Cu")
		(net "SAS_GF_EXP_RX_DN11")
	)
	(segment
		(start 110.312962 -105.157524)
		(end 110.313216 -105.157524)
		(width 0.1016)
		(layer "B.Cu")
		(net "SAS_GF_EXP_RX_DN11")
	)
	(segment
		(start 87.288624 -241.9096)
		(end 87.288624 -220.205808)
		(width 0.1016)
		(layer "B.Cu")
		(net "SAS_GF_EXP_RX_DN11")
	)
	(segment
		(start 109.644942 -157.800548)
		(end 109.644942 -108.166408)
		(width 0.1016)
		(layer "B.Cu")
		(net "SAS_GF_EXP_RX_DN11")
	)
	(segment
		(start 110.51667 -103.29926)
		(end 110.808516 -103.007414)
		(width 0.1016)
		(layer "B.Cu")
		(net "SAS_GF_EXP_RX_DN11")
	)
	(segment
		(start 110.849664 -102.908354)
		(end 110.849664 -102.850188)
		(width 0.1016)
		(layer "B.Cu")
		(net "SAS_GF_EXP_RX_DN11")
	)
	(segment
		(start 110.058962 -105.858056)
		(end 110.312962 -105.157524)
		(width 0.1016)
		(layer "B.Cu")
		(net "SAS_GF_EXP_RX_DN11")
	)
	(segment
		(start 110.000542 -107.307888)
		(end 110.000542 -106.191304)
		(width 0.1016)
		(layer "B.Cu")
		(net "SAS_GF_EXP_RX_DN11")
	)
	(segment
		(start 88.999822 -256.50444)
		(end 88.999822 -254.455676)
		(width 0.1016)
		(layer "B.Cu")
		(net "SAS_GF_EXP_RX_DN11")
	)
	(segment
		(start 89.328752 -253.969774)
		(end 89.328752 -246.428006)
		(width 0.1016)
		(layer "B.Cu")
		(net "SAS_GF_EXP_RX_DN11")
	)
	(segment
		(start 110.335314 -104.107742)
		(end 110.330742 -103.748332)
		(width 0.1016)
		(layer "B.Cu")
		(net "SAS_GF_EXP_RX_DN11")
	)
	(segment
		(start 89.055448 -254.321818)
		(end 89.0778 -254.299466)
		(width 0.1016)
		(layer "B.Cu")
		(net "SAS_GF_EXP_RX_DN11")
	)
	(segment
		(start 89.154254 -254.248158)
		(end 89.171272 -254.241046)
		(width 0.1016)
		(layer "B.Cu")
		(net "SAS_GF_EXP_RX_DN11")
	)
	(segment
		(start 110.330742 -105.057956)
		(end 110.330742 -104.18064)
		(width 0.1016)
		(layer "B.Cu")
		(net "SAS_GF_EXP_RX_DN11")
	)
	(segment
		(start 93.250258 -176.915572)
		(end 107.7214 -162.44443)
		(width 0.1016)
		(layer "B.Cu")
		(net "SAS_GF_EXP_RX_DN11")
	)
	(segment
		(start 89.217246 -254.210566)
		(end 89.237312 -254.1905)
		(width 0.1016)
		(layer "B.Cu")
		(net "SAS_GF_EXP_RX_DN11")
	)
	(segment
		(start 92.6211 -213.438486)
		(end 92.6211 -178.434746)
		(width 0.1016)
		(layer "B.Cu")
		(net "SAS_GF_EXP_RX_DN11")
	)
	(segment
		(start 87.757 -219.075)
		(end 92.075 -214.757)
		(width 0.1016)
		(layer "B.Cu")
		(net "SAS_GF_EXP_RX_DN11")
	)
	(segment
		(start 88.651842 -244.79377)
		(end 88.363806 -244.505734)
		(width 0.1016)
		(layer "B.Cu")
		(net "SAS_GF_EXP_RX_DN11")
	)
	(arc
		(start 109.644942 -108.166408)
		(mid 109.71717 -107.80282)
		(end 109.923072 -107.494578)
		(width 0.1016)
		(layer "B.Cu")
		(net "SAS_GF_EXP_RX_DN11")
	)
	(arc
		(start 87.288624 -220.205808)
		(mid 87.41034 -219.593813)
		(end 87.757 -219.075)
		(width 0.1016)
		(layer "B.Cu")
		(net "SAS_GF_EXP_RX_DN11")
	)
	(arc
		(start 110.330742 -103.748332)
		(mid 110.379063 -103.505314)
		(end 110.51667 -103.29926)
		(width 0.1016)
		(layer "B.Cu")
		(net "SAS_GF_EXP_RX_DN11")
	)
	(arc
		(start 89.237312 -254.1905)
		(mid 89.304978 -254.08923)
		(end 89.328752 -253.969774)
		(width 0.1016)
		(layer "B.Cu")
		(net "SAS_GF_EXP_RX_DN11")
	)
	(arc
		(start 110.000542 -106.191304)
		(mid 110.015237 -106.022136)
		(end 110.058962 -105.858056)
		(width 0.1016)
		(layer "B.Cu")
		(net "SAS_GF_EXP_RX_DN11")
	)
	(arc
		(start 92.075 -214.757)
		(mid 92.479208 -214.152061)
		(end 92.6211 -213.438486)
		(width 0.1016)
		(layer "B.Cu")
		(net "SAS_GF_EXP_RX_DN11")
	)
	(arc
		(start 110.330742 -104.18064)
		(mid 110.329575 -104.143937)
		(end 110.330742 -104.107234)
		(width 0.1016)
		(layer "B.Cu")
		(net "SAS_GF_EXP_RX_DN11")
	)
	(arc
		(start 89.328752 -246.428006)
		(mid 89.152826 -245.543569)
		(end 88.651842 -244.79377)
		(width 0.1016)
		(layer "B.Cu")
		(net "SAS_GF_EXP_RX_DN11")
	)
	(arc
		(start 89.0778 -254.299466)
		(mid 89.113478 -254.270015)
		(end 89.154254 -254.248158)
		(width 0.1016)
		(layer "B.Cu")
		(net "SAS_GF_EXP_RX_DN11")
	)
	(arc
		(start 107.7214 -162.44443)
		(mid 109.145042 -160.313799)
		(end 109.644942 -157.800548)
		(width 0.1016)
		(layer "B.Cu")
		(net "SAS_GF_EXP_RX_DN11")
	)
	(arc
		(start 109.923072 -107.494578)
		(mid 109.980387 -107.408939)
		(end 110.000542 -107.307888)
		(width 0.1016)
		(layer "B.Cu")
		(net "SAS_GF_EXP_RX_DN11")
	)
	(arc
		(start 110.808516 -103.007414)
		(mid 110.838967 -102.96198)
		(end 110.849664 -102.908354)
		(width 0.1016)
		(layer "B.Cu")
		(net "SAS_GF_EXP_RX_DN11")
	)
	(arc
		(start 110.330742 -104.107234)
		(mid 110.333045 -104.107341)
		(end 110.335314 -104.107742)
		(width 0.1016)
		(layer "B.Cu")
		(net "SAS_GF_EXP_RX_DN11")
	)
	(arc
		(start 88.363806 -244.505734)
		(mid 87.568064 -243.314588)
		(end 87.288624 -241.9096)
		(width 0.1016)
		(layer "B.Cu")
		(net "SAS_GF_EXP_RX_DN11")
	)
	(arc
		(start 110.313216 -105.157524)
		(mid 110.326304 -105.108503)
		(end 110.330742 -105.057956)
		(width 0.1016)
		(layer "B.Cu")
		(net "SAS_GF_EXP_RX_DN11")
	)
	(arc
		(start 92.6211 -178.434746)
		(mid 92.784602 -177.612586)
		(end 93.250258 -176.915572)
		(width 0.1016)
		(layer "B.Cu")
		(net "SAS_GF_EXP_RX_DN11")
	)
	(arc
		(start 88.999822 -254.455676)
		(mid 89.014329 -254.383217)
		(end 89.055448 -254.321818)
		(width 0.1016)
		(layer "B.Cu")
		(net "SAS_GF_EXP_RX_DN11")
	)
	(arc
		(start 89.171272 -254.241046)
		(mid 89.195777 -254.228092)
		(end 89.217246 -254.210566)
		(width 0.1016)
		(layer "B.Cu")
		(net "SAS_GF_EXP_RX_DN11")
	)
	(segment
		(start 317.582042 -115.297458)
		(end 318.135 -115.297458)
		(width 0.254)
		(layer "F.Cu")
		(net "P3V3_STBY_RF")
	)
	(segment
		(start 317.0555 -114.681)
		(end 317.0555 -115.824)
		(width 0.254)
		(layer "F.Cu")
		(net "P3V3_STBY_RF")
	)
	(segment
		(start 317.0555 -115.824)
		(end 317.582042 -115.297458)
		(width 0.254)
		(layer "F.Cu")
		(net "P3V3_STBY_RF")
	)
	(segment
		(start 319.94475 -115.297458)
		(end 318.135 -115.297458)
		(width 0.254)
		(layer "F.Cu")
		(net "P3V3_STBY_RF")
	)
	(via
		(at 318.135 -115.297458)
		(size 0.7112)
		(drill 0.3556)
		(layers "F.Cu" "B.Cu")
		(net "P3V3_STBY_RF")
	)
	(segment
		(start 334.3275 -80.772)
		(end 334.3275 -82.1055)
		(width 0.1143)
		(layer "F.Cu")
		(net "ROMD2_R")
	)
	(segment
		(start 334.3275 -83.312)
		(end 334.518 -83.5025)
		(width 0.1143)
		(layer "F.Cu")
		(net "ROMD2_R")
	)
	(segment
		(start 342.413336 -81.256378)
		(end 336.764122 -81.256378)
		(width 0.1143)
		(layer "F.Cu")
		(net "ROMD2_R")
	)
	(segment
		(start 336.764122 -81.256378)
		(end 334.518 -83.5025)
		(width 0.1143)
		(layer "F.Cu")
		(net "ROMD2_R")
	)
	(segment
		(start 334.3275 -82.1055)
		(end 334.3275 -83.312)
		(width 0.1143)
		(layer "F.Cu")
		(net "ROMD2_R")
	)
	(via
		(at 334.3275 -82.1055)
		(size 0.7112)
		(drill 0.3556)
		(layers "F.Cu" "B.Cu")
		(net "ROMD2_R")
	)
	(segment
		(start 333.366872 -232.037636)
		(end 333.366872 -229.307136)
		(width 0.1143)
		(layer "F.Cu")
		(net "VOL_SEN_ALERT")
	)
	(segment
		(start 332.597252 -228.537516)
		(end 332.597252 -226.297236)
		(width 0.1143)
		(layer "F.Cu")
		(net "VOL_SEN_ALERT")
	)
	(segment
		(start 333.366872 -229.307136)
		(end 332.597252 -228.537516)
		(width 0.1143)
		(layer "F.Cu")
		(net "VOL_SEN_ALERT")
	)
	(segment
		(start 321.444874 -110.398814)
		(end 321.444874 -108.465874)
		(width 0.3048)
		(layer "F.Cu")
		(net "P3V3_STBY_VBST")
	)
	(segment
		(start 321.444874 -108.465874)
		(end 321.31 -108.331)
		(width 0.3048)
		(layer "F.Cu")
		(net "P3V3_STBY_VBST")
	)
	(via
		(at 321.31 -108.331)
		(size 0.5588)
		(drill 0.3048)
		(layers "F.Cu" "B.Cu")
		(net "P3V3_STBY_VBST")
	)
	(via
		(at 322.199 -108.458)
		(size 0.7112)
		(drill 0.3556)
		(layers "F.Cu" "B.Cu")
		(net "P3V3_STBY_VBST")
	)
	(segment
		(start 322.199 -108.458)
		(end 322.072 -108.331)
		(width 0.508)
		(layer "B.Cu")
		(net "P3V3_STBY_VBST")
	)
	(segment
		(start 321.9958 -109.982)
		(end 322.199 -109.7788)
		(width 0.508)
		(layer "B.Cu")
		(net "P3V3_STBY_VBST")
	)
	(segment
		(start 322.072 -108.331)
		(end 321.31 -108.331)
		(width 0.508)
		(layer "B.Cu")
		(net "P3V3_STBY_VBST")
	)
	(segment
		(start 322.199 -109.7788)
		(end 322.199 -108.458)
		(width 0.508)
		(layer "B.Cu")
		(net "P3V3_STBY_VBST")
	)
	(segment
		(start 331.2287 -75.311)
		(end 326.992488 -75.311)
		(width 0.1143)
		(layer "F.Cu")
		(net "FLA_WPN")
	)
	(segment
		(start 342.9 -70.231)
		(end 342.413336 -70.717664)
		(width 0.1143)
		(layer "F.Cu")
		(net "FLA_WPN")
	)
	(segment
		(start 342.413336 -71.641462)
		(end 342.413336 -71.820278)
		(width 0.1143)
		(layer "F.Cu")
		(net "FLA_WPN")
	)
	(segment
		(start 342.413336 -70.717664)
		(end 342.413336 -71.641462)
		(width 0.1143)
		(layer "F.Cu")
		(net "FLA_WPN")
	)
	(via
		(at 331.2287 -75.311)
		(size 0.5588)
		(drill 0.3048)
		(layers "F.Cu" "B.Cu")
		(net "FLA_WPN")
	)
	(via
		(at 343.916 -71.374)
		(size 0.7112)
		(drill 0.3556)
		(layers "F.Cu" "B.Cu")
		(net "FLA_WPN")
	)
	(via
		(at 342.9 -70.231)
		(size 0.5588)
		(drill 0.3048)
		(layers "F.Cu" "B.Cu")
		(net "FLA_WPN")
	)
	(segment
		(start 342.921336 -71.353172)
		(end 343.895172 -71.353172)
		(width 0.1143)
		(layer "B.Cu")
		(net "FLA_WPN")
	)
	(segment
		(start 343.895172 -71.353172)
		(end 343.916 -71.374)
		(width 0.1143)
		(layer "B.Cu")
		(net "FLA_WPN")
	)
	(segment
		(start 331.2287 -75.311)
		(end 331.47 -75.311)
		(width 0.1143)
		(layer "B.Cu")
		(net "FLA_WPN")
	)
	(segment
		(start 340.868 -70.231)
		(end 342.9 -70.231)
		(width 0.1143)
		(layer "B.Cu")
		(net "FLA_WPN")
	)
	(segment
		(start 339.852 -71.247)
		(end 340.868 -70.231)
		(width 0.1143)
		(layer "B.Cu")
		(net "FLA_WPN")
	)
	(segment
		(start 345.080336 -71.353172)
		(end 343.936828 -71.353172)
		(width 0.1143)
		(layer "B.Cu")
		(net "FLA_WPN")
	)
	(segment
		(start 342.9 -70.231)
		(end 342.921336 -70.252336)
		(width 0.1143)
		(layer "B.Cu")
		(net "FLA_WPN")
	)
	(segment
		(start 331.47 -75.311)
		(end 335.534 -71.247)
		(width 0.1143)
		(layer "B.Cu")
		(net "FLA_WPN")
	)
	(segment
		(start 343.936828 -71.353172)
		(end 343.916 -71.374)
		(width 0.1143)
		(layer "B.Cu")
		(net "FLA_WPN")
	)
	(segment
		(start 342.921336 -70.252336)
		(end 342.921336 -71.353172)
		(width 0.1143)
		(layer "B.Cu")
		(net "FLA_WPN")
	)
	(segment
		(start 335.534 -71.247)
		(end 339.852 -71.247)
		(width 0.1143)
		(layer "B.Cu")
		(net "FLA_WPN")
	)
	(segment
		(start 306.578 -194.2465)
		(end 306.6415 -194.2465)
		(width 0.127)
		(layer "F.Cu")
		(net "LED_DR_LED0")
	)
	(segment
		(start 306.752752 -194.992752)
		(end 306.578 -194.818)
		(width 0.127)
		(layer "F.Cu")
		(net "LED_DR_LED0")
	)
	(segment
		(start 316.611 -188.665104)
		(end 316.611 -187.579)
		(width 0.127)
		(layer "F.Cu")
		(net "LED_DR_LED0")
	)
	(segment
		(start 316.611 -186.055)
		(end 316.611 -187.579)
		(width 0.127)
		(layer "F.Cu")
		(net "LED_DR_LED0")
	)
	(segment
		(start 307.34 -193.548)
		(end 307.34 -192.212468)
		(width 0.127)
		(layer "F.Cu")
		(net "LED_DR_LED0")
	)
	(segment
		(start 310.605424 -190.881)
		(end 312.125106 -189.361318)
		(width 0.127)
		(layer "F.Cu")
		(net "LED_DR_LED0")
	)
	(segment
		(start 315.849 -185.293)
		(end 316.611 -186.055)
		(width 0.127)
		(layer "F.Cu")
		(net "LED_DR_LED0")
	)
	(segment
		(start 315.914786 -189.361318)
		(end 316.611 -188.665104)
		(width 0.127)
		(layer "F.Cu")
		(net "LED_DR_LED0")
	)
	(segment
		(start 306.6415 -194.2465)
		(end 307.34 -193.548)
		(width 0.127)
		(layer "F.Cu")
		(net "LED_DR_LED0")
	)
	(segment
		(start 307.34 -192.212468)
		(end 308.671468 -190.881)
		(width 0.127)
		(layer "F.Cu")
		(net "LED_DR_LED0")
	)
	(segment
		(start 308.671468 -190.881)
		(end 310.605424 -190.881)
		(width 0.127)
		(layer "F.Cu")
		(net "LED_DR_LED0")
	)
	(segment
		(start 312.125106 -189.361318)
		(end 315.914786 -189.361318)
		(width 0.127)
		(layer "F.Cu")
		(net "LED_DR_LED0")
	)
	(segment
		(start 306.578 -194.818)
		(end 306.578 -194.2465)
		(width 0.127)
		(layer "F.Cu")
		(net "LED_DR_LED0")
	)
	(segment
		(start 315.1505 -185.293)
		(end 315.849 -185.293)
		(width 0.127)
		(layer "F.Cu")
		(net "LED_DR_LED0")
	)
	(segment
		(start 306.76088 -197.0659)
		(end 306.752752 -194.992752)
		(width 0.127)
		(layer "F.Cu")
		(net "LED_DR_LED0")
	)
	(via
		(at 316.611 -187.579)
		(size 0.7112)
		(drill 0.3556)
		(layers "F.Cu" "B.Cu")
		(net "LED_DR_LED0")
	)
	(segment
		(start 118.435374 -26.407364)
		(end 118.435374 -26.891234)
		(width 0.1397)
		(layer "F.Cu")
		(net "PCIE_SAS_CPU_TX_P7")
	)
	(segment
		(start 155.711652 -74.238612)
		(end 156.17952 -74.70648)
		(width 0.1397)
		(layer "F.Cu")
		(net "PCIE_SAS_CPU_TX_P7")
	)
	(segment
		(start 105.296716 -30.126432)
		(end 105.296716 -28.500324)
		(width 0.1397)
		(layer "F.Cu")
		(net "PCIE_SAS_CPU_TX_P7")
	)
	(segment
		(start 109.900974 -23.517352)
		(end 115.282472 -23.517352)
		(width 0.1397)
		(layer "F.Cu")
		(net "PCIE_SAS_CPU_TX_P7")
	)
	(segment
		(start 137.141966 -27.756612)
		(end 155.16479 -45.779436)
		(width 0.1397)
		(layer "F.Cu")
		(net "PCIE_SAS_CPU_TX_P7")
	)
	(segment
		(start 155.63723 -46.919896)
		(end 155.63723 -74.059034)
		(width 0.1397)
		(layer "F.Cu")
		(net "PCIE_SAS_CPU_TX_P7")
	)
	(segment
		(start 156.63164 -75.798426)
		(end 156.63164 -76.30922)
		(width 0.1397)
		(layer "F.Cu")
		(net "PCIE_SAS_CPU_TX_P7")
	)
	(segment
		(start 103.786432 -31.784036)
		(end 105.192322 -30.378146)
		(width 0.1397)
		(layer "F.Cu")
		(net "PCIE_SAS_CPU_TX_P7")
	)
	(segment
		(start 103.581708 -33.323276)
		(end 103.581708 -32.27832)
		(width 0.1397)
		(layer "F.Cu")
		(net "PCIE_SAS_CPU_TX_P7")
	)
	(segment
		(start 119.01424 -27.4701)
		(end 136.450324 -27.4701)
		(width 0.1397)
		(layer "F.Cu")
		(net "PCIE_SAS_CPU_TX_P7")
	)
	(segment
		(start 116.422932 -23.989792)
		(end 118.148862 -25.715722)
		(width 0.1397)
		(layer "F.Cu")
		(net "PCIE_SAS_CPU_TX_P7")
	)
	(segment
		(start 105.769156 -27.359864)
		(end 109.406944 -23.722076)
		(width 0.1397)
		(layer "F.Cu")
		(net "PCIE_SAS_CPU_TX_P7")
	)
	(via
		(at 156.928312 -77.0255)
		(size 0.5588)
		(drill 0.3048)
		(layers "F.Cu" "B.Cu")
		(net "PCIE_SAS_CPU_TX_P7")
	)
	(arc
		(start 103.581708 -32.27832)
		(mid 103.634917 -32.010821)
		(end 103.786432 -31.784036)
		(width 0.1397)
		(layer "F.Cu")
		(net "PCIE_SAS_CPU_TX_P7")
	)
	(arc
		(start 118.148862 -25.715722)
		(mid 118.360948 -26.033036)
		(end 118.435374 -26.407364)
		(width 0.1397)
		(layer "F.Cu")
		(net "PCIE_SAS_CPU_TX_P7")
	)
	(arc
		(start 155.63723 -74.059034)
		(mid 155.656565 -74.156236)
		(end 155.711652 -74.238612)
		(width 0.1397)
		(layer "F.Cu")
		(net "PCIE_SAS_CPU_TX_P7")
	)
	(arc
		(start 103.549958 -33.399984)
		(mid 103.573474 -33.36479)
		(end 103.581708 -33.323276)
		(width 0.1397)
		(layer "F.Cu")
		(net "PCIE_SAS_CPU_TX_P7")
	)
	(arc
		(start 118.435374 -26.891234)
		(mid 118.60492 -27.300554)
		(end 119.01424 -27.4701)
		(width 0.1397)
		(layer "F.Cu")
		(net "PCIE_SAS_CPU_TX_P7")
	)
	(arc
		(start 155.16479 -45.779436)
		(mid 155.514413 -46.302683)
		(end 155.63723 -46.919896)
		(width 0.1397)
		(layer "F.Cu")
		(net "PCIE_SAS_CPU_TX_P7")
	)
	(arc
		(start 105.192322 -30.378146)
		(mid 105.269571 -30.262674)
		(end 105.296716 -30.126432)
		(width 0.1397)
		(layer "F.Cu")
		(net "PCIE_SAS_CPU_TX_P7")
	)
	(arc
		(start 109.406944 -23.722076)
		(mid 109.633606 -23.570595)
		(end 109.900974 -23.517352)
		(width 0.1397)
		(layer "F.Cu")
		(net "PCIE_SAS_CPU_TX_P7")
	)
	(arc
		(start 156.17952 -74.70648)
		(mid 156.514187 -75.207484)
		(end 156.63164 -75.798426)
		(width 0.1397)
		(layer "F.Cu")
		(net "PCIE_SAS_CPU_TX_P7")
	)
	(arc
		(start 105.296716 -28.500324)
		(mid 105.419491 -27.883094)
		(end 105.769156 -27.359864)
		(width 0.1397)
		(layer "F.Cu")
		(net "PCIE_SAS_CPU_TX_P7")
	)
	(arc
		(start 115.282472 -23.517352)
		(mid 115.899702 -23.640127)
		(end 116.422932 -23.989792)
		(width 0.1397)
		(layer "F.Cu")
		(net "PCIE_SAS_CPU_TX_P7")
	)
	(arc
		(start 136.450324 -27.4701)
		(mid 136.824633 -27.544573)
		(end 137.141966 -27.756612)
		(width 0.1397)
		(layer "F.Cu")
		(net "PCIE_SAS_CPU_TX_P7")
	)
	(arc
		(start 156.63164 -76.30922)
		(mid 156.708746 -76.69686)
		(end 156.928312 -77.0255)
		(width 0.1397)
		(layer "F.Cu")
		(net "PCIE_SAS_CPU_TX_P7")
	)
	(segment
		(start 156.6037 -78.55331)
		(end 156.6037 -77.44206)
		(width 0.1397)
		(layer "B.Cu")
		(net "PCIE_SAS_CPU_TX_P7")
	)
	(segment
		(start 157.450536 -78.24978)
		(end 157.450536 -78.672436)
		(width 0.1397)
		(layer "B.Cu")
		(net "PCIE_SAS_CPU_TX_P7")
	)
	(segment
		(start 157.089348 -79.033624)
		(end 156.927042 -79.033624)
		(width 0.1397)
		(layer "B.Cu")
		(net "PCIE_SAS_CPU_TX_P7")
	)
	(segment
		(start 156.668724 -77.285088)
		(end 156.928312 -77.0255)
		(width 0.1397)
		(layer "B.Cu")
		(net "PCIE_SAS_CPU_TX_P7")
	)
	(arc
		(start 156.6037 -77.44206)
		(mid 156.620598 -77.357106)
		(end 156.668724 -77.285088)
		(width 0.1397)
		(layer "B.Cu")
		(net "PCIE_SAS_CPU_TX_P7")
	)
	(arc
		(start 156.776928 -78.971394)
		(mid 156.648759 -78.779575)
		(end 156.6037 -78.55331)
		(width 0.1397)
		(layer "B.Cu")
		(net "PCIE_SAS_CPU_TX_P7")
	)
	(arc
		(start 156.927042 -79.033624)
		(mid 156.845781 -79.01746)
		(end 156.776928 -78.971394)
		(width 0.1397)
		(layer "B.Cu")
		(net "PCIE_SAS_CPU_TX_P7")
	)
	(arc
		(start 157.450536 -78.672436)
		(mid 157.344746 -78.927834)
		(end 157.089348 -79.033624)
		(width 0.1397)
		(layer "B.Cu")
		(net "PCIE_SAS_CPU_TX_P7")
	)
	(segment
		(start 317.0555 -110.617)
		(end 317.0555 -111.5695)
		(width 0.254)
		(layer "F.Cu")
		(net "P3V3_STBY_LL_R")
	)
	(via
		(at 319.151 -109.474)
		(size 0.7112)
		(drill 0.3556)
		(layers "F.Cu" "B.Cu")
		(net "P3V3_STBY_LL_R")
	)
	(via
		(at 317.0555 -111.5695)
		(size 0.5588)
		(drill 0.3048)
		(layers "F.Cu" "B.Cu")
		(net "P3V3_STBY_LL_R")
	)
	(segment
		(start 326.136 -105.664254)
		(end 327.850754 -103.9495)
		(width 0.254)
		(layer "B.Cu")
		(net "P3V3_STBY_LL_R")
	)
	(segment
		(start 327.850754 -103.9495)
		(end 328.295 -103.9495)
		(width 0.254)
		(layer "B.Cu")
		(net "P3V3_STBY_LL_R")
	)
	(segment
		(start 319.151 -109.474)
		(end 321.183 -107.442)
		(width 0.254)
		(layer "B.Cu")
		(net "P3V3_STBY_LL_R")
	)
	(segment
		(start 325.275448 -107.442)
		(end 326.136 -106.581448)
		(width 0.254)
		(layer "B.Cu")
		(net "P3V3_STBY_LL_R")
	)
	(segment
		(start 328.295 -103.9495)
		(end 328.295 -104.9655)
		(width 0.254)
		(layer "B.Cu")
		(net "P3V3_STBY_LL_R")
	)
	(segment
		(start 321.183 -107.442)
		(end 325.275448 -107.442)
		(width 0.254)
		(layer "B.Cu")
		(net "P3V3_STBY_LL_R")
	)
	(segment
		(start 317.0555 -111.5695)
		(end 319.151 -109.474)
		(width 0.254)
		(layer "B.Cu")
		(net "P3V3_STBY_LL_R")
	)
	(segment
		(start 326.136 -106.581448)
		(end 326.136 -105.664254)
		(width 0.254)
		(layer "B.Cu")
		(net "P3V3_STBY_LL_R")
	)
	(segment
		(start 110.567978 -222.970852)
		(end 110.603284 -222.885254)
		(width 0.1016)
		(layer "B.Cu")
		(net "SAS_GF_EXP_RX_DP8")
	)
	(segment
		(start 110.975902 -222.531432)
		(end 111.195612 -222.4405)
		(width 0.1016)
		(layer "B.Cu")
		(net "SAS_GF_EXP_RX_DP8")
	)
	(segment
		(start 110.992412 -225.5774)
		(end 110.822486 -225.407728)
		(width 0.1016)
		(layer "B.Cu")
		(net "SAS_GF_EXP_RX_DP8")
	)
	(segment
		(start 116.000022 -256.50444)
		(end 116.000022 -254.546354)
		(width 0.1016)
		(layer "B.Cu")
		(net "SAS_GF_EXP_RX_DP8")
	)
	(segment
		(start 115.309904 -229.894892)
		(end 110.992412 -225.5774)
		(width 0.1016)
		(layer "B.Cu")
		(net "SAS_GF_EXP_RX_DP8")
	)
	(segment
		(start 110.819692 -222.621094)
		(end 110.86465 -222.590868)
		(width 0.1016)
		(layer "B.Cu")
		(net "SAS_GF_EXP_RX_DP8")
	)
	(segment
		(start 115.615212 -253.635256)
		(end 115.615212 -230.632)
		(width 0.1016)
		(layer "B.Cu")
		(net "SAS_GF_EXP_RX_DP8")
	)
	(segment
		(start 115.814094 -254.097282)
		(end 115.80114 -254.084328)
		(width 0.1016)
		(layer "B.Cu")
		(net "SAS_GF_EXP_RX_DP8")
	)
	(segment
		(start 110.535212 -224.7138)
		(end 110.535212 -223.13519)
		(width 0.1016)
		(layer "B.Cu")
		(net "SAS_GF_EXP_RX_DP8")
	)
	(arc
		(start 110.822486 -225.407728)
		(mid 110.609836 -225.089336)
		(end 110.535212 -224.7138)
		(width 0.1016)
		(layer "B.Cu")
		(net "SAS_GF_EXP_RX_DP8")
	)
	(arc
		(start 115.615212 -230.632)
		(mid 115.535863 -230.233085)
		(end 115.309904 -229.894892)
		(width 0.1016)
		(layer "B.Cu")
		(net "SAS_GF_EXP_RX_DP8")
	)
	(arc
		(start 115.80114 -254.084328)
		(mid 115.663525 -253.878278)
		(end 115.615212 -253.635256)
		(width 0.1016)
		(layer "B.Cu")
		(net "SAS_GF_EXP_RX_DP8")
	)
	(arc
		(start 110.603284 -222.885254)
		(mid 110.691937 -222.737154)
		(end 110.819692 -222.621094)
		(width 0.1016)
		(layer "B.Cu")
		(net "SAS_GF_EXP_RX_DP8")
	)
	(arc
		(start 110.86465 -222.590868)
		(mid 110.918798 -222.558383)
		(end 110.975902 -222.531432)
		(width 0.1016)
		(layer "B.Cu")
		(net "SAS_GF_EXP_RX_DP8")
	)
	(arc
		(start 116.000022 -254.546354)
		(mid 115.951701 -254.303336)
		(end 115.814094 -254.097282)
		(width 0.1016)
		(layer "B.Cu")
		(net "SAS_GF_EXP_RX_DP8")
	)
	(arc
		(start 110.535212 -223.13519)
		(mid 110.543503 -223.051407)
		(end 110.567978 -222.970852)
		(width 0.1016)
		(layer "B.Cu")
		(net "SAS_GF_EXP_RX_DP8")
	)
	(via
		(at 327.406 -105.537)
		(size 0.5588)
		(drill 0.3048)
		(layers "F.Cu" "B.Cu")
		(net "P3V3_STBY_LL")
	)
	(via
		(at 327.025 -108.712)
		(size 0.7112)
		(drill 0.4064)
		(layers "F.Cu" "B.Cu")
		(net "P3V3_STBY_LL")
	)
	(via
		(at 327.914 -107.95)
		(size 0.7112)
		(drill 0.3556)
		(layers "F.Cu" "B.Cu")
		(net "P3V3_STBY_LL")
	)
	(segment
		(start 327.787 -109.093)
		(end 327.406 -108.712)
		(width 0.508)
		(layer "B.Cu")
		(net "P3V3_STBY_LL")
	)
	(segment
		(start 327.787 -109.982)
		(end 327.787 -109.093)
		(width 0.508)
		(layer "B.Cu")
		(net "P3V3_STBY_LL")
	)
	(segment
		(start 328.295 -105.8545)
		(end 327.7235 -105.8545)
		(width 0.508)
		(layer "B.Cu")
		(net "P3V3_STBY_LL")
	)
	(segment
		(start 327.7235 -105.8545)
		(end 327.406 -105.537)
		(width 0.508)
		(layer "B.Cu")
		(net "P3V3_STBY_LL")
	)
	(segment
		(start 327.406 -108.712)
		(end 327.025 -108.712)
		(width 0.508)
		(layer "B.Cu")
		(net "P3V3_STBY_LL")
	)
	(segment
		(start 306.586128 -204.652372)
		(end 306.752752 -204.485748)
		(width 0.1143)
		(layer "F.Cu")
		(net "LED_DR_I2C_SDA")
	)
	(segment
		(start 306.752752 -203.374752)
		(end 306.76088 -201.2061)
		(width 0.1143)
		(layer "F.Cu")
		(net "LED_DR_I2C_SDA")
	)
	(segment
		(start 306.586128 -204.652372)
		(end 306.578 -204.6605)
		(width 0.1143)
		(layer "F.Cu")
		(net "LED_DR_I2C_SDA")
	)
	(segment
		(start 307.648864 -204.652372)
		(end 306.586128 -204.652372)
		(width 0.1143)
		(layer "F.Cu")
		(net "LED_DR_I2C_SDA")
	)
	(segment
		(start 306.752752 -204.485748)
		(end 306.752752 -203.374752)
		(width 0.1143)
		(layer "F.Cu")
		(net "LED_DR_I2C_SDA")
	)
	(via
		(at 306.752752 -203.374752)
		(size 0.7112)
		(drill 0.3556)
		(layers "F.Cu" "B.Cu")
		(net "LED_DR_I2C_SDA")
	)
	(segment
		(start 99.45116 -31.3436)
		(end 99.60864 -31.186374)
		(width 0.1397)
		(layer "B.Cu")
		(net "PCIE_SAS_CPU_RX_P4")
	)
	(segment
		(start 127.964438 -13.875512)
		(end 148.688298 -34.599372)
		(width 0.1397)
		(layer "B.Cu")
		(net "PCIE_SAS_CPU_RX_P4")
	)
	(segment
		(start 116.668296 -17.720564)
		(end 120.513348 -13.875512)
		(width 0.1397)
		(layer "B.Cu")
		(net "PCIE_SAS_CPU_RX_P4")
	)
	(segment
		(start 121.20499 -13.589)
		(end 127.272796 -13.589)
		(width 0.1397)
		(layer "B.Cu")
		(net "PCIE_SAS_CPU_RX_P4")
	)
	(segment
		(start 154.523694 -35.071812)
		(end 171.31284 -51.860958)
		(width 0.1397)
		(layer "B.Cu")
		(net "PCIE_SAS_CPU_RX_P4")
	)
	(segment
		(start 100.029772 -25.77973)
		(end 107.616498 -18.193004)
		(width 0.1397)
		(layer "B.Cu")
		(net "PCIE_SAS_CPU_RX_P4")
	)
	(segment
		(start 149.13737 -34.7853)
		(end 153.832052 -34.7853)
		(width 0.1397)
		(layer "B.Cu")
		(net "PCIE_SAS_CPU_RX_P4")
	)
	(segment
		(start 171.401232 -75.701906)
		(end 171.449746 -75.75042)
		(width 0.1397)
		(layer "B.Cu")
		(net "PCIE_SAS_CPU_RX_P4")
	)
	(segment
		(start 99.74326 -30.861)
		(end 99.74326 -26.471372)
		(width 0.1397)
		(layer "B.Cu")
		(net "PCIE_SAS_CPU_RX_P4")
	)
	(segment
		(start 171.599352 -52.5526)
		(end 171.599352 -74.168)
		(width 0.1397)
		(layer "B.Cu")
		(net "PCIE_SAS_CPU_RX_P4")
	)
	(segment
		(start 108.30814 -17.906492)
		(end 116.219224 -17.906492)
		(width 0.1397)
		(layer "B.Cu")
		(net "PCIE_SAS_CPU_RX_P4")
	)
	(arc
		(start 120.513348 -13.875512)
		(mid 120.830662 -13.663426)
		(end 121.20499 -13.589)
		(width 0.1397)
		(layer "B.Cu")
		(net "PCIE_SAS_CPU_RX_P4")
	)
	(arc
		(start 171.599352 -74.168)
		(mid 171.543366 -74.464214)
		(end 171.382944 -74.719434)
		(width 0.1397)
		(layer "B.Cu")
		(net "PCIE_SAS_CPU_RX_P4")
	)
	(arc
		(start 116.219224 -17.906492)
		(mid 116.462228 -17.858156)
		(end 116.668296 -17.720564)
		(width 0.1397)
		(layer "B.Cu")
		(net "PCIE_SAS_CPU_RX_P4")
	)
	(arc
		(start 148.688298 -34.599372)
		(mid 148.894334 -34.737041)
		(end 149.13737 -34.7853)
		(width 0.1397)
		(layer "B.Cu")
		(net "PCIE_SAS_CPU_RX_P4")
	)
	(arc
		(start 171.31284 -51.860958)
		(mid 171.524926 -52.178272)
		(end 171.599352 -52.5526)
		(width 0.1397)
		(layer "B.Cu")
		(net "PCIE_SAS_CPU_RX_P4")
	)
	(arc
		(start 99.74326 -26.471372)
		(mid 99.817733 -26.097063)
		(end 100.029772 -25.77973)
		(width 0.1397)
		(layer "B.Cu")
		(net "PCIE_SAS_CPU_RX_P4")
	)
	(arc
		(start 171.382944 -74.719434)
		(mid 171.193858 -75.214385)
		(end 171.401232 -75.701906)
		(width 0.1397)
		(layer "B.Cu")
		(net "PCIE_SAS_CPU_RX_P4")
	)
	(arc
		(start 99.60864 -31.186374)
		(mid 99.708305 -31.037076)
		(end 99.74326 -30.861)
		(width 0.1397)
		(layer "B.Cu")
		(net "PCIE_SAS_CPU_RX_P4")
	)
	(arc
		(start 107.616498 -18.193004)
		(mid 107.933812 -17.980918)
		(end 108.30814 -17.906492)
		(width 0.1397)
		(layer "B.Cu")
		(net "PCIE_SAS_CPU_RX_P4")
	)
	(arc
		(start 153.832052 -34.7853)
		(mid 154.206361 -34.859773)
		(end 154.523694 -35.071812)
		(width 0.1397)
		(layer "B.Cu")
		(net "PCIE_SAS_CPU_RX_P4")
	)
	(arc
		(start 127.272796 -13.589)
		(mid 127.647105 -13.663473)
		(end 127.964438 -13.875512)
		(width 0.1397)
		(layer "B.Cu")
		(net "PCIE_SAS_CPU_RX_P4")
	)
	(segment
		(start 315.204856 -107.95)
		(end 314.198 -108.956856)
		(width 0.254)
		(layer "F.Cu")
		(net "P3V3_STBY_EN")
	)
	(segment
		(start 320.444876 -109.624876)
		(end 318.77 -107.95)
		(width 0.254)
		(layer "F.Cu")
		(net "P3V3_STBY_EN")
	)
	(segment
		(start 318.77 -107.95)
		(end 315.204856 -107.95)
		(width 0.254)
		(layer "F.Cu")
		(net "P3V3_STBY_EN")
	)
	(segment
		(start 320.444876 -110.398814)
		(end 320.444876 -109.624876)
		(width 0.254)
		(layer "F.Cu")
		(net "P3V3_STBY_EN")
	)
	(segment
		(start 314.198 -112.014)
		(end 314.198 -109.728)
		(width 0.254)
		(layer "F.Cu")
		(net "P3V3_STBY_EN")
	)
	(segment
		(start 313.4995 -112.7125)
		(end 314.198 -112.014)
		(width 0.254)
		(layer "F.Cu")
		(net "P3V3_STBY_EN")
	)
	(segment
		(start 311.531 -112.7125)
		(end 313.4995 -112.7125)
		(width 0.254)
		(layer "F.Cu")
		(net "P3V3_STBY_EN")
	)
	(segment
		(start 309.245 -112.7125)
		(end 309.1815 -112.776)
		(width 0.254)
		(layer "F.Cu")
		(net "P3V3_STBY_EN")
	)
	(segment
		(start 314.198 -108.956856)
		(end 314.198 -109.728)
		(width 0.254)
		(layer "F.Cu")
		(net "P3V3_STBY_EN")
	)
	(segment
		(start 310.388 -112.7125)
		(end 311.531 -112.7125)
		(width 0.254)
		(layer "F.Cu")
		(net "P3V3_STBY_EN")
	)
	(segment
		(start 310.388 -112.7125)
		(end 309.245 -112.7125)
		(width 0.254)
		(layer "F.Cu")
		(net "P3V3_STBY_EN")
	)
	(via
		(at 314.198 -109.728)
		(size 0.7112)
		(drill 0.3556)
		(layers "F.Cu" "B.Cu")
		(net "P3V3_STBY_EN")
	)
	(segment
		(start 83.000342 -256.25044)
		(end 83.000342 -254.28194)
		(width 0.1016)
		(layer "F.Cu")
		(net "SAS_EXP_GF_TX_DN12")
	)
	(segment
		(start 79.454502 -194.517518)
		(end 106.529632 -167.442388)
		(width 0.1016)
		(layer "F.Cu")
		(net "SAS_EXP_GF_TX_DN12")
	)
	(segment
		(start 107.148122 -114.855752)
		(end 107.146852 -114.854482)
		(width 0.1016)
		(layer "F.Cu")
		(net "SAS_EXP_GF_TX_DN12")
	)
	(segment
		(start 107.07497 -114.681)
		(end 107.07497 -114.5794)
		(width 0.1016)
		(layer "F.Cu")
		(net "SAS_EXP_GF_TX_DN12")
	)
	(segment
		(start 78.994 -246.804942)
		(end 78.994 -195.629276)
		(width 0.1016)
		(layer "F.Cu")
		(net "SAS_EXP_GF_TX_DN12")
	)
	(segment
		(start 107.22102 -165.773354)
		(end 107.22102 -115.032028)
		(width 0.1016)
		(layer "F.Cu")
		(net "SAS_EXP_GF_TX_DN12")
	)
	(segment
		(start 83.014566 -251.797566)
		(end 79.68107 -248.46407)
		(width 0.1016)
		(layer "F.Cu")
		(net "SAS_EXP_GF_TX_DN12")
	)
	(segment
		(start 83.101942 -254.18034)
		(end 83.227164 -254.18034)
		(width 0.1016)
		(layer "F.Cu")
		(net "SAS_EXP_GF_TX_DN12")
	)
	(segment
		(start 83.328764 -254.07874)
		(end 83.328764 -252.555756)
		(width 0.1016)
		(layer "F.Cu")
		(net "SAS_EXP_GF_TX_DN12")
	)
	(arc
		(start 107.22102 -115.032028)
		(mid 107.202083 -114.936645)
		(end 107.148122 -114.855752)
		(width 0.1016)
		(layer "F.Cu")
		(net "SAS_EXP_GF_TX_DN12")
	)
	(arc
		(start 83.227164 -254.18034)
		(mid 83.299006 -254.150582)
		(end 83.328764 -254.07874)
		(width 0.1016)
		(layer "F.Cu")
		(net "SAS_EXP_GF_TX_DN12")
	)
	(arc
		(start 79.68107 -248.46407)
		(mid 79.172526 -247.702841)
		(end 78.994 -246.804942)
		(width 0.1016)
		(layer "F.Cu")
		(net "SAS_EXP_GF_TX_DN12")
	)
	(arc
		(start 78.994 -195.629276)
		(mid 79.113666 -195.027584)
		(end 79.454502 -194.517518)
		(width 0.1016)
		(layer "F.Cu")
		(net "SAS_EXP_GF_TX_DN12")
	)
	(arc
		(start 83.328764 -252.555756)
		(mid 83.24705 -252.145425)
		(end 83.014566 -251.797566)
		(width 0.1016)
		(layer "F.Cu")
		(net "SAS_EXP_GF_TX_DN12")
	)
	(arc
		(start 83.000342 -254.28194)
		(mid 83.0301 -254.210098)
		(end 83.101942 -254.18034)
		(width 0.1016)
		(layer "F.Cu")
		(net "SAS_EXP_GF_TX_DN12")
	)
	(arc
		(start 106.529632 -167.442388)
		(mid 107.041296 -166.676629)
		(end 107.22102 -165.773354)
		(width 0.1016)
		(layer "F.Cu")
		(net "SAS_EXP_GF_TX_DN12")
	)
	(arc
		(start 107.146852 -114.854482)
		(mid 107.093669 -114.774888)
		(end 107.07497 -114.681)
		(width 0.1016)
		(layer "F.Cu")
		(net "SAS_EXP_GF_TX_DN12")
	)
	(segment
		(start 310.515 -109.7915)
		(end 309.452264 -109.7915)
		(width 0.254)
		(layer "F.Cu")
		(net "P3V3_STBY_ROVP")
	)
	(segment
		(start 311.531 -109.7915)
		(end 312.3565 -109.7915)
		(width 0.254)
		(layer "F.Cu")
		(net "P3V3_STBY_ROVP")
	)
	(segment
		(start 315.0235 -106.299)
		(end 313.53125 -107.79125)
		(width 0.254)
		(layer "F.Cu")
		(net "P3V3_STBY_ROVP")
	)
	(segment
		(start 309.452264 -109.7915)
		(end 309.380636 -109.863128)
		(width 0.254)
		(layer "F.Cu")
		(net "P3V3_STBY_ROVP")
	)
	(segment
		(start 321.944746 -107.378246)
		(end 320.8655 -106.299)
		(width 0.254)
		(layer "F.Cu")
		(net "P3V3_STBY_ROVP")
	)
	(segment
		(start 320.8655 -106.299)
		(end 315.0235 -106.299)
		(width 0.254)
		(layer "F.Cu")
		(net "P3V3_STBY_ROVP")
	)
	(segment
		(start 310.515 -109.7915)
		(end 311.531 -109.7915)
		(width 0.254)
		(layer "F.Cu")
		(net "P3V3_STBY_ROVP")
	)
	(segment
		(start 313.53125 -108.61675)
		(end 312.547 -109.601)
		(width 0.254)
		(layer "F.Cu")
		(net "P3V3_STBY_ROVP")
	)
	(segment
		(start 321.944746 -110.398814)
		(end 321.944746 -107.378246)
		(width 0.254)
		(layer "F.Cu")
		(net "P3V3_STBY_ROVP")
	)
	(segment
		(start 313.53125 -107.79125)
		(end 313.53125 -108.61675)
		(width 0.254)
		(layer "F.Cu")
		(net "P3V3_STBY_ROVP")
	)
	(segment
		(start 312.3565 -109.7915)
		(end 312.547 -109.601)
		(width 0.254)
		(layer "F.Cu")
		(net "P3V3_STBY_ROVP")
	)
	(via
		(at 312.547 -109.601)
		(size 0.7112)
		(drill 0.3556)
		(layers "F.Cu" "B.Cu")
		(net "P3V3_STBY_ROVP")
	)
	(segment
		(start 333.883 -230.509064)
		(end 334.509872 -231.135936)
		(width 0.1143)
		(layer "F.Cu")
		(net "VOL_SEN_ADDR")
	)
	(segment
		(start 334.645 -229.2985)
		(end 333.883 -230.0605)
		(width 0.1143)
		(layer "F.Cu")
		(net "VOL_SEN_ADDR")
	)
	(segment
		(start 333.883 -230.0605)
		(end 333.883 -230.509064)
		(width 0.1143)
		(layer "F.Cu")
		(net "VOL_SEN_ADDR")
	)
	(segment
		(start 333.096362 -227.749862)
		(end 334.645 -229.2985)
		(width 0.1143)
		(layer "F.Cu")
		(net "VOL_SEN_ADDR")
	)
	(segment
		(start 334.509872 -232.037636)
		(end 334.509872 -231.135936)
		(width 0.1143)
		(layer "F.Cu")
		(net "VOL_SEN_ADDR")
	)
	(segment
		(start 333.096362 -226.297236)
		(end 333.096362 -227.749862)
		(width 0.1143)
		(layer "F.Cu")
		(net "VOL_SEN_ADDR")
	)
	(via
		(at 334.509872 -231.135936)
		(size 0.7112)
		(drill 0.3556)
		(layers "F.Cu" "B.Cu")
		(net "VOL_SEN_ADDR")
	)
	(segment
		(start 115.067334 -230.137462)
		(end 113.798096 -228.868224)
		(width 0.1016)
		(layer "B.Cu")
		(net "SAS_GF_EXP_RX_DN8")
	)
	(segment
		(start 109.857286 -222.527622)
		(end 109.775244 -222.48368)
		(width 0.1016)
		(layer "B.Cu")
		(net "SAS_GF_EXP_RX_DN8")
	)
	(segment
		(start 110.192312 -224.7138)
		(end 110.192312 -223.087438)
		(width 0.1016)
		(layer "B.Cu")
		(net "SAS_GF_EXP_RX_DN8")
	)
	(segment
		(start 111.130588 -226.20097)
		(end 110.579916 -225.650298)
		(width 0.1016)
		(layer "B.Cu")
		(net "SAS_GF_EXP_RX_DN8")
	)
	(segment
		(start 115.000532 -256.50444)
		(end 115.000532 -254.273558)
		(width 0.1016)
		(layer "B.Cu")
		(net "SAS_GF_EXP_RX_DN8")
	)
	(segment
		(start 115.272312 -253.617222)
		(end 115.272312 -230.632)
		(width 0.1016)
		(layer "B.Cu")
		(net "SAS_GF_EXP_RX_DN8")
	)
	(segment
		(start 113.798096 -228.868224)
		(end 111.130588 -226.20097)
		(width 0.1016)
		(layer "B.Cu")
		(net "SAS_GF_EXP_RX_DN8")
	)
	(segment
		(start 109.603794 -222.4405)
		(end 109.544612 -222.4405)
		(width 0.1016)
		(layer "B.Cu")
		(net "SAS_GF_EXP_RX_DN8")
	)
	(arc
		(start 110.192312 -223.087438)
		(mid 110.102235 -222.761171)
		(end 109.857286 -222.527622)
		(width 0.1016)
		(layer "B.Cu")
		(net "SAS_GF_EXP_RX_DN8")
	)
	(arc
		(start 115.272312 -230.632)
		(mid 115.218982 -230.364361)
		(end 115.067334 -230.137462)
		(width 0.1016)
		(layer "B.Cu")
		(net "SAS_GF_EXP_RX_DN8")
	)
	(arc
		(start 109.775244 -222.48368)
		(mid 109.692188 -222.45149)
		(end 109.603794 -222.4405)
		(width 0.1016)
		(layer "B.Cu")
		(net "SAS_GF_EXP_RX_DN8")
	)
	(arc
		(start 115.136422 -253.94539)
		(mid 115.236972 -253.794811)
		(end 115.272312 -253.617222)
		(width 0.1016)
		(layer "B.Cu")
		(net "SAS_GF_EXP_RX_DN8")
	)
	(arc
		(start 115.000532 -254.273558)
		(mid 115.035841 -254.095956)
		(end 115.136422 -253.94539)
		(width 0.1016)
		(layer "B.Cu")
		(net "SAS_GF_EXP_RX_DN8")
	)
	(arc
		(start 110.579916 -225.650298)
		(mid 110.292957 -225.2206)
		(end 110.192312 -224.7138)
		(width 0.1016)
		(layer "B.Cu")
		(net "SAS_GF_EXP_RX_DN8")
	)
	(segment
		(start 319.913 -116.586)
		(end 320.444876 -116.054124)
		(width 0.254)
		(layer "F.Cu")
		(net "P3V3_STBY_TRIP")
	)
	(segment
		(start 317.0555 -116.586)
		(end 319.913 -116.586)
		(width 0.254)
		(layer "F.Cu")
		(net "P3V3_STBY_TRIP")
	)
	(segment
		(start 316.3697 -117.2718)
		(end 317.0555 -116.586)
		(width 0.254)
		(layer "F.Cu")
		(net "P3V3_STBY_TRIP")
	)
	(segment
		(start 316.357 -117.2718)
		(end 316.3697 -117.2718)
		(width 0.254)
		(layer "F.Cu")
		(net "P3V3_STBY_TRIP")
	)
	(segment
		(start 315.468 -118.1735)
		(end 316.357 -117.2845)
		(width 0.254)
		(layer "F.Cu")
		(net "P3V3_STBY_TRIP")
	)
	(segment
		(start 316.357 -117.2845)
		(end 316.357 -117.2718)
		(width 0.254)
		(layer "F.Cu")
		(net "P3V3_STBY_TRIP")
	)
	(segment
		(start 320.444876 -116.054124)
		(end 320.444876 -115.297458)
		(width 0.254)
		(layer "F.Cu")
		(net "P3V3_STBY_TRIP")
	)
	(via
		(at 316.357 -117.2718)
		(size 0.7112)
		(drill 0.3556)
		(layers "F.Cu" "B.Cu")
		(net "P3V3_STBY_TRIP")
	)
	(segment
		(start 285.010352 -179.776628)
		(end 285.346902 -179.440078)
		(width 0.1143)
		(layer "F.Cu")
		(net "ROMD1")
	)
	(segment
		(start 352.81235 -147.35429)
		(end 352.81235 -167.37965)
		(width 0.1143)
		(layer "F.Cu")
		(net "ROMD1")
	)
	(segment
		(start 273.760692 -239.0521)
		(end 273.355308 -239.0521)
		(width 0.1143)
		(layer "F.Cu")
		(net "ROMD1")
	)
	(segment
		(start 276.0091 -181.70525)
		(end 276.0091 -181.576726)
		(width 0.1143)
		(layer "F.Cu")
		(net "ROMD1")
	)
	(segment
		(start 273.317462 -239.089946)
		(end 264.897108 -239.089946)
		(width 0.1143)
		(layer "F.Cu")
		(net "ROMD1")
	)
	(segment
		(start 352.81235 -167.37965)
		(end 342.519 -177.673)
		(width 0.1143)
		(layer "F.Cu")
		(net "ROMD1")
	)
	(segment
		(start 277.847298 -179.738528)
		(end 283.38399 -179.738528)
		(width 0.1143)
		(layer "F.Cu")
		(net "ROMD1")
	)
	(segment
		(start 264.897108 -239.089946)
		(end 255.297178 -229.490016)
		(width 0.1143)
		(layer "F.Cu")
		(net "ROMD1")
	)
	(segment
		(start 273.355308 -239.0521)
		(end 273.317462 -239.089946)
		(width 0.1143)
		(layer "F.Cu")
		(net "ROMD1")
	)
	(segment
		(start 255.297178 -191.715898)
		(end 262.482076 -184.531)
		(width 0.1143)
		(layer "F.Cu")
		(net "ROMD1")
	)
	(segment
		(start 285.346902 -179.440078)
		(end 285.634938 -179.440078)
		(width 0.1143)
		(layer "F.Cu")
		(net "ROMD1")
	)
	(segment
		(start 351.140014 -145.681954)
		(end 352.81235 -147.35429)
		(width 0.1143)
		(layer "F.Cu")
		(net "ROMD1")
	)
	(segment
		(start 274.200366 -239.491774)
		(end 273.760692 -239.0521)
		(width 0.1143)
		(layer "F.Cu")
		(net "ROMD1")
	)
	(segment
		(start 342.519 -234.3023)
		(end 337.329526 -239.491774)
		(width 0.1143)
		(layer "F.Cu")
		(net "ROMD1")
	)
	(segment
		(start 262.482076 -184.531)
		(end 270.400526 -184.531)
		(width 0.1143)
		(layer "F.Cu")
		(net "ROMD1")
	)
	(segment
		(start 283.42209 -179.776628)
		(end 285.010352 -179.776628)
		(width 0.1143)
		(layer "F.Cu")
		(net "ROMD1")
	)
	(segment
		(start 350.266 -76.581)
		(end 352.15195 -78.46695)
		(width 0.1143)
		(layer "F.Cu")
		(net "ROMD1")
	)
	(segment
		(start 342.519 -177.673)
		(end 342.519 -234.3023)
		(width 0.1143)
		(layer "F.Cu")
		(net "ROMD1")
	)
	(segment
		(start 352.15195 -90.18905)
		(end 351.140014 -91.200986)
		(width 0.1143)
		(layer "F.Cu")
		(net "ROMD1")
	)
	(segment
		(start 349.504 -74.168)
		(end 350.266 -74.93)
		(width 0.1143)
		(layer "F.Cu")
		(net "ROMD1")
	)
	(segment
		(start 352.15195 -78.46695)
		(end 352.15195 -90.18905)
		(width 0.1143)
		(layer "F.Cu")
		(net "ROMD1")
	)
	(segment
		(start 270.400526 -184.531)
		(end 272.161 -182.770526)
		(width 0.1143)
		(layer "F.Cu")
		(net "ROMD1")
	)
	(segment
		(start 351.140014 -91.200986)
		(end 351.140014 -145.681954)
		(width 0.1143)
		(layer "F.Cu")
		(net "ROMD1")
	)
	(segment
		(start 255.297178 -229.490016)
		(end 255.297178 -191.715898)
		(width 0.1143)
		(layer "F.Cu")
		(net "ROMD1")
	)
	(segment
		(start 274.943824 -182.770526)
		(end 276.0091 -181.70525)
		(width 0.1143)
		(layer "F.Cu")
		(net "ROMD1")
	)
	(segment
		(start 337.329526 -239.491774)
		(end 274.200366 -239.491774)
		(width 0.1143)
		(layer "F.Cu")
		(net "ROMD1")
	)
	(segment
		(start 350.266 -74.93)
		(end 350.266 -76.581)
		(width 0.1143)
		(layer "F.Cu")
		(net "ROMD1")
	)
	(segment
		(start 276.0091 -181.576726)
		(end 277.847298 -179.738528)
		(width 0.1143)
		(layer "F.Cu")
		(net "ROMD1")
	)
	(segment
		(start 283.38399 -179.738528)
		(end 283.42209 -179.776628)
		(width 0.1143)
		(layer "F.Cu")
		(net "ROMD1")
	)
	(segment
		(start 272.161 -182.770526)
		(end 274.943824 -182.770526)
		(width 0.1143)
		(layer "F.Cu")
		(net "ROMD1")
	)
	(via
		(at 349.504 -74.168)
		(size 0.5588)
		(drill 0.3048)
		(layers "F.Cu" "B.Cu")
		(net "ROMD1")
	)
	(via
		(at 349.5802 -73.406)
		(size 0.7112)
		(drill 0.3556)
		(layers "F.Cu" "B.Cu")
		(net "ROMD1")
	)
	(segment
		(start 349.5802 -74.0918)
		(end 349.5802 -73.406)
		(width 0.1143)
		(layer "B.Cu")
		(net "ROMD1")
	)
	(segment
		(start 349.5802 -73.406)
		(end 349.5802 -72.2503)
		(width 0.1143)
		(layer "B.Cu")
		(net "ROMD1")
	)
	(segment
		(start 349.504 -74.168)
		(end 349.5802 -74.0918)
		(width 0.1143)
		(layer "B.Cu")
		(net "ROMD1")
	)
	(segment
		(start 308.06136 -201.2061)
		(end 309.4609 -201.2061)
		(width 0.1143)
		(layer "F.Cu")
		(net "LED_DR_RESET#")
	)
	(segment
		(start 309.4609 -201.2061)
		(end 309.807864 -200.859136)
		(width 0.1143)
		(layer "F.Cu")
		(net "LED_DR_RESET#")
	)
	(segment
		(start 309.807864 -200.859136)
		(end 309.871872 -200.859136)
		(width 0.1143)
		(layer "F.Cu")
		(net "LED_DR_RESET#")
	)
	(segment
		(start 311.014364 -200.859136)
		(end 309.871872 -200.859136)
		(width 0.1143)
		(layer "F.Cu")
		(net "LED_DR_RESET#")
	)
	(segment
		(start 311.277 -200.5965)
		(end 311.014364 -200.859136)
		(width 0.1143)
		(layer "F.Cu")
		(net "LED_DR_RESET#")
	)
	(segment
		(start 93.751908 -180.705252)
		(end 93.967554 -180.489606)
		(width 0.1016)
		(layer "F.Cu")
		(net "SAS_EXP_GF_TX_DP12")
	)
	(segment
		(start 95.964756 -178.492404)
		(end 98.652076 -175.805084)
		(width 0.1016)
		(layer "F.Cu")
		(net "SAS_EXP_GF_TX_DP12")
	)
	(segment
		(start 93.367606 -181.427374)
		(end 93.582998 -181.211728)
		(width 0.1016)
		(layer "F.Cu")
		(net "SAS_EXP_GF_TX_DP12")
	)
	(segment
		(start 84.10067 -190.35649)
		(end 92.86113 -181.59603)
		(width 0.1016)
		(layer "F.Cu")
		(net "SAS_EXP_GF_TX_DP12")
	)
	(segment
		(start 107.56392 -165.773608)
		(end 107.56392 -114.961924)
		(width 0.1016)
		(layer "F.Cu")
		(net "SAS_EXP_GF_TX_DP12")
	)
	(segment
		(start 83.999832 -256.25044)
		(end 83.999832 -254.28194)
		(width 0.1016)
		(layer "F.Cu")
		(net "SAS_EXP_GF_TX_DP12")
	)
	(segment
		(start 94.858332 -179.598828)
		(end 95.073724 -179.383436)
		(width 0.1016)
		(layer "F.Cu")
		(net "SAS_EXP_GF_TX_DP12")
	)
	(segment
		(start 95.5802 -179.214526)
		(end 95.795846 -178.99888)
		(width 0.1016)
		(layer "F.Cu")
		(net "SAS_EXP_GF_TX_DP12")
	)
	(segment
		(start 82.609944 -192.184782)
		(end 82.825336 -191.96939)
		(width 0.1016)
		(layer "F.Cu")
		(net "SAS_EXP_GF_TX_DP12")
	)
	(segment
		(start 99.158552 -175.636174)
		(end 99.374198 -175.420782)
		(width 0.1016)
		(layer "F.Cu")
		(net "SAS_EXP_GF_TX_DP12")
	)
	(segment
		(start 107.636564 -114.785902)
		(end 107.636818 -114.785648)
		(width 0.1016)
		(layer "F.Cu")
		(net "SAS_EXP_GF_TX_DP12")
	)
	(segment
		(start 94.47403 -180.32095)
		(end 94.689422 -180.105304)
		(width 0.1016)
		(layer "F.Cu")
		(net "SAS_EXP_GF_TX_DP12")
	)
	(segment
		(start 99.542854 -174.914306)
		(end 106.772202 -167.684958)
		(width 0.1016)
		(layer "F.Cu")
		(net "SAS_EXP_GF_TX_DP12")
	)
	(segment
		(start 79.3369 -246.804942)
		(end 79.3369 -195.62953)
		(width 0.1016)
		(layer "F.Cu")
		(net "SAS_EXP_GF_TX_DP12")
	)
	(segment
		(start 107.70997 -114.609372)
		(end 107.70997 -114.5794)
		(width 0.1016)
		(layer "F.Cu")
		(net "SAS_EXP_GF_TX_DP12")
	)
	(segment
		(start 79.697072 -194.760088)
		(end 80.997044 -193.460116)
		(width 0.1016)
		(layer "F.Cu")
		(net "SAS_EXP_GF_TX_DP12")
	)
	(segment
		(start 82.994246 -191.462914)
		(end 83.209892 -191.247268)
		(width 0.1016)
		(layer "F.Cu")
		(net "SAS_EXP_GF_TX_DP12")
	)
	(segment
		(start 83.257136 -251.554996)
		(end 79.92364 -248.2215)
		(width 0.1016)
		(layer "F.Cu")
		(net "SAS_EXP_GF_TX_DP12")
	)
	(segment
		(start 81.887822 -192.569338)
		(end 82.103468 -192.353692)
		(width 0.1016)
		(layer "F.Cu")
		(net "SAS_EXP_GF_TX_DP12")
	)
	(segment
		(start 83.671664 -254.07874)
		(end 83.671664 -252.555756)
		(width 0.1016)
		(layer "F.Cu")
		(net "SAS_EXP_GF_TX_DP12")
	)
	(segment
		(start 83.898232 -254.18034)
		(end 83.773264 -254.18034)
		(width 0.1016)
		(layer "F.Cu")
		(net "SAS_EXP_GF_TX_DP12")
	)
	(segment
		(start 81.50352 -193.291206)
		(end 81.719166 -193.075814)
		(width 0.1016)
		(layer "F.Cu")
		(net "SAS_EXP_GF_TX_DP12")
	)
	(segment
		(start 83.716368 -191.078612)
		(end 83.93176 -190.862966)
		(width 0.1016)
		(layer "F.Cu")
		(net "SAS_EXP_GF_TX_DP12")
	)
	(arc
		(start 83.93176 -190.862966)
		(mid 84.004983 -190.746678)
		(end 84.016342 -190.609728)
		(width 0.1016)
		(layer "F.Cu")
		(net "SAS_EXP_GF_TX_DP12")
	)
	(arc
		(start 99.458526 -175.167544)
		(mid 99.469756 -175.030619)
		(end 99.542854 -174.914306)
		(width 0.1016)
		(layer "F.Cu")
		(net "SAS_EXP_GF_TX_DP12")
	)
	(arc
		(start 83.999832 -254.28194)
		(mid 83.970074 -254.210098)
		(end 83.898232 -254.18034)
		(width 0.1016)
		(layer "F.Cu")
		(net "SAS_EXP_GF_TX_DP12")
	)
	(arc
		(start 83.773264 -254.18034)
		(mid 83.701422 -254.150582)
		(end 83.671664 -254.07874)
		(width 0.1016)
		(layer "F.Cu")
		(net "SAS_EXP_GF_TX_DP12")
	)
	(arc
		(start 79.92364 -248.2215)
		(mid 79.489376 -247.571578)
		(end 79.3369 -246.804942)
		(width 0.1016)
		(layer "F.Cu")
		(net "SAS_EXP_GF_TX_DP12")
	)
	(arc
		(start 95.073724 -179.383436)
		(mid 95.190012 -179.310213)
		(end 95.326962 -179.298854)
		(width 0.1016)
		(layer "F.Cu")
		(net "SAS_EXP_GF_TX_DP12")
	)
	(arc
		(start 99.374198 -175.420782)
		(mid 99.447258 -175.304457)
		(end 99.458526 -175.167544)
		(width 0.1016)
		(layer "F.Cu")
		(net "SAS_EXP_GF_TX_DP12")
	)
	(arc
		(start 98.652076 -175.805084)
		(mid 98.768364 -175.731861)
		(end 98.905314 -175.720502)
		(width 0.1016)
		(layer "F.Cu")
		(net "SAS_EXP_GF_TX_DP12")
	)
	(arc
		(start 95.326962 -179.298854)
		(mid 95.463887 -179.287624)
		(end 95.5802 -179.214526)
		(width 0.1016)
		(layer "F.Cu")
		(net "SAS_EXP_GF_TX_DP12")
	)
	(arc
		(start 83.209892 -191.247268)
		(mid 83.326217 -191.174208)
		(end 83.46313 -191.16294)
		(width 0.1016)
		(layer "F.Cu")
		(net "SAS_EXP_GF_TX_DP12")
	)
	(arc
		(start 94.689422 -180.105304)
		(mid 94.762482 -179.988979)
		(end 94.77375 -179.852066)
		(width 0.1016)
		(layer "F.Cu")
		(net "SAS_EXP_GF_TX_DP12")
	)
	(arc
		(start 82.909918 -191.716152)
		(mid 82.921148 -191.579227)
		(end 82.994246 -191.462914)
		(width 0.1016)
		(layer "F.Cu")
		(net "SAS_EXP_GF_TX_DP12")
	)
	(arc
		(start 79.3369 -195.62953)
		(mid 79.430499 -195.158977)
		(end 79.697072 -194.760088)
		(width 0.1016)
		(layer "F.Cu")
		(net "SAS_EXP_GF_TX_DP12")
	)
	(arc
		(start 94.77375 -179.852066)
		(mid 94.785114 -179.715118)
		(end 94.858332 -179.598828)
		(width 0.1016)
		(layer "F.Cu")
		(net "SAS_EXP_GF_TX_DP12")
	)
	(arc
		(start 81.719166 -193.075814)
		(mid 81.792226 -192.959489)
		(end 81.803494 -192.822576)
		(width 0.1016)
		(layer "F.Cu")
		(net "SAS_EXP_GF_TX_DP12")
	)
	(arc
		(start 93.582998 -181.211728)
		(mid 93.656221 -181.09544)
		(end 93.66758 -180.95849)
		(width 0.1016)
		(layer "F.Cu")
		(net "SAS_EXP_GF_TX_DP12")
	)
	(arc
		(start 98.905314 -175.720502)
		(mid 99.042239 -175.709272)
		(end 99.158552 -175.636174)
		(width 0.1016)
		(layer "F.Cu")
		(net "SAS_EXP_GF_TX_DP12")
	)
	(arc
		(start 107.636818 -114.785648)
		(mid 107.690965 -114.7048)
		(end 107.70997 -114.609372)
		(width 0.1016)
		(layer "F.Cu")
		(net "SAS_EXP_GF_TX_DP12")
	)
	(arc
		(start 107.56392 -114.961924)
		(mid 107.582789 -114.866707)
		(end 107.636564 -114.785902)
		(width 0.1016)
		(layer "F.Cu")
		(net "SAS_EXP_GF_TX_DP12")
	)
	(arc
		(start 92.86113 -181.59603)
		(mid 92.977455 -181.52297)
		(end 93.114368 -181.511702)
		(width 0.1016)
		(layer "F.Cu")
		(net "SAS_EXP_GF_TX_DP12")
	)
	(arc
		(start 82.103468 -192.353692)
		(mid 82.219793 -192.280632)
		(end 82.356706 -192.269364)
		(width 0.1016)
		(layer "F.Cu")
		(net "SAS_EXP_GF_TX_DP12")
	)
	(arc
		(start 83.46313 -191.16294)
		(mid 83.600055 -191.15171)
		(end 83.716368 -191.078612)
		(width 0.1016)
		(layer "F.Cu")
		(net "SAS_EXP_GF_TX_DP12")
	)
	(arc
		(start 81.803494 -192.822576)
		(mid 81.814724 -192.685651)
		(end 81.887822 -192.569338)
		(width 0.1016)
		(layer "F.Cu")
		(net "SAS_EXP_GF_TX_DP12")
	)
	(arc
		(start 82.825336 -191.96939)
		(mid 82.898559 -191.853102)
		(end 82.909918 -191.716152)
		(width 0.1016)
		(layer "F.Cu")
		(net "SAS_EXP_GF_TX_DP12")
	)
	(arc
		(start 95.880174 -178.745642)
		(mid 95.891538 -178.608694)
		(end 95.964756 -178.492404)
		(width 0.1016)
		(layer "F.Cu")
		(net "SAS_EXP_GF_TX_DP12")
	)
	(arc
		(start 94.220792 -180.405278)
		(mid 94.357717 -180.394048)
		(end 94.47403 -180.32095)
		(width 0.1016)
		(layer "F.Cu")
		(net "SAS_EXP_GF_TX_DP12")
	)
	(arc
		(start 84.016342 -190.609728)
		(mid 84.027572 -190.472803)
		(end 84.10067 -190.35649)
		(width 0.1016)
		(layer "F.Cu")
		(net "SAS_EXP_GF_TX_DP12")
	)
	(arc
		(start 106.772202 -167.684958)
		(mid 107.35818 -166.808024)
		(end 107.56392 -165.773608)
		(width 0.1016)
		(layer "F.Cu")
		(net "SAS_EXP_GF_TX_DP12")
	)
	(arc
		(start 81.250282 -193.375788)
		(mid 81.38723 -193.364424)
		(end 81.50352 -193.291206)
		(width 0.1016)
		(layer "F.Cu")
		(net "SAS_EXP_GF_TX_DP12")
	)
	(arc
		(start 93.114368 -181.511702)
		(mid 93.251293 -181.500472)
		(end 93.367606 -181.427374)
		(width 0.1016)
		(layer "F.Cu")
		(net "SAS_EXP_GF_TX_DP12")
	)
	(arc
		(start 80.997044 -193.460116)
		(mid 81.113369 -193.387056)
		(end 81.250282 -193.375788)
		(width 0.1016)
		(layer "F.Cu")
		(net "SAS_EXP_GF_TX_DP12")
	)
	(arc
		(start 93.967554 -180.489606)
		(mid 94.083879 -180.416546)
		(end 94.220792 -180.405278)
		(width 0.1016)
		(layer "F.Cu")
		(net "SAS_EXP_GF_TX_DP12")
	)
	(arc
		(start 82.356706 -192.269364)
		(mid 82.493654 -192.258)
		(end 82.609944 -192.184782)
		(width 0.1016)
		(layer "F.Cu")
		(net "SAS_EXP_GF_TX_DP12")
	)
	(arc
		(start 95.795846 -178.99888)
		(mid 95.868906 -178.882555)
		(end 95.880174 -178.745642)
		(width 0.1016)
		(layer "F.Cu")
		(net "SAS_EXP_GF_TX_DP12")
	)
	(arc
		(start 83.671664 -252.555756)
		(mid 83.563932 -252.014149)
		(end 83.257136 -251.554996)
		(width 0.1016)
		(layer "F.Cu")
		(net "SAS_EXP_GF_TX_DP12")
	)
	(arc
		(start 93.66758 -180.95849)
		(mid 93.67881 -180.821565)
		(end 93.751908 -180.705252)
		(width 0.1016)
		(layer "F.Cu")
		(net "SAS_EXP_GF_TX_DP12")
	)
	(segment
		(start 106.977434 -16.4211)
		(end 109.703616 -16.4211)
		(width 0.1397)
		(layer "F.Cu")
		(net "PCIE_SAS_CPU_TX_P3")
	)
	(segment
		(start 134.245858 -8.922258)
		(end 137.1854 -11.8618)
		(width 0.1397)
		(layer "F.Cu")
		(net "PCIE_SAS_CPU_TX_P3")
	)
	(segment
		(start 137.7569 -13.241528)
		(end 137.7569 -17.80794)
		(width 0.1397)
		(layer "F.Cu")
		(net "PCIE_SAS_CPU_TX_P3")
	)
	(segment
		(start 98.78187 -32.434784)
		(end 98.78187 -31.38932)
		(width 0.1397)
		(layer "F.Cu")
		(net "PCIE_SAS_CPU_TX_P3")
	)
	(segment
		(start 118.15699 -8.636)
		(end 133.553962 -8.636)
		(width 0.1397)
		(layer "F.Cu")
		(net "PCIE_SAS_CPU_TX_P3")
	)
	(segment
		(start 98.695256 -24.403304)
		(end 102.58044 -20.51812)
		(width 0.1397)
		(layer "F.Cu")
		(net "PCIE_SAS_CPU_TX_P3")
	)
	(segment
		(start 98.781616 -33.324038)
		(end 98.781616 -32.435038)
		(width 0.1397)
		(layer "F.Cu")
		(net "PCIE_SAS_CPU_TX_P3")
	)
	(segment
		(start 98.781616 -32.435038)
		(end 98.78187 -32.434784)
		(width 0.1397)
		(layer "F.Cu")
		(net "PCIE_SAS_CPU_TX_P3")
	)
	(segment
		(start 138.128756 -18.70583)
		(end 191.029336 -71.60641)
		(width 0.1397)
		(layer "F.Cu")
		(net "PCIE_SAS_CPU_TX_P3")
	)
	(segment
		(start 98.222816 -30.353254)
		(end 98.222816 -25.543764)
		(width 0.1397)
		(layer "F.Cu")
		(net "PCIE_SAS_CPU_TX_P3")
	)
	(segment
		(start 191.63792 -73.076308)
		(end 191.63792 -73.939146)
		(width 0.1397)
		(layer "F.Cu")
		(net "PCIE_SAS_CPU_TX_P3")
	)
	(segment
		(start 102.58044 -20.51812)
		(end 106.465878 -16.632936)
		(width 0.1397)
		(layer "F.Cu")
		(net "PCIE_SAS_CPU_TX_P3")
	)
	(segment
		(start 191.63792 -73.939146)
		(end 191.638174 -73.9394)
		(width 0.1397)
		(layer "F.Cu")
		(net "PCIE_SAS_CPU_TX_P3")
	)
	(segment
		(start 191.796924 -74.323194)
		(end 192.35293 -74.8792)
		(width 0.1397)
		(layer "F.Cu")
		(net "PCIE_SAS_CPU_TX_P3")
	)
	(segment
		(start 98.677476 -31.137606)
		(end 98.474784 -30.934914)
		(width 0.1397)
		(layer "F.Cu")
		(net "PCIE_SAS_CPU_TX_P3")
	)
	(segment
		(start 110.152688 -16.235172)
		(end 117.465348 -8.922512)
		(width 0.1397)
		(layer "F.Cu")
		(net "PCIE_SAS_CPU_TX_P3")
	)
	(segment
		(start 98.474784 -30.934914)
		(end 98.455226 -30.915102)
		(width 0.1397)
		(layer "F.Cu")
		(net "PCIE_SAS_CPU_TX_P3")
	)
	(segment
		(start 192.63233 -75.553824)
		(end 192.63233 -76.30922)
		(width 0.1397)
		(layer "F.Cu")
		(net "PCIE_SAS_CPU_TX_P3")
	)
	(via
		(at 192.929002 -77.0255)
		(size 0.5588)
		(drill 0.3048)
		(layers "F.Cu" "B.Cu")
		(net "PCIE_SAS_CPU_TX_P3")
	)
	(arc
		(start 133.553962 -8.636)
		(mid 133.928379 -8.710307)
		(end 134.245858 -8.922258)
		(width 0.1397)
		(layer "F.Cu")
		(net "PCIE_SAS_CPU_TX_P3")
	)
	(arc
		(start 106.465878 -16.632936)
		(mid 106.700595 -16.476136)
		(end 106.977434 -16.4211)
		(width 0.1397)
		(layer "F.Cu")
		(net "PCIE_SAS_CPU_TX_P3")
	)
	(arc
		(start 137.1854 -11.8618)
		(mid 137.608374 -12.494825)
		(end 137.7569 -13.241528)
		(width 0.1397)
		(layer "F.Cu")
		(net "PCIE_SAS_CPU_TX_P3")
	)
	(arc
		(start 98.222816 -25.543764)
		(mid 98.345591 -24.926534)
		(end 98.695256 -24.403304)
		(width 0.1397)
		(layer "F.Cu")
		(net "PCIE_SAS_CPU_TX_P3")
	)
	(arc
		(start 109.703616 -16.4211)
		(mid 109.94662 -16.372764)
		(end 110.152688 -16.235172)
		(width 0.1397)
		(layer "F.Cu")
		(net "PCIE_SAS_CPU_TX_P3")
	)
	(arc
		(start 191.638174 -73.9394)
		(mid 191.67939 -74.147076)
		(end 191.796924 -74.323194)
		(width 0.1397)
		(layer "F.Cu")
		(net "PCIE_SAS_CPU_TX_P3")
	)
	(arc
		(start 192.35293 -74.8792)
		(mid 192.559745 -75.18872)
		(end 192.63233 -75.553824)
		(width 0.1397)
		(layer "F.Cu")
		(net "PCIE_SAS_CPU_TX_P3")
	)
	(arc
		(start 98.75012 -33.399984)
		(mid 98.773402 -33.36514)
		(end 98.781616 -33.324038)
		(width 0.1397)
		(layer "F.Cu")
		(net "PCIE_SAS_CPU_TX_P3")
	)
	(arc
		(start 192.63233 -76.30922)
		(mid 192.709436 -76.69686)
		(end 192.929002 -77.0255)
		(width 0.1397)
		(layer "F.Cu")
		(net "PCIE_SAS_CPU_TX_P3")
	)
	(arc
		(start 191.029336 -71.60641)
		(mid 191.47984 -72.280821)
		(end 191.63792 -73.076308)
		(width 0.1397)
		(layer "F.Cu")
		(net "PCIE_SAS_CPU_TX_P3")
	)
	(arc
		(start 137.7569 -17.80794)
		(mid 137.853539 -18.293865)
		(end 138.128756 -18.70583)
		(width 0.1397)
		(layer "F.Cu")
		(net "PCIE_SAS_CPU_TX_P3")
	)
	(arc
		(start 117.465348 -8.922512)
		(mid 117.782662 -8.710426)
		(end 118.15699 -8.636)
		(width 0.1397)
		(layer "F.Cu")
		(net "PCIE_SAS_CPU_TX_P3")
	)
	(arc
		(start 98.78187 -31.38932)
		(mid 98.75468 -31.253097)
		(end 98.677476 -31.137606)
		(width 0.1397)
		(layer "F.Cu")
		(net "PCIE_SAS_CPU_TX_P3")
	)
	(arc
		(start 98.455226 -30.915102)
		(mid 98.283277 -30.65724)
		(end 98.222816 -30.353254)
		(width 0.1397)
		(layer "F.Cu")
		(net "PCIE_SAS_CPU_TX_P3")
	)
	(segment
		(start 193.090038 -79.033624)
		(end 192.927732 -79.033624)
		(width 0.1397)
		(layer "B.Cu")
		(net "PCIE_SAS_CPU_TX_P3")
	)
	(segment
		(start 193.449956 -78.24978)
		(end 193.449956 -78.673706)
		(width 0.1397)
		(layer "B.Cu")
		(net "PCIE_SAS_CPU_TX_P3")
	)
	(segment
		(start 192.60439 -78.55331)
		(end 192.60439 -77.44206)
		(width 0.1397)
		(layer "B.Cu")
		(net "PCIE_SAS_CPU_TX_P3")
	)
	(segment
		(start 192.669414 -77.285088)
		(end 192.929002 -77.0255)
		(width 0.1397)
		(layer "B.Cu")
		(net "PCIE_SAS_CPU_TX_P3")
	)
	(arc
		(start 192.927732 -79.033624)
		(mid 192.846471 -79.01746)
		(end 192.777618 -78.971394)
		(width 0.1397)
		(layer "B.Cu")
		(net "PCIE_SAS_CPU_TX_P3")
	)
	(arc
		(start 192.60439 -77.44206)
		(mid 192.621288 -77.357106)
		(end 192.669414 -77.285088)
		(width 0.1397)
		(layer "B.Cu")
		(net "PCIE_SAS_CPU_TX_P3")
	)
	(arc
		(start 193.449956 -78.673706)
		(mid 193.344538 -78.928206)
		(end 193.090038 -79.033624)
		(width 0.1397)
		(layer "B.Cu")
		(net "PCIE_SAS_CPU_TX_P3")
	)
	(arc
		(start 192.777618 -78.971394)
		(mid 192.649449 -78.779575)
		(end 192.60439 -78.55331)
		(width 0.1397)
		(layer "B.Cu")
		(net "PCIE_SAS_CPU_TX_P3")
	)
	(segment
		(start 316.1665 -115.8875)
		(end 315.468 -116.586)
		(width 0.508)
		(layer "F.Cu")
		(net "P3V3_STBY_VREG")
	)
	(segment
		(start 321.944746 -115.297458)
		(end 321.944746 -118.06301)
		(width 0.3048)
		(layer "F.Cu")
		(net "P3V3_STBY_VREG")
	)
	(segment
		(start 322.190872 -118.309136)
		(end 322.398136 -118.5164)
		(width 0.508)
		(layer "F.Cu")
		(net "P3V3_STBY_VREG")
	)
	(segment
		(start 316.1665 -115.824)
		(end 316.1665 -115.8875)
		(width 0.508)
		(layer "F.Cu")
		(net "P3V3_STBY_VREG")
	)
	(segment
		(start 317.754 -120.9675)
		(end 316.6745 -120.9675)
		(width 0.508)
		(layer "F.Cu")
		(net "P3V3_STBY_VREG")
	)
	(segment
		(start 322.398136 -118.5164)
		(end 323.215 -118.5164)
		(width 0.508)
		(layer "F.Cu")
		(net "P3V3_STBY_VREG")
	)
	(segment
		(start 321.944746 -118.06301)
		(end 322.190872 -118.309136)
		(width 0.3048)
		(layer "F.Cu")
		(net "P3V3_STBY_VREG")
	)
	(via
		(at 323.215 -118.5164)
		(size 0.5588)
		(drill 0.3048)
		(layers "F.Cu" "B.Cu")
		(net "P3V3_STBY_VREG")
	)
	(via
		(at 315.468 -116.586)
		(size 0.5588)
		(drill 0.3048)
		(layers "F.Cu" "B.Cu")
		(net "P3V3_STBY_VREG")
	)
	(via
		(at 323.088 -117.729)
		(size 0.7112)
		(drill 0.3556)
		(layers "F.Cu" "B.Cu")
		(net "P3V3_STBY_VREG")
	)
	(via
		(at 316.6745 -120.9675)
		(size 0.5588)
		(drill 0.3048)
		(layers "F.Cu" "B.Cu")
		(net "P3V3_STBY_VREG")
	)
	(segment
		(start 323.088 -118.3894)
		(end 323.215 -118.5164)
		(width 0.508)
		(layer "B.Cu")
		(net "P3V3_STBY_VREG")
	)
	(segment
		(start 323.088 -117.729)
		(end 323.088 -118.3894)
		(width 0.508)
		(layer "B.Cu")
		(net "P3V3_STBY_VREG")
	)
	(segment
		(start 315.468 -116.586)
		(end 315.468 -119.761)
		(width 0.508)
		(layer "In5.Cu")
		(net "P3V3_STBY_VREG")
	)
	(segment
		(start 321.2846 -116.586)
		(end 315.468 -116.586)
		(width 0.508)
		(layer "In5.Cu")
		(net "P3V3_STBY_VREG")
	)
	(segment
		(start 315.468 -119.761)
		(end 316.6745 -120.9675)
		(width 0.508)
		(layer "In5.Cu")
		(net "P3V3_STBY_VREG")
	)
	(segment
		(start 323.215 -118.5164)
		(end 321.2846 -116.586)
		(width 0.508)
		(layer "In5.Cu")
		(net "P3V3_STBY_VREG")
	)
	(segment
		(start 287.234884 -175.440086)
		(end 286.843978 -175.04918)
		(width 0.1143)
		(layer "F.Cu")
		(net "ROMA13")
	)
	(segment
		(start 286.843978 -175.04918)
		(end 286.835342 -175.04918)
		(width 0.1143)
		(layer "F.Cu")
		(net "ROMA13")
	)
	(via
		(at 286.835342 -175.04918)
		(size 0.508)
		(drill 0.254)
		(layers "F.Cu" "B.Cu")
		(net "ROMA13")
	)
	(via
		(at 276.1996 -174.244)
		(size 0.7112)
		(drill 0.3556)
		(layers "F.Cu" "B.Cu")
		(net "ROMA13")
	)
	(segment
		(start 279.189688 -174.244)
		(end 276.1996 -174.244)
		(width 0.1143)
		(layer "B.Cu")
		(net "ROMA13")
	)
	(segment
		(start 275.082 -174.244)
		(end 276.1996 -174.244)
		(width 0.1143)
		(layer "B.Cu")
		(net "ROMA13")
	)
	(segment
		(start 286.835342 -175.04918)
		(end 286.435546 -174.649384)
		(width 0.0889)
		(layer "B.Cu")
		(net "ROMA13")
	)
	(segment
		(start 284.74924 -174.8536)
		(end 279.799288 -174.8536)
		(width 0.1143)
		(layer "B.Cu")
		(net "ROMA13")
	)
	(segment
		(start 274.701 -174.625)
		(end 275.082 -174.244)
		(width 0.1143)
		(layer "B.Cu")
		(net "ROMA13")
	)
	(segment
		(start 284.953456 -174.649384)
		(end 284.74924 -174.8536)
		(width 0.1143)
		(layer "B.Cu")
		(net "ROMA13")
	)
	(segment
		(start 279.799288 -174.8536)
		(end 279.189688 -174.244)
		(width 0.1143)
		(layer "B.Cu")
		(net "ROMA13")
	)
	(segment
		(start 286.435546 -174.649384)
		(end 285.327852 -174.649384)
		(width 0.0889)
		(layer "B.Cu")
		(net "ROMA13")
	)
	(segment
		(start 285.327852 -174.649384)
		(end 284.953456 -174.649384)
		(width 0.1143)
		(layer "B.Cu")
		(net "ROMA13")
	)
	(segment
		(start 274.6375 -174.625)
		(end 274.701 -174.625)
		(width 0.1143)
		(layer "B.Cu")
		(net "ROMA13")
	)
	(segment
		(start 108.349796 -103.35006)
		(end 107.84967 -103.850186)
		(width 0.1016)
		(layer "F.Cu")
		(net "SAS_GF_EXP_RX_DP14")
	)
	(via
		(at 107.84967 -103.850186)
		(size 0.508)
		(drill 0.254)
		(layers "F.Cu" "B.Cu")
		(net "SAS_GF_EXP_RX_DP14")
	)
	(segment
		(start 87.122 -210.556602)
		(end 87.122 -173.821344)
		(width 0.1016)
		(layer "B.Cu")
		(net "SAS_GF_EXP_RX_DP14")
	)
	(segment
		(start 77.642212 -236.651292)
		(end 77.642212 -230.581708)
		(width 0.1016)
		(layer "B.Cu")
		(net "SAS_GF_EXP_RX_DP14")
	)
	(segment
		(start 77.880972 -246.902732)
		(end 77.880972 -246.597932)
		(width 0.1016)
		(layer "B.Cu")
		(net "SAS_GF_EXP_RX_DP14")
	)
	(segment
		(start 77.958442 -254.259588)
		(end 77.684122 -253.543816)
		(width 0.1016)
		(layer "B.Cu")
		(net "SAS_GF_EXP_RX_DP14")
	)
	(segment
		(start 107.424982 -104.394508)
		(end 107.444794 -104.346756)
		(width 0.1016)
		(layer "B.Cu")
		(net "SAS_GF_EXP_RX_DP14")
	)
	(segment
		(start 77.880972 -238.998252)
		(end 77.880972 -238.693452)
		(width 0.1016)
		(layer "B.Cu")
		(net "SAS_GF_EXP_RX_DP14")
	)
	(segment
		(start 107.444794 -104.346756)
		(end 107.465114 -104.298242)
		(width 0.1016)
		(layer "B.Cu")
		(net "SAS_GF_EXP_RX_DP14")
	)
	(segment
		(start 77.642212 -246.120412)
		(end 77.642212 -241.040412)
		(width 0.1016)
		(layer "B.Cu")
		(net "SAS_GF_EXP_RX_DP14")
	)
	(segment
		(start 77.642212 -229.321868)
		(end 77.642212 -229.017068)
		(width 0.1016)
		(layer "B.Cu")
		(net "SAS_GF_EXP_RX_DP14")
	)
	(segment
		(start 77.880972 -240.562892)
		(end 77.880972 -240.258092)
		(width 0.1016)
		(layer "B.Cu")
		(net "SAS_GF_EXP_RX_DP14")
	)
	(segment
		(start 107.465114 -104.298242)
		(end 107.465622 -104.29748)
		(width 0.1016)
		(layer "B.Cu")
		(net "SAS_GF_EXP_RX_DP14")
	)
	(segment
		(start 77.642212 -227.757228)
		(end 77.642212 -221.589346)
		(width 0.1016)
		(layer "B.Cu")
		(net "SAS_GF_EXP_RX_DP14")
	)
	(segment
		(start 78.105 -220.472)
		(end 86.487 -212.09)
		(width 0.1016)
		(layer "B.Cu")
		(net "SAS_GF_EXP_RX_DP14")
	)
	(segment
		(start 107.38739 -108.275628)
		(end 107.38739 -104.582722)
		(width 0.1016)
		(layer "B.Cu")
		(net "SAS_GF_EXP_RX_DP14")
	)
	(segment
		(start 78.000352 -256.50444)
		(end 78.000352 -254.486664)
		(width 0.1016)
		(layer "B.Cu")
		(net "SAS_GF_EXP_RX_DP14")
	)
	(segment
		(start 77.642212 -247.685052)
		(end 77.642212 -247.380252)
		(width 0.1016)
		(layer "B.Cu")
		(net "SAS_GF_EXP_RX_DP14")
	)
	(segment
		(start 77.880972 -248.467372)
		(end 77.880972 -248.162572)
		(width 0.1016)
		(layer "B.Cu")
		(net "SAS_GF_EXP_RX_DP14")
	)
	(segment
		(start 77.880972 -230.104188)
		(end 77.880972 -229.799388)
		(width 0.1016)
		(layer "B.Cu")
		(net "SAS_GF_EXP_RX_DP14")
	)
	(segment
		(start 77.880972 -237.433612)
		(end 77.880972 -237.128812)
		(width 0.1016)
		(layer "B.Cu")
		(net "SAS_GF_EXP_RX_DP14")
	)
	(segment
		(start 104.463342 -114.15395)
		(end 106.278934 -112.338358)
		(width 0.1016)
		(layer "B.Cu")
		(net "SAS_GF_EXP_RX_DP14")
	)
	(segment
		(start 104.190292 -154.35707)
		(end 104.190292 -114.81308)
		(width 0.1016)
		(layer "B.Cu")
		(net "SAS_GF_EXP_RX_DP14")
	)
	(segment
		(start 77.642212 -239.780572)
		(end 77.642212 -239.475772)
		(width 0.1016)
		(layer "B.Cu")
		(net "SAS_GF_EXP_RX_DP14")
	)
	(segment
		(start 87.890858 -171.965112)
		(end 103.26497 -156.591)
		(width 0.1016)
		(layer "B.Cu")
		(net "SAS_GF_EXP_RX_DP14")
	)
	(segment
		(start 77.880972 -228.539548)
		(end 77.880972 -228.234748)
		(width 0.1016)
		(layer "B.Cu")
		(net "SAS_GF_EXP_RX_DP14")
	)
	(segment
		(start 77.642212 -238.215932)
		(end 77.642212 -237.911132)
		(width 0.1016)
		(layer "B.Cu")
		(net "SAS_GF_EXP_RX_DP14")
	)
	(segment
		(start 106.660442 -111.416592)
		(end 106.660442 -110.030514)
		(width 0.1016)
		(layer "B.Cu")
		(net "SAS_GF_EXP_RX_DP14")
	)
	(segment
		(start 77.642212 -253.31674)
		(end 77.642212 -248.944892)
		(width 0.1016)
		(layer "B.Cu")
		(net "SAS_GF_EXP_RX_DP14")
	)
	(arc
		(start 103.26497 -156.591)
		(mid 103.949757 -155.56605)
		(end 104.190292 -154.35707)
		(width 0.1016)
		(layer "B.Cu")
		(net "SAS_GF_EXP_RX_DP14")
	)
	(arc
		(start 77.761592 -247.923812)
		(mid 77.672704 -247.819017)
		(end 77.642212 -247.685052)
		(width 0.1016)
		(layer "B.Cu")
		(net "SAS_GF_EXP_RX_DP14")
	)
	(arc
		(start 77.642212 -239.475772)
		(mid 77.672704 -239.341779)
		(end 77.761592 -239.237012)
		(width 0.1016)
		(layer "B.Cu")
		(net "SAS_GF_EXP_RX_DP14")
	)
	(arc
		(start 77.761592 -247.141492)
		(mid 77.85048 -247.036697)
		(end 77.880972 -246.902732)
		(width 0.1016)
		(layer "B.Cu")
		(net "SAS_GF_EXP_RX_DP14")
	)
	(arc
		(start 77.880972 -228.234748)
		(mid 77.85048 -228.100755)
		(end 77.761592 -227.995988)
		(width 0.1016)
		(layer "B.Cu")
		(net "SAS_GF_EXP_RX_DP14")
	)
	(arc
		(start 104.190292 -114.81308)
		(mid 104.26125 -114.45635)
		(end 104.463342 -114.15395)
		(width 0.1016)
		(layer "B.Cu")
		(net "SAS_GF_EXP_RX_DP14")
	)
	(arc
		(start 77.642212 -230.581708)
		(mid 77.672704 -230.447715)
		(end 77.761592 -230.342948)
		(width 0.1016)
		(layer "B.Cu")
		(net "SAS_GF_EXP_RX_DP14")
	)
	(arc
		(start 77.761592 -248.706132)
		(mid 77.85048 -248.601337)
		(end 77.880972 -248.467372)
		(width 0.1016)
		(layer "B.Cu")
		(net "SAS_GF_EXP_RX_DP14")
	)
	(arc
		(start 77.684122 -253.543816)
		(mid 77.652767 -253.432198)
		(end 77.642212 -253.31674)
		(width 0.1016)
		(layer "B.Cu")
		(net "SAS_GF_EXP_RX_DP14")
	)
	(arc
		(start 107.38739 -104.582722)
		(mid 107.39688 -104.486756)
		(end 107.424982 -104.394508)
		(width 0.1016)
		(layer "B.Cu")
		(net "SAS_GF_EXP_RX_DP14")
	)
	(arc
		(start 77.642212 -237.911132)
		(mid 77.672704 -237.777139)
		(end 77.761592 -237.672372)
		(width 0.1016)
		(layer "B.Cu")
		(net "SAS_GF_EXP_RX_DP14")
	)
	(arc
		(start 77.880972 -237.128812)
		(mid 77.85048 -236.994819)
		(end 77.761592 -236.890052)
		(width 0.1016)
		(layer "B.Cu")
		(net "SAS_GF_EXP_RX_DP14")
	)
	(arc
		(start 77.880972 -248.162572)
		(mid 77.85048 -248.028579)
		(end 77.761592 -247.923812)
		(width 0.1016)
		(layer "B.Cu")
		(net "SAS_GF_EXP_RX_DP14")
	)
	(arc
		(start 107.465622 -104.29748)
		(mid 107.47449 -104.280708)
		(end 107.48645 -104.265984)
		(width 0.1016)
		(layer "B.Cu")
		(net "SAS_GF_EXP_RX_DP14")
	)
	(arc
		(start 77.761592 -240.801652)
		(mid 77.85048 -240.696857)
		(end 77.880972 -240.562892)
		(width 0.1016)
		(layer "B.Cu")
		(net "SAS_GF_EXP_RX_DP14")
	)
	(arc
		(start 77.761592 -236.890052)
		(mid 77.672704 -236.785257)
		(end 77.642212 -236.651292)
		(width 0.1016)
		(layer "B.Cu")
		(net "SAS_GF_EXP_RX_DP14")
	)
	(arc
		(start 87.122 -173.821344)
		(mid 87.321823 -172.816766)
		(end 87.890858 -171.965112)
		(width 0.1016)
		(layer "B.Cu")
		(net "SAS_GF_EXP_RX_DP14")
	)
	(arc
		(start 77.761592 -229.560628)
		(mid 77.672798 -229.455814)
		(end 77.642212 -229.321868)
		(width 0.1016)
		(layer "B.Cu")
		(net "SAS_GF_EXP_RX_DP14")
	)
	(arc
		(start 77.761592 -246.359172)
		(mid 77.672704 -246.254377)
		(end 77.642212 -246.120412)
		(width 0.1016)
		(layer "B.Cu")
		(net "SAS_GF_EXP_RX_DP14")
	)
	(arc
		(start 78.000352 -254.486664)
		(mid 77.989814 -254.371203)
		(end 77.958442 -254.259588)
		(width 0.1016)
		(layer "B.Cu")
		(net "SAS_GF_EXP_RX_DP14")
	)
	(arc
		(start 77.761592 -230.342948)
		(mid 77.850386 -230.238134)
		(end 77.880972 -230.104188)
		(width 0.1016)
		(layer "B.Cu")
		(net "SAS_GF_EXP_RX_DP14")
	)
	(arc
		(start 77.761592 -227.995988)
		(mid 77.672798 -227.891174)
		(end 77.642212 -227.757228)
		(width 0.1016)
		(layer "B.Cu")
		(net "SAS_GF_EXP_RX_DP14")
	)
	(arc
		(start 77.642212 -248.944892)
		(mid 77.672704 -248.810899)
		(end 77.761592 -248.706132)
		(width 0.1016)
		(layer "B.Cu")
		(net "SAS_GF_EXP_RX_DP14")
	)
	(arc
		(start 77.761592 -239.237012)
		(mid 77.85048 -239.132217)
		(end 77.880972 -238.998252)
		(width 0.1016)
		(layer "B.Cu")
		(net "SAS_GF_EXP_RX_DP14")
	)
	(arc
		(start 77.761592 -237.672372)
		(mid 77.85048 -237.567577)
		(end 77.880972 -237.433612)
		(width 0.1016)
		(layer "B.Cu")
		(net "SAS_GF_EXP_RX_DP14")
	)
	(arc
		(start 107.48645 -104.265984)
		(mid 107.675068 -104.064207)
		(end 107.84967 -103.850186)
		(width 0.1016)
		(layer "B.Cu")
		(net "SAS_GF_EXP_RX_DP14")
	)
	(arc
		(start 106.660442 -110.030514)
		(mid 106.735499 -109.653177)
		(end 106.94924 -109.333284)
		(width 0.1016)
		(layer "B.Cu")
		(net "SAS_GF_EXP_RX_DP14")
	)
	(arc
		(start 77.642212 -221.589346)
		(mid 77.762493 -220.984655)
		(end 78.105 -220.472)
		(width 0.1016)
		(layer "B.Cu")
		(net "SAS_GF_EXP_RX_DP14")
	)
	(arc
		(start 86.487 -212.09)
		(mid 86.957 -211.386456)
		(end 87.122 -210.556602)
		(width 0.1016)
		(layer "B.Cu")
		(net "SAS_GF_EXP_RX_DP14")
	)
	(arc
		(start 77.880972 -238.693452)
		(mid 77.85048 -238.559459)
		(end 77.761592 -238.454692)
		(width 0.1016)
		(layer "B.Cu")
		(net "SAS_GF_EXP_RX_DP14")
	)
	(arc
		(start 77.642212 -241.040412)
		(mid 77.672704 -240.906419)
		(end 77.761592 -240.801652)
		(width 0.1016)
		(layer "B.Cu")
		(net "SAS_GF_EXP_RX_DP14")
	)
	(arc
		(start 77.761592 -238.454692)
		(mid 77.672704 -238.349897)
		(end 77.642212 -238.215932)
		(width 0.1016)
		(layer "B.Cu")
		(net "SAS_GF_EXP_RX_DP14")
	)
	(arc
		(start 77.761592 -228.778308)
		(mid 77.850386 -228.673494)
		(end 77.880972 -228.539548)
		(width 0.1016)
		(layer "B.Cu")
		(net "SAS_GF_EXP_RX_DP14")
	)
	(arc
		(start 77.761592 -240.019332)
		(mid 77.672704 -239.914537)
		(end 77.642212 -239.780572)
		(width 0.1016)
		(layer "B.Cu")
		(net "SAS_GF_EXP_RX_DP14")
	)
	(arc
		(start 77.642212 -247.380252)
		(mid 77.672704 -247.246259)
		(end 77.761592 -247.141492)
		(width 0.1016)
		(layer "B.Cu")
		(net "SAS_GF_EXP_RX_DP14")
	)
	(arc
		(start 106.94924 -109.333284)
		(mid 107.273507 -108.848028)
		(end 107.38739 -108.275628)
		(width 0.1016)
		(layer "B.Cu")
		(net "SAS_GF_EXP_RX_DP14")
	)
	(arc
		(start 77.880972 -240.258092)
		(mid 77.85048 -240.124099)
		(end 77.761592 -240.019332)
		(width 0.1016)
		(layer "B.Cu")
		(net "SAS_GF_EXP_RX_DP14")
	)
	(arc
		(start 77.642212 -229.017068)
		(mid 77.672704 -228.883075)
		(end 77.761592 -228.778308)
		(width 0.1016)
		(layer "B.Cu")
		(net "SAS_GF_EXP_RX_DP14")
	)
	(arc
		(start 77.880972 -246.597932)
		(mid 77.85048 -246.463939)
		(end 77.761592 -246.359172)
		(width 0.1016)
		(layer "B.Cu")
		(net "SAS_GF_EXP_RX_DP14")
	)
	(arc
		(start 77.880972 -229.799388)
		(mid 77.85048 -229.665395)
		(end 77.761592 -229.560628)
		(width 0.1016)
		(layer "B.Cu")
		(net "SAS_GF_EXP_RX_DP14")
	)
	(arc
		(start 106.278934 -112.338358)
		(mid 106.561401 -111.915432)
		(end 106.660442 -111.416592)
		(width 0.1016)
		(layer "B.Cu")
		(net "SAS_GF_EXP_RX_DP14")
	)
	(segment
		(start 322.944998 -115.297458)
		(end 322.944998 -116.569998)
		(width 0.254)
		(layer "F.Cu")
		(net "P3V3_STBY_VIN")
	)
	(segment
		(start 323.44487 -115.297458)
		(end 323.44487 -116.43487)
		(width 0.254)
		(layer "F.Cu")
		(net "P3V3_STBY_VIN")
	)
	(segment
		(start 324.944994 -115.297458)
		(end 324.944994 -116.410994)
		(width 0.254)
		(layer "F.Cu")
		(net "P3V3_STBY_VIN")
	)
	(segment
		(start 324.444868 -115.297458)
		(end 324.444868 -116.545868)
		(width 0.254)
		(layer "F.Cu")
		(net "P3V3_STBY_VIN")
	)
	(segment
		(start 323.944996 -115.297458)
		(end 323.944996 -116.553996)
		(width 0.254)
		(layer "F.Cu")
		(net "P3V3_STBY_VIN")
	)
	(segment
		(start 322.444872 -115.297458)
		(end 322.444872 -116.577872)
		(width 0.254)
		(layer "F.Cu")
		(net "P3V3_STBY_VIN")
	)
	(via
		(at 330.835 -115.57)
		(size 0.7112)
		(drill 0.3556)
		(layers "F.Cu" "B.Cu")
		(net "P3V3_STBY_VIN")
	)
	(segment
		(start 333.828136 -200.460864)
		(end 333.828136 -200.477628)
		(width 0.127)
		(layer "F.Cu")
		(net "EEPROM_A2_R")
	)
	(segment
		(start 334.55864 -198.16064)
		(end 334.55864 -200.11644)
		(width 0.127)
		(layer "F.Cu")
		(net "EEPROM_A2_R")
	)
	(segment
		(start 333.739236 -202.566778)
		(end 333.739236 -201.692764)
		(width 0.127)
		(layer "F.Cu")
		(net "EEPROM_A2_R")
	)
	(segment
		(start 334.55864 -200.11644)
		(end 334.407002 -200.268078)
		(width 0.127)
		(layer "F.Cu")
		(net "EEPROM_A2_R")
	)
	(segment
		(start 334.021176 -200.268078)
		(end 333.828136 -200.460864)
		(width 0.127)
		(layer "F.Cu")
		(net "EEPROM_A2_R")
	)
	(segment
		(start 333.701136 -203.462128)
		(end 333.739236 -202.566778)
		(width 0.127)
		(layer "F.Cu")
		(net "EEPROM_A2_R")
	)
	(segment
		(start 333.756 -200.549764)
		(end 333.756 -201.676)
		(width 0.127)
		(layer "F.Cu")
		(net "EEPROM_A2_R")
	)
	(segment
		(start 334.208628 -197.810628)
		(end 334.55864 -198.16064)
		(width 0.127)
		(layer "F.Cu")
		(net "EEPROM_A2_R")
	)
	(segment
		(start 334.407002 -200.268078)
		(end 334.021176 -200.268078)
		(width 0.127)
		(layer "F.Cu")
		(net "EEPROM_A2_R")
	)
	(segment
		(start 333.701136 -197.810628)
		(end 334.208628 -197.810628)
		(width 0.127)
		(layer "F.Cu")
		(net "EEPROM_A2_R")
	)
	(segment
		(start 333.828136 -200.477628)
		(end 333.756 -200.549764)
		(width 0.127)
		(layer "F.Cu")
		(net "EEPROM_A2_R")
	)
	(segment
		(start 333.739236 -201.692764)
		(end 333.756 -201.676)
		(width 0.127)
		(layer "F.Cu")
		(net "EEPROM_A2_R")
	)
	(via
		(at 333.756 -201.676)
		(size 0.7112)
		(drill 0.3556)
		(layers "F.Cu" "B.Cu")
		(net "EEPROM_A2_R")
	)
	(segment
		(start 110.349792 -102.350062)
		(end 109.849666 -102.850188)
		(width 0.1016)
		(layer "F.Cu")
		(net "SAS_GF_EXP_RX_DN12")
	)
	(via
		(at 109.849666 -102.850188)
		(size 0.508)
		(drill 0.254)
		(layers "F.Cu" "B.Cu")
		(net "SAS_GF_EXP_RX_DN12")
	)
	(segment
		(start 91.204288 -175.024542)
		(end 106.8324 -159.39643)
		(width 0.1016)
		(layer "B.Cu")
		(net "SAS_GF_EXP_RX_DN12")
	)
	(segment
		(start 108.806742 -113.425478)
		(end 108.806742 -107.535472)
		(width 0.1016)
		(layer "B.Cu")
		(net "SAS_GF_EXP_RX_DN12")
	)
	(segment
		(start 107.930442 -156.745432)
		(end 107.930442 -114.894614)
		(width 0.1016)
		(layer "B.Cu")
		(net "SAS_GF_EXP_RX_DN12")
	)
	(segment
		(start 109.276642 -105.736136)
		(end 109.276388 -105.736136)
		(width 0.1016)
		(layer "B.Cu")
		(net "SAS_GF_EXP_RX_DN12")
	)
	(segment
		(start 108.263436 -114.08918)
		(end 108.72089 -113.63198)
		(width 0.1016)
		(layer "B.Cu")
		(net "SAS_GF_EXP_RX_DN12")
	)
	(segment
		(start 109.281468 -103.948992)
		(end 109.281468 -103.768906)
		(width 0.1016)
		(layer "B.Cu")
		(net "SAS_GF_EXP_RX_DN12")
	)
	(segment
		(start 90.4621 -212.852)
		(end 90.4621 -176.81702)
		(width 0.1016)
		(layer "B.Cu")
		(net "SAS_GF_EXP_RX_DN12")
	)
	(segment
		(start 84.273644 -249.159268)
		(end 84.273644 -249.157744)
		(width 0.1016)
		(layer "B.Cu")
		(net "SAS_GF_EXP_RX_DN12")
	)
	(segment
		(start 109.24413 -105.535476)
		(end 109.118654 -105.159302)
		(width 0.1016)
		(layer "B.Cu")
		(net "SAS_GF_EXP_RX_DN12")
	)
	(segment
		(start 109.13491 -104.285542)
		(end 109.17809 -104.19842)
		(width 0.1016)
		(layer "B.Cu")
		(net "SAS_GF_EXP_RX_DN12")
	)
	(segment
		(start 83.288124 -246.462042)
		(end 83.288124 -221.850458)
		(width 0.1016)
		(layer "B.Cu")
		(net "SAS_GF_EXP_RX_DN12")
	)
	(segment
		(start 109.078268 -104.972358)
		(end 109.078268 -104.526588)
		(width 0.1016)
		(layer "B.Cu")
		(net "SAS_GF_EXP_RX_DN12")
	)
	(segment
		(start 83.870546 -220.444314)
		(end 89.754456 -214.560404)
		(width 0.1016)
		(layer "B.Cu")
		(net "SAS_GF_EXP_RX_DN12")
	)
	(segment
		(start 109.093 -106.84383)
		(end 109.19079 -106.745786)
		(width 0.1016)
		(layer "B.Cu")
		(net "SAS_GF_EXP_RX_DN12")
	)
	(segment
		(start 109.100112 -105.091738)
		(end 109.082078 -105.007664)
		(width 0.1016)
		(layer "B.Cu")
		(net "SAS_GF_EXP_RX_DN12")
	)
	(segment
		(start 84.999322 -256.50444)
		(end 84.999322 -254.51435)
		(width 0.1016)
		(layer "B.Cu")
		(net "SAS_GF_EXP_RX_DN12")
	)
	(segment
		(start 84.982558 -249.868182)
		(end 84.273644 -249.159268)
		(width 0.1016)
		(layer "B.Cu")
		(net "SAS_GF_EXP_RX_DN12")
	)
	(segment
		(start 109.467396 -103.319834)
		(end 109.787944 -102.999286)
		(width 0.1016)
		(layer "B.Cu")
		(net "SAS_GF_EXP_RX_DN12")
	)
	(segment
		(start 109.276642 -106.539284)
		(end 109.276642 -105.736136)
		(width 0.1016)
		(layer "B.Cu")
		(net "SAS_GF_EXP_RX_DN12")
	)
	(segment
		(start 85.328252 -253.720092)
		(end 85.328252 -250.702826)
		(width 0.1016)
		(layer "B.Cu")
		(net "SAS_GF_EXP_RX_DN12")
	)
	(segment
		(start 108.26369 -114.089434)
		(end 108.263436 -114.08918)
		(width 0.1016)
		(layer "B.Cu")
		(net "SAS_GF_EXP_RX_DN12")
	)
	(arc
		(start 108.806742 -107.535472)
		(mid 108.881082 -107.161178)
		(end 109.093 -106.84383)
		(width 0.1016)
		(layer "B.Cu")
		(net "SAS_GF_EXP_RX_DN12")
	)
	(arc
		(start 109.281468 -103.768906)
		(mid 109.329789 -103.525888)
		(end 109.467396 -103.319834)
		(width 0.1016)
		(layer "B.Cu")
		(net "SAS_GF_EXP_RX_DN12")
	)
	(arc
		(start 109.118654 -105.159302)
		(mid 109.108447 -105.125777)
		(end 109.100112 -105.091738)
		(width 0.1016)
		(layer "B.Cu")
		(net "SAS_GF_EXP_RX_DN12")
	)
	(arc
		(start 108.72089 -113.63198)
		(mid 108.784415 -113.53728)
		(end 108.806742 -113.425478)
		(width 0.1016)
		(layer "B.Cu")
		(net "SAS_GF_EXP_RX_DN12")
	)
	(arc
		(start 109.082078 -105.007664)
		(mid 109.079233 -104.990112)
		(end 109.078268 -104.972358)
		(width 0.1016)
		(layer "B.Cu")
		(net "SAS_GF_EXP_RX_DN12")
	)
	(arc
		(start 109.787944 -102.999286)
		(mid 109.833652 -102.930879)
		(end 109.849666 -102.850188)
		(width 0.1016)
		(layer "B.Cu")
		(net "SAS_GF_EXP_RX_DN12")
	)
	(arc
		(start 109.078268 -104.526588)
		(mid 109.092617 -104.402782)
		(end 109.13491 -104.285542)
		(width 0.1016)
		(layer "B.Cu")
		(net "SAS_GF_EXP_RX_DN12")
	)
	(arc
		(start 109.276388 -105.736136)
		(mid 109.268324 -105.634511)
		(end 109.24413 -105.535476)
		(width 0.1016)
		(layer "B.Cu")
		(net "SAS_GF_EXP_RX_DN12")
	)
	(arc
		(start 107.930442 -114.894614)
		(mid 108.016949 -114.458863)
		(end 108.26369 -114.089434)
		(width 0.1016)
		(layer "B.Cu")
		(net "SAS_GF_EXP_RX_DN12")
	)
	(arc
		(start 109.19079 -106.745786)
		(mid 109.254315 -106.651086)
		(end 109.276642 -106.539284)
		(width 0.1016)
		(layer "B.Cu")
		(net "SAS_GF_EXP_RX_DN12")
	)
	(arc
		(start 84.999322 -254.51435)
		(mid 85.042036 -254.29952)
		(end 85.16366 -254.117348)
		(width 0.1016)
		(layer "B.Cu")
		(net "SAS_GF_EXP_RX_DN12")
	)
	(arc
		(start 85.328252 -250.702826)
		(mid 85.238404 -250.25113)
		(end 84.982558 -249.868182)
		(width 0.1016)
		(layer "B.Cu")
		(net "SAS_GF_EXP_RX_DN12")
	)
	(arc
		(start 89.754456 -214.560404)
		(mid 90.278189 -213.776582)
		(end 90.4621 -212.852)
		(width 0.1016)
		(layer "B.Cu")
		(net "SAS_GF_EXP_RX_DN12")
	)
	(arc
		(start 83.288124 -221.850458)
		(mid 83.43948 -221.089453)
		(end 83.870546 -220.444314)
		(width 0.1016)
		(layer "B.Cu")
		(net "SAS_GF_EXP_RX_DN12")
	)
	(arc
		(start 84.273644 -249.157744)
		(mid 83.542081 -247.897189)
		(end 83.288124 -246.462042)
		(width 0.1016)
		(layer "B.Cu")
		(net "SAS_GF_EXP_RX_DN12")
	)
	(arc
		(start 85.16366 -254.117348)
		(mid 85.285498 -253.9351)
		(end 85.328252 -253.720092)
		(width 0.1016)
		(layer "B.Cu")
		(net "SAS_GF_EXP_RX_DN12")
	)
	(arc
		(start 106.8324 -159.39643)
		(mid 107.645098 -158.180142)
		(end 107.930442 -156.745432)
		(width 0.1016)
		(layer "B.Cu")
		(net "SAS_GF_EXP_RX_DN12")
	)
	(arc
		(start 109.17809 -104.19842)
		(mid 109.254609 -104.083996)
		(end 109.281468 -103.948992)
		(width 0.1016)
		(layer "B.Cu")
		(net "SAS_GF_EXP_RX_DN12")
	)
	(arc
		(start 90.4621 -176.81702)
		(mid 90.654889 -175.846952)
		(end 91.204288 -175.024542)
		(width 0.1016)
		(layer "B.Cu")
		(net "SAS_GF_EXP_RX_DN12")
	)
	(segment
		(start 316.611 -118.1735)
		(end 317.754 -118.1735)
		(width 0.254)
		(layer "F.Cu")
		(net "P3V3_STBY_MODE")
	)
	(segment
		(start 318.389 -117.5385)
		(end 318.389 -117.221)
		(width 0.254)
		(layer "F.Cu")
		(net "P3V3_STBY_MODE")
	)
	(segment
		(start 320.167 -117.221)
		(end 318.389 -117.221)
		(width 0.254)
		(layer "F.Cu")
		(net "P3V3_STBY_MODE")
	)
	(segment
		(start 320.944748 -115.297458)
		(end 320.944748 -116.443252)
		(width 0.254)
		(layer "F.Cu")
		(net "P3V3_STBY_MODE")
	)
	(segment
		(start 317.754 -118.1735)
		(end 318.389 -117.5385)
		(width 0.254)
		(layer "F.Cu")
		(net "P3V3_STBY_MODE")
	)
	(segment
		(start 320.944748 -116.443252)
		(end 320.167 -117.221)
		(width 0.254)
		(layer "F.Cu")
		(net "P3V3_STBY_MODE")
	)
	(via
		(at 318.389 -117.221)
		(size 0.7112)
		(drill 0.3556)
		(layers "F.Cu" "B.Cu")
		(net "P3V3_STBY_MODE")
	)
	(segment
		(start 332.431136 -209.350864)
		(end 331.724 -210.058)
		(width 0.127)
		(layer "F.Cu")
		(net "EEPROM_WP")
	)
	(segment
		(start 332.431136 -208.542128)
		(end 332.431136 -209.350864)
		(width 0.127)
		(layer "F.Cu")
		(net "EEPROM_WP")
	)
	(segment
		(start 331.343 -211.0105)
		(end 331.343 -210.439)
		(width 0.127)
		(layer "F.Cu")
		(net "EEPROM_WP")
	)
	(segment
		(start 331.343 -210.439)
		(end 331.724 -210.058)
		(width 0.127)
		(layer "F.Cu")
		(net "EEPROM_WP")
	)
	(via
		(at 331.724 -210.058)
		(size 0.7112)
		(drill 0.3556)
		(layers "F.Cu" "B.Cu")
		(net "EEPROM_WP")
	)
	(segment
		(start 263.2075 -46.5455)
		(end 265.43 -48.768)
		(width 0.254)
		(layer "F.Cu")
		(net "P3V3_STBY_PG")
	)
	(segment
		(start 2.1082 -217.8812)
		(end 2.0828 -217.8558)
		(width 0.254)
		(layer "F.Cu")
		(net "P3V3_STBY_PG")
	)
	(segment
		(start 5.8547 -216.9668)
		(end 4.3434 -216.9668)
		(width 0.254)
		(layer "F.Cu")
		(net "P3V3_STBY_PG")
	)
	(segment
		(start 265.43 -48.768)
		(end 267.843 -48.768)
		(width 0.254)
		(layer "F.Cu")
		(net "P3V3_STBY_PG")
	)
	(segment
		(start 260.4135 -46.5455)
		(end 263.2075 -46.5455)
		(width 0.254)
		(layer "F.Cu")
		(net "P3V3_STBY_PG")
	)
	(segment
		(start 258.8895 -30.6705)
		(end 257.556 -32.004)
		(width 0.254)
		(layer "F.Cu")
		(net "P3V3_STBY_PG")
	)
	(segment
		(start 4.3434 -216.9668)
		(end 3.429 -217.8812)
		(width 0.254)
		(layer "F.Cu")
		(net "P3V3_STBY_PG")
	)
	(segment
		(start 320.944748 -108.981748)
		(end 319.151 -107.188)
		(width 0.254)
		(layer "F.Cu")
		(net "P3V3_STBY_PG")
	)
	(segment
		(start 320.944748 -110.398814)
		(end 320.944748 -108.981748)
		(width 0.254)
		(layer "F.Cu")
		(net "P3V3_STBY_PG")
	)
	(segment
		(start 257.556 -43.688)
		(end 260.4135 -46.5455)
		(width 0.254)
		(layer "F.Cu")
		(net "P3V3_STBY_PG")
	)
	(segment
		(start 257.556 -32.004)
		(end 257.556 -43.688)
		(width 0.254)
		(layer "F.Cu")
		(net "P3V3_STBY_PG")
	)
	(segment
		(start 317.754 -119.0625)
		(end 317.754 -120.0785)
		(width 0.254)
		(layer "F.Cu")
		(net "P3V3_STBY_PG")
	)
	(segment
		(start 261.493 -30.6705)
		(end 258.8895 -30.6705)
		(width 0.254)
		(layer "F.Cu")
		(net "P3V3_STBY_PG")
	)
	(segment
		(start 3.429 -217.8812)
		(end 2.1082 -217.8812)
		(width 0.254)
		(layer "F.Cu")
		(net "P3V3_STBY_PG")
	)
	(segment
		(start 319.151 -107.188)
		(end 317.5 -107.188)
		(width 0.254)
		(layer "F.Cu")
		(net "P3V3_STBY_PG")
	)
	(segment
		(start 317.754 -120.0785)
		(end 316.9412 -120.0785)
		(width 0.254)
		(layer "F.Cu")
		(net "P3V3_STBY_PG")
	)
	(segment
		(start 267.843 -48.768)
		(end 268.351 -49.276)
		(width 0.254)
		(layer "F.Cu")
		(net "P3V3_STBY_PG")
	)
	(via
		(at 316.9412 -120.0785)
		(size 0.5588)
		(drill 0.3048)
		(layers "F.Cu" "B.Cu")
		(net "P3V3_STBY_PG")
	)
	(via
		(at 268.351 -49.276)
		(size 0.5588)
		(drill 0.3048)
		(layers "F.Cu" "B.Cu")
		(net "P3V3_STBY_PG")
	)
	(via
		(at 2.0828 -217.8558)
		(size 0.5588)
		(drill 0.3048)
		(layers "F.Cu" "B.Cu")
		(net "P3V3_STBY_PG")
	)
	(via
		(at 330.708 -120.65)
		(size 0.5588)
		(drill 0.3048)
		(layers "F.Cu" "B.Cu")
		(net "P3V3_STBY_PG")
	)
	(via
		(at 317.5 -107.188)
		(size 0.5588)
		(drill 0.3048)
		(layers "F.Cu" "B.Cu")
		(net "P3V3_STBY_PG")
	)
	(via
		(at 317.6143 -117.348)
		(size 0.5588)
		(drill 0.3048)
		(layers "F.Cu" "B.Cu")
		(net "P3V3_STBY_PG")
	)
	(via
		(at 320.802 -70.739)
		(size 0.5588)
		(drill 0.3048)
		(layers "F.Cu" "B.Cu")
		(net "P3V3_STBY_PG")
	)
	(via
		(at 327.152 -119.38)
		(size 0.7112)
		(drill 0.3556)
		(layers "F.Cu" "B.Cu")
		(net "P3V3_STBY_PG")
	)
	(segment
		(start 319.839086 -117.253766)
		(end 317.848234 -117.253766)
		(width 0.254)
		(layer "B.Cu")
		(net "P3V3_STBY_PG")
	)
	(segment
		(start 327.152 -119.38)
		(end 321.96532 -119.38)
		(width 0.254)
		(layer "B.Cu")
		(net "P3V3_STBY_PG")
	)
	(segment
		(start 330.327 -120.65)
		(end 330.708 -120.65)
		(width 0.254)
		(layer "B.Cu")
		(net "P3V3_STBY_PG")
	)
	(segment
		(start 321.96532 -119.38)
		(end 319.839086 -117.253766)
		(width 0.254)
		(layer "B.Cu")
		(net "P3V3_STBY_PG")
	)
	(segment
		(start 317.848234 -117.253766)
		(end 317.754 -117.348)
		(width 0.254)
		(layer "B.Cu")
		(net "P3V3_STBY_PG")
	)
	(segment
		(start 329.057 -119.38)
		(end 330.327 -120.65)
		(width 0.254)
		(layer "B.Cu")
		(net "P3V3_STBY_PG")
	)
	(segment
		(start 327.152 -119.38)
		(end 329.057 -119.38)
		(width 0.254)
		(layer "B.Cu")
		(net "P3V3_STBY_PG")
	)
	(segment
		(start 317.754 -117.348)
		(end 317.6143 -117.348)
		(width 0.254)
		(layer "B.Cu")
		(net "P3V3_STBY_PG")
	)
	(segment
		(start 107.0229 -250.7869)
		(end 105.918 -251.8918)
		(width 0.254)
		(layer "In2.Cu")
		(net "P3V3_STBY_PG")
	)
	(segment
		(start 98.0694 -251.4346)
		(end 97.613978 -251.890022)
		(width 0.254)
		(layer "In2.Cu")
		(net "P3V3_STBY_PG")
	)
	(segment
		(start 316.836552 -110.998)
		(end 317.043562 -110.998)
		(width 0.254)
		(layer "In2.Cu")
		(net "P3V3_STBY_PG")
	)
	(segment
		(start 74.803 -248.539)
		(end 30.726888 -248.539)
		(width 0.254)
		(layer "In2.Cu")
		(net "P3V3_STBY_PG")
	)
	(segment
		(start 338.3153 -173.124876)
		(end 338.3153 -213.936072)
		(width 0.254)
		(layer "In2.Cu")
		(net "P3V3_STBY_PG")
	)
	(segment
		(start 275.643594 -244.1829)
		(end 261.972044 -244.1829)
		(width 0.254)
		(layer "In2.Cu")
		(net "P3V3_STBY_PG")
	)
	(segment
		(start 250.932696 -195.111116)
		(end 234.367324 -195.111116)
		(width 0.254)
		(layer "In2.Cu")
		(net "P3V3_STBY_PG")
	)
	(segment
		(start 334.179672 -218.0717)
		(end 323.973444 -218.0717)
		(width 0.254)
		(layer "In2.Cu")
		(net "P3V3_STBY_PG")
	)
	(segment
		(start 213.868 -221.869)
		(end 200.45426 -235.28274)
		(width 0.254)
		(layer "In2.Cu")
		(net "P3V3_STBY_PG")
	)
	(segment
		(start 321.437 -80.391)
		(end 317.5 -84.328)
		(width 0.254)
		(layer "In2.Cu")
		(net "P3V3_STBY_PG")
	)
	(segment
		(start 298.617894 -243.42725)
		(end 276.399244 -243.42725)
		(width 0.254)
		(layer "In2.Cu")
		(net "P3V3_STBY_PG")
	)
	(segment
		(start 124.46 -249.174)
		(end 122.8471 -250.7869)
		(width 0.254)
		(layer "In2.Cu")
		(net "P3V3_STBY_PG")
	)
	(segment
		(start 337.1596 -146.042126)
		(end 340.592918 -149.475444)
		(width 0.254)
		(layer "In2.Cu")
		(net "P3V3_STBY_PG")
	)
	(segment
		(start 99.5426 -251.4346)
		(end 98.0694 -251.4346)
		(width 0.254)
		(layer "In2.Cu")
		(net "P3V3_STBY_PG")
	)
	(segment
		(start 331.1144 -132.6642)
		(end 337.1596 -138.7094)
		(width 0.254)
		(layer "In2.Cu")
		(net "P3V3_STBY_PG")
	)
	(segment
		(start 197.455028 -249.174)
		(end 124.46 -249.174)
		(width 0.254)
		(layer "In2.Cu")
		(net "P3V3_STBY_PG")
	)
	(segment
		(start 317.6143 -112.711738)
		(end 317.043562 -112.141)
		(width 0.254)
		(layer "In2.Cu")
		(net "P3V3_STBY_PG")
	)
	(segment
		(start 330.708 -120.65)
		(end 331.1144 -121.0564)
		(width 0.254)
		(layer "In2.Cu")
		(net "P3V3_STBY_PG")
	)
	(segment
		(start 316.9412 -120.0785)
		(end 316.9412 -119.1768)
		(width 0.254)
		(layer "In2.Cu")
		(net "P3V3_STBY_PG")
	)
	(segment
		(start 317.6143 -118.5037)
		(end 317.6143 -117.348)
		(width 0.254)
		(layer "In2.Cu")
		(net "P3V3_STBY_PG")
	)
	(segment
		(start 200.45426 -235.28274)
		(end 200.45426 -246.174768)
		(width 0.254)
		(layer "In2.Cu")
		(net "P3V3_STBY_PG")
	)
	(segment
		(start 122.8471 -250.7869)
		(end 107.0229 -250.7869)
		(width 0.254)
		(layer "In2.Cu")
		(net "P3V3_STBY_PG")
	)
	(segment
		(start 317.043562 -110.998)
		(end 317.5 -110.541562)
		(width 0.254)
		(layer "In2.Cu")
		(net "P3V3_STBY_PG")
	)
	(segment
		(start 8.001 -225.375216)
		(end 8.001 -222.030544)
		(width 0.254)
		(layer "In2.Cu")
		(net "P3V3_STBY_PG")
	)
	(segment
		(start 323.973444 -218.0717)
		(end 298.617894 -243.42725)
		(width 0.254)
		(layer "In2.Cu")
		(net "P3V3_STBY_PG")
	)
	(segment
		(start 252.095 -196.27342)
		(end 250.932696 -195.111116)
		(width 0.254)
		(layer "In2.Cu")
		(net "P3V3_STBY_PG")
	)
	(segment
		(start 317.043562 -112.141)
		(end 316.836552 -112.141)
		(width 0.254)
		(layer "In2.Cu")
		(net "P3V3_STBY_PG")
	)
	(segment
		(start 316.4967 -111.337852)
		(end 316.836552 -110.998)
		(width 0.254)
		(layer "In2.Cu")
		(net "P3V3_STBY_PG")
	)
	(segment
		(start 340.592918 -154.453082)
		(end 338.328 -156.718)
		(width 0.254)
		(layer "In2.Cu")
		(net "P3V3_STBY_PG")
	)
	(segment
		(start 316.4967 -111.801148)
		(end 316.4967 -111.337852)
		(width 0.254)
		(layer "In2.Cu")
		(net "P3V3_STBY_PG")
	)
	(segment
		(start 338.328 -156.718)
		(end 338.328 -172.302424)
		(width 0.254)
		(layer "In2.Cu")
		(net "P3V3_STBY_PG")
	)
	(segment
		(start 338.328 -172.302424)
		(end 338.142072 -172.488352)
		(width 0.254)
		(layer "In2.Cu")
		(net "P3V3_STBY_PG")
	)
	(segment
		(start 317.5 -110.541562)
		(end 317.5 -107.188)
		(width 0.254)
		(layer "In2.Cu")
		(net "P3V3_STBY_PG")
	)
	(segment
		(start 12.701016 -230.513128)
		(end 12.701016 -230.075232)
		(width 0.254)
		(layer "In2.Cu")
		(net "P3V3_STBY_PG")
	)
	(segment
		(start 320.802 -70.739)
		(end 320.802 -72.136)
		(width 0.254)
		(layer "In2.Cu")
		(net "P3V3_STBY_PG")
	)
	(segment
		(start 338.3153 -213.936072)
		(end 334.179672 -218.0717)
		(width 0.254)
		(layer "In2.Cu")
		(net "P3V3_STBY_PG")
	)
	(segment
		(start 317.5 -84.328)
		(end 317.5 -107.188)
		(width 0.254)
		(layer "In2.Cu")
		(net "P3V3_STBY_PG")
	)
	(segment
		(start 105.918 -251.8918)
		(end 99.9998 -251.8918)
		(width 0.254)
		(layer "In2.Cu")
		(net "P3V3_STBY_PG")
	)
	(segment
		(start 316.836552 -112.141)
		(end 316.4967 -111.801148)
		(width 0.254)
		(layer "In2.Cu")
		(net "P3V3_STBY_PG")
	)
	(segment
		(start 338.142072 -172.488352)
		(end 338.142072 -172.951648)
		(width 0.254)
		(layer "In2.Cu")
		(net "P3V3_STBY_PG")
	)
	(segment
		(start 338.142072 -172.951648)
		(end 338.3153 -173.124876)
		(width 0.254)
		(layer "In2.Cu")
		(net "P3V3_STBY_PG")
	)
	(segment
		(start 200.45426 -246.174768)
		(end 197.455028 -249.174)
		(width 0.254)
		(layer "In2.Cu")
		(net "P3V3_STBY_PG")
	)
	(segment
		(start 213.868 -215.61044)
		(end 213.868 -221.869)
		(width 0.254)
		(layer "In2.Cu")
		(net "P3V3_STBY_PG")
	)
	(segment
		(start 320.802 -72.136)
		(end 321.437 -72.771)
		(width 0.254)
		(layer "In2.Cu")
		(net "P3V3_STBY_PG")
	)
	(segment
		(start 3.826256 -217.8558)
		(end 2.0828 -217.8558)
		(width 0.254)
		(layer "In2.Cu")
		(net "P3V3_STBY_PG")
	)
	(segment
		(start 30.726888 -248.539)
		(end 12.701016 -230.513128)
		(width 0.254)
		(layer "In2.Cu")
		(net "P3V3_STBY_PG")
	)
	(segment
		(start 276.399244 -243.42725)
		(end 275.643594 -244.1829)
		(width 0.254)
		(layer "In2.Cu")
		(net "P3V3_STBY_PG")
	)
	(segment
		(start 340.592918 -149.475444)
		(end 340.592918 -154.453082)
		(width 0.254)
		(layer "In2.Cu")
		(net "P3V3_STBY_PG")
	)
	(segment
		(start 234.367324 -195.111116)
		(end 213.868 -215.61044)
		(width 0.254)
		(layer "In2.Cu")
		(net "P3V3_STBY_PG")
	)
	(segment
		(start 261.972044 -244.1829)
		(end 252.095 -234.305856)
		(width 0.254)
		(layer "In2.Cu")
		(net "P3V3_STBY_PG")
	)
	(segment
		(start 252.095 -234.305856)
		(end 252.095 -196.27342)
		(width 0.254)
		(layer "In2.Cu")
		(net "P3V3_STBY_PG")
	)
	(segment
		(start 78.154022 -251.890022)
		(end 74.803 -248.539)
		(width 0.254)
		(layer "In2.Cu")
		(net "P3V3_STBY_PG")
	)
	(segment
		(start 12.701016 -230.075232)
		(end 8.001 -225.375216)
		(width 0.254)
		(layer "In2.Cu")
		(net "P3V3_STBY_PG")
	)
	(segment
		(start 316.9412 -119.1768)
		(end 317.6143 -118.5037)
		(width 0.254)
		(layer "In2.Cu")
		(net "P3V3_STBY_PG")
	)
	(segment
		(start 99.9998 -251.8918)
		(end 99.5426 -251.4346)
		(width 0.254)
		(layer "In2.Cu")
		(net "P3V3_STBY_PG")
	)
	(segment
		(start 317.6143 -117.348)
		(end 317.6143 -112.711738)
		(width 0.254)
		(layer "In2.Cu")
		(net "P3V3_STBY_PG")
	)
	(segment
		(start 97.613978 -251.890022)
		(end 78.154022 -251.890022)
		(width 0.254)
		(layer "In2.Cu")
		(net "P3V3_STBY_PG")
	)
	(segment
		(start 8.001 -222.030544)
		(end 3.826256 -217.8558)
		(width 0.254)
		(layer "In2.Cu")
		(net "P3V3_STBY_PG")
	)
	(segment
		(start 321.437 -72.771)
		(end 321.437 -80.391)
		(width 0.254)
		(layer "In2.Cu")
		(net "P3V3_STBY_PG")
	)
	(segment
		(start 331.1144 -121.0564)
		(end 331.1144 -132.6642)
		(width 0.254)
		(layer "In2.Cu")
		(net "P3V3_STBY_PG")
	)
	(segment
		(start 337.1596 -138.7094)
		(end 337.1596 -146.042126)
		(width 0.254)
		(layer "In2.Cu")
		(net "P3V3_STBY_PG")
	)
	(segment
		(start 268.351 -53.213)
		(end 268.351 -49.276)
		(width 0.254)
		(layer "In5.Cu")
		(net "P3V3_STBY_PG")
	)
	(segment
		(start 276.728936 -62.738)
		(end 268.732 -54.741064)
		(width 0.254)
		(layer "In5.Cu")
		(net "P3V3_STBY_PG")
	)
	(segment
		(start 317.370206 -66.04)
		(end 306.959 -66.04)
		(width 0.254)
		(layer "In5.Cu")
		(net "P3V3_STBY_PG")
	)
	(segment
		(start 301.4218 -62.5602)
		(end 301.244 -62.738)
		(width 0.254)
		(layer "In5.Cu")
		(net "P3V3_STBY_PG")
	)
	(segment
		(start 306.197 -65.278)
		(end 304.701448 -65.278)
		(width 0.254)
		(layer "In5.Cu")
		(net "P3V3_STBY_PG")
	)
	(segment
		(start 304.701448 -65.278)
		(end 301.983648 -62.5602)
		(width 0.254)
		(layer "In5.Cu")
		(net "P3V3_STBY_PG")
	)
	(segment
		(start 292.227 -62.738)
		(end 276.728936 -62.738)
		(width 0.254)
		(layer "In5.Cu")
		(net "P3V3_STBY_PG")
	)
	(segment
		(start 297.815 -62.738)
		(end 296.672 -63.881)
		(width 0.254)
		(layer "In5.Cu")
		(net "P3V3_STBY_PG")
	)
	(segment
		(start 296.672 -63.881)
		(end 293.37 -63.881)
		(width 0.254)
		(layer "In5.Cu")
		(net "P3V3_STBY_PG")
	)
	(segment
		(start 301.983648 -62.5602)
		(end 301.4218 -62.5602)
		(width 0.254)
		(layer "In5.Cu")
		(net "P3V3_STBY_PG")
	)
	(segment
		(start 320.802 -70.739)
		(end 320.802 -69.471794)
		(width 0.254)
		(layer "In5.Cu")
		(net "P3V3_STBY_PG")
	)
	(segment
		(start 306.959 -66.04)
		(end 306.197 -65.278)
		(width 0.254)
		(layer "In5.Cu")
		(net "P3V3_STBY_PG")
	)
	(segment
		(start 301.244 -62.738)
		(end 297.815 -62.738)
		(width 0.254)
		(layer "In5.Cu")
		(net "P3V3_STBY_PG")
	)
	(segment
		(start 268.732 -54.741064)
		(end 268.732 -53.594)
		(width 0.254)
		(layer "In5.Cu")
		(net "P3V3_STBY_PG")
	)
	(segment
		(start 293.37 -63.881)
		(end 292.227 -62.738)
		(width 0.254)
		(layer "In5.Cu")
		(net "P3V3_STBY_PG")
	)
	(segment
		(start 320.802 -69.471794)
		(end 317.370206 -66.04)
		(width 0.254)
		(layer "In5.Cu")
		(net "P3V3_STBY_PG")
	)
	(segment
		(start 268.732 -53.594)
		(end 268.351 -53.213)
		(width 0.254)
		(layer "In5.Cu")
		(net "P3V3_STBY_PG")
	)
	(segment
		(start 276.5298 -183.071262)
		(end 276.5298 -182.866538)
		(width 0.1143)
		(layer "F.Cu")
		(net "ROMD4")
	)
	(segment
		(start 276.53615 -182.860188)
		(end 276.53615 -182.445914)
		(width 0.1143)
		(layer "F.Cu")
		(net "ROMD4")
	)
	(segment
		(start 275.832062 -183.769)
		(end 276.5298 -183.071262)
		(width 0.1143)
		(layer "F.Cu")
		(net "ROMD4")
	)
	(segment
		(start 285.010352 -180.576728)
		(end 278.401272 -180.576728)
		(width 0.1143)
		(layer "F.Cu")
		(net "ROMD4")
	)
	(segment
		(start 274.6375 -184.531)
		(end 275.832062 -183.769)
		(width 0.1143)
		(layer "F.Cu")
		(net "ROMD4")
	)
	(segment
		(start 276.5298 -182.866538)
		(end 276.53615 -182.860188)
		(width 0.1143)
		(layer "F.Cu")
		(net "ROMD4")
	)
	(segment
		(start 285.634938 -180.240178)
		(end 285.346902 -180.240178)
		(width 0.1143)
		(layer "F.Cu")
		(net "ROMD4")
	)
	(segment
		(start 278.401272 -180.576728)
		(end 278.13 -180.848)
		(width 0.1143)
		(layer "F.Cu")
		(net "ROMD4")
	)
	(segment
		(start 285.346902 -180.240178)
		(end 285.010352 -180.576728)
		(width 0.1143)
		(layer "F.Cu")
		(net "ROMD4")
	)
	(segment
		(start 276.8473 -182.1307)
		(end 278.13 -180.848)
		(width 0.1143)
		(layer "F.Cu")
		(net "ROMD4")
	)
	(segment
		(start 276.8473 -182.13451)
		(end 276.8473 -182.1307)
		(width 0.1143)
		(layer "F.Cu")
		(net "ROMD4")
	)
	(segment
		(start 276.53615 -182.445914)
		(end 276.8473 -182.13451)
		(width 0.1143)
		(layer "F.Cu")
		(net "ROMD4")
	)
	(via
		(at 278.13 -180.848)
		(size 0.7112)
		(drill 0.3556)
		(layers "F.Cu" "B.Cu")
		(net "ROMD4")
	)
	(segment
		(start 123.35002 -90.349832)
		(end 123.850146 -89.849706)
		(width 0.1016)
		(layer "F.Cu")
		(net "SAS_GF_EXP_RX_DP0")
	)
	(via
		(at 123.850146 -89.849706)
		(size 0.508)
		(drill 0.254)
		(layers "F.Cu" "B.Cu")
		(net "SAS_GF_EXP_RX_DP0")
	)
	(segment
		(start 149.44217 -251.49683)
		(end 148.74367 -250.79833)
		(width 0.1016)
		(layer "B.Cu")
		(net "SAS_GF_EXP_RX_DP0")
	)
	(segment
		(start 136.71423 -119.749316)
		(end 136.71423 -119.444516)
		(width 0.1016)
		(layer "B.Cu")
		(net "SAS_GF_EXP_RX_DP0")
	)
	(segment
		(start 136.47547 -134.935214)
		(end 136.47547 -121.791476)
		(width 0.1016)
		(layer "B.Cu")
		(net "SAS_GF_EXP_RX_DP0")
	)
	(segment
		(start 136.47547 -144.995138)
		(end 136.47547 -136.195054)
		(width 0.1016)
		(layer "B.Cu")
		(net "SAS_GF_EXP_RX_DP0")
	)
	(segment
		(start 136.71423 -135.717534)
		(end 136.71423 -135.412734)
		(width 0.1016)
		(layer "B.Cu")
		(net "SAS_GF_EXP_RX_DP0")
	)
	(segment
		(start 148.279612 -249.677936)
		(end 148.279612 -158.496)
		(width 0.1016)
		(layer "B.Cu")
		(net "SAS_GF_EXP_RX_DP0")
	)
	(segment
		(start 135.972042 -97.717102)
		(end 129.88417 -91.62923)
		(width 0.1016)
		(layer "B.Cu")
		(net "SAS_GF_EXP_RX_DP0")
	)
	(segment
		(start 124.361448 -90.120724)
		(end 124.305314 -90.064336)
		(width 0.1016)
		(layer "B.Cu")
		(net "SAS_GF_EXP_RX_DP0")
	)
	(segment
		(start 136.47547 -118.966996)
		(end 136.47547 -118.662196)
		(width 0.1016)
		(layer "B.Cu")
		(net "SAS_GF_EXP_RX_DP0")
	)
	(segment
		(start 128.803654 -91.181682)
		(end 127.483362 -91.181682)
		(width 0.1016)
		(layer "B.Cu")
		(net "SAS_GF_EXP_RX_DP0")
	)
	(segment
		(start 136.71423 -121.313956)
		(end 136.71423 -121.009156)
		(width 0.1016)
		(layer "B.Cu")
		(net "SAS_GF_EXP_RX_DP0")
	)
	(segment
		(start 150.000462 -256.50444)
		(end 150.000462 -254.402082)
		(width 0.1016)
		(layer "B.Cu")
		(net "SAS_GF_EXP_RX_DP0")
	)
	(segment
		(start 147.701254 -157.098746)
		(end 147.573746 -156.971746)
		(width 0.1016)
		(layer "B.Cu")
		(net "SAS_GF_EXP_RX_DP0")
	)
	(segment
		(start 136.47547 -120.531636)
		(end 136.47547 -120.226836)
		(width 0.1016)
		(layer "B.Cu")
		(net "SAS_GF_EXP_RX_DP0")
	)
	(segment
		(start 148.279612 -158.496)
		(end 148.279866 -158.496)
		(width 0.1016)
		(layer "B.Cu")
		(net "SAS_GF_EXP_RX_DP0")
	)
	(segment
		(start 149.952202 -254.159004)
		(end 149.8727 -253.967488)
		(width 0.1016)
		(layer "B.Cu")
		(net "SAS_GF_EXP_RX_DP0")
	)
	(segment
		(start 126.00305 -90.346022)
		(end 124.90577 -90.346022)
		(width 0.1016)
		(layer "B.Cu")
		(net "SAS_GF_EXP_RX_DP0")
	)
	(segment
		(start 136.71423 -118.184676)
		(end 136.71423 -117.879876)
		(width 0.1016)
		(layer "B.Cu")
		(net "SAS_GF_EXP_RX_DP0")
	)
	(segment
		(start 124.305314 -90.064336)
		(end 124.198126 -89.957148)
		(width 0.1016)
		(layer "B.Cu")
		(net "SAS_GF_EXP_RX_DP0")
	)
	(segment
		(start 147.573746 -156.971746)
		(end 137.0965 -146.4945)
		(width 0.1016)
		(layer "B.Cu")
		(net "SAS_GF_EXP_RX_DP0")
	)
	(segment
		(start 123.938792 -89.849706)
		(end 123.850146 -89.849706)
		(width 0.1016)
		(layer "B.Cu")
		(net "SAS_GF_EXP_RX_DP0")
	)
	(segment
		(start 127.118618 -91.030552)
		(end 126.738634 -90.650568)
		(width 0.1016)
		(layer "B.Cu")
		(net "SAS_GF_EXP_RX_DP0")
	)
	(segment
		(start 149.745192 -253.57963)
		(end 149.745192 -252.228858)
		(width 0.1016)
		(layer "B.Cu")
		(net "SAS_GF_EXP_RX_DP0")
	)
	(segment
		(start 136.47547 -117.402356)
		(end 136.47547 -98.932746)
		(width 0.1016)
		(layer "B.Cu")
		(net "SAS_GF_EXP_RX_DP0")
	)
	(segment
		(start 149.8727 -253.967488)
		(end 149.775926 -253.733554)
		(width 0.1016)
		(layer "B.Cu")
		(net "SAS_GF_EXP_RX_DP0")
	)
	(arc
		(start 136.59485 -117.641116)
		(mid 136.506056 -117.536302)
		(end 136.47547 -117.402356)
		(width 0.1016)
		(layer "B.Cu")
		(net "SAS_GF_EXP_RX_DP0")
	)
	(arc
		(start 136.71423 -117.879876)
		(mid 136.683738 -117.745883)
		(end 136.59485 -117.641116)
		(width 0.1016)
		(layer "B.Cu")
		(net "SAS_GF_EXP_RX_DP0")
	)
	(arc
		(start 136.59485 -135.956294)
		(mid 136.683644 -135.85148)
		(end 136.71423 -135.717534)
		(width 0.1016)
		(layer "B.Cu")
		(net "SAS_GF_EXP_RX_DP0")
	)
	(arc
		(start 136.47547 -120.226836)
		(mid 136.505962 -120.092843)
		(end 136.59485 -119.988076)
		(width 0.1016)
		(layer "B.Cu")
		(net "SAS_GF_EXP_RX_DP0")
	)
	(arc
		(start 136.47547 -98.932746)
		(mid 136.344643 -98.274857)
		(end 135.972042 -97.717102)
		(width 0.1016)
		(layer "B.Cu")
		(net "SAS_GF_EXP_RX_DP0")
	)
	(arc
		(start 136.59485 -121.552716)
		(mid 136.683644 -121.447902)
		(end 136.71423 -121.313956)
		(width 0.1016)
		(layer "B.Cu")
		(net "SAS_GF_EXP_RX_DP0")
	)
	(arc
		(start 129.88417 -91.62923)
		(mid 129.388411 -91.298038)
		(end 128.803654 -91.181682)
		(width 0.1016)
		(layer "B.Cu")
		(net "SAS_GF_EXP_RX_DP0")
	)
	(arc
		(start 136.59485 -118.423436)
		(mid 136.683644 -118.318622)
		(end 136.71423 -118.184676)
		(width 0.1016)
		(layer "B.Cu")
		(net "SAS_GF_EXP_RX_DP0")
	)
	(arc
		(start 136.71423 -135.412734)
		(mid 136.683738 -135.278741)
		(end 136.59485 -135.173974)
		(width 0.1016)
		(layer "B.Cu")
		(net "SAS_GF_EXP_RX_DP0")
	)
	(arc
		(start 137.0965 -146.4945)
		(mid 136.636851 -145.806587)
		(end 136.47547 -144.995138)
		(width 0.1016)
		(layer "B.Cu")
		(net "SAS_GF_EXP_RX_DP0")
	)
	(arc
		(start 148.279866 -158.496)
		(mid 148.12953 -157.739829)
		(end 147.701254 -157.098746)
		(width 0.1016)
		(layer "B.Cu")
		(net "SAS_GF_EXP_RX_DP0")
	)
	(arc
		(start 136.59485 -119.205756)
		(mid 136.506056 -119.100942)
		(end 136.47547 -118.966996)
		(width 0.1016)
		(layer "B.Cu")
		(net "SAS_GF_EXP_RX_DP0")
	)
	(arc
		(start 124.198126 -89.957148)
		(mid 124.079143 -89.877646)
		(end 123.938792 -89.849706)
		(width 0.1016)
		(layer "B.Cu")
		(net "SAS_GF_EXP_RX_DP0")
	)
	(arc
		(start 150.000462 -254.402082)
		(mid 149.988305 -254.278166)
		(end 149.952202 -254.159004)
		(width 0.1016)
		(layer "B.Cu")
		(net "SAS_GF_EXP_RX_DP0")
	)
	(arc
		(start 124.90577 -90.346022)
		(mid 124.693597 -90.31627)
		(end 124.497846 -90.229182)
		(width 0.1016)
		(layer "B.Cu")
		(net "SAS_GF_EXP_RX_DP0")
	)
	(arc
		(start 136.47547 -118.662196)
		(mid 136.505962 -118.528203)
		(end 136.59485 -118.423436)
		(width 0.1016)
		(layer "B.Cu")
		(net "SAS_GF_EXP_RX_DP0")
	)
	(arc
		(start 127.483362 -91.181682)
		(mid 127.285946 -91.142413)
		(end 127.118618 -91.030552)
		(width 0.1016)
		(layer "B.Cu")
		(net "SAS_GF_EXP_RX_DP0")
	)
	(arc
		(start 126.738634 -90.650568)
		(mid 126.40113 -90.425148)
		(end 126.00305 -90.346022)
		(width 0.1016)
		(layer "B.Cu")
		(net "SAS_GF_EXP_RX_DP0")
	)
	(arc
		(start 136.59485 -135.173974)
		(mid 136.506056 -135.06916)
		(end 136.47547 -134.935214)
		(width 0.1016)
		(layer "B.Cu")
		(net "SAS_GF_EXP_RX_DP0")
	)
	(arc
		(start 136.47547 -121.791476)
		(mid 136.505962 -121.657483)
		(end 136.59485 -121.552716)
		(width 0.1016)
		(layer "B.Cu")
		(net "SAS_GF_EXP_RX_DP0")
	)
	(arc
		(start 149.745192 -252.228858)
		(mid 149.666486 -251.832708)
		(end 149.44217 -251.49683)
		(width 0.1016)
		(layer "B.Cu")
		(net "SAS_GF_EXP_RX_DP0")
	)
	(arc
		(start 148.74367 -250.79833)
		(mid 148.400199 -250.284289)
		(end 148.279612 -249.677936)
		(width 0.1016)
		(layer "B.Cu")
		(net "SAS_GF_EXP_RX_DP0")
	)
	(arc
		(start 149.775926 -253.733554)
		(mid 149.752975 -253.658106)
		(end 149.745192 -253.57963)
		(width 0.1016)
		(layer "B.Cu")
		(net "SAS_GF_EXP_RX_DP0")
	)
	(arc
		(start 136.47547 -136.195054)
		(mid 136.505962 -136.061061)
		(end 136.59485 -135.956294)
		(width 0.1016)
		(layer "B.Cu")
		(net "SAS_GF_EXP_RX_DP0")
	)
	(arc
		(start 136.59485 -119.988076)
		(mid 136.683644 -119.883262)
		(end 136.71423 -119.749316)
		(width 0.1016)
		(layer "B.Cu")
		(net "SAS_GF_EXP_RX_DP0")
	)
	(arc
		(start 136.71423 -119.444516)
		(mid 136.683738 -119.310523)
		(end 136.59485 -119.205756)
		(width 0.1016)
		(layer "B.Cu")
		(net "SAS_GF_EXP_RX_DP0")
	)
	(arc
		(start 136.71423 -121.009156)
		(mid 136.683738 -120.875163)
		(end 136.59485 -120.770396)
		(width 0.1016)
		(layer "B.Cu")
		(net "SAS_GF_EXP_RX_DP0")
	)
	(arc
		(start 124.497846 -90.229182)
		(mid 124.426563 -90.178831)
		(end 124.361448 -90.120724)
		(width 0.1016)
		(layer "B.Cu")
		(net "SAS_GF_EXP_RX_DP0")
	)
	(arc
		(start 136.59485 -120.770396)
		(mid 136.506056 -120.665582)
		(end 136.47547 -120.531636)
		(width 0.1016)
		(layer "B.Cu")
		(net "SAS_GF_EXP_RX_DP0")
	)
	(segment
		(start 319.578736 -118.6688)
		(end 320.9798 -118.6688)
		(width 0.508)
		(layer "F.Cu")
		(net "P3V3_STBY_VDD")
	)
	(segment
		(start 321.444874 -116.705126)
		(end 321.047872 -117.102128)
		(width 0.3048)
		(layer "F.Cu")
		(net "P3V3_STBY_VDD")
	)
	(segment
		(start 321.444874 -115.297458)
		(end 321.444874 -116.705126)
		(width 0.3048)
		(layer "F.Cu")
		(net "P3V3_STBY_VDD")
	)
	(segment
		(start 320.9798 -117.6782)
		(end 321.047872 -117.610128)
		(width 0.3048)
		(layer "F.Cu")
		(net "P3V3_STBY_VDD")
	)
	(segment
		(start 319.396872 -118.486936)
		(end 319.578736 -118.6688)
		(width 0.508)
		(layer "F.Cu")
		(net "P3V3_STBY_VDD")
	)
	(segment
		(start 320.9798 -118.6688)
		(end 320.9798 -117.6782)
		(width 0.3048)
		(layer "F.Cu")
		(net "P3V3_STBY_VDD")
	)
	(segment
		(start 321.047872 -117.102128)
		(end 321.047872 -117.610128)
		(width 0.3048)
		(layer "F.Cu")
		(net "P3V3_STBY_VDD")
	)
	(via
		(at 321.047872 -117.610128)
		(size 0.7112)
		(drill 0.3556)
		(layers "F.Cu" "B.Cu")
		(net "P3V3_STBY_VDD")
	)
	(segment
		(start 332.431136 -201.748136)
		(end 332.431136 -203.462128)
		(width 0.127)
		(layer "F.Cu")
		(net "EEPROM_A1_R")
	)
	(segment
		(start 333.129636 -198.509128)
		(end 332.431136 -197.810628)
		(width 0.127)
		(layer "F.Cu")
		(net "EEPROM_A1_R")
	)
	(segment
		(start 332.541372 -200.477628)
		(end 333.129636 -199.889364)
		(width 0.127)
		(layer "F.Cu")
		(net "EEPROM_A1_R")
	)
	(segment
		(start 333.129636 -199.889364)
		(end 333.129636 -198.509128)
		(width 0.127)
		(layer "F.Cu")
		(net "EEPROM_A1_R")
	)
	(segment
		(start 332.431136 -200.477628)
		(end 332.541372 -200.477628)
		(width 0.127)
		(layer "F.Cu")
		(net "EEPROM_A1_R")
	)
	(segment
		(start 332.431136 -201.748136)
		(end 332.431136 -200.477628)
		(width 0.127)
		(layer "F.Cu")
		(net "EEPROM_A1_R")
	)
	(via
		(at 332.431136 -201.748136)
		(size 0.7112)
		(drill 0.3556)
		(layers "F.Cu" "B.Cu")
		(net "EEPROM_A1_R")
	)
	(segment
		(start 108.349796 -102.350062)
		(end 107.84967 -102.850188)
		(width 0.1016)
		(layer "F.Cu")
		(net "SAS_GF_EXP_RX_DN14")
	)
	(via
		(at 107.84967 -102.850188)
		(size 0.508)
		(drill 0.254)
		(layers "F.Cu" "B.Cu")
		(net "SAS_GF_EXP_RX_DN14")
	)
	(segment
		(start 106.317542 -111.416846)
		(end 106.317542 -110.030514)
		(width 0.1016)
		(layer "B.Cu")
		(net "SAS_GF_EXP_RX_DN14")
	)
	(segment
		(start 107.371642 -103.84409)
		(end 107.688888 -103.128318)
		(width 0.1016)
		(layer "B.Cu")
		(net "SAS_GF_EXP_RX_DN14")
	)
	(segment
		(start 107.245658 -104.021636)
		(end 107.246674 -104.02062)
		(width 0.1016)
		(layer "B.Cu")
		(net "SAS_GF_EXP_RX_DN14")
	)
	(segment
		(start 103.847392 -154.356816)
		(end 103.847392 -114.81308)
		(width 0.1016)
		(layer "B.Cu")
		(net "SAS_GF_EXP_RX_DN14")
	)
	(segment
		(start 87.648288 -171.722542)
		(end 103.0224 -156.34843)
		(width 0.1016)
		(layer "B.Cu")
		(net "SAS_GF_EXP_RX_DN14")
	)
	(segment
		(start 86.7791 -210.556602)
		(end 86.7791 -173.821598)
		(width 0.1016)
		(layer "B.Cu")
		(net "SAS_GF_EXP_RX_DN14")
	)
	(segment
		(start 77.86243 -220.22943)
		(end 86.24443 -211.84743)
		(width 0.1016)
		(layer "B.Cu")
		(net "SAS_GF_EXP_RX_DN14")
	)
	(segment
		(start 107.246674 -104.02062)
		(end 107.267248 -104.000554)
		(width 0.1016)
		(layer "B.Cu")
		(net "SAS_GF_EXP_RX_DN14")
	)
	(segment
		(start 104.220772 -113.91138)
		(end 106.036364 -112.095788)
		(width 0.1016)
		(layer "B.Cu")
		(net "SAS_GF_EXP_RX_DN14")
	)
	(segment
		(start 107.108244 -104.262428)
		(end 107.14863 -104.166162)
		(width 0.1016)
		(layer "B.Cu")
		(net "SAS_GF_EXP_RX_DN14")
	)
	(segment
		(start 107.04449 -108.275374)
		(end 107.04449 -104.582722)
		(width 0.1016)
		(layer "B.Cu")
		(net "SAS_GF_EXP_RX_DN14")
	)
	(segment
		(start 76.956412 -256.4003)
		(end 76.956412 -254.31877)
		(width 0.1016)
		(layer "B.Cu")
		(net "SAS_GF_EXP_RX_DN14")
	)
	(segment
		(start 77.299312 -253.49073)
		(end 77.299312 -221.589346)
		(width 0.1016)
		(layer "B.Cu")
		(net "SAS_GF_EXP_RX_DN14")
	)
	(arc
		(start 107.803696 -102.961186)
		(mid 107.837724 -102.91026)
		(end 107.84967 -102.850188)
		(width 0.1016)
		(layer "B.Cu")
		(net "SAS_GF_EXP_RX_DN14")
	)
	(arc
		(start 106.036364 -112.095788)
		(mid 106.244502 -111.784287)
		(end 106.317542 -111.416846)
		(width 0.1016)
		(layer "B.Cu")
		(net "SAS_GF_EXP_RX_DN14")
	)
	(arc
		(start 107.688888 -103.128318)
		(mid 107.738585 -103.039459)
		(end 107.803696 -102.961186)
		(width 0.1016)
		(layer "B.Cu")
		(net "SAS_GF_EXP_RX_DN14")
	)
	(arc
		(start 106.70667 -109.090714)
		(mid 106.956623 -108.716633)
		(end 107.04449 -108.275374)
		(width 0.1016)
		(layer "B.Cu")
		(net "SAS_GF_EXP_RX_DN14")
	)
	(arc
		(start 77.299312 -221.589346)
		(mid 77.445611 -220.853379)
		(end 77.86243 -220.22943)
		(width 0.1016)
		(layer "B.Cu")
		(net "SAS_GF_EXP_RX_DN14")
	)
	(arc
		(start 77.127862 -253.90475)
		(mid 77.254503 -253.715119)
		(end 77.299058 -253.491492)
		(width 0.1016)
		(layer "B.Cu")
		(net "SAS_GF_EXP_RX_DN14")
	)
	(arc
		(start 107.267248 -104.000554)
		(mid 107.327144 -103.92746)
		(end 107.371642 -103.84409)
		(width 0.1016)
		(layer "B.Cu")
		(net "SAS_GF_EXP_RX_DN14")
	)
	(arc
		(start 77.299058 -253.491492)
		(mid 77.299185 -253.491111)
		(end 77.299312 -253.49073)
		(width 0.1016)
		(layer "B.Cu")
		(net "SAS_GF_EXP_RX_DN14")
	)
	(arc
		(start 103.0224 -156.34843)
		(mid 103.632955 -155.43467)
		(end 103.847392 -154.356816)
		(width 0.1016)
		(layer "B.Cu")
		(net "SAS_GF_EXP_RX_DN14")
	)
	(arc
		(start 107.14863 -104.166162)
		(mid 107.189955 -104.089076)
		(end 107.245658 -104.021636)
		(width 0.1016)
		(layer "B.Cu")
		(net "SAS_GF_EXP_RX_DN14")
	)
	(arc
		(start 86.24443 -211.84743)
		(mid 86.64015 -211.255193)
		(end 86.7791 -210.556602)
		(width 0.1016)
		(layer "B.Cu")
		(net "SAS_GF_EXP_RX_DN14")
	)
	(arc
		(start 107.04449 -104.582722)
		(mid 107.0605 -104.419415)
		(end 107.108244 -104.262428)
		(width 0.1016)
		(layer "B.Cu")
		(net "SAS_GF_EXP_RX_DN14")
	)
	(arc
		(start 86.7791 -173.821598)
		(mid 87.004893 -172.685607)
		(end 87.648288 -171.722542)
		(width 0.1016)
		(layer "B.Cu")
		(net "SAS_GF_EXP_RX_DN14")
	)
	(arc
		(start 103.847392 -114.81308)
		(mid 103.944369 -114.325074)
		(end 104.220772 -113.91138)
		(width 0.1016)
		(layer "B.Cu")
		(net "SAS_GF_EXP_RX_DN14")
	)
	(arc
		(start 76.999592 -256.50444)
		(mid 76.967613 -256.456674)
		(end 76.956412 -256.4003)
		(width 0.1016)
		(layer "B.Cu")
		(net "SAS_GF_EXP_RX_DN14")
	)
	(arc
		(start 106.317542 -110.030514)
		(mid 106.418618 -109.521902)
		(end 106.70667 -109.090714)
		(width 0.1016)
		(layer "B.Cu")
		(net "SAS_GF_EXP_RX_DN14")
	)
	(arc
		(start 76.956412 -254.31877)
		(mid 77.000963 -254.094706)
		(end 77.127862 -253.90475)
		(width 0.1016)
		(layer "B.Cu")
		(net "SAS_GF_EXP_RX_DN14")
	)
	(via
		(at 325.247 -109.982)
		(size 0.7112)
		(drill 0.3556)
		(layers "F.Cu" "B.Cu")
		(net "P3V3_STBY_VBST_RC")
	)
	(segment
		(start 323.9262 -109.982)
		(end 325.247 -109.982)
		(width 0.508)
		(layer "B.Cu")
		(net "P3V3_STBY_VBST_RC")
	)
	(segment
		(start 325.247 -109.982)
		(end 326.263 -109.982)
		(width 0.508)
		(layer "B.Cu")
		(net "P3V3_STBY_VBST_RC")
	)
	(segment
		(start 286.038798 -178.22672)
		(end 286.032956 -178.232562)
		(width 0.1143)
		(layer "F.Cu")
		(net "ROMA5")
	)
	(segment
		(start 286.048196 -178.22672)
		(end 286.038798 -178.22672)
		(width 0.1143)
		(layer "F.Cu")
		(net "ROMA5")
	)
	(segment
		(start 286.434784 -177.840132)
		(end 286.048196 -178.22672)
		(width 0.1143)
		(layer "F.Cu")
		(net "ROMA5")
	)
	(via
		(at 277.7744 -181.8894)
		(size 0.7112)
		(drill 0.3556)
		(layers "F.Cu" "B.Cu")
		(net "ROMA5")
	)
	(via
		(at 286.032956 -178.232562)
		(size 0.508)
		(drill 0.254)
		(layers "F.Cu" "B.Cu")
		(net "ROMA5")
	)
	(segment
		(start 277.7744 -181.8894)
		(end 277.797768 -181.866032)
		(width 0.1143)
		(layer "B.Cu")
		(net "ROMA5")
	)
	(segment
		(start 277.4188 -182.245)
		(end 277.7744 -181.8894)
		(width 0.1143)
		(layer "B.Cu")
		(net "ROMA5")
	)
	(segment
		(start 277.797768 -181.864)
		(end 281.475688 -178.18608)
		(width 0.1143)
		(layer "B.Cu")
		(net "ROMA5")
	)
	(segment
		(start 275.59 -181.737)
		(end 276.098 -182.245)
		(width 0.1143)
		(layer "B.Cu")
		(net "ROMA5")
	)
	(segment
		(start 274.6375 -181.737)
		(end 275.59 -181.737)
		(width 0.1143)
		(layer "B.Cu")
		(net "ROMA5")
	)
	(segment
		(start 281.475688 -178.18608)
		(end 283.375608 -178.18608)
		(width 0.1143)
		(layer "B.Cu")
		(net "ROMA5")
	)
	(segment
		(start 283.42209 -178.232562)
		(end 286.032956 -178.232562)
		(width 0.1143)
		(layer "B.Cu")
		(net "ROMA5")
	)
	(segment
		(start 276.098 -182.245)
		(end 277.4188 -182.245)
		(width 0.1143)
		(layer "B.Cu")
		(net "ROMA5")
	)
	(segment
		(start 277.797768 -181.866032)
		(end 277.797768 -181.864)
		(width 0.1143)
		(layer "B.Cu")
		(net "ROMA5")
	)
	(segment
		(start 283.375608 -178.18608)
		(end 283.42209 -178.232562)
		(width 0.1143)
		(layer "B.Cu")
		(net "ROMA5")
	)
	(segment
		(start 174.314358 -15.24)
		(end 173.954694 -14.880336)
		(width 0.1143)
		(layer "F.Cu")
		(net "TEMP_SENSOR_DXN_BJT")
	)
	(segment
		(start 178.8795 -16.129)
		(end 176.53 -16.129)
		(width 0.1143)
		(layer "F.Cu")
		(net "TEMP_SENSOR_DXN_BJT")
	)
	(segment
		(start 175.641 -15.24)
		(end 174.314358 -15.24)
		(width 0.1143)
		(layer "F.Cu")
		(net "TEMP_SENSOR_DXN_BJT")
	)
	(segment
		(start 178.8795 -17.272)
		(end 178.8795 -16.129)
		(width 0.1143)
		(layer "F.Cu")
		(net "TEMP_SENSOR_DXN_BJT")
	)
	(segment
		(start 176.53 -16.129)
		(end 175.641 -15.24)
		(width 0.1143)
		(layer "F.Cu")
		(net "TEMP_SENSOR_DXN_BJT")
	)
	(via
		(at 176.53 -16.129)
		(size 0.7112)
		(drill 0.3556)
		(layers "F.Cu" "B.Cu")
		(net "TEMP_SENSOR_DXN_BJT")
	)
	(via
		(at 173.954694 -14.880336)
		(size 0.5588)
		(drill 0.3048)
		(layers "F.Cu" "B.Cu")
		(net "TEMP_SENSOR_DXN_BJT")
	)
	(segment
		(start 105.914952 -6.964934)
		(end 112.415066 -6.964934)
		(width 0.127)
		(layer "In2.Cu")
		(net "TEMP_SENSOR_DXN_BJT")
	)
	(segment
		(start 112.415066 -6.964934)
		(end 121.833132 -16.383)
		(width 0.127)
		(layer "In2.Cu")
		(net "TEMP_SENSOR_DXN_BJT")
	)
	(segment
		(start 136.652 -16.383)
		(end 145.4912 -25.2222)
		(width 0.127)
		(layer "In2.Cu")
		(net "TEMP_SENSOR_DXN_BJT")
	)
	(segment
		(start 164.4523 -25.1587)
		(end 173.7487 -15.8623)
		(width 0.127)
		(layer "In2.Cu")
		(net "TEMP_SENSOR_DXN_BJT")
	)
	(segment
		(start 145.4912 -25.2222)
		(end 163.942268 -25.2222)
		(width 0.127)
		(layer "In2.Cu")
		(net "TEMP_SENSOR_DXN_BJT")
	)
	(segment
		(start 163.942268 -25.2222)
		(end 164.005768 -25.1587)
		(width 0.127)
		(layer "In2.Cu")
		(net "TEMP_SENSOR_DXN_BJT")
	)
	(segment
		(start 164.005768 -25.1587)
		(end 164.4523 -25.1587)
		(width 0.127)
		(layer "In2.Cu")
		(net "TEMP_SENSOR_DXN_BJT")
	)
	(segment
		(start 104.950006 -5.999988)
		(end 105.914952 -6.964934)
		(width 0.127)
		(layer "In2.Cu")
		(net "TEMP_SENSOR_DXN_BJT")
	)
	(segment
		(start 173.7487 -15.8623)
		(end 173.7487 -15.08633)
		(width 0.127)
		(layer "In2.Cu")
		(net "TEMP_SENSOR_DXN_BJT")
	)
	(segment
		(start 121.833132 -16.383)
		(end 136.652 -16.383)
		(width 0.127)
		(layer "In2.Cu")
		(net "TEMP_SENSOR_DXN_BJT")
	)
	(segment
		(start 173.7487 -15.08633)
		(end 173.954694 -14.880336)
		(width 0.127)
		(layer "In2.Cu")
		(net "TEMP_SENSOR_DXN_BJT")
	)
	(segment
		(start 313.563 -111.506)
		(end 312.801 -111.506)
		(width 0.254)
		(layer "F.Cu")
		(net "AGND_P3V3_STBY")
	)
	(segment
		(start 314.198 -117.729)
		(end 314.198 -116.6495)
		(width 0.254)
		(layer "F.Cu")
		(net "AGND_P3V3_STBY")
	)
	(segment
		(start 314.198 -116.6495)
		(end 316.1665 -114.681)
		(width 0.254)
		(layer "F.Cu")
		(net "AGND_P3V3_STBY")
	)
	(segment
		(start 311.531 -111.8235)
		(end 312.4835 -111.8235)
		(width 0.254)
		(layer "F.Cu")
		(net "AGND_P3V3_STBY")
	)
	(segment
		(start 316.1665 -114.0841)
		(end 317.2206 -113.03)
		(width 0.254)
		(layer "F.Cu")
		(net "AGND_P3V3_STBY")
	)
	(segment
		(start 310.515 -110.6805)
		(end 311.531 -110.6805)
		(width 0.254)
		(layer "F.Cu")
		(net "AGND_P3V3_STBY")
	)
	(segment
		(start 316.357 -112.1664)
		(end 317.2206 -113.03)
		(width 0.254)
		(layer "F.Cu")
		(net "AGND_P3V3_STBY")
	)
	(segment
		(start 316.1665 -114.681)
		(end 316.1665 -114.0841)
		(width 0.254)
		(layer "F.Cu")
		(net "AGND_P3V3_STBY")
	)
	(segment
		(start 311.531 -110.6805)
		(end 311.531 -111.8235)
		(width 0.254)
		(layer "F.Cu")
		(net "AGND_P3V3_STBY")
	)
	(segment
		(start 315.722 -109.601)
		(end 317.0555 -109.601)
		(width 0.254)
		(layer "F.Cu")
		(net "AGND_P3V3_STBY")
	)
	(segment
		(start 316.357 -110.2995)
		(end 316.357 -112.1664)
		(width 0.254)
		(layer "F.Cu")
		(net "AGND_P3V3_STBY")
	)
	(segment
		(start 312.4835 -111.8235)
		(end 312.801 -111.506)
		(width 0.254)
		(layer "F.Cu")
		(net "AGND_P3V3_STBY")
	)
	(segment
		(start 316.611 -119.0625)
		(end 315.468 -119.0625)
		(width 0.254)
		(layer "F.Cu")
		(net "AGND_P3V3_STBY")
	)
	(segment
		(start 314.198 -118.745)
		(end 314.198 -117.729)
		(width 0.254)
		(layer "F.Cu")
		(net "AGND_P3V3_STBY")
	)
	(segment
		(start 315.468 -119.0625)
		(end 314.5155 -119.0625)
		(width 0.254)
		(layer "F.Cu")
		(net "AGND_P3V3_STBY")
	)
	(segment
		(start 314.5155 -119.0625)
		(end 314.198 -118.745)
		(width 0.254)
		(layer "F.Cu")
		(net "AGND_P3V3_STBY")
	)
	(segment
		(start 317.0555 -109.601)
		(end 316.357 -110.2995)
		(width 0.254)
		(layer "F.Cu")
		(net "AGND_P3V3_STBY")
	)
	(via
		(at 313.563 -111.506)
		(size 0.5588)
		(drill 0.3048)
		(layers "F.Cu" "B.Cu")
		(net "AGND_P3V3_STBY")
	)
	(via
		(at 315.722 -109.601)
		(size 0.5588)
		(drill 0.3048)
		(layers "F.Cu" "B.Cu")
		(net "AGND_P3V3_STBY")
	)
	(via
		(at 312.801 -111.506)
		(size 0.7112)
		(drill 0.3556)
		(layers "F.Cu" "B.Cu")
		(net "AGND_P3V3_STBY")
	)
	(via
		(at 314.198 -117.729)
		(size 0.7112)
		(drill 0.3556)
		(layers "F.Cu" "B.Cu")
		(net "AGND_P3V3_STBY")
	)
	(segment
		(start 315.722 -109.601)
		(end 313.817 -111.506)
		(width 0.254)
		(layer "In5.Cu")
		(net "AGND_P3V3_STBY")
	)
	(segment
		(start 313.817 -111.506)
		(end 313.563 -111.506)
		(width 0.254)
		(layer "In5.Cu")
		(net "AGND_P3V3_STBY")
	)
	(segment
		(start 293.634922 -169.040048)
		(end 294.030146 -168.644824)
		(width 0.1143)
		(layer "F.Cu")
		(net "RMII0_PHY_BMC_C_RXD0")
	)
	(via
		(at 293.751 -167.005)
		(size 0.7112)
		(drill 0.3556)
		(layers "F.Cu" "B.Cu")
		(net "RMII0_PHY_BMC_C_RXD0")
	)
	(via
		(at 294.030146 -168.644824)
		(size 0.508)
		(drill 0.254)
		(layers "F.Cu" "B.Cu")
		(net "RMII0_PHY_BMC_C_RXD0")
	)
	(segment
		(start 296.164 -164.767768)
		(end 293.926768 -167.005)
		(width 0.1143)
		(layer "B.Cu")
		(net "RMII0_PHY_BMC_C_RXD0")
	)
	(segment
		(start 293.751 -168.365678)
		(end 293.751 -167.005)
		(width 0.1143)
		(layer "B.Cu")
		(net "RMII0_PHY_BMC_C_RXD0")
	)
	(segment
		(start 296.164 -164.6555)
		(end 296.164 -164.767768)
		(width 0.1143)
		(layer "B.Cu")
		(net "RMII0_PHY_BMC_C_RXD0")
	)
	(segment
		(start 294.030146 -168.644824)
		(end 293.751 -168.365678)
		(width 0.1143)
		(layer "B.Cu")
		(net "RMII0_PHY_BMC_C_RXD0")
	)
	(segment
		(start 293.926768 -167.005)
		(end 293.751 -167.005)
		(width 0.1143)
		(layer "B.Cu")
		(net "RMII0_PHY_BMC_C_RXD0")
	)
	(segment
		(start 260.7945 -42.1005)
		(end 261.112 -41.783)
		(width 0.508)
		(layer "F.Cu")
		(net "P1V8_STBY_VREG")
	)
	(segment
		(start 260.7945 -42.799)
		(end 260.7945 -42.1005)
		(width 0.508)
		(layer "F.Cu")
		(net "P1V8_STBY_VREG")
	)
	(segment
		(start 265.937746 -42.798746)
		(end 266.192 -43.053)
		(width 0.3048)
		(layer "F.Cu")
		(net "P1V8_STBY_VREG")
	)
	(segment
		(start 267.5128 -43.053)
		(end 268.4018 -43.942)
		(width 0.3048)
		(layer "F.Cu")
		(net "P1V8_STBY_VREG")
	)
	(segment
		(start 265.937746 -41.891458)
		(end 265.937746 -42.798746)
		(width 0.3048)
		(layer "F.Cu")
		(net "P1V8_STBY_VREG")
	)
	(segment
		(start 266.192 -43.053)
		(end 267.5128 -43.053)
		(width 0.3048)
		(layer "F.Cu")
		(net "P1V8_STBY_VREG")
	)
	(segment
		(start 268.537436 -44.077636)
		(end 269.4686 -44.077636)
		(width 0.508)
		(layer "F.Cu")
		(net "P1V8_STBY_VREG")
	)
	(segment
		(start 268.4018 -43.942)
		(end 268.537436 -44.077636)
		(width 0.508)
		(layer "F.Cu")
		(net "P1V8_STBY_VREG")
	)
	(via
		(at 261.112 -41.783)
		(size 0.5588)
		(drill 0.3048)
		(layers "F.Cu" "B.Cu")
		(net "P1V8_STBY_VREG")
	)
	(via
		(at 266.962636 -44.077636)
		(size 0.7112)
		(drill 0.3556)
		(layers "F.Cu" "B.Cu")
		(net "P1V8_STBY_VREG")
	)
	(via
		(at 269.4686 -44.077636)
		(size 0.5588)
		(drill 0.3048)
		(layers "F.Cu" "B.Cu")
		(net "P1V8_STBY_VREG")
	)
	(segment
		(start 266.962636 -44.077636)
		(end 263.406636 -44.077636)
		(width 0.508)
		(layer "B.Cu")
		(net "P1V8_STBY_VREG")
	)
	(segment
		(start 263.406636 -44.077636)
		(end 261.112 -41.783)
		(width 0.508)
		(layer "B.Cu")
		(net "P1V8_STBY_VREG")
	)
	(segment
		(start 269.4686 -44.077636)
		(end 266.962636 -44.077636)
		(width 0.508)
		(layer "B.Cu")
		(net "P1V8_STBY_VREG")
	)
	(segment
		(start 261.366 -38.6715)
		(end 261.366 -41.529)
		(width 0.508)
		(layer "B.Cu")
		(net "P1V8_STBY_VREG")
	)
	(segment
		(start 263.0805 -36.957)
		(end 261.366 -38.6715)
		(width 0.508)
		(layer "B.Cu")
		(net "P1V8_STBY_VREG")
	)
	(segment
		(start 261.366 -41.529)
		(end 261.112 -41.783)
		(width 0.508)
		(layer "B.Cu")
		(net "P1V8_STBY_VREG")
	)
	(segment
		(start 286.86252 -179.812442)
		(end 286.86252 -179.822094)
		(width 0.1143)
		(layer "F.Cu")
		(net "ROMD5")
	)
	(segment
		(start 287.234884 -179.440078)
		(end 286.86252 -179.812442)
		(width 0.1143)
		(layer "F.Cu")
		(net "ROMD5")
	)
	(segment
		(start 286.86252 -179.822094)
		(end 286.83839 -179.846224)
		(width 0.1143)
		(layer "F.Cu")
		(net "ROMD5")
	)
	(via
		(at 286.83839 -179.846224)
		(size 0.508)
		(drill 0.254)
		(layers "F.Cu" "B.Cu")
		(net "ROMD5")
	)
	(via
		(at 282.6004 -181.1274)
		(size 0.7112)
		(drill 0.3556)
		(layers "F.Cu" "B.Cu")
		(net "ROMD5")
	)
	(segment
		(start 286.217614 -180.239416)
		(end 286.610806 -179.846224)
		(width 0.0889)
		(layer "B.Cu")
		(net "ROMD5")
	)
	(segment
		(start 285.20136 -180.39588)
		(end 285.357824 -180.239416)
		(width 0.0889)
		(layer "B.Cu")
		(net "ROMD5")
	)
	(segment
		(start 285.357824 -180.239416)
		(end 286.217614 -180.239416)
		(width 0.0889)
		(layer "B.Cu")
		(net "ROMD5")
	)
	(segment
		(start 283.33192 -180.39588)
		(end 285.20136 -180.39588)
		(width 0.1143)
		(layer "B.Cu")
		(net "ROMD5")
	)
	(segment
		(start 274.6375 -184.785)
		(end 275.1455 -185.293)
		(width 0.1143)
		(layer "B.Cu")
		(net "ROMD5")
	)
	(segment
		(start 275.1455 -185.293)
		(end 278.4348 -185.293)
		(width 0.1143)
		(layer "B.Cu")
		(net "ROMD5")
	)
	(segment
		(start 286.610806 -179.846224)
		(end 286.83839 -179.846224)
		(width 0.0889)
		(layer "B.Cu")
		(net "ROMD5")
	)
	(segment
		(start 278.4348 -185.293)
		(end 282.6004 -181.1274)
		(width 0.1143)
		(layer "B.Cu")
		(net "ROMD5")
	)
	(segment
		(start 282.6004 -181.1274)
		(end 283.33192 -180.39588)
		(width 0.1143)
		(layer "B.Cu")
		(net "ROMD5")
	)
	(segment
		(start 261.874 -35.814)
		(end 261.874 -36.8935)
		(width 0.254)
		(layer "F.Cu")
		(net "P1V8_STBY_VFB")
	)
	(segment
		(start 262.509 -36.992814)
		(end 263.93775 -36.992814)
		(width 0.254)
		(layer "F.Cu")
		(net "P1V8_STBY_VFB")
	)
	(segment
		(start 262.409686 -36.8935)
		(end 262.509 -36.992814)
		(width 0.254)
		(layer "F.Cu")
		(net "P1V8_STBY_VFB")
	)
	(segment
		(start 260.477 -34.7345)
		(end 261.493 -34.7345)
		(width 0.254)
		(layer "F.Cu")
		(net "P1V8_STBY_VFB")
	)
	(segment
		(start 261.493 -34.7345)
		(end 261.5565 -34.798)
		(width 0.254)
		(layer "F.Cu")
		(net "P1V8_STBY_VFB")
	)
	(segment
		(start 261.5565 -34.798)
		(end 261.5565 -35.4965)
		(width 0.254)
		(layer "F.Cu")
		(net "P1V8_STBY_VFB")
	)
	(segment
		(start 261.874 -36.8935)
		(end 262.409686 -36.8935)
		(width 0.254)
		(layer "F.Cu")
		(net "P1V8_STBY_VFB")
	)
	(segment
		(start 261.5565 -35.4965)
		(end 261.874 -35.814)
		(width 0.254)
		(layer "F.Cu")
		(net "P1V8_STBY_VFB")
	)
	(via
		(at 261.874 -35.814)
		(size 0.7112)
		(drill 0.3556)
		(layers "F.Cu" "B.Cu")
		(net "P1V8_STBY_VFB")
	)
	(segment
		(start 294.513 -156.845)
		(end 294.513 -157.5435)
		(width 0.1143)
		(layer "F.Cu")
		(net "CLK_50M_BMC0")
	)
	(segment
		(start 294.5765 -157.607)
		(end 295.529 -157.607)
		(width 0.1143)
		(layer "F.Cu")
		(net "CLK_50M_BMC0")
	)
	(segment
		(start 296.4815 -158.5595)
		(end 295.529 -157.607)
		(width 0.1143)
		(layer "F.Cu")
		(net "CLK_50M_BMC0")
	)
	(segment
		(start 296.545 -158.5595)
		(end 296.4815 -158.5595)
		(width 0.1143)
		(layer "F.Cu")
		(net "CLK_50M_BMC0")
	)
	(segment
		(start 294.623236 -156.126688)
		(end 294.623236 -156.734764)
		(width 0.1143)
		(layer "F.Cu")
		(net "CLK_50M_BMC0")
	)
	(segment
		(start 294.623236 -156.734764)
		(end 294.513 -156.845)
		(width 0.1143)
		(layer "F.Cu")
		(net "CLK_50M_BMC0")
	)
	(segment
		(start 294.513 -157.5435)
		(end 294.5765 -157.607)
		(width 0.1143)
		(layer "F.Cu")
		(net "CLK_50M_BMC0")
	)
	(via
		(at 295.529 -157.607)
		(size 0.7112)
		(drill 0.3556)
		(layers "F.Cu" "B.Cu")
		(net "CLK_50M_BMC0")
	)
	(segment
		(start 180.5305 -18.415)
		(end 179.7685 -18.415)
		(width 0.1143)
		(layer "F.Cu")
		(net "TEMP_SENSOR_DXP")
	)
	(segment
		(start 185.40476 -18.17624)
		(end 181.89702 -18.17624)
		(width 0.1143)
		(layer "F.Cu")
		(net "TEMP_SENSOR_DXP")
	)
	(segment
		(start 186.055 -16.764)
		(end 186.055 -17.526)
		(width 0.1143)
		(layer "F.Cu")
		(net "TEMP_SENSOR_DXP")
	)
	(segment
		(start 187.2488 -16.21536)
		(end 186.60364 -16.21536)
		(width 0.1143)
		(layer "F.Cu")
		(net "TEMP_SENSOR_DXP")
	)
	(segment
		(start 186.055 -17.526)
		(end 185.40476 -18.17624)
		(width 0.1143)
		(layer "F.Cu")
		(net "TEMP_SENSOR_DXP")
	)
	(segment
		(start 180.721 -18.2245)
		(end 180.5305 -18.415)
		(width 0.1143)
		(layer "F.Cu")
		(net "TEMP_SENSOR_DXP")
	)
	(segment
		(start 181.89702 -18.17624)
		(end 181.84876 -18.2245)
		(width 0.1143)
		(layer "F.Cu")
		(net "TEMP_SENSOR_DXP")
	)
	(segment
		(start 186.60364 -16.21536)
		(end 186.055 -16.764)
		(width 0.1143)
		(layer "F.Cu")
		(net "TEMP_SENSOR_DXP")
	)
	(segment
		(start 181.84876 -18.2245)
		(end 180.721 -18.2245)
		(width 0.1143)
		(layer "F.Cu")
		(net "TEMP_SENSOR_DXP")
	)
	(via
		(at 181.84876 -18.2245)
		(size 0.7112)
		(drill 0.3556)
		(layers "F.Cu" "B.Cu")
		(net "TEMP_SENSOR_DXP")
	)
	(segment
		(start 261.493 -31.6865)
		(end 261.493 -31.5595)
		(width 0.254)
		(layer "F.Cu")
		(net "P1V8_STBY_EN")
	)
	(segment
		(start 264.437876 -36.992814)
		(end 264.437876 -36.218876)
		(width 0.254)
		(layer "F.Cu")
		(net "P1V8_STBY_EN")
	)
	(segment
		(start 263.97839 -35.75939)
		(end 263.97839 -35.433)
		(width 0.254)
		(layer "F.Cu")
		(net "P1V8_STBY_EN")
	)
	(segment
		(start 263.5885 -33.782)
		(end 263.97839 -34.17189)
		(width 0.254)
		(layer "F.Cu")
		(net "P1V8_STBY_EN")
	)
	(segment
		(start 262.4455 -32.639)
		(end 262.4455 -33.782)
		(width 0.254)
		(layer "F.Cu")
		(net "P1V8_STBY_EN")
	)
	(segment
		(start 262.4455 -32.639)
		(end 261.493 -31.6865)
		(width 0.254)
		(layer "F.Cu")
		(net "P1V8_STBY_EN")
	)
	(segment
		(start 263.97839 -34.17189)
		(end 263.97839 -35.433)
		(width 0.254)
		(layer "F.Cu")
		(net "P1V8_STBY_EN")
	)
	(segment
		(start 262.4455 -33.782)
		(end 263.5885 -33.782)
		(width 0.254)
		(layer "F.Cu")
		(net "P1V8_STBY_EN")
	)
	(segment
		(start 264.437876 -36.218876)
		(end 263.97839 -35.75939)
		(width 0.254)
		(layer "F.Cu")
		(net "P1V8_STBY_EN")
	)
	(via
		(at 263.97839 -35.433)
		(size 0.7112)
		(drill 0.3556)
		(layers "F.Cu" "B.Cu")
		(net "P1V8_STBY_EN")
	)
	(segment
		(start 276.436328 -183.75757)
		(end 276.722586 -183.471312)
		(width 0.1143)
		(layer "F.Cu")
		(net "ROMD6")
	)
	(segment
		(start 277.190708 -182.6514)
		(end 277.189946 -182.652162)
		(width 0.1143)
		(layer "F.Cu")
		(net "ROMD6")
	)
	(segment
		(start 274.6375 -185.547)
		(end 275.439124 -184.785)
		(width 0.1143)
		(layer "F.Cu")
		(net "ROMD6")
	)
	(segment
		(start 283.410406 -181.01945)
		(end 278.846026 -181.01945)
		(width 0.1143)
		(layer "F.Cu")
		(net "ROMD6")
	)
	(segment
		(start 278.846026 -181.01945)
		(end 277.214076 -182.6514)
		(width 0.1143)
		(layer "F.Cu")
		(net "ROMD6")
	)
	(segment
		(start 275.439124 -184.785)
		(end 276.436328 -183.787796)
		(width 0.1143)
		(layer "F.Cu")
		(net "ROMD6")
	)
	(segment
		(start 276.86 -183.471312)
		(end 277.1648 -183.166512)
		(width 0.1143)
		(layer "F.Cu")
		(net "ROMD6")
	)
	(segment
		(start 277.1648 -183.166512)
		(end 277.1648 -182.677308)
		(width 0.1143)
		(layer "F.Cu")
		(net "ROMD6")
	)
	(segment
		(start 276.722586 -183.471312)
		(end 276.86 -183.471312)
		(width 0.1143)
		(layer "F.Cu")
		(net "ROMD6")
	)
	(segment
		(start 283.43098 -181.040024)
		(end 283.410406 -181.01945)
		(width 0.1143)
		(layer "F.Cu")
		(net "ROMD6")
	)
	(segment
		(start 277.214076 -182.6514)
		(end 277.190708 -182.6514)
		(width 0.1143)
		(layer "F.Cu")
		(net "ROMD6")
	)
	(segment
		(start 277.1648 -182.677308)
		(end 277.189946 -182.652162)
		(width 0.1143)
		(layer "F.Cu")
		(net "ROMD6")
	)
	(segment
		(start 276.436328 -183.787796)
		(end 276.436328 -183.75757)
		(width 0.1143)
		(layer "F.Cu")
		(net "ROMD6")
	)
	(segment
		(start 284.834838 -181.040024)
		(end 283.43098 -181.040024)
		(width 0.1143)
		(layer "F.Cu")
		(net "ROMD6")
	)
	(via
		(at 277.189946 -182.652162)
		(size 0.7112)
		(drill 0.3556)
		(layers "F.Cu" "B.Cu")
		(net "ROMD6")
	)
	(segment
		(start 122.350022 -90.349832)
		(end 122.850148 -89.849706)
		(width 0.1016)
		(layer "F.Cu")
		(net "SAS_GF_EXP_RX_DN0")
	)
	(via
		(at 122.850148 -89.849706)
		(size 0.508)
		(drill 0.254)
		(layers "F.Cu" "B.Cu")
		(net "SAS_GF_EXP_RX_DN0")
	)
	(segment
		(start 136.13257 -144.995138)
		(end 136.13257 -98.933)
		(width 0.1016)
		(layer "B.Cu")
		(net "SAS_GF_EXP_RX_DN0")
	)
	(segment
		(start 148.999702 -256.50444)
		(end 148.999702 -254.533654)
		(width 0.1016)
		(layer "B.Cu")
		(net "SAS_GF_EXP_RX_DN0")
	)
	(segment
		(start 126.00305 -90.688922)
		(end 124.90577 -90.688922)
		(width 0.1016)
		(layer "B.Cu")
		(net "SAS_GF_EXP_RX_DN0")
	)
	(segment
		(start 135.729472 -97.959672)
		(end 129.6416 -91.8718)
		(width 0.1016)
		(layer "B.Cu")
		(net "SAS_GF_EXP_RX_DN0")
	)
	(segment
		(start 149.1996 -251.7394)
		(end 148.5011 -251.0409)
		(width 0.1016)
		(layer "B.Cu")
		(net "SAS_GF_EXP_RX_DN0")
	)
	(segment
		(start 147.33143 -157.21457)
		(end 136.85393 -146.73707)
		(width 0.1016)
		(layer "B.Cu")
		(net "SAS_GF_EXP_RX_DN0")
	)
	(segment
		(start 122.925332 -89.849706)
		(end 122.850148 -89.849706)
		(width 0.1016)
		(layer "B.Cu")
		(net "SAS_GF_EXP_RX_DN0")
	)
	(segment
		(start 147.458684 -157.34157)
		(end 147.33143 -157.21457)
		(width 0.1016)
		(layer "B.Cu")
		(net "SAS_GF_EXP_RX_DN0")
	)
	(segment
		(start 123.55449 -90.21572)
		(end 123.374404 -90.035634)
		(width 0.1016)
		(layer "B.Cu")
		(net "SAS_GF_EXP_RX_DN0")
	)
	(segment
		(start 147.936712 -249.677936)
		(end 147.936712 -158.496)
		(width 0.1016)
		(layer "B.Cu")
		(net "SAS_GF_EXP_RX_DN0")
	)
	(segment
		(start 149.18563 -254.084582)
		(end 149.216364 -254.053848)
		(width 0.1016)
		(layer "B.Cu")
		(net "SAS_GF_EXP_RX_DN0")
	)
	(segment
		(start 126.876048 -91.273122)
		(end 126.496064 -90.893138)
		(width 0.1016)
		(layer "B.Cu")
		(net "SAS_GF_EXP_RX_DN0")
	)
	(segment
		(start 149.402292 -253.604776)
		(end 149.402292 -252.228858)
		(width 0.1016)
		(layer "B.Cu")
		(net "SAS_GF_EXP_RX_DN0")
	)
	(segment
		(start 128.8034 -91.524582)
		(end 127.483108 -91.524582)
		(width 0.1016)
		(layer "B.Cu")
		(net "SAS_GF_EXP_RX_DN0")
	)
	(segment
		(start 124.90577 -90.688922)
		(end 124.90577 -90.689176)
		(width 0.1016)
		(layer "B.Cu")
		(net "SAS_GF_EXP_RX_DN0")
	)
	(arc
		(start 123.91009 -90.36304)
		(mid 123.71767 -90.32469)
		(end 123.55449 -90.21572)
		(width 0.1016)
		(layer "B.Cu")
		(net "SAS_GF_EXP_RX_DN0")
	)
	(arc
		(start 123.374404 -90.035634)
		(mid 123.168354 -89.898019)
		(end 122.925332 -89.849706)
		(width 0.1016)
		(layer "B.Cu")
		(net "SAS_GF_EXP_RX_DN0")
	)
	(arc
		(start 149.402292 -252.228858)
		(mid 149.349605 -251.963984)
		(end 149.1996 -251.7394)
		(width 0.1016)
		(layer "B.Cu")
		(net "SAS_GF_EXP_RX_DN0")
	)
	(arc
		(start 124.90577 -90.689176)
		(mid 124.599125 -90.646164)
		(end 124.316236 -90.520266)
		(width 0.1016)
		(layer "B.Cu")
		(net "SAS_GF_EXP_RX_DN0")
	)
	(arc
		(start 124.316236 -90.520266)
		(mid 124.127845 -90.403729)
		(end 123.91009 -90.36304)
		(width 0.1016)
		(layer "B.Cu")
		(net "SAS_GF_EXP_RX_DN0")
	)
	(arc
		(start 136.13257 -98.933)
		(mid 136.027811 -98.40625)
		(end 135.729472 -97.959672)
		(width 0.1016)
		(layer "B.Cu")
		(net "SAS_GF_EXP_RX_DN0")
	)
	(arc
		(start 136.85393 -146.73707)
		(mid 136.320001 -145.93785)
		(end 136.13257 -144.995138)
		(width 0.1016)
		(layer "B.Cu")
		(net "SAS_GF_EXP_RX_DN0")
	)
	(arc
		(start 127.483108 -91.524582)
		(mid 127.154606 -91.459163)
		(end 126.876048 -91.273122)
		(width 0.1016)
		(layer "B.Cu")
		(net "SAS_GF_EXP_RX_DN0")
	)
	(arc
		(start 148.999702 -254.533654)
		(mid 149.048023 -254.290636)
		(end 149.18563 -254.084582)
		(width 0.1016)
		(layer "B.Cu")
		(net "SAS_GF_EXP_RX_DN0")
	)
	(arc
		(start 129.6416 -91.8718)
		(mid 129.257031 -91.614839)
		(end 128.8034 -91.524582)
		(width 0.1016)
		(layer "B.Cu")
		(net "SAS_GF_EXP_RX_DN0")
	)
	(arc
		(start 126.496064 -90.893138)
		(mid 126.269867 -90.741998)
		(end 126.00305 -90.688922)
		(width 0.1016)
		(layer "B.Cu")
		(net "SAS_GF_EXP_RX_DN0")
	)
	(arc
		(start 149.216364 -254.053848)
		(mid 149.353979 -253.847798)
		(end 149.402292 -253.604776)
		(width 0.1016)
		(layer "B.Cu")
		(net "SAS_GF_EXP_RX_DN0")
	)
	(arc
		(start 148.5011 -251.0409)
		(mid 148.083349 -250.415552)
		(end 147.936712 -249.677936)
		(width 0.1016)
		(layer "B.Cu")
		(net "SAS_GF_EXP_RX_DN0")
	)
	(arc
		(start 147.936712 -158.496)
		(mid 147.812532 -157.871232)
		(end 147.458684 -157.34157)
		(width 0.1016)
		(layer "B.Cu")
		(net "SAS_GF_EXP_RX_DN0")
	)
	(segment
		(start 129.217928 -10.587228)
		(end 149.967188 -31.336488)
		(width 0.1397)
		(layer "B.Cu")
		(net "PCIE_SAS_CPU_RX_N2")
	)
	(segment
		(start 150.65883 -31.623)
		(end 155.28417 -31.623)
		(width 0.1397)
		(layer "B.Cu")
		(net "PCIE_SAS_CPU_RX_N2")
	)
	(segment
		(start 96.581214 -29.216858)
		(end 96.58096 -29.217112)
		(width 0.1397)
		(layer "B.Cu")
		(net "PCIE_SAS_CPU_RX_N2")
	)
	(segment
		(start 114.67846 -14.45768)
		(end 118.548912 -10.587228)
		(width 0.1397)
		(layer "B.Cu")
		(net "PCIE_SAS_CPU_RX_N2")
	)
	(segment
		(start 96.58096 -29.217112)
		(end 96.58096 -25.019254)
		(width 0.1397)
		(layer "B.Cu")
		(net "PCIE_SAS_CPU_RX_N2")
	)
	(segment
		(start 118.997984 -10.4013)
		(end 128.768856 -10.4013)
		(width 0.1397)
		(layer "B.Cu")
		(net "PCIE_SAS_CPU_RX_N2")
	)
	(segment
		(start 195.072254 -74.421746)
		(end 195.072 -74.422)
		(width 0.1397)
		(layer "B.Cu")
		(net "PCIE_SAS_CPU_RX_N2")
	)
	(segment
		(start 155.733242 -31.808928)
		(end 195.087494 -71.16318)
		(width 0.1397)
		(layer "B.Cu")
		(net "PCIE_SAS_CPU_RX_N2")
	)
	(segment
		(start 106.856022 -14.744192)
		(end 113.986818 -14.744192)
		(width 0.1397)
		(layer "B.Cu")
		(net "PCIE_SAS_CPU_RX_N2")
	)
	(segment
		(start 96.921066 -31.060898)
		(end 96.921066 -29.844746)
		(width 0.1397)
		(layer "B.Cu")
		(net "PCIE_SAS_CPU_RX_N2")
	)
	(segment
		(start 96.635824 -29.34843)
		(end 96.63557 -29.34843)
		(width 0.1397)
		(layer "B.Cu")
		(net "PCIE_SAS_CPU_RX_N2")
	)
	(segment
		(start 195.273422 -71.612252)
		(end 195.273422 -73.935844)
		(width 0.1397)
		(layer "B.Cu")
		(net "PCIE_SAS_CPU_RX_N2")
	)
	(segment
		(start 96.771968 -29.485082)
		(end 96.635824 -29.34843)
		(width 0.1397)
		(layer "B.Cu")
		(net "PCIE_SAS_CPU_RX_N2")
	)
	(segment
		(start 96.766888 -24.570182)
		(end 106.40695 -14.93012)
		(width 0.1397)
		(layer "B.Cu")
		(net "PCIE_SAS_CPU_RX_N2")
	)
	(segment
		(start 194.31 -73.889616)
		(end 194.449446 -73.75017)
		(width 0.1397)
		(layer "B.Cu")
		(net "PCIE_SAS_CPU_RX_N2")
	)
	(arc
		(start 155.28417 -31.623)
		(mid 155.527174 -31.671336)
		(end 155.733242 -31.808928)
		(width 0.1397)
		(layer "B.Cu")
		(net "PCIE_SAS_CPU_RX_N2")
	)
	(arc
		(start 195.072 -74.422)
		(mid 194.691 -74.579815)
		(end 194.31 -74.422)
		(width 0.1397)
		(layer "B.Cu")
		(net "PCIE_SAS_CPU_RX_N2")
	)
	(arc
		(start 195.273422 -73.935844)
		(mid 195.221137 -74.198789)
		(end 195.072254 -74.421746)
		(width 0.1397)
		(layer "B.Cu")
		(net "PCIE_SAS_CPU_RX_N2")
	)
	(arc
		(start 118.548912 -10.587228)
		(mid 118.754948 -10.449559)
		(end 118.997984 -10.4013)
		(width 0.1397)
		(layer "B.Cu")
		(net "PCIE_SAS_CPU_RX_N2")
	)
	(arc
		(start 128.768856 -10.4013)
		(mid 129.01186 -10.449636)
		(end 129.217928 -10.587228)
		(width 0.1397)
		(layer "B.Cu")
		(net "PCIE_SAS_CPU_RX_N2")
	)
	(arc
		(start 96.921066 -29.844746)
		(mid 96.882271 -29.650091)
		(end 96.771968 -29.485082)
		(width 0.1397)
		(layer "B.Cu")
		(net "PCIE_SAS_CPU_RX_N2")
	)
	(arc
		(start 149.967188 -31.336488)
		(mid 150.284502 -31.548574)
		(end 150.65883 -31.623)
		(width 0.1397)
		(layer "B.Cu")
		(net "PCIE_SAS_CPU_RX_N2")
	)
	(arc
		(start 106.40695 -14.93012)
		(mid 106.612986 -14.792451)
		(end 106.856022 -14.744192)
		(width 0.1397)
		(layer "B.Cu")
		(net "PCIE_SAS_CPU_RX_N2")
	)
	(arc
		(start 194.31 -74.422)
		(mid 194.19974 -74.155808)
		(end 194.31 -73.889616)
		(width 0.1397)
		(layer "B.Cu")
		(net "PCIE_SAS_CPU_RX_N2")
	)
	(arc
		(start 195.087494 -71.16318)
		(mid 195.225163 -71.369216)
		(end 195.273422 -71.612252)
		(width 0.1397)
		(layer "B.Cu")
		(net "PCIE_SAS_CPU_RX_N2")
	)
	(arc
		(start 97.03816 -31.3436)
		(mid 96.951494 -31.213895)
		(end 96.921066 -31.060898)
		(width 0.1397)
		(layer "B.Cu")
		(net "PCIE_SAS_CPU_RX_N2")
	)
	(arc
		(start 113.986818 -14.744192)
		(mid 114.361127 -14.669719)
		(end 114.67846 -14.45768)
		(width 0.1397)
		(layer "B.Cu")
		(net "PCIE_SAS_CPU_RX_N2")
	)
	(arc
		(start 96.58096 -25.019254)
		(mid 96.629296 -24.77625)
		(end 96.766888 -24.570182)
		(width 0.1397)
		(layer "B.Cu")
		(net "PCIE_SAS_CPU_RX_N2")
	)
	(arc
		(start 96.63557 -29.34843)
		(mid 96.595318 -29.288049)
		(end 96.581214 -29.216858)
		(width 0.1397)
		(layer "B.Cu")
		(net "PCIE_SAS_CPU_RX_N2")
	)
	(via
		(at 275.844 -42.418)
		(size 0.7112)
		(drill 0.3556)
		(layers "F.Cu" "B.Cu")
		(net "P1V8_STBY_VIN")
	)
	(segment
		(start 351.303336 -81.256378)
		(end 351.303336 -78.888336)
		(width 0.1143)
		(layer "F.Cu")
		(net "PU_IBMC_BT_HOLD_N")
	)
	(segment
		(start 347.23705 -74.82205)
		(end 341.35695 -74.82205)
		(width 0.1143)
		(layer "F.Cu")
		(net "PU_IBMC_BT_HOLD_N")
	)
	(segment
		(start 351.303336 -83.841336)
		(end 351.303336 -81.435194)
		(width 0.1143)
		(layer "F.Cu")
		(net "PU_IBMC_BT_HOLD_N")
	)
	(segment
		(start 351.303336 -78.888336)
		(end 347.23705 -74.82205)
		(width 0.1143)
		(layer "F.Cu")
		(net "PU_IBMC_BT_HOLD_N")
	)
	(segment
		(start 339.598 -76.581)
		(end 333.977488 -76.581)
		(width 0.1143)
		(layer "F.Cu")
		(net "PU_IBMC_BT_HOLD_N")
	)
	(segment
		(start 351.663 -84.201)
		(end 351.303336 -83.841336)
		(width 0.1143)
		(layer "F.Cu")
		(net "PU_IBMC_BT_HOLD_N")
	)
	(segment
		(start 341.35695 -74.82205)
		(end 339.598 -76.581)
		(width 0.1143)
		(layer "F.Cu")
		(net "PU_IBMC_BT_HOLD_N")
	)
	(segment
		(start 351.303336 -81.435194)
		(end 351.303336 -81.256378)
		(width 0.1143)
		(layer "F.Cu")
		(net "PU_IBMC_BT_HOLD_N")
	)
	(via
		(at 351.663 -83.185)
		(size 0.7112)
		(drill 0.3556)
		(layers "F.Cu" "B.Cu")
		(net "PU_IBMC_BT_HOLD_N")
	)
	(via
		(at 351.663 -84.201)
		(size 0.5588)
		(drill 0.3048)
		(layers "F.Cu" "B.Cu")
		(net "PU_IBMC_BT_HOLD_N")
	)
	(segment
		(start 351.663 -83.185)
		(end 351.663 -81.9785)
		(width 0.1143)
		(layer "B.Cu")
		(net "PU_IBMC_BT_HOLD_N")
	)
	(segment
		(start 351.663 -84.201)
		(end 351.663 -83.185)
		(width 0.1143)
		(layer "B.Cu")
		(net "PU_IBMC_BT_HOLD_N")
	)
	(segment
		(start 306.11064 -195.49364)
		(end 305.943 -195.326)
		(width 0.1143)
		(layer "F.Cu")
		(net "LED_DR_A0")
	)
	(segment
		(start 305.299872 -194.682872)
		(end 305.943 -195.326)
		(width 0.1143)
		(layer "F.Cu")
		(net "LED_DR_A0")
	)
	(segment
		(start 306.11064 -197.0659)
		(end 306.11064 -195.49364)
		(width 0.1143)
		(layer "F.Cu")
		(net "LED_DR_A0")
	)
	(segment
		(start 305.299872 -194.191636)
		(end 305.299872 -194.682872)
		(width 0.1143)
		(layer "F.Cu")
		(net "LED_DR_A0")
	)
	(via
		(at 305.943 -195.326)
		(size 0.7112)
		(drill 0.3556)
		(layers "F.Cu" "B.Cu")
		(net "LED_DR_A0")
	)
	(via
		(at 270.002 -35.687)
		(size 0.7112)
		(drill 0.3556)
		(layers "F.Cu" "B.Cu")
		(net "P1V8_STBY_VBST_RC")
	)
	(segment
		(start 268.6812 -35.687)
		(end 270.002 -35.687)
		(width 0.508)
		(layer "B.Cu")
		(net "P1V8_STBY_VBST_RC")
	)
	(segment
		(start 270.002 -35.687)
		(end 271.145 -35.687)
		(width 0.508)
		(layer "B.Cu")
		(net "P1V8_STBY_VBST_RC")
	)
	(segment
		(start 180.6575 -17.272)
		(end 179.7685 -17.272)
		(width 0.1143)
		(layer "F.Cu")
		(net "TEMP_SENSOR_DXN")
	)
	(segment
		(start 183.900064 -17.526)
		(end 185.42 -17.526)
		(width 0.1143)
		(layer "F.Cu")
		(net "TEMP_SENSOR_DXN")
	)
	(segment
		(start 183.891936 -17.526)
		(end 183.896 -17.530064)
		(width 0.1143)
		(layer "F.Cu")
		(net "TEMP_SENSOR_DXN")
	)
	(segment
		(start 185.674 -17.272)
		(end 185.674 -16.51)
		(width 0.1143)
		(layer "F.Cu")
		(net "TEMP_SENSOR_DXN")
	)
	(segment
		(start 180.721 -17.3355)
		(end 180.6575 -17.272)
		(width 0.1143)
		(layer "F.Cu")
		(net "TEMP_SENSOR_DXN")
	)
	(segment
		(start 180.9115 -17.526)
		(end 183.891936 -17.526)
		(width 0.1143)
		(layer "F.Cu")
		(net "TEMP_SENSOR_DXN")
	)
	(segment
		(start 185.42 -17.526)
		(end 185.674 -17.272)
		(width 0.1143)
		(layer "F.Cu")
		(net "TEMP_SENSOR_DXN")
	)
	(segment
		(start 186.61888 -15.56512)
		(end 187.2488 -15.56512)
		(width 0.1143)
		(layer "F.Cu")
		(net "TEMP_SENSOR_DXN")
	)
	(segment
		(start 183.896 -17.530064)
		(end 183.900064 -17.526)
		(width 0.1143)
		(layer "F.Cu")
		(net "TEMP_SENSOR_DXN")
	)
	(segment
		(start 185.674 -16.51)
		(end 186.61888 -15.56512)
		(width 0.1143)
		(layer "F.Cu")
		(net "TEMP_SENSOR_DXN")
	)
	(segment
		(start 180.721 -17.3355)
		(end 180.9115 -17.526)
		(width 0.1143)
		(layer "F.Cu")
		(net "TEMP_SENSOR_DXN")
	)
	(via
		(at 183.896 -17.530064)
		(size 0.7112)
		(drill 0.3556)
		(layers "F.Cu" "B.Cu")
		(net "TEMP_SENSOR_DXN")
	)
	(segment
		(start 100.318316 -30.613604)
		(end 100.318316 -26.306018)
		(width 0.1397)
		(layer "F.Cu")
		(net "PCIE_SAS_CPU_TX_N4")
	)
	(segment
		(start 167.553894 -74.565764)
		(end 168.1099 -75.12177)
		(width 0.1397)
		(layer "F.Cu")
		(net "PCIE_SAS_CPU_TX_N4")
	)
	(segment
		(start 168.28897 -75.55357)
		(end 168.28897 -76.198984)
		(width 0.1397)
		(layer "F.Cu")
		(net "PCIE_SAS_CPU_TX_N4")
	)
	(segment
		(start 100.690172 -25.408128)
		(end 107.444794 -18.653506)
		(width 0.1397)
		(layer "F.Cu")
		(net "PCIE_SAS_CPU_TX_N4")
	)
	(segment
		(start 168.288716 -75.553824)
		(end 168.28897 -75.55357)
		(width 0.1397)
		(layer "F.Cu")
		(net "PCIE_SAS_CPU_TX_N4")
	)
	(segment
		(start 132.558028 -10.917428)
		(end 134.5692 -12.9286)
		(width 0.1397)
		(layer "F.Cu")
		(net "PCIE_SAS_CPU_TX_N4")
	)
	(segment
		(start 100.718366 -33.5026)
		(end 100.718366 -31.579566)
		(width 0.1397)
		(layer "F.Cu")
		(net "PCIE_SAS_CPU_TX_N4")
	)
	(segment
		(start 135.509 -15.197582)
		(end 135.509 -18.38198)
		(width 0.1397)
		(layer "F.Cu")
		(net "PCIE_SAS_CPU_TX_N4")
	)
	(segment
		(start 100.31857 -30.61335)
		(end 100.318316 -30.613604)
		(width 0.1397)
		(layer "F.Cu")
		(net "PCIE_SAS_CPU_TX_N4")
	)
	(segment
		(start 110.776512 -18.255488)
		(end 118.114572 -10.917428)
		(width 0.1397)
		(layer "F.Cu")
		(net "PCIE_SAS_CPU_TX_N4")
	)
	(segment
		(start 167.29456 -51.361594)
		(end 167.29456 -73.9394)
		(width 0.1397)
		(layer "F.Cu")
		(net "PCIE_SAS_CPU_TX_N4")
	)
	(segment
		(start 135.98144 -19.52244)
		(end 166.922704 -50.463704)
		(width 0.1397)
		(layer "F.Cu")
		(net "PCIE_SAS_CPU_TX_N4")
	)
	(segment
		(start 107.714034 -18.542)
		(end 110.08487 -18.542)
		(width 0.1397)
		(layer "F.Cu")
		(net "PCIE_SAS_CPU_TX_N4")
	)
	(segment
		(start 100.350066 -34.19983)
		(end 100.485702 -34.06394)
		(width 0.1397)
		(layer "F.Cu")
		(net "PCIE_SAS_CPU_TX_N4")
	)
	(segment
		(start 118.563644 -10.7315)
		(end 132.108956 -10.7315)
		(width 0.1397)
		(layer "F.Cu")
		(net "PCIE_SAS_CPU_TX_N4")
	)
	(via
		(at 167.946578 -77.0255)
		(size 0.5588)
		(drill 0.3048)
		(layers "F.Cu" "B.Cu")
		(net "PCIE_SAS_CPU_TX_N4")
	)
	(arc
		(start 167.29456 -73.9394)
		(mid 167.361897 -74.278396)
		(end 167.553894 -74.565764)
		(width 0.1397)
		(layer "F.Cu")
		(net "PCIE_SAS_CPU_TX_N4")
	)
	(arc
		(start 132.108956 -10.7315)
		(mid 132.35196 -10.779836)
		(end 132.558028 -10.917428)
		(width 0.1397)
		(layer "F.Cu")
		(net "PCIE_SAS_CPU_TX_N4")
	)
	(arc
		(start 134.5692 -12.9286)
		(mid 135.264786 -13.969618)
		(end 135.509 -15.197582)
		(width 0.1397)
		(layer "F.Cu")
		(net "PCIE_SAS_CPU_TX_N4")
	)
	(arc
		(start 100.485702 -34.06394)
		(mid 100.657871 -33.80641)
		(end 100.718366 -33.5026)
		(width 0.1397)
		(layer "F.Cu")
		(net "PCIE_SAS_CPU_TX_N4")
	)
	(arc
		(start 100.718366 -31.579566)
		(mid 100.642551 -31.197568)
		(end 100.426266 -30.8737)
		(width 0.1397)
		(layer "F.Cu")
		(net "PCIE_SAS_CPU_TX_N4")
	)
	(arc
		(start 100.426266 -30.8737)
		(mid 100.346535 -30.754235)
		(end 100.31857 -30.61335)
		(width 0.1397)
		(layer "F.Cu")
		(net "PCIE_SAS_CPU_TX_N4")
	)
	(arc
		(start 110.08487 -18.542)
		(mid 110.459179 -18.467527)
		(end 110.776512 -18.255488)
		(width 0.1397)
		(layer "F.Cu")
		(net "PCIE_SAS_CPU_TX_N4")
	)
	(arc
		(start 135.509 -18.38198)
		(mid 135.631775 -18.99921)
		(end 135.98144 -19.52244)
		(width 0.1397)
		(layer "F.Cu")
		(net "PCIE_SAS_CPU_TX_N4")
	)
	(arc
		(start 168.28897 -76.198984)
		(mid 168.199992 -76.646306)
		(end 167.946578 -77.0255)
		(width 0.1397)
		(layer "F.Cu")
		(net "PCIE_SAS_CPU_TX_N4")
	)
	(arc
		(start 118.114572 -10.917428)
		(mid 118.320608 -10.779759)
		(end 118.563644 -10.7315)
		(width 0.1397)
		(layer "F.Cu")
		(net "PCIE_SAS_CPU_TX_N4")
	)
	(arc
		(start 166.922704 -50.463704)
		(mid 167.19791 -50.875674)
		(end 167.29456 -51.361594)
		(width 0.1397)
		(layer "F.Cu")
		(net "PCIE_SAS_CPU_TX_N4")
	)
	(arc
		(start 100.318316 -26.306018)
		(mid 100.414955 -25.820093)
		(end 100.690172 -25.408128)
		(width 0.1397)
		(layer "F.Cu")
		(net "PCIE_SAS_CPU_TX_N4")
	)
	(arc
		(start 168.1099 -75.12177)
		(mid 168.242269 -75.320013)
		(end 168.288716 -75.553824)
		(width 0.1397)
		(layer "F.Cu")
		(net "PCIE_SAS_CPU_TX_N4")
	)
	(arc
		(start 107.444794 -18.653506)
		(mid 107.568337 -18.571021)
		(end 107.714034 -18.542)
		(width 0.1397)
		(layer "F.Cu")
		(net "PCIE_SAS_CPU_TX_N4")
	)
	(segment
		(start 168.748456 -79.34071)
		(end 168.748456 -79.340964)
		(width 0.1397)
		(layer "B.Cu")
		(net "PCIE_SAS_CPU_TX_N4")
	)
	(segment
		(start 168.748964 -79.340964)
		(end 168.748456 -79.34071)
		(width 0.1397)
		(layer "B.Cu")
		(net "PCIE_SAS_CPU_TX_N4")
	)
	(segment
		(start 168.747948 -79.340202)
		(end 168.5798 -79.256128)
		(width 0.1397)
		(layer "B.Cu")
		(net "PCIE_SAS_CPU_TX_N4")
	)
	(segment
		(start 168.450006 -80.25003)
		(end 168.811448 -79.528416)
		(width 0.1397)
		(layer "B.Cu")
		(net "PCIE_SAS_CPU_TX_N4")
	)
	(segment
		(start 168.26103 -78.553564)
		(end 168.26103 -77.44206)
		(width 0.1397)
		(layer "B.Cu")
		(net "PCIE_SAS_CPU_TX_N4")
	)
	(segment
		(start 168.188894 -77.267562)
		(end 167.946578 -77.0255)
		(width 0.1397)
		(layer "B.Cu")
		(net "PCIE_SAS_CPU_TX_N4")
	)
	(segment
		(start 168.749218 -79.340964)
		(end 168.748964 -79.340964)
		(width 0.1397)
		(layer "B.Cu")
		(net "PCIE_SAS_CPU_TX_N4")
	)
	(arc
		(start 168.5798 -79.256128)
		(mid 168.344511 -78.939287)
		(end 168.26103 -78.553564)
		(width 0.1397)
		(layer "B.Cu")
		(net "PCIE_SAS_CPU_TX_N4")
	)
	(arc
		(start 168.748456 -79.340964)
		(mid 168.748202 -79.340583)
		(end 168.747948 -79.340202)
		(width 0.1397)
		(layer "B.Cu")
		(net "PCIE_SAS_CPU_TX_N4")
	)
	(arc
		(start 168.26103 -77.44206)
		(mid 168.242339 -77.347624)
		(end 168.188894 -77.267562)
		(width 0.1397)
		(layer "B.Cu")
		(net "PCIE_SAS_CPU_TX_N4")
	)
	(arc
		(start 168.811448 -79.528416)
		(mid 168.819064 -79.421857)
		(end 168.749218 -79.340964)
		(width 0.1397)
		(layer "B.Cu")
		(net "PCIE_SAS_CPU_TX_N4")
	)
	(segment
		(start 308.791864 -204.652372)
		(end 308.791864 -203.381864)
		(width 0.1143)
		(layer "F.Cu")
		(net "LED_DR_I2C_SCL")
	)
	(segment
		(start 308.791864 -203.381864)
		(end 308.737 -203.327)
		(width 0.1143)
		(layer "F.Cu")
		(net "LED_DR_I2C_SCL")
	)
	(segment
		(start 307.42382 -200.791064)
		(end 307.42382 -202.01382)
		(width 0.1143)
		(layer "F.Cu")
		(net "LED_DR_I2C_SCL")
	)
	(segment
		(start 309.88 -204.6605)
		(end 308.799992 -204.6605)
		(width 0.1143)
		(layer "F.Cu")
		(net "LED_DR_I2C_SCL")
	)
	(segment
		(start 307.41112 -201.2061)
		(end 307.42382 -200.791064)
		(width 0.1143)
		(layer "F.Cu")
		(net "LED_DR_I2C_SCL")
	)
	(segment
		(start 307.42382 -202.01382)
		(end 308.737 -203.327)
		(width 0.1143)
		(layer "F.Cu")
		(net "LED_DR_I2C_SCL")
	)
	(segment
		(start 308.799992 -204.6605)
		(end 308.791864 -204.652372)
		(width 0.1143)
		(layer "F.Cu")
		(net "LED_DR_I2C_SCL")
	)
	(via
		(at 308.737 -203.327)
		(size 0.7112)
		(drill 0.3556)
		(layers "F.Cu" "B.Cu")
		(net "LED_DR_I2C_SCL")
	)
	(segment
		(start 93.50121 -30.991048)
		(end 93.50121 -29.963364)
		(width 0.1397)
		(layer "B.Cu")
		(net "PCIE_SAS_CPU_RX_P0")
	)
	(segment
		(start 93.396816 -29.71165)
		(end 92.936822 -29.251656)
		(width 0.1397)
		(layer "B.Cu")
		(net "PCIE_SAS_CPU_RX_P0")
	)
	(segment
		(start 92.732098 -28.757372)
		(end 92.732098 -23.56739)
		(width 0.1397)
		(layer "B.Cu")
		(net "PCIE_SAS_CPU_RX_P0")
	)
	(segment
		(start 93.01861 -22.875748)
		(end 104.711754 -11.182604)
		(width 0.1397)
		(layer "B.Cu")
		(net "PCIE_SAS_CPU_RX_P0")
	)
	(segment
		(start 112.81791 -10.710164)
		(end 116.764562 -6.763512)
		(width 0.1397)
		(layer "B.Cu")
		(net "PCIE_SAS_CPU_RX_P0")
	)
	(segment
		(start 130.872738 -6.763512)
		(end 151.698198 -27.588972)
		(width 0.1397)
		(layer "B.Cu")
		(net "PCIE_SAS_CPU_RX_P0")
	)
	(segment
		(start 203.645516 -73.279)
		(end 203.645516 -74.164698)
		(width 0.1397)
		(layer "B.Cu")
		(net "PCIE_SAS_CPU_RX_P0")
	)
	(segment
		(start 117.456204 -6.477)
		(end 130.181096 -6.477)
		(width 0.1397)
		(layer "B.Cu")
		(net "PCIE_SAS_CPU_RX_P0")
	)
	(segment
		(start 199.304148 -67.882008)
		(end 202.899264 -71.477124)
		(width 0.1397)
		(layer "B.Cu")
		(net "PCIE_SAS_CPU_RX_P0")
	)
	(segment
		(start 152.14727 -27.7749)
		(end 157.277308 -27.7749)
		(width 0.1397)
		(layer "B.Cu")
		(net "PCIE_SAS_CPU_RX_P0")
	)
	(segment
		(start 203.408026 -74.738484)
		(end 203.051918 -75.094592)
		(width 0.1397)
		(layer "B.Cu")
		(net "PCIE_SAS_CPU_RX_P0")
	)
	(segment
		(start 105.403396 -10.896092)
		(end 112.368838 -10.896092)
		(width 0.1397)
		(layer "B.Cu")
		(net "PCIE_SAS_CPU_RX_P0")
	)
	(segment
		(start 198.341488 -67.6021)
		(end 198.627746 -67.6021)
		(width 0.1397)
		(layer "B.Cu")
		(net "PCIE_SAS_CPU_RX_P0")
	)
	(segment
		(start 203.310744 -75.75042)
		(end 203.449936 -75.75042)
		(width 0.1397)
		(layer "B.Cu")
		(net "PCIE_SAS_CPU_RX_P0")
	)
	(segment
		(start 157.968442 -28.061412)
		(end 196.920358 -67.013328)
		(width 0.1397)
		(layer "B.Cu")
		(net "PCIE_SAS_CPU_RX_P0")
	)
	(arc
		(start 104.711754 -11.182604)
		(mid 105.029068 -10.970518)
		(end 105.403396 -10.896092)
		(width 0.1397)
		(layer "B.Cu")
		(net "PCIE_SAS_CPU_RX_P0")
	)
	(arc
		(start 92.732098 -23.56739)
		(mid 92.806571 -23.193081)
		(end 93.01861 -22.875748)
		(width 0.1397)
		(layer "B.Cu")
		(net "PCIE_SAS_CPU_RX_P0")
	)
	(arc
		(start 157.277308 -27.7749)
		(mid 157.651344 -27.84947)
		(end 157.968442 -28.061412)
		(width 0.1397)
		(layer "B.Cu")
		(net "PCIE_SAS_CPU_RX_P0")
	)
	(arc
		(start 151.698198 -27.588972)
		(mid 151.904234 -27.726641)
		(end 152.14727 -27.7749)
		(width 0.1397)
		(layer "B.Cu")
		(net "PCIE_SAS_CPU_RX_P0")
	)
	(arc
		(start 116.764562 -6.763512)
		(mid 117.081876 -6.551426)
		(end 117.456204 -6.477)
		(width 0.1397)
		(layer "B.Cu")
		(net "PCIE_SAS_CPU_RX_P0")
	)
	(arc
		(start 202.899264 -71.477124)
		(mid 203.451569 -72.303847)
		(end 203.645516 -73.279)
		(width 0.1397)
		(layer "B.Cu")
		(net "PCIE_SAS_CPU_RX_P0")
	)
	(arc
		(start 203.051918 -75.643232)
		(mid 203.170668 -75.722578)
		(end 203.310744 -75.75042)
		(width 0.1397)
		(layer "B.Cu")
		(net "PCIE_SAS_CPU_RX_P0")
	)
	(arc
		(start 196.920358 -67.013328)
		(mid 197.572363 -67.449077)
		(end 198.341488 -67.6021)
		(width 0.1397)
		(layer "B.Cu")
		(net "PCIE_SAS_CPU_RX_P0")
	)
	(arc
		(start 112.368838 -10.896092)
		(mid 112.611842 -10.847756)
		(end 112.81791 -10.710164)
		(width 0.1397)
		(layer "B.Cu")
		(net "PCIE_SAS_CPU_RX_P0")
	)
	(arc
		(start 92.936822 -29.251656)
		(mid 92.785293 -29.024877)
		(end 92.732098 -28.757372)
		(width 0.1397)
		(layer "B.Cu")
		(net "PCIE_SAS_CPU_RX_P0")
	)
	(arc
		(start 203.051918 -75.094592)
		(mid 202.938291 -75.368912)
		(end 203.051918 -75.643232)
		(width 0.1397)
		(layer "B.Cu")
		(net "PCIE_SAS_CPU_RX_P0")
	)
	(arc
		(start 130.181096 -6.477)
		(mid 130.555405 -6.551473)
		(end 130.872738 -6.763512)
		(width 0.1397)
		(layer "B.Cu")
		(net "PCIE_SAS_CPU_RX_P0")
	)
	(arc
		(start 93.35516 -31.3436)
		(mid 93.463239 -31.181848)
		(end 93.50121 -30.991048)
		(width 0.1397)
		(layer "B.Cu")
		(net "PCIE_SAS_CPU_RX_P0")
	)
	(arc
		(start 203.645516 -74.164698)
		(mid 203.583844 -74.475214)
		(end 203.408026 -74.738484)
		(width 0.1397)
		(layer "B.Cu")
		(net "PCIE_SAS_CPU_RX_P0")
	)
	(arc
		(start 93.50121 -29.963364)
		(mid 93.47402 -29.827141)
		(end 93.396816 -29.71165)
		(width 0.1397)
		(layer "B.Cu")
		(net "PCIE_SAS_CPU_RX_P0")
	)
	(arc
		(start 198.627746 -67.6021)
		(mid 198.993803 -67.674744)
		(end 199.304148 -67.882008)
		(width 0.1397)
		(layer "B.Cu")
		(net "PCIE_SAS_CPU_RX_P0")
	)
	(segment
		(start 262.4455 -34.798)
		(end 263.41959 -34.798)
		(width 0.254)
		(layer "F.Cu")
		(net "P1V8_STBY_LL_R")
	)
	(via
		(at 267.716 -31.623)
		(size 0.7112)
		(drill 0.3556)
		(layers "F.Cu" "B.Cu")
		(net "P1V8_STBY_LL_R")
	)
	(via
		(at 263.41959 -34.798)
		(size 0.5588)
		(drill 0.3048)
		(layers "F.Cu" "B.Cu")
		(net "P1V8_STBY_LL_R")
	)
	(segment
		(start 267.716 -31.623)
		(end 269.3035 -31.623)
		(width 0.254)
		(layer "B.Cu")
		(net "P1V8_STBY_LL_R")
	)
	(segment
		(start 269.3035 -31.623)
		(end 269.3035 -30.607)
		(width 0.254)
		(layer "B.Cu")
		(net "P1V8_STBY_LL_R")
	)
	(segment
		(start 266.59459 -31.623)
		(end 263.41959 -34.798)
		(width 0.254)
		(layer "B.Cu")
		(net "P1V8_STBY_LL_R")
	)
	(segment
		(start 267.716 -31.623)
		(end 266.59459 -31.623)
		(width 0.254)
		(layer "B.Cu")
		(net "P1V8_STBY_LL_R")
	)
	(segment
		(start 286.034734 -180.640228)
		(end 286.034734 -180.649372)
		(width 0.1143)
		(layer "F.Cu")
		(net "ROMD7")
	)
	(segment
		(start 286.434784 -180.240178)
		(end 286.034734 -180.640228)
		(width 0.1143)
		(layer "F.Cu")
		(net "ROMD7")
	)
	(via
		(at 286.034734 -180.649372)
		(size 0.508)
		(drill 0.254)
		(layers "F.Cu" "B.Cu")
		(net "ROMD7")
	)
	(via
		(at 283.591 -182.4482)
		(size 0.7112)
		(drill 0.3556)
		(layers "F.Cu" "B.Cu")
		(net "ROMD7")
	)
	(segment
		(start 283.591 -182.4482)
		(end 283.591 -181.521354)
		(width 0.1143)
		(layer "B.Cu")
		(net "ROMD7")
	)
	(segment
		(start 275.1455 -186.817)
		(end 279.287478 -186.817)
		(width 0.1143)
		(layer "B.Cu")
		(net "ROMD7")
	)
	(segment
		(start 284.462982 -180.649372)
		(end 286.034734 -180.649372)
		(width 0.1143)
		(layer "B.Cu")
		(net "ROMD7")
	)
	(segment
		(start 279.287478 -186.817)
		(end 283.591 -182.513478)
		(width 0.1143)
		(layer "B.Cu")
		(net "ROMD7")
	)
	(segment
		(start 283.591 -182.513478)
		(end 283.591 -182.4482)
		(width 0.1143)
		(layer "B.Cu")
		(net "ROMD7")
	)
	(segment
		(start 274.8915 -187.071)
		(end 275.1455 -186.817)
		(width 0.1143)
		(layer "B.Cu")
		(net "ROMD7")
	)
	(segment
		(start 283.591 -181.521354)
		(end 284.462982 -180.649372)
		(width 0.1143)
		(layer "B.Cu")
		(net "ROMD7")
	)
	(segment
		(start 333.096362 -222.157036)
		(end 333.096362 -221.131638)
		(width 0.1143)
		(layer "F.Cu")
		(net "VOL_SEN_SCL")
	)
	(segment
		(start 335.661 -218.567)
		(end 335.28 -218.948)
		(width 0.1143)
		(layer "F.Cu")
		(net "VOL_SEN_SCL")
	)
	(segment
		(start 335.661 -217.805)
		(end 335.661 -218.567)
		(width 0.1143)
		(layer "F.Cu")
		(net "VOL_SEN_SCL")
	)
	(segment
		(start 333.096362 -221.131638)
		(end 335.28 -218.948)
		(width 0.1143)
		(layer "F.Cu")
		(net "VOL_SEN_SCL")
	)
	(segment
		(start 336.804 -217.805)
		(end 335.661 -217.805)
		(width 0.1143)
		(layer "F.Cu")
		(net "VOL_SEN_SCL")
	)
	(via
		(at 335.28 -218.948)
		(size 0.7112)
		(drill 0.3556)
		(layers "F.Cu" "B.Cu")
		(net "VOL_SEN_SCL")
	)
	(segment
		(start 123.35002 -92.349574)
		(end 122.850148 -91.849702)
		(width 0.1016)
		(layer "F.Cu")
		(net "SAS_GF_EXP_RX_DP2")
	)
	(segment
		(start 123.35002 -92.349828)
		(end 123.35002 -92.349574)
		(width 0.1016)
		(layer "F.Cu")
		(net "SAS_GF_EXP_RX_DP2")
	)
	(via
		(at 122.850148 -91.849702)
		(size 0.508)
		(drill 0.254)
		(layers "F.Cu" "B.Cu")
		(net "SAS_GF_EXP_RX_DP2")
	)
	(segment
		(start 141.732 -253.820422)
		(end 141.732 -162.694874)
		(width 0.1016)
		(layer "B.Cu")
		(net "SAS_GF_EXP_RX_DP2")
	)
	(segment
		(start 125.01499 -92.87002)
		(end 124.58954 -92.44457)
		(width 0.1016)
		(layer "B.Cu")
		(net "SAS_GF_EXP_RX_DP2")
	)
	(segment
		(start 123.604782 -92.218256)
		(end 123.063 -91.993974)
		(width 0.1016)
		(layer "B.Cu")
		(net "SAS_GF_EXP_RX_DP2")
	)
	(segment
		(start 140.836904 -160.533842)
		(end 127.946404 -147.643342)
		(width 0.1016)
		(layer "B.Cu")
		(net "SAS_GF_EXP_RX_DP2")
	)
	(segment
		(start 129.0574 -94.781624)
		(end 128.51003 -94.781624)
		(width 0.1016)
		(layer "B.Cu")
		(net "SAS_GF_EXP_RX_DP2")
	)
	(segment
		(start 133.04647 -106.88066)
		(end 133.04647 -98.856546)
		(width 0.1016)
		(layer "B.Cu")
		(net "SAS_GF_EXP_RX_DP2")
	)
	(segment
		(start 128.021334 -94.579186)
		(end 126.834392 -93.392244)
		(width 0.1016)
		(layer "B.Cu")
		(net "SAS_GF_EXP_RX_DP2")
	)
	(segment
		(start 132.632704 -97.857564)
		(end 129.90957 -95.13443)
		(width 0.1016)
		(layer "B.Cu")
		(net "SAS_GF_EXP_RX_DP2")
	)
	(segment
		(start 127.4699 -146.492976)
		(end 127.4699 -115.135152)
		(width 0.1016)
		(layer "B.Cu")
		(net "SAS_GF_EXP_RX_DP2")
	)
	(segment
		(start 141.999462 -256.50444)
		(end 141.999462 -254.46609)
		(width 0.1016)
		(layer "B.Cu")
		(net "SAS_GF_EXP_RX_DP2")
	)
	(segment
		(start 141.749018 -253.940818)
		(end 141.749018 -253.940564)
		(width 0.1016)
		(layer "B.Cu")
		(net "SAS_GF_EXP_RX_DP2")
	)
	(segment
		(start 122.856752 -91.856306)
		(end 122.850148 -91.849702)
		(width 0.1016)
		(layer "B.Cu")
		(net "SAS_GF_EXP_RX_DP2")
	)
	(segment
		(start 126.04115 -93.063822)
		(end 125.482858 -93.063822)
		(width 0.1016)
		(layer "B.Cu")
		(net "SAS_GF_EXP_RX_DP2")
	)
	(segment
		(start 124.140468 -92.258642)
		(end 123.80722 -92.258642)
		(width 0.1016)
		(layer "B.Cu")
		(net "SAS_GF_EXP_RX_DP2")
	)
	(segment
		(start 128.506728 -112.631982)
		(end 132.189728 -108.948982)
		(width 0.1016)
		(layer "B.Cu")
		(net "SAS_GF_EXP_RX_DP2")
	)
	(arc
		(start 125.482858 -93.063822)
		(mid 125.229648 -93.013455)
		(end 125.01499 -92.87002)
		(width 0.1016)
		(layer "B.Cu")
		(net "SAS_GF_EXP_RX_DP2")
	)
	(arc
		(start 127.4699 -115.135152)
		(mid 127.739366 -113.780453)
		(end 128.506728 -112.631982)
		(width 0.1016)
		(layer "B.Cu")
		(net "SAS_GF_EXP_RX_DP2")
	)
	(arc
		(start 128.51003 -94.781624)
		(mid 128.245544 -94.729015)
		(end 128.021334 -94.579186)
		(width 0.1016)
		(layer "B.Cu")
		(net "SAS_GF_EXP_RX_DP2")
	)
	(arc
		(start 127.946404 -147.643342)
		(mid 127.593744 -147.11555)
		(end 127.4699 -146.492976)
		(width 0.1016)
		(layer "B.Cu")
		(net "SAS_GF_EXP_RX_DP2")
	)
	(arc
		(start 123.805188 -92.258388)
		(mid 123.714669 -92.250186)
		(end 123.62688 -92.226638)
		(width 0.1016)
		(layer "B.Cu")
		(net "SAS_GF_EXP_RX_DP2")
	)
	(arc
		(start 123.62688 -92.226638)
		(mid 123.615785 -92.22257)
		(end 123.604782 -92.218256)
		(width 0.1016)
		(layer "B.Cu")
		(net "SAS_GF_EXP_RX_DP2")
	)
	(arc
		(start 141.757908 -253.967996)
		(mid 141.753238 -253.954481)
		(end 141.749018 -253.940818)
		(width 0.1016)
		(layer "B.Cu")
		(net "SAS_GF_EXP_RX_DP2")
	)
	(arc
		(start 132.189728 -108.948982)
		(mid 132.823799 -108.000028)
		(end 133.04647 -106.88066)
		(width 0.1016)
		(layer "B.Cu")
		(net "SAS_GF_EXP_RX_DP2")
	)
	(arc
		(start 133.04647 -98.856546)
		(mid 132.938946 -98.315897)
		(end 132.632704 -97.857564)
		(width 0.1016)
		(layer "B.Cu")
		(net "SAS_GF_EXP_RX_DP2")
	)
	(arc
		(start 123.063 -91.993974)
		(mid 122.953089 -91.935307)
		(end 122.856752 -91.856306)
		(width 0.1016)
		(layer "B.Cu")
		(net "SAS_GF_EXP_RX_DP2")
	)
	(arc
		(start 141.73327 -253.855474)
		(mid 141.732278 -253.837961)
		(end 141.732 -253.820422)
		(width 0.1016)
		(layer "B.Cu")
		(net "SAS_GF_EXP_RX_DP2")
	)
	(arc
		(start 126.834392 -93.392244)
		(mid 126.470434 -93.149148)
		(end 126.04115 -93.063822)
		(width 0.1016)
		(layer "B.Cu")
		(net "SAS_GF_EXP_RX_DP2")
	)
	(arc
		(start 129.90957 -95.13443)
		(mid 129.518576 -94.873269)
		(end 129.0574 -94.781624)
		(width 0.1016)
		(layer "B.Cu")
		(net "SAS_GF_EXP_RX_DP2")
	)
	(arc
		(start 141.749018 -253.940564)
		(mid 141.739005 -253.898414)
		(end 141.73327 -253.855474)
		(width 0.1016)
		(layer "B.Cu")
		(net "SAS_GF_EXP_RX_DP2")
	)
	(arc
		(start 123.80722 -92.258642)
		(mid 123.806204 -92.258516)
		(end 123.805188 -92.258388)
		(width 0.1016)
		(layer "B.Cu")
		(net "SAS_GF_EXP_RX_DP2")
	)
	(arc
		(start 141.859 -254.127)
		(mid 141.799708 -254.053058)
		(end 141.757908 -253.967996)
		(width 0.1016)
		(layer "B.Cu")
		(net "SAS_GF_EXP_RX_DP2")
	)
	(arc
		(start 141.732 -162.694874)
		(mid 141.499366 -161.525344)
		(end 140.836904 -160.533842)
		(width 0.1016)
		(layer "B.Cu")
		(net "SAS_GF_EXP_RX_DP2")
	)
	(arc
		(start 141.999462 -254.46609)
		(mid 141.962958 -254.282573)
		(end 141.859 -254.127)
		(width 0.1016)
		(layer "B.Cu")
		(net "SAS_GF_EXP_RX_DP2")
	)
	(arc
		(start 124.58954 -92.44457)
		(mid 124.38349 -92.306955)
		(end 124.140468 -92.258642)
		(width 0.1016)
		(layer "B.Cu")
		(net "SAS_GF_EXP_RX_DP2")
	)
	(segment
		(start 265.437874 -41.891458)
		(end 265.437874 -43.699938)
		(width 0.3048)
		(layer "F.Cu")
		(net "P1V8_STBY_VDD")
	)
	(segment
		(start 267.2334 -43.9674)
		(end 267.081 -43.815)
		(width 0.508)
		(layer "F.Cu")
		(net "P1V8_STBY_VDD")
	)
	(segment
		(start 266.958064 -43.937936)
		(end 267.081 -43.815)
		(width 0.508)
		(layer "F.Cu")
		(net "P1V8_STBY_VDD")
	)
	(segment
		(start 265.675872 -43.937936)
		(end 266.958064 -43.937936)
		(width 0.508)
		(layer "F.Cu")
		(net "P1V8_STBY_VDD")
	)
	(segment
		(start 265.437874 -43.699938)
		(end 265.675872 -43.937936)
		(width 0.3048)
		(layer "F.Cu")
		(net "P1V8_STBY_VDD")
	)
	(segment
		(start 267.2334 -44.8564)
		(end 267.2334 -43.9674)
		(width 0.508)
		(layer "F.Cu")
		(net "P1V8_STBY_VDD")
	)
	(via
		(at 267.081 -43.815)
		(size 0.7112)
		(drill 0.3556)
		(layers "F.Cu" "B.Cu")
		(net "P1V8_STBY_VDD")
	)
	(segment
		(start 110.349792 -103.35006)
		(end 109.849666 -103.850186)
		(width 0.1016)
		(layer "F.Cu")
		(net "SAS_GF_EXP_RX_DP12")
	)
	(via
		(at 109.849666 -103.850186)
		(size 0.508)
		(drill 0.254)
		(layers "F.Cu" "B.Cu")
		(net "SAS_GF_EXP_RX_DP12")
	)
	(segment
		(start 109.603794 -104.238298)
		(end 109.618272 -104.238298)
		(width 0.1016)
		(layer "B.Cu")
		(net "SAS_GF_EXP_RX_DP12")
	)
	(segment
		(start 83.631024 -239.907826)
		(end 83.631024 -234.827826)
		(width 0.1016)
		(layer "B.Cu")
		(net "SAS_GF_EXP_RX_DP12")
	)
	(segment
		(start 83.869784 -245.384066)
		(end 83.869784 -245.079266)
		(width 0.1016)
		(layer "B.Cu")
		(net "SAS_GF_EXP_RX_DP12")
	)
	(segment
		(start 83.631024 -233.567986)
		(end 83.631024 -233.263186)
		(width 0.1016)
		(layer "B.Cu")
		(net "SAS_GF_EXP_RX_DP12")
	)
	(segment
		(start 83.631024 -230.438706)
		(end 83.631024 -221.850712)
		(width 0.1016)
		(layer "B.Cu")
		(net "SAS_GF_EXP_RX_DP12")
	)
	(segment
		(start 109.503718 -104.368092)
		(end 109.603794 -104.238298)
		(width 0.1016)
		(layer "B.Cu")
		(net "SAS_GF_EXP_RX_DP12")
	)
	(segment
		(start 84.113116 -220.686884)
		(end 89.997026 -214.802974)
		(width 0.1016)
		(layer "B.Cu")
		(net "SAS_GF_EXP_RX_DP12")
	)
	(segment
		(start 109.149642 -113.425478)
		(end 109.149642 -107.535472)
		(width 0.1016)
		(layer "B.Cu")
		(net "SAS_GF_EXP_RX_DP12")
	)
	(segment
		(start 83.869784 -242.254786)
		(end 83.869784 -241.949986)
		(width 0.1016)
		(layer "B.Cu")
		(net "SAS_GF_EXP_RX_DP12")
	)
	(segment
		(start 83.869784 -234.350306)
		(end 83.869784 -234.045506)
		(width 0.1016)
		(layer "B.Cu")
		(net "SAS_GF_EXP_RX_DP12")
	)
	(segment
		(start 83.869784 -231.221026)
		(end 83.869784 -230.916226)
		(width 0.1016)
		(layer "B.Cu")
		(net "SAS_GF_EXP_RX_DP12")
	)
	(segment
		(start 109.444028 -105.05059)
		(end 109.444028 -105.050336)
		(width 0.1016)
		(layer "B.Cu")
		(net "SAS_GF_EXP_RX_DP12")
	)
	(segment
		(start 83.869784 -243.819426)
		(end 83.869784 -243.514626)
		(width 0.1016)
		(layer "B.Cu")
		(net "SAS_GF_EXP_RX_DP12")
	)
	(segment
		(start 85.225128 -249.625612)
		(end 84.536026 -248.93651)
		(width 0.1016)
		(layer "B.Cu")
		(net "SAS_GF_EXP_RX_DP12")
	)
	(segment
		(start 109.849666 -103.928672)
		(end 109.849666 -103.850186)
		(width 0.1016)
		(layer "B.Cu")
		(net "SAS_GF_EXP_RX_DP12")
	)
	(segment
		(start 90.805 -212.852)
		(end 90.805 -176.816766)
		(width 0.1016)
		(layer "B.Cu")
		(net "SAS_GF_EXP_RX_DP12")
	)
	(segment
		(start 108.50626 -114.332004)
		(end 108.963714 -113.87455)
		(width 0.1016)
		(layer "B.Cu")
		(net "SAS_GF_EXP_RX_DP12")
	)
	(segment
		(start 109.569504 -105.427018)
		(end 109.444028 -105.05059)
		(width 0.1016)
		(layer "B.Cu")
		(net "SAS_GF_EXP_RX_DP12")
	)
	(segment
		(start 83.631024 -241.472466)
		(end 83.631024 -241.167666)
		(width 0.1016)
		(layer "B.Cu")
		(net "SAS_GF_EXP_RX_DP12")
	)
	(segment
		(start 86.000082 -256.50444)
		(end 86.000082 -254.56388)
		(width 0.1016)
		(layer "B.Cu")
		(net "SAS_GF_EXP_RX_DP12")
	)
	(segment
		(start 83.869784 -232.785666)
		(end 83.869784 -232.480866)
		(width 0.1016)
		(layer "B.Cu")
		(net "SAS_GF_EXP_RX_DP12")
	)
	(segment
		(start 83.631024 -246.462296)
		(end 83.631024 -245.861586)
		(width 0.1016)
		(layer "B.Cu")
		(net "SAS_GF_EXP_RX_DP12")
	)
	(segment
		(start 109.435392 -105.019602)
		(end 109.423454 -104.963722)
		(width 0.1016)
		(layer "B.Cu")
		(net "SAS_GF_EXP_RX_DP12")
	)
	(segment
		(start 109.33557 -107.0864)
		(end 109.433614 -106.988356)
		(width 0.1016)
		(layer "B.Cu")
		(net "SAS_GF_EXP_RX_DP12")
	)
	(segment
		(start 108.273342 -156.745178)
		(end 108.273342 -114.89436)
		(width 0.1016)
		(layer "B.Cu")
		(net "SAS_GF_EXP_RX_DP12")
	)
	(segment
		(start 109.618272 -104.238298)
		(end 109.794294 -104.062276)
		(width 0.1016)
		(layer "B.Cu")
		(net "SAS_GF_EXP_RX_DP12")
	)
	(segment
		(start 109.421168 -104.94264)
		(end 109.421168 -104.622346)
		(width 0.1016)
		(layer "B.Cu")
		(net "SAS_GF_EXP_RX_DP12")
	)
	(segment
		(start 85.671152 -253.769876)
		(end 85.671152 -250.702826)
		(width 0.1016)
		(layer "B.Cu")
		(net "SAS_GF_EXP_RX_DP12")
	)
	(segment
		(start 109.619542 -106.539284)
		(end 109.619542 -105.73639)
		(width 0.1016)
		(layer "B.Cu")
		(net "SAS_GF_EXP_RX_DP12")
	)
	(segment
		(start 83.869784 -240.690146)
		(end 83.869784 -240.385346)
		(width 0.1016)
		(layer "B.Cu")
		(net "SAS_GF_EXP_RX_DP12")
	)
	(segment
		(start 91.446858 -175.267112)
		(end 107.07497 -159.639)
		(width 0.1016)
		(layer "B.Cu")
		(net "SAS_GF_EXP_RX_DP12")
	)
	(segment
		(start 83.631024 -232.003346)
		(end 83.631024 -231.698546)
		(width 0.1016)
		(layer "B.Cu")
		(net "SAS_GF_EXP_RX_DP12")
	)
	(segment
		(start 83.631024 -243.037106)
		(end 83.631024 -242.732306)
		(width 0.1016)
		(layer "B.Cu")
		(net "SAS_GF_EXP_RX_DP12")
	)
	(segment
		(start 83.631024 -244.601746)
		(end 83.631024 -244.296946)
		(width 0.1016)
		(layer "B.Cu")
		(net "SAS_GF_EXP_RX_DP12")
	)
	(arc
		(start 83.869784 -240.385346)
		(mid 83.839292 -240.251353)
		(end 83.750404 -240.146586)
		(width 0.1016)
		(layer "B.Cu")
		(net "SAS_GF_EXP_RX_DP12")
	)
	(arc
		(start 108.273342 -114.89436)
		(mid 108.333879 -114.590022)
		(end 108.50626 -114.332004)
		(width 0.1016)
		(layer "B.Cu")
		(net "SAS_GF_EXP_RX_DP12")
	)
	(arc
		(start 90.805 -176.816766)
		(mid 90.971819 -175.978111)
		(end 91.446858 -175.267112)
		(width 0.1016)
		(layer "B.Cu")
		(net "SAS_GF_EXP_RX_DP12")
	)
	(arc
		(start 109.444028 -105.050336)
		(mid 109.43929 -105.035087)
		(end 109.435392 -105.019602)
		(width 0.1016)
		(layer "B.Cu")
		(net "SAS_GF_EXP_RX_DP12")
	)
	(arc
		(start 109.149642 -107.535472)
		(mid 109.197963 -107.292454)
		(end 109.33557 -107.0864)
		(width 0.1016)
		(layer "B.Cu")
		(net "SAS_GF_EXP_RX_DP12")
	)
	(arc
		(start 109.794294 -104.062276)
		(mid 109.835281 -104.000979)
		(end 109.849666 -103.928672)
		(width 0.1016)
		(layer "B.Cu")
		(net "SAS_GF_EXP_RX_DP12")
	)
	(arc
		(start 107.07497 -159.639)
		(mid 107.961996 -158.311287)
		(end 108.273342 -156.745178)
		(width 0.1016)
		(layer "B.Cu")
		(net "SAS_GF_EXP_RX_DP12")
	)
	(arc
		(start 83.869784 -241.949986)
		(mid 83.839292 -241.815993)
		(end 83.750404 -241.711226)
		(width 0.1016)
		(layer "B.Cu")
		(net "SAS_GF_EXP_RX_DP12")
	)
	(arc
		(start 89.997026 -214.802974)
		(mid 90.595039 -213.907844)
		(end 90.805 -212.852)
		(width 0.1016)
		(layer "B.Cu")
		(net "SAS_GF_EXP_RX_DP12")
	)
	(arc
		(start 83.750404 -242.493546)
		(mid 83.839198 -242.388732)
		(end 83.869784 -242.254786)
		(width 0.1016)
		(layer "B.Cu")
		(net "SAS_GF_EXP_RX_DP12")
	)
	(arc
		(start 83.750404 -240.928906)
		(mid 83.839198 -240.824092)
		(end 83.869784 -240.690146)
		(width 0.1016)
		(layer "B.Cu")
		(net "SAS_GF_EXP_RX_DP12")
	)
	(arc
		(start 83.869784 -245.079266)
		(mid 83.839292 -244.945273)
		(end 83.750404 -244.840506)
		(width 0.1016)
		(layer "B.Cu")
		(net "SAS_GF_EXP_RX_DP12")
	)
	(arc
		(start 83.750404 -233.806746)
		(mid 83.66161 -233.701932)
		(end 83.631024 -233.567986)
		(width 0.1016)
		(layer "B.Cu")
		(net "SAS_GF_EXP_RX_DP12")
	)
	(arc
		(start 83.869784 -232.480866)
		(mid 83.839292 -232.346873)
		(end 83.750404 -232.242106)
		(width 0.1016)
		(layer "B.Cu")
		(net "SAS_GF_EXP_RX_DP12")
	)
	(arc
		(start 85.671152 -250.702826)
		(mid 85.555285 -250.119854)
		(end 85.225128 -249.625612)
		(width 0.1016)
		(layer "B.Cu")
		(net "SAS_GF_EXP_RX_DP12")
	)
	(arc
		(start 83.750404 -230.677466)
		(mid 83.66161 -230.572652)
		(end 83.631024 -230.438706)
		(width 0.1016)
		(layer "B.Cu")
		(net "SAS_GF_EXP_RX_DP12")
	)
	(arc
		(start 83.750404 -233.024426)
		(mid 83.839198 -232.919612)
		(end 83.869784 -232.785666)
		(width 0.1016)
		(layer "B.Cu")
		(net "SAS_GF_EXP_RX_DP12")
	)
	(arc
		(start 109.421168 -104.622346)
		(mid 109.44894 -104.490838)
		(end 109.503718 -104.368092)
		(width 0.1016)
		(layer "B.Cu")
		(net "SAS_GF_EXP_RX_DP12")
	)
	(arc
		(start 83.750404 -244.840506)
		(mid 83.66161 -244.735692)
		(end 83.631024 -244.601746)
		(width 0.1016)
		(layer "B.Cu")
		(net "SAS_GF_EXP_RX_DP12")
	)
	(arc
		(start 83.750404 -234.589066)
		(mid 83.839198 -234.484252)
		(end 83.869784 -234.350306)
		(width 0.1016)
		(layer "B.Cu")
		(net "SAS_GF_EXP_RX_DP12")
	)
	(arc
		(start 83.750404 -241.711226)
		(mid 83.66161 -241.606412)
		(end 83.631024 -241.472466)
		(width 0.1016)
		(layer "B.Cu")
		(net "SAS_GF_EXP_RX_DP12")
	)
	(arc
		(start 109.423454 -104.963722)
		(mid 109.42177 -104.95324)
		(end 109.421168 -104.94264)
		(width 0.1016)
		(layer "B.Cu")
		(net "SAS_GF_EXP_RX_DP12")
	)
	(arc
		(start 83.869784 -243.514626)
		(mid 83.839292 -243.380633)
		(end 83.750404 -243.275866)
		(width 0.1016)
		(layer "B.Cu")
		(net "SAS_GF_EXP_RX_DP12")
	)
	(arc
		(start 83.750404 -245.622826)
		(mid 83.839198 -245.518012)
		(end 83.869784 -245.384066)
		(width 0.1016)
		(layer "B.Cu")
		(net "SAS_GF_EXP_RX_DP12")
	)
	(arc
		(start 83.631024 -233.263186)
		(mid 83.661516 -233.129193)
		(end 83.750404 -233.024426)
		(width 0.1016)
		(layer "B.Cu")
		(net "SAS_GF_EXP_RX_DP12")
	)
	(arc
		(start 84.536026 -248.93651)
		(mid 83.864413 -247.779553)
		(end 83.631024 -246.462296)
		(width 0.1016)
		(layer "B.Cu")
		(net "SAS_GF_EXP_RX_DP12")
	)
	(arc
		(start 83.869784 -234.045506)
		(mid 83.839292 -233.911513)
		(end 83.750404 -233.806746)
		(width 0.1016)
		(layer "B.Cu")
		(net "SAS_GF_EXP_RX_DP12")
	)
	(arc
		(start 109.619542 -105.73639)
		(mid 109.606988 -105.579689)
		(end 109.569504 -105.427018)
		(width 0.1016)
		(layer "B.Cu")
		(net "SAS_GF_EXP_RX_DP12")
	)
	(arc
		(start 86.000082 -254.56388)
		(mid 85.957372 -254.349162)
		(end 85.835744 -254.167132)
		(width 0.1016)
		(layer "B.Cu")
		(net "SAS_GF_EXP_RX_DP12")
	)
	(arc
		(start 83.750404 -244.058186)
		(mid 83.839198 -243.953372)
		(end 83.869784 -243.819426)
		(width 0.1016)
		(layer "B.Cu")
		(net "SAS_GF_EXP_RX_DP12")
	)
	(arc
		(start 83.631024 -244.296946)
		(mid 83.661516 -244.162953)
		(end 83.750404 -244.058186)
		(width 0.1016)
		(layer "B.Cu")
		(net "SAS_GF_EXP_RX_DP12")
	)
	(arc
		(start 83.631024 -234.827826)
		(mid 83.661516 -234.693833)
		(end 83.750404 -234.589066)
		(width 0.1016)
		(layer "B.Cu")
		(net "SAS_GF_EXP_RX_DP12")
	)
	(arc
		(start 83.750404 -231.459786)
		(mid 83.839198 -231.354972)
		(end 83.869784 -231.221026)
		(width 0.1016)
		(layer "B.Cu")
		(net "SAS_GF_EXP_RX_DP12")
	)
	(arc
		(start 83.750404 -240.146586)
		(mid 83.66161 -240.041772)
		(end 83.631024 -239.907826)
		(width 0.1016)
		(layer "B.Cu")
		(net "SAS_GF_EXP_RX_DP12")
	)
	(arc
		(start 85.835744 -254.167132)
		(mid 85.713906 -253.984884)
		(end 85.671152 -253.769876)
		(width 0.1016)
		(layer "B.Cu")
		(net "SAS_GF_EXP_RX_DP12")
	)
	(arc
		(start 108.963714 -113.87455)
		(mid 109.101329 -113.6685)
		(end 109.149642 -113.425478)
		(width 0.1016)
		(layer "B.Cu")
		(net "SAS_GF_EXP_RX_DP12")
	)
	(arc
		(start 83.631024 -241.167666)
		(mid 83.661516 -241.033673)
		(end 83.750404 -240.928906)
		(width 0.1016)
		(layer "B.Cu")
		(net "SAS_GF_EXP_RX_DP12")
	)
	(arc
		(start 83.631024 -245.861586)
		(mid 83.661516 -245.727593)
		(end 83.750404 -245.622826)
		(width 0.1016)
		(layer "B.Cu")
		(net "SAS_GF_EXP_RX_DP12")
	)
	(arc
		(start 83.631024 -221.850712)
		(mid 83.756312 -221.220846)
		(end 84.113116 -220.686884)
		(width 0.1016)
		(layer "B.Cu")
		(net "SAS_GF_EXP_RX_DP12")
	)
	(arc
		(start 109.433614 -106.988356)
		(mid 109.571229 -106.782306)
		(end 109.619542 -106.539284)
		(width 0.1016)
		(layer "B.Cu")
		(net "SAS_GF_EXP_RX_DP12")
	)
	(arc
		(start 83.631024 -231.698546)
		(mid 83.661516 -231.564553)
		(end 83.750404 -231.459786)
		(width 0.1016)
		(layer "B.Cu")
		(net "SAS_GF_EXP_RX_DP12")
	)
	(arc
		(start 83.750404 -232.242106)
		(mid 83.66161 -232.137292)
		(end 83.631024 -232.003346)
		(width 0.1016)
		(layer "B.Cu")
		(net "SAS_GF_EXP_RX_DP12")
	)
	(arc
		(start 83.869784 -230.916226)
		(mid 83.839292 -230.782233)
		(end 83.750404 -230.677466)
		(width 0.1016)
		(layer "B.Cu")
		(net "SAS_GF_EXP_RX_DP12")
	)
	(arc
		(start 83.750404 -243.275866)
		(mid 83.66161 -243.171052)
		(end 83.631024 -243.037106)
		(width 0.1016)
		(layer "B.Cu")
		(net "SAS_GF_EXP_RX_DP12")
	)
	(arc
		(start 83.631024 -242.732306)
		(mid 83.661516 -242.598313)
		(end 83.750404 -242.493546)
		(width 0.1016)
		(layer "B.Cu")
		(net "SAS_GF_EXP_RX_DP12")
	)
	(via
		(at 271.526 -31.623)
		(size 0.5588)
		(drill 0.3048)
		(layers "F.Cu" "B.Cu")
		(net "P1V8_STBY_LL")
	)
	(via
		(at 273.939 -35.687)
		(size 0.7112)
		(drill 0.3556)
		(layers "F.Cu" "B.Cu")
		(net "P1V8_STBY_LL")
	)
	(via
		(at 272.288 -34.544)
		(size 0.5588)
		(drill 0.3048)
		(layers "F.Cu" "B.Cu")
		(net "P1V8_STBY_LL")
	)
	(segment
		(start 272.288 -34.544)
		(end 272.669 -34.925)
		(width 0.508)
		(layer "B.Cu")
		(net "P1V8_STBY_LL")
	)
	(segment
		(start 270.1925 -31.623)
		(end 271.526 -31.623)
		(width 0.508)
		(layer "B.Cu")
		(net "P1V8_STBY_LL")
	)
	(segment
		(start 272.669 -34.925)
		(end 272.669 -35.687)
		(width 0.508)
		(layer "B.Cu")
		(net "P1V8_STBY_LL")
	)
	(segment
		(start 272.669 -35.687)
		(end 273.939 -35.687)
		(width 0.3048)
		(layer "B.Cu")
		(net "P1V8_STBY_LL")
	)
	(segment
		(start 271.800574 -182.351426)
		(end 270.129 -184.023)
		(width 0.1143)
		(layer "F.Cu")
		(net "ROMD0")
	)
	(segment
		(start 337.384136 -240.03)
		(end 343.027 -234.387136)
		(width 0.1143)
		(layer "F.Cu")
		(net "ROMD0")
	)
	(segment
		(start 254.878078 -191.542162)
		(end 254.878078 -229.663752)
		(width 0.1143)
		(layer "F.Cu")
		(net "ROMD0")
	)
	(segment
		(start 352.57105 -90.65895)
		(end 352.57105 -78.25105)
		(width 0.1143)
		(layer "F.Cu")
		(net "ROMD0")
	)
	(segment
		(start 352.57105 -78.25105)
		(end 350.901 -76.581)
		(width 0.1143)
		(layer "F.Cu")
		(net "ROMD0")
	)
	(segment
		(start 284.834838 -179.440078)
		(end 283.50464 -179.440078)
		(width 0.1143)
		(layer "F.Cu")
		(net "ROMD0")
	)
	(segment
		(start 353.23145 -167.849296)
		(end 353.23145 -146.34845)
		(width 0.1143)
		(layer "F.Cu")
		(net "ROMD0")
	)
	(segment
		(start 351.559622 -91.670378)
		(end 352.57105 -90.65895)
		(width 0.1143)
		(layer "F.Cu")
		(net "ROMD0")
	)
	(segment
		(start 275.59 -181.40299)
		(end 275.59 -181.531514)
		(width 0.1143)
		(layer "F.Cu")
		(net "ROMD0")
	)
	(segment
		(start 283.50464 -179.440078)
		(end 283.38399 -179.319428)
		(width 0.1143)
		(layer "F.Cu")
		(net "ROMD0")
	)
	(segment
		(start 262.39724 -184.023)
		(end 254.878078 -191.542162)
		(width 0.1143)
		(layer "F.Cu")
		(net "ROMD0")
	)
	(segment
		(start 270.129 -184.023)
		(end 262.39724 -184.023)
		(width 0.1143)
		(layer "F.Cu")
		(net "ROMD0")
	)
	(segment
		(start 343.027 -234.387136)
		(end 343.027 -178.053746)
		(width 0.1143)
		(layer "F.Cu")
		(net "ROMD0")
	)
	(segment
		(start 265.244326 -240.03)
		(end 337.384136 -240.03)
		(width 0.1143)
		(layer "F.Cu")
		(net "ROMD0")
	)
	(segment
		(start 277.673562 -179.319428)
		(end 275.59 -181.40299)
		(width 0.1143)
		(layer "F.Cu")
		(net "ROMD0")
	)
	(segment
		(start 351.559622 -144.676622)
		(end 351.559622 -91.670378)
		(width 0.1143)
		(layer "F.Cu")
		(net "ROMD0")
	)
	(segment
		(start 350.901 -76.581)
		(end 350.901 -74.168)
		(width 0.1143)
		(layer "F.Cu")
		(net "ROMD0")
	)
	(segment
		(start 275.59 -181.531514)
		(end 274.770088 -182.351426)
		(width 0.1143)
		(layer "F.Cu")
		(net "ROMD0")
	)
	(segment
		(start 283.38399 -179.319428)
		(end 277.673562 -179.319428)
		(width 0.1143)
		(layer "F.Cu")
		(net "ROMD0")
	)
	(segment
		(start 343.027 -178.053746)
		(end 353.23145 -167.849296)
		(width 0.1143)
		(layer "F.Cu")
		(net "ROMD0")
	)
	(segment
		(start 353.23145 -146.34845)
		(end 351.559622 -144.676622)
		(width 0.1143)
		(layer "F.Cu")
		(net "ROMD0")
	)
	(segment
		(start 274.770088 -182.351426)
		(end 271.800574 -182.351426)
		(width 0.1143)
		(layer "F.Cu")
		(net "ROMD0")
	)
	(segment
		(start 254.878078 -229.663752)
		(end 265.244326 -240.03)
		(width 0.1143)
		(layer "F.Cu")
		(net "ROMD0")
	)
	(via
		(at 350.901 -74.168)
		(size 0.5588)
		(drill 0.3048)
		(layers "F.Cu" "B.Cu")
		(net "ROMD0")
	)
	(via
		(at 350.901 -73.279)
		(size 0.7112)
		(drill 0.3556)
		(layers "F.Cu" "B.Cu")
		(net "ROMD0")
	)
	(segment
		(start 350.901 -73.279)
		(end 350.901 -74.168)
		(width 0.1143)
		(layer "B.Cu")
		(net "ROMD0")
	)
	(segment
		(start 350.5962 -72.9742)
		(end 350.901 -73.279)
		(width 0.1143)
		(layer "B.Cu")
		(net "ROMD0")
	)
	(segment
		(start 350.5962 -72.2503)
		(end 350.5962 -72.9742)
		(width 0.1143)
		(layer "B.Cu")
		(net "ROMD0")
	)
	(segment
		(start 200.63206 -75.553824)
		(end 200.63206 -76.30922)
		(width 0.1397)
		(layer "F.Cu")
		(net "PCIE_SAS_CPU_TX_P1")
	)
	(segment
		(start 199.63765 -73.405746)
		(end 199.63765 -74.041)
		(width 0.1397)
		(layer "F.Cu")
		(net "PCIE_SAS_CPU_TX_P1")
	)
	(segment
		(start 94.717616 -30.010608)
		(end 94.717616 -23.702264)
		(width 0.1397)
		(layer "F.Cu")
		(net "PCIE_SAS_CPU_TX_P1")
	)
	(segment
		(start 117.64899 -5.08)
		(end 135.712962 -5.08)
		(width 0.1397)
		(layer "F.Cu")
		(net "PCIE_SAS_CPU_TX_P1")
	)
	(segment
		(start 141.913356 -17.349216)
		(end 185.592212 -61.028072)
		(width 0.1397)
		(layer "F.Cu")
		(net "PCIE_SAS_CPU_TX_P1")
	)
	(segment
		(start 186.041284 -61.214)
		(end 187.55487 -61.214)
		(width 0.1397)
		(layer "F.Cu")
		(net "PCIE_SAS_CPU_TX_P1")
	)
	(segment
		(start 188.246512 -61.500512)
		(end 199.274176 -72.528176)
		(width 0.1397)
		(layer "F.Cu")
		(net "PCIE_SAS_CPU_TX_P1")
	)
	(segment
		(start 96.381824 -33.323276)
		(end 96.381824 -32.766)
		(width 0.1397)
		(layer "F.Cu")
		(net "PCIE_SAS_CPU_TX_P1")
	)
	(segment
		(start 105.292144 -12.8651)
		(end 109.195616 -12.8651)
		(width 0.1397)
		(layer "F.Cu")
		(net "PCIE_SAS_CPU_TX_P1")
	)
	(segment
		(start 96.082358 -32.04337)
		(end 95.190056 -31.151068)
		(width 0.1397)
		(layer "F.Cu")
		(net "PCIE_SAS_CPU_TX_P1")
	)
	(segment
		(start 109.644688 -12.679172)
		(end 116.957348 -5.366512)
		(width 0.1397)
		(layer "F.Cu")
		(net "PCIE_SAS_CPU_TX_P1")
	)
	(segment
		(start 141.5415 -11.311128)
		(end 141.5415 -16.451326)
		(width 0.1397)
		(layer "F.Cu")
		(net "PCIE_SAS_CPU_TX_P1")
	)
	(segment
		(start 199.724772 -74.251312)
		(end 200.35266 -74.8792)
		(width 0.1397)
		(layer "F.Cu")
		(net "PCIE_SAS_CPU_TX_P1")
	)
	(segment
		(start 95.190056 -22.561804)
		(end 104.600502 -13.151358)
		(width 0.1397)
		(layer "F.Cu")
		(net "PCIE_SAS_CPU_TX_P1")
	)
	(segment
		(start 136.404858 -5.366258)
		(end 140.97 -9.9314)
		(width 0.1397)
		(layer "F.Cu")
		(net "PCIE_SAS_CPU_TX_P1")
	)
	(via
		(at 200.928732 -77.0255)
		(size 0.5588)
		(drill 0.3048)
		(layers "F.Cu" "B.Cu")
		(net "PCIE_SAS_CPU_TX_P1")
	)
	(arc
		(start 199.274176 -72.528176)
		(mid 199.543153 -72.930823)
		(end 199.63765 -73.405746)
		(width 0.1397)
		(layer "F.Cu")
		(net "PCIE_SAS_CPU_TX_P1")
	)
	(arc
		(start 141.5415 -16.451326)
		(mid 141.638139 -16.937251)
		(end 141.913356 -17.349216)
		(width 0.1397)
		(layer "F.Cu")
		(net "PCIE_SAS_CPU_TX_P1")
	)
	(arc
		(start 199.63765 -74.041)
		(mid 199.660291 -74.154823)
		(end 199.724772 -74.251312)
		(width 0.1397)
		(layer "F.Cu")
		(net "PCIE_SAS_CPU_TX_P1")
	)
	(arc
		(start 96.381824 -32.766)
		(mid 96.303939 -32.374914)
		(end 96.082358 -32.04337)
		(width 0.1397)
		(layer "F.Cu")
		(net "PCIE_SAS_CPU_TX_P1")
	)
	(arc
		(start 104.600502 -13.151358)
		(mid 104.917845 -12.939409)
		(end 105.292144 -12.8651)
		(width 0.1397)
		(layer "F.Cu")
		(net "PCIE_SAS_CPU_TX_P1")
	)
	(arc
		(start 200.63206 -76.30922)
		(mid 200.709166 -76.69686)
		(end 200.928732 -77.0255)
		(width 0.1397)
		(layer "F.Cu")
		(net "PCIE_SAS_CPU_TX_P1")
	)
	(arc
		(start 200.35266 -74.8792)
		(mid 200.559475 -75.18872)
		(end 200.63206 -75.553824)
		(width 0.1397)
		(layer "F.Cu")
		(net "PCIE_SAS_CPU_TX_P1")
	)
	(arc
		(start 96.350074 -33.399984)
		(mid 96.37359 -33.36479)
		(end 96.381824 -33.323276)
		(width 0.1397)
		(layer "F.Cu")
		(net "PCIE_SAS_CPU_TX_P1")
	)
	(arc
		(start 187.55487 -61.214)
		(mid 187.929179 -61.288473)
		(end 188.246512 -61.500512)
		(width 0.1397)
		(layer "F.Cu")
		(net "PCIE_SAS_CPU_TX_P1")
	)
	(arc
		(start 109.195616 -12.8651)
		(mid 109.43862 -12.816764)
		(end 109.644688 -12.679172)
		(width 0.1397)
		(layer "F.Cu")
		(net "PCIE_SAS_CPU_TX_P1")
	)
	(arc
		(start 135.712962 -5.08)
		(mid 136.087379 -5.154307)
		(end 136.404858 -5.366258)
		(width 0.1397)
		(layer "F.Cu")
		(net "PCIE_SAS_CPU_TX_P1")
	)
	(arc
		(start 95.190056 -31.151068)
		(mid 94.840433 -30.627821)
		(end 94.717616 -30.010608)
		(width 0.1397)
		(layer "F.Cu")
		(net "PCIE_SAS_CPU_TX_P1")
	)
	(arc
		(start 140.97 -9.9314)
		(mid 141.392974 -10.564425)
		(end 141.5415 -11.311128)
		(width 0.1397)
		(layer "F.Cu")
		(net "PCIE_SAS_CPU_TX_P1")
	)
	(arc
		(start 185.592212 -61.028072)
		(mid 185.798248 -61.165741)
		(end 186.041284 -61.214)
		(width 0.1397)
		(layer "F.Cu")
		(net "PCIE_SAS_CPU_TX_P1")
	)
	(arc
		(start 116.957348 -5.366512)
		(mid 117.274662 -5.154426)
		(end 117.64899 -5.08)
		(width 0.1397)
		(layer "F.Cu")
		(net "PCIE_SAS_CPU_TX_P1")
	)
	(arc
		(start 94.717616 -23.702264)
		(mid 94.840391 -23.085034)
		(end 95.190056 -22.561804)
		(width 0.1397)
		(layer "F.Cu")
		(net "PCIE_SAS_CPU_TX_P1")
	)
	(segment
		(start 201.449686 -78.24978)
		(end 201.449686 -78.673706)
		(width 0.1397)
		(layer "B.Cu")
		(net "PCIE_SAS_CPU_TX_P1")
	)
	(segment
		(start 200.669144 -77.285088)
		(end 200.928732 -77.0255)
		(width 0.1397)
		(layer "B.Cu")
		(net "PCIE_SAS_CPU_TX_P1")
	)
	(segment
		(start 201.089768 -79.033624)
		(end 200.927462 -79.033624)
		(width 0.1397)
		(layer "B.Cu")
		(net "PCIE_SAS_CPU_TX_P1")
	)
	(segment
		(start 200.60412 -78.55331)
		(end 200.60412 -77.44206)
		(width 0.1397)
		(layer "B.Cu")
		(net "PCIE_SAS_CPU_TX_P1")
	)
	(arc
		(start 201.449686 -78.673706)
		(mid 201.344268 -78.928206)
		(end 201.089768 -79.033624)
		(width 0.1397)
		(layer "B.Cu")
		(net "PCIE_SAS_CPU_TX_P1")
	)
	(arc
		(start 200.60412 -77.44206)
		(mid 200.621018 -77.357106)
		(end 200.669144 -77.285088)
		(width 0.1397)
		(layer "B.Cu")
		(net "PCIE_SAS_CPU_TX_P1")
	)
	(arc
		(start 200.777348 -78.971394)
		(mid 200.649179 -78.779575)
		(end 200.60412 -78.55331)
		(width 0.1397)
		(layer "B.Cu")
		(net "PCIE_SAS_CPU_TX_P1")
	)
	(arc
		(start 200.927462 -79.033624)
		(mid 200.846201 -79.01746)
		(end 200.777348 -78.971394)
		(width 0.1397)
		(layer "B.Cu")
		(net "PCIE_SAS_CPU_TX_P1")
	)
	(segment
		(start 51.0413 -119.0117)
		(end 46.5074 -123.5456)
		(width 0.4064)
		(layer "F.Cu")
		(net "P1V8_STBY")
	)
	(segment
		(start 51.5747 -118.4783)
		(end 51.569112 -118.4783)
		(width 0.4064)
		(layer "F.Cu")
		(net "P1V8_STBY")
	)
	(segment
		(start 58.42 -111.633)
		(end 51.5747 -118.4783)
		(width 0.4064)
		(layer "F.Cu")
		(net "P1V8_STBY")
	)
	(segment
		(start 325.374 -181.9275)
		(end 325.501 -181.8005)
		(width 0.508)
		(layer "F.Cu")
		(net "P1V8_STBY")
	)
	(segment
		(start 99.7204 -66.675)
		(end 99.7204 -67.2338)
		(width 0.4064)
		(layer "F.Cu")
		(net "P1V8_STBY")
	)
	(segment
		(start 317.3984 -211.9249)
		(end 315.12764 -211.9249)
		(width 0.3048)
		(layer "F.Cu")
		(net "P1V8_STBY")
	)
	(segment
		(start 45.654722 -137.070084)
		(end 45.083222 -136.498584)
		(width 0.508)
		(layer "F.Cu")
		(net "P1V8_STBY")
	)
	(segment
		(start 45.98797 -146.44497)
		(end 46.228 -146.685)
		(width 0.381)
		(layer "F.Cu")
		(net "P1V8_STBY")
	)
	(segment
		(start 45.083222 -136.498584)
		(end 45.083222 -135.507222)
		(width 0.508)
		(layer "F.Cu")
		(net "P1V8_STBY")
	)
	(segment
		(start 51.0413 -119.006112)
		(end 51.0413 -119.0117)
		(width 0.4064)
		(layer "F.Cu")
		(net "P1V8_STBY")
	)
	(segment
		(start 224.2058 -112.5474)
		(end 224.2058 -112.3188)
		(width 0.508)
		(layer "F.Cu")
		(net "P1V8_STBY")
	)
	(segment
		(start 260.731 -35.941)
		(end 259.334 -35.941)
		(width 0.508)
		(layer "F.Cu")
		(net "P1V8_STBY")
	)
	(segment
		(start 215.8365 -162.179)
		(end 216.13876 -162.179)
		(width 0.4572)
		(layer "F.Cu")
		(net "P1V8_STBY")
	)
	(segment
		(start 315.12764 -210.00466)
		(end 315.12764 -210.566)
		(width 0.3048)
		(layer "F.Cu")
		(net "P1V8_STBY")
	)
	(segment
		(start 259.334 -35.941)
		(end 259.207 -36.068)
		(width 0.508)
		(layer "F.Cu")
		(net "P1V8_STBY")
	)
	(segment
		(start 223.8375 -111.9505)
		(end 223.393 -111.9505)
		(width 0.508)
		(layer "F.Cu")
		(net "P1V8_STBY")
	)
	(segment
		(start 63.589662 -105.574338)
		(end 60.160662 -105.574338)
		(width 0.4064)
		(layer "F.Cu")
		(net "P1V8_STBY")
	)
	(segment
		(start 216.535 -161.78276)
		(end 218.1352 -161.78276)
		(width 0.4064)
		(layer "F.Cu")
		(net "P1V8_STBY")
	)
	(segment
		(start 60.1472 -105.5878)
		(end 58.707528 -105.5878)
		(width 0.4064)
		(layer "F.Cu")
		(net "P1V8_STBY")
	)
	(segment
		(start 99.6188 -70.714362)
		(end 96.844612 -73.48855)
		(width 0.4064)
		(layer "F.Cu")
		(net "P1V8_STBY")
	)
	(segment
		(start 317.6524 -212.1789)
		(end 317.3984 -211.9249)
		(width 0.3048)
		(layer "F.Cu")
		(net "P1V8_STBY")
	)
	(segment
		(start 60.160662 -105.574338)
		(end 60.1472 -105.5878)
		(width 0.4064)
		(layer "F.Cu")
		(net "P1V8_STBY")
	)
	(segment
		(start 45.654722 -138.200384)
		(end 45.654722 -137.070084)
		(width 0.508)
		(layer "F.Cu")
		(net "P1V8_STBY")
	)
	(segment
		(start 58.42 -105.875328)
		(end 58.42 -111.633)
		(width 0.4064)
		(layer "F.Cu")
		(net "P1V8_STBY")
	)
	(segment
		(start 45.98797 -145.7833)
		(end 45.98797 -146.44497)
		(width 0.381)
		(layer "F.Cu")
		(net "P1V8_STBY")
	)
	(segment
		(start 216.13876 -162.179)
		(end 216.535 -161.78276)
		(width 0.4572)
		(layer "F.Cu")
		(net "P1V8_STBY")
	)
	(segment
		(start 99.6188 -67.3354)
		(end 99.6188 -70.714362)
		(width 0.4064)
		(layer "F.Cu")
		(net "P1V8_STBY")
	)
	(segment
		(start 313.964066 -198.755)
		(end 313.182 -198.755)
		(width 0.3048)
		(layer "F.Cu")
		(net "P1V8_STBY")
	)
	(segment
		(start 46.637956 -146.275044)
		(end 46.228 -146.685)
		(width 0.381)
		(layer "F.Cu")
		(net "P1V8_STBY")
	)
	(segment
		(start 215.80475 -157.988)
		(end 215.8365 -158.01975)
		(width 0.508)
		(layer "F.Cu")
		(net "P1V8_STBY")
	)
	(segment
		(start 262.89 -30.353)
		(end 262.509 -29.972)
		(width 0.508)
		(layer "F.Cu")
		(net "P1V8_STBY")
	)
	(segment
		(start 99.695 -66.6496)
		(end 99.7204 -66.675)
		(width 0.4064)
		(layer "F.Cu")
		(net "P1V8_STBY")
	)
	(segment
		(start 58.707528 -105.5878)
		(end 58.42 -105.875328)
		(width 0.4064)
		(layer "F.Cu")
		(net "P1V8_STBY")
	)
	(segment
		(start 64.663574 -104.50068)
		(end 64.66332 -104.50068)
		(width 0.4064)
		(layer "F.Cu")
		(net "P1V8_STBY")
	)
	(segment
		(start 315.4934 -209.6389)
		(end 315.12764 -210.00466)
		(width 0.3048)
		(layer "F.Cu")
		(net "P1V8_STBY")
	)
	(segment
		(start 99.310952 -65.1383)
		(end 99.310952 -66.036952)
		(width 0.4064)
		(layer "F.Cu")
		(net "P1V8_STBY")
	)
	(segment
		(start 215.773 -157.988)
		(end 215.80475 -157.988)
		(width 0.508)
		(layer "F.Cu")
		(net "P1V8_STBY")
	)
	(segment
		(start 80.42275 -73.48855)
		(end 80.3656 -73.4314)
		(width 0.4064)
		(layer "F.Cu")
		(net "P1V8_STBY")
	)
	(segment
		(start 99.695 -66.421)
		(end 99.695 -66.6496)
		(width 0.4064)
		(layer "F.Cu")
		(net "P1V8_STBY")
	)
	(segment
		(start 46.637956 -145.7833)
		(end 46.637956 -146.275044)
		(width 0.381)
		(layer "F.Cu")
		(net "P1V8_STBY")
	)
	(segment
		(start 51.569112 -118.4783)
		(end 51.0413 -119.006112)
		(width 0.4064)
		(layer "F.Cu")
		(net "P1V8_STBY")
	)
	(segment
		(start 263.5885 -30.353)
		(end 262.89 -30.353)
		(width 0.508)
		(layer "F.Cu")
		(net "P1V8_STBY")
	)
	(segment
		(start 71.1708 -79.4004)
		(end 71.1708 -97.9932)
		(width 0.4064)
		(layer "F.Cu")
		(net "P1V8_STBY")
	)
	(segment
		(start 96.844612 -73.48855)
		(end 80.42275 -73.48855)
		(width 0.4064)
		(layer "F.Cu")
		(net "P1V8_STBY")
	)
	(segment
		(start 99.310952 -66.036952)
		(end 99.695 -66.421)
		(width 0.4064)
		(layer "F.Cu")
		(net "P1V8_STBY")
	)
	(segment
		(start 224.2058 -112.3188)
		(end 223.8375 -111.9505)
		(width 0.508)
		(layer "F.Cu")
		(net "P1V8_STBY")
	)
	(segment
		(start 99.7204 -67.2338)
		(end 99.6188 -67.3354)
		(width 0.4064)
		(layer "F.Cu")
		(net "P1V8_STBY")
	)
	(segment
		(start 64.66332 -104.50068)
		(end 63.589662 -105.574338)
		(width 0.4064)
		(layer "F.Cu")
		(net "P1V8_STBY")
	)
	(segment
		(start 215.8365 -158.01975)
		(end 215.8365 -162.179)
		(width 0.508)
		(layer "F.Cu")
		(net "P1V8_STBY")
	)
	(segment
		(start 71.1708 -97.9932)
		(end 64.663574 -104.50068)
		(width 0.4064)
		(layer "F.Cu")
		(net "P1V8_STBY")
	)
	(segment
		(start 77.1398 -73.4314)
		(end 71.1708 -79.4004)
		(width 0.4064)
		(layer "F.Cu")
		(net "P1V8_STBY")
	)
	(segment
		(start 80.3656 -73.4314)
		(end 77.1398 -73.4314)
		(width 0.4064)
		(layer "F.Cu")
		(net "P1V8_STBY")
	)
	(segment
		(start 325.501 -181.8005)
		(end 325.501 -181.102)
		(width 0.508)
		(layer "F.Cu")
		(net "P1V8_STBY")
	)
	(segment
		(start 46.5074 -123.5456)
		(end 43.688 -123.5456)
		(width 0.4064)
		(layer "F.Cu")
		(net "P1V8_STBY")
	)
	(segment
		(start 315.12764 -211.9249)
		(end 315.12764 -210.566)
		(width 0.3048)
		(layer "F.Cu")
		(net "P1V8_STBY")
	)
	(via
		(at 343.154 -170.688)
		(size 0.7112)
		(drill 0.4064)
		(layers "F.Cu" "B.Cu")
		(net "P1V8_STBY")
	)
	(via
		(at 275.59 -110.236)
		(size 0.7112)
		(drill 0.4064)
		(layers "F.Cu" "B.Cu")
		(net "P1V8_STBY")
	)
	(via
		(at 226.568 -155.067)
		(size 0.7112)
		(drill 0.3556)
		(layers "F.Cu" "B.Cu")
		(net "P1V8_STBY")
	)
	(via
		(at 270.256 -20.32)
		(size 0.5588)
		(drill 0.3048)
		(layers "F.Cu" "B.Cu")
		(net "P1V8_STBY")
	)
	(via
		(at 271.272 -19.304)
		(size 0.5588)
		(drill 0.3048)
		(layers "F.Cu" "B.Cu")
		(net "P1V8_STBY")
	)
	(via
		(at 224.3328 -114.681)
		(size 0.7112)
		(drill 0.3556)
		(layers "F.Cu" "B.Cu")
		(net "P1V8_STBY")
	)
	(via
		(at 325.501 -181.102)
		(size 0.5588)
		(drill 0.3048)
		(layers "F.Cu" "B.Cu")
		(net "P1V8_STBY")
	)
	(via
		(at 268.097 -19.304)
		(size 0.5588)
		(drill 0.3048)
		(layers "F.Cu" "B.Cu")
		(net "P1V8_STBY")
	)
	(via
		(at 227.076 -102.997)
		(size 0.7112)
		(drill 0.4064)
		(layers "F.Cu" "B.Cu")
		(net "P1V8_STBY")
	)
	(via
		(at 271.399 -30.099)
		(size 0.5588)
		(drill 0.3048)
		(layers "F.Cu" "B.Cu")
		(net "P1V8_STBY")
	)
	(via
		(at 227.33 -156.845)
		(size 0.7112)
		(drill 0.4064)
		(layers "F.Cu" "B.Cu")
		(net "P1V8_STBY")
	)
	(via
		(at 225.806 -156.718)
		(size 0.7112)
		(drill 0.4064)
		(layers "F.Cu" "B.Cu")
		(net "P1V8_STBY")
	)
	(via
		(at 259.207 -36.068)
		(size 0.5588)
		(drill 0.3048)
		(layers "F.Cu" "B.Cu")
		(net "P1V8_STBY")
	)
	(via
		(at 228.346 -102.997)
		(size 0.7112)
		(drill 0.4064)
		(layers "F.Cu" "B.Cu")
		(net "P1V8_STBY")
	)
	(via
		(at 45.083222 -135.507222)
		(size 0.5588)
		(drill 0.3048)
		(layers "F.Cu" "B.Cu")
		(net "P1V8_STBY")
	)
	(via
		(at 269.24 -236.093)
		(size 0.7112)
		(drill 0.4064)
		(layers "F.Cu" "B.Cu")
		(net "P1V8_STBY")
	)
	(via
		(at 269.113 -20.32)
		(size 0.5588)
		(drill 0.3048)
		(layers "F.Cu" "B.Cu")
		(net "P1V8_STBY")
	)
	(via
		(at 223.393 -100.711)
		(size 0.7112)
		(drill 0.4064)
		(layers "F.Cu" "B.Cu")
		(net "P1V8_STBY")
	)
	(via
		(at 269.113 -19.304)
		(size 0.5588)
		(drill 0.3048)
		(layers "F.Cu" "B.Cu")
		(net "P1V8_STBY")
	)
	(via
		(at 226.9744 -112.5474)
		(size 0.5588)
		(drill 0.3048)
		(layers "F.Cu" "B.Cu")
		(net "P1V8_STBY")
	)
	(via
		(at 224.2058 -112.5474)
		(size 0.5588)
		(drill 0.3048)
		(layers "F.Cu" "B.Cu")
		(net "P1V8_STBY")
	)
	(via
		(at 343.154 -171.958)
		(size 0.7112)
		(drill 0.4064)
		(layers "F.Cu" "B.Cu")
		(net "P1V8_STBY")
	)
	(via
		(at 249.0216 -110.5662)
		(size 0.7112)
		(drill 0.3556)
		(layers "F.Cu" "B.Cu")
		(net "P1V8_STBY")
	)
	(via
		(at 42.672 -146.05)
		(size 0.7112)
		(drill 0.4064)
		(layers "F.Cu" "B.Cu")
		(net "P1V8_STBY")
	)
	(via
		(at 270.256 -19.304)
		(size 0.5588)
		(drill 0.3048)
		(layers "F.Cu" "B.Cu")
		(net "P1V8_STBY")
	)
	(via
		(at 226.0346 -112.5474)
		(size 0.5588)
		(drill 0.3048)
		(layers "F.Cu" "B.Cu")
		(net "P1V8_STBY")
	)
	(via
		(at 42.2148 -128.651)
		(size 0.508)
		(drill 0.254)
		(layers "F.Cu" "B.Cu")
		(net "P1V8_STBY")
	)
	(via
		(at 225.1202 -112.5474)
		(size 0.5588)
		(drill 0.3048)
		(layers "F.Cu" "B.Cu")
		(net "P1V8_STBY")
	)
	(via
		(at 313.182 -198.755)
		(size 0.5588)
		(drill 0.3048)
		(layers "F.Cu" "B.Cu")
		(net "P1V8_STBY")
	)
	(via
		(at 223.52 -94.361)
		(size 0.7112)
		(drill 0.3556)
		(layers "F.Cu" "B.Cu")
		(net "P1V8_STBY")
	)
	(via
		(at 43.688 -123.5456)
		(size 0.508)
		(drill 0.254)
		(layers "F.Cu" "B.Cu")
		(net "P1V8_STBY")
	)
	(via
		(at 268.097 -20.32)
		(size 0.5588)
		(drill 0.3048)
		(layers "F.Cu" "B.Cu")
		(net "P1V8_STBY")
	)
	(via
		(at 271.272 -20.32)
		(size 0.5588)
		(drill 0.3048)
		(layers "F.Cu" "B.Cu")
		(net "P1V8_STBY")
	)
	(via
		(at 344.17 -171.323)
		(size 0.7112)
		(drill 0.4064)
		(layers "F.Cu" "B.Cu")
		(net "P1V8_STBY")
	)
	(via
		(at 262.509 -29.972)
		(size 0.5588)
		(drill 0.3048)
		(layers "F.Cu" "B.Cu")
		(net "P1V8_STBY")
	)
	(via
		(at 344.043 -169.926)
		(size 0.7112)
		(drill 0.4064)
		(layers "F.Cu" "B.Cu")
		(net "P1V8_STBY")
	)
	(via
		(at 46.228 -146.685)
		(size 0.508)
		(drill 0.254)
		(layers "F.Cu" "B.Cu")
		(net "P1V8_STBY")
	)
	(via
		(at 42.672 -147.32)
		(size 0.7112)
		(drill 0.4064)
		(layers "F.Cu" "B.Cu")
		(net "P1V8_STBY")
	)
	(via
		(at 215.773 -157.988)
		(size 0.5588)
		(drill 0.3048)
		(layers "F.Cu" "B.Cu")
		(net "P1V8_STBY")
	)
	(via
		(at 227.076 -104.267)
		(size 0.7112)
		(drill 0.4064)
		(layers "F.Cu" "B.Cu")
		(net "P1V8_STBY")
	)
	(via
		(at 274.0914 -108.966)
		(size 0.7112)
		(drill 0.4064)
		(layers "F.Cu" "B.Cu")
		(net "P1V8_STBY")
	)
	(via
		(at 315.12764 -210.566)
		(size 0.5588)
		(drill 0.3048)
		(layers "F.Cu" "B.Cu")
		(net "P1V8_STBY")
	)
	(via
		(at 228.346 -104.267)
		(size 0.7112)
		(drill 0.4064)
		(layers "F.Cu" "B.Cu")
		(net "P1V8_STBY")
	)
	(via
		(at 348.488 -125.857)
		(size 0.7112)
		(drill 0.3556)
		(layers "F.Cu" "B.Cu")
		(net "P1V8_STBY")
	)
	(via
		(at 224.536 -100.711)
		(size 0.7112)
		(drill 0.4064)
		(layers "F.Cu" "B.Cu")
		(net "P1V8_STBY")
	)
	(via
		(at 274.066 -110.236)
		(size 0.7112)
		(drill 0.4064)
		(layers "F.Cu" "B.Cu")
		(net "P1V8_STBY")
	)
	(segment
		(start 262.001 -29.972)
		(end 259.588 -32.385)
		(width 0.508)
		(layer "B.Cu")
		(net "P1V8_STBY")
	)
	(segment
		(start 270.1925 -30.607)
		(end 270.891 -30.607)
		(width 0.508)
		(layer "B.Cu")
		(net "P1V8_STBY")
	)
	(segment
		(start 259.588 -35.687)
		(end 259.207 -36.068)
		(width 0.508)
		(layer "B.Cu")
		(net "P1V8_STBY")
	)
	(segment
		(start 270.891 -30.607)
		(end 271.399 -30.099)
		(width 0.508)
		(layer "B.Cu")
		(net "P1V8_STBY")
	)
	(segment
		(start 259.588 -32.385)
		(end 259.588 -35.687)
		(width 0.508)
		(layer "B.Cu")
		(net "P1V8_STBY")
	)
	(segment
		(start 262.509 -29.972)
		(end 262.001 -29.972)
		(width 0.508)
		(layer "B.Cu")
		(net "P1V8_STBY")
	)
	(segment
		(start 304.8 -221.742)
		(end 309.626 -216.916)
		(width 1.016)
		(layer "In2.Cu")
		(net "P1V8_STBY")
	)
	(segment
		(start 274.701 -236.093)
		(end 275.336 -235.458)
		(width 1.016)
		(layer "In2.Cu")
		(net "P1V8_STBY")
	)
	(segment
		(start 291.846 -235.458)
		(end 304.8 -222.504)
		(width 1.016)
		(layer "In2.Cu")
		(net "P1V8_STBY")
	)
	(segment
		(start 309.626 -215.138)
		(end 312.166 -212.598)
		(width 1.016)
		(layer "In2.Cu")
		(net "P1V8_STBY")
	)
	(segment
		(start 304.8 -222.504)
		(end 304.8 -221.742)
		(width 1.016)
		(layer "In2.Cu")
		(net "P1V8_STBY")
	)
	(segment
		(start 45.083222 -131.519422)
		(end 42.2148 -128.651)
		(width 0.508)
		(layer "In2.Cu")
		(net "P1V8_STBY")
	)
	(segment
		(start 313.09564 -212.598)
		(end 315.12764 -210.566)
		(width 1.016)
		(layer "In2.Cu")
		(net "P1V8_STBY")
	)
	(segment
		(start 275.336 -235.458)
		(end 291.846 -235.458)
		(width 1.016)
		(layer "In2.Cu")
		(net "P1V8_STBY")
	)
	(segment
		(start 309.626 -216.916)
		(end 309.626 -215.138)
		(width 1.016)
		(layer "In2.Cu")
		(net "P1V8_STBY")
	)
	(segment
		(start 45.083222 -135.507222)
		(end 45.083222 -131.519422)
		(width 0.508)
		(layer "In2.Cu")
		(net "P1V8_STBY")
	)
	(segment
		(start 269.24 -236.093)
		(end 274.701 -236.093)
		(width 1.016)
		(layer "In2.Cu")
		(net "P1V8_STBY")
	)
	(segment
		(start 312.166 -212.598)
		(end 313.09564 -212.598)
		(width 1.016)
		(layer "In2.Cu")
		(net "P1V8_STBY")
	)
	(segment
		(start 313.182 -198.755)
		(end 313.662822 -198.274178)
		(width 0.508)
		(layer "In5.Cu")
		(net "P1V8_STBY")
	)
	(segment
		(start 313.662822 -193.752216)
		(end 322.757038 -184.658)
		(width 0.508)
		(layer "In5.Cu")
		(net "P1V8_STBY")
	)
	(segment
		(start 42.2148 -125.0188)
		(end 43.688 -123.5456)
		(width 0.508)
		(layer "In5.Cu")
		(net "P1V8_STBY")
	)
	(segment
		(start 325.501 -182.372)
		(end 325.501 -181.102)
		(width 0.508)
		(layer "In5.Cu")
		(net "P1V8_STBY")
	)
	(segment
		(start 315.12764 -207.68564)
		(end 313.182 -205.74)
		(width 0.508)
		(layer "In5.Cu")
		(net "P1V8_STBY")
	)
	(segment
		(start 313.182 -205.74)
		(end 313.182 -198.755)
		(width 0.508)
		(layer "In5.Cu")
		(net "P1V8_STBY")
	)
	(segment
		(start 313.662822 -198.274178)
		(end 313.662822 -193.752216)
		(width 0.508)
		(layer "In5.Cu")
		(net "P1V8_STBY")
	)
	(segment
		(start 315.12764 -210.566)
		(end 315.12764 -207.68564)
		(width 0.508)
		(layer "In5.Cu")
		(net "P1V8_STBY")
	)
	(segment
		(start 322.757038 -184.658)
		(end 323.215 -184.658)
		(width 0.508)
		(layer "In5.Cu")
		(net "P1V8_STBY")
	)
	(segment
		(start 323.215 -184.658)
		(end 325.501 -182.372)
		(width 0.508)
		(layer "In5.Cu")
		(net "P1V8_STBY")
	)
	(segment
		(start 42.2148 -128.651)
		(end 42.2148 -125.0188)
		(width 0.508)
		(layer "In5.Cu")
		(net "P1V8_STBY")
	)
	(segment
		(start 287.234884 -177.840132)
		(end 286.83966 -178.235356)
		(width 0.1143)
		(layer "F.Cu")
		(net "ROMA4")
	)
	(segment
		(start 286.83966 -178.235356)
		(end 286.83458 -178.235356)
		(width 0.1143)
		(layer "F.Cu")
		(net "ROMA4")
	)
	(via
		(at 286.83458 -178.235356)
		(size 0.508)
		(drill 0.254)
		(layers "F.Cu" "B.Cu")
		(net "ROMA4")
	)
	(via
		(at 275.9202 -182.9054)
		(size 0.7112)
		(drill 0.3556)
		(layers "F.Cu" "B.Cu")
		(net "ROMA4")
	)
	(segment
		(start 286.35325 -178.62169)
		(end 286.739584 -178.235356)
		(width 0.0889)
		(layer "B.Cu")
		(net "ROMA4")
	)
	(segment
		(start 277.603204 -182.9054)
		(end 281.903424 -178.60518)
		(width 0.1143)
		(layer "B.Cu")
		(net "ROMA4")
	)
	(segment
		(start 275.7678 -182.753)
		(end 275.9202 -182.9054)
		(width 0.1143)
		(layer "B.Cu")
		(net "ROMA4")
	)
	(segment
		(start 286.739584 -178.235356)
		(end 286.83458 -178.235356)
		(width 0.0889)
		(layer "B.Cu")
		(net "ROMA4")
	)
	(segment
		(start 274.6375 -182.753)
		(end 275.7678 -182.753)
		(width 0.1143)
		(layer "B.Cu")
		(net "ROMA4")
	)
	(segment
		(start 285.129732 -178.632612)
		(end 286.342074 -178.632612)
		(width 0.0889)
		(layer "B.Cu")
		(net "ROMA4")
	)
	(segment
		(start 275.9202 -182.9054)
		(end 277.603204 -182.9054)
		(width 0.1143)
		(layer "B.Cu")
		(net "ROMA4")
	)
	(segment
		(start 281.903424 -178.60518)
		(end 285.1023 -178.60518)
		(width 0.1143)
		(layer "B.Cu")
		(net "ROMA4")
	)
	(segment
		(start 285.1023 -178.60518)
		(end 285.129732 -178.632612)
		(width 0.0889)
		(layer "B.Cu")
		(net "ROMA4")
	)
	(segment
		(start 286.342074 -178.632612)
		(end 286.35325 -178.62169)
		(width 0.0889)
		(layer "B.Cu")
		(net "ROMA4")
	)
	(segment
		(start 86.868 -26.130504)
		(end 86.868 -25.908)
		(width 0.1397)
		(layer "F.Cu")
		(net "CLK_100M_PCIE_SAS_C_P")
	)
	(via
		(at 86.868 -25.908)
		(size 0.5588)
		(drill 0.3048)
		(layers "F.Cu" "B.Cu")
		(net "CLK_100M_PCIE_SAS_C_P")
	)
	(arc
		(start 86.614 -26.74366)
		(mid 86.801971 -26.462342)
		(end 86.868 -26.130504)
		(width 0.1397)
		(layer "F.Cu")
		(net "CLK_100M_PCIE_SAS_C_P")
	)
	(segment
		(start 87.2871 -24.13889)
		(end 87.2871 -25.273)
		(width 0.1397)
		(layer "B.Cu")
		(net "CLK_100M_PCIE_SAS_C_P")
	)
	(segment
		(start 111.520224 -9.143492)
		(end 104.67721 -9.143492)
		(width 0.1397)
		(layer "B.Cu")
		(net "CLK_100M_PCIE_SAS_C_P")
	)
	(segment
		(start 152.424384 -25.836372)
		(end 131.573524 -4.985512)
		(width 0.1397)
		(layer "B.Cu")
		(net "CLK_100M_PCIE_SAS_C_P")
	)
	(segment
		(start 103.985568 -9.430004)
		(end 92.78239 -20.633182)
		(width 0.1397)
		(layer "B.Cu")
		(net "CLK_100M_PCIE_SAS_C_P")
	)
	(segment
		(start 158.002986 -26.0223)
		(end 152.873456 -26.0223)
		(width 0.1397)
		(layer "B.Cu")
		(net "CLK_100M_PCIE_SAS_C_P")
	)
	(segment
		(start 207.635094 -74.112882)
		(end 207.635094 -73.18883)
		(width 0.1397)
		(layer "B.Cu")
		(net "CLK_100M_PCIE_SAS_C_P")
	)
	(segment
		(start 207.641444 -74.119232)
		(end 207.635094 -74.112882)
		(width 0.1397)
		(layer "B.Cu")
		(net "CLK_100M_PCIE_SAS_C_P")
	)
	(segment
		(start 87.134446 -25.641554)
		(end 86.868 -25.908)
		(width 0.1397)
		(layer "B.Cu")
		(net "CLK_100M_PCIE_SAS_C_P")
	)
	(segment
		(start 207.348582 -72.497188)
		(end 200.453752 -65.602358)
		(width 0.1397)
		(layer "B.Cu")
		(net "CLK_100M_PCIE_SAS_C_P")
	)
	(segment
		(start 199.76211 -65.315846)
		(end 197.964806 -65.315846)
		(width 0.1397)
		(layer "B.Cu")
		(net "CLK_100M_PCIE_SAS_C_P")
	)
	(segment
		(start 115.941348 -4.985512)
		(end 111.969296 -8.957564)
		(width 0.1397)
		(layer "B.Cu")
		(net "CLK_100M_PCIE_SAS_C_P")
	)
	(segment
		(start 197.515734 -65.129918)
		(end 158.694628 -26.308812)
		(width 0.1397)
		(layer "B.Cu")
		(net "CLK_100M_PCIE_SAS_C_P")
	)
	(segment
		(start 89.915238 -21.105622)
		(end 87.573612 -23.447248)
		(width 0.1397)
		(layer "B.Cu")
		(net "CLK_100M_PCIE_SAS_C_P")
	)
	(segment
		(start 130.881882 -4.699)
		(end 116.63299 -4.699)
		(width 0.1397)
		(layer "B.Cu")
		(net "CLK_100M_PCIE_SAS_C_P")
	)
	(segment
		(start 92.333318 -20.81911)
		(end 90.60688 -20.81911)
		(width 0.1397)
		(layer "B.Cu")
		(net "CLK_100M_PCIE_SAS_C_P")
	)
	(arc
		(start 116.63299 -4.699)
		(mid 116.258681 -4.773473)
		(end 115.941348 -4.985512)
		(width 0.1397)
		(layer "B.Cu")
		(net "CLK_100M_PCIE_SAS_C_P")
	)
	(arc
		(start 92.78239 -20.633182)
		(mid 92.576354 -20.770851)
		(end 92.333318 -20.81911)
		(width 0.1397)
		(layer "B.Cu")
		(net "CLK_100M_PCIE_SAS_C_P")
	)
	(arc
		(start 131.573524 -4.985512)
		(mid 131.25621 -4.773426)
		(end 130.881882 -4.699)
		(width 0.1397)
		(layer "B.Cu")
		(net "CLK_100M_PCIE_SAS_C_P")
	)
	(arc
		(start 207.635094 -73.18883)
		(mid 207.560621 -72.814521)
		(end 207.348582 -72.497188)
		(width 0.1397)
		(layer "B.Cu")
		(net "CLK_100M_PCIE_SAS_C_P")
	)
	(arc
		(start 104.67721 -9.143492)
		(mid 104.302901 -9.217965)
		(end 103.985568 -9.430004)
		(width 0.1397)
		(layer "B.Cu")
		(net "CLK_100M_PCIE_SAS_C_P")
	)
	(arc
		(start 87.2871 -25.273)
		(mid 87.247425 -25.472458)
		(end 87.134446 -25.641554)
		(width 0.1397)
		(layer "B.Cu")
		(net "CLK_100M_PCIE_SAS_C_P")
	)
	(arc
		(start 200.453752 -65.602358)
		(mid 200.136438 -65.390272)
		(end 199.76211 -65.315846)
		(width 0.1397)
		(layer "B.Cu")
		(net "CLK_100M_PCIE_SAS_C_P")
	)
	(arc
		(start 152.873456 -26.0223)
		(mid 152.630452 -25.973964)
		(end 152.424384 -25.836372)
		(width 0.1397)
		(layer "B.Cu")
		(net "CLK_100M_PCIE_SAS_C_P")
	)
	(arc
		(start 87.573612 -23.447248)
		(mid 87.361526 -23.764562)
		(end 87.2871 -24.13889)
		(width 0.1397)
		(layer "B.Cu")
		(net "CLK_100M_PCIE_SAS_C_P")
	)
	(arc
		(start 111.969296 -8.957564)
		(mid 111.76326 -9.095233)
		(end 111.520224 -9.143492)
		(width 0.1397)
		(layer "B.Cu")
		(net "CLK_100M_PCIE_SAS_C_P")
	)
	(arc
		(start 90.60688 -20.81911)
		(mid 90.232571 -20.893583)
		(end 89.915238 -21.105622)
		(width 0.1397)
		(layer "B.Cu")
		(net "CLK_100M_PCIE_SAS_C_P")
	)
	(arc
		(start 158.694628 -26.308812)
		(mid 158.377314 -26.096726)
		(end 158.002986 -26.0223)
		(width 0.1397)
		(layer "B.Cu")
		(net "CLK_100M_PCIE_SAS_C_P")
	)
	(arc
		(start 197.964806 -65.315846)
		(mid 197.721802 -65.26751)
		(end 197.515734 -65.129918)
		(width 0.1397)
		(layer "B.Cu")
		(net "CLK_100M_PCIE_SAS_C_P")
	)
	(arc
		(start 207.450436 -75.75042)
		(mid 207.593527 -74.940398)
		(end 207.641444 -74.119232)
		(width 0.1397)
		(layer "B.Cu")
		(net "CLK_100M_PCIE_SAS_C_P")
	)
	(segment
		(start 265.437874 -36.992814)
		(end 265.437874 -35.059874)
		(width 0.3048)
		(layer "F.Cu")
		(net "P1V8_STBY_VBST")
	)
	(via
		(at 265.437874 -35.059874)
		(size 0.5588)
		(drill 0.3048)
		(layers "F.Cu" "B.Cu")
		(net "P1V8_STBY_VBST")
	)
	(via
		(at 265.43 -35.941)
		(size 0.7112)
		(drill 0.3556)
		(layers "F.Cu" "B.Cu")
		(net "P1V8_STBY_VBST")
	)
	(segment
		(start 266.4968 -35.941)
		(end 265.43 -35.941)
		(width 0.508)
		(layer "B.Cu")
		(net "P1V8_STBY_VBST")
	)
	(segment
		(start 265.43 -35.941)
		(end 265.43 -35.067748)
		(width 0.508)
		(layer "B.Cu")
		(net "P1V8_STBY_VBST")
	)
	(segment
		(start 266.7508 -35.687)
		(end 266.4968 -35.941)
		(width 0.508)
		(layer "B.Cu")
		(net "P1V8_STBY_VBST")
	)
	(segment
		(start 265.43 -35.067748)
		(end 265.437874 -35.059874)
		(width 0.508)
		(layer "B.Cu")
		(net "P1V8_STBY_VBST")
	)
	(segment
		(start 122.372628 -92.349828)
		(end 122.850402 -92.827602)
		(width 0.1016)
		(layer "F.Cu")
		(net "SAS_GF_EXP_RX_DN2")
	)
	(segment
		(start 122.350022 -92.349828)
		(end 122.372628 -92.349828)
		(width 0.1016)
		(layer "F.Cu")
		(net "SAS_GF_EXP_RX_DN2")
	)
	(via
		(at 122.850402 -92.827602)
		(size 0.508)
		(drill 0.254)
		(layers "F.Cu" "B.Cu")
		(net "SAS_GF_EXP_RX_DN2")
	)
	(segment
		(start 141.3891 -247.804178)
		(end 141.3891 -162.69462)
		(width 0.1016)
		(layer "B.Cu")
		(net "SAS_GF_EXP_RX_DN2")
	)
	(segment
		(start 129.0574 -95.124524)
		(end 128.509776 -95.124524)
		(width 0.1016)
		(layer "B.Cu")
		(net "SAS_GF_EXP_RX_DN2")
	)
	(segment
		(start 132.390134 -98.100134)
		(end 129.667 -95.377)
		(width 0.1016)
		(layer "B.Cu")
		(net "SAS_GF_EXP_RX_DN2")
	)
	(segment
		(start 126.04115 -93.406722)
		(end 125.482604 -93.406722)
		(width 0.1016)
		(layer "B.Cu")
		(net "SAS_GF_EXP_RX_DN2")
	)
	(segment
		(start 140.999972 -256.50444)
		(end 140.999972 -254.234188)
		(width 0.1016)
		(layer "B.Cu")
		(net "SAS_GF_EXP_RX_DN2")
	)
	(segment
		(start 123.80341 -92.601542)
		(end 123.80341 -92.601288)
		(width 0.1016)
		(layer "B.Cu")
		(net "SAS_GF_EXP_RX_DN2")
	)
	(segment
		(start 123.473718 -92.535502)
		(end 123.175014 -92.412058)
		(width 0.1016)
		(layer "B.Cu")
		(net "SAS_GF_EXP_RX_DN2")
	)
	(segment
		(start 141.3891 -162.69462)
		(end 141.388846 -162.694874)
		(width 0.1016)
		(layer "B.Cu")
		(net "SAS_GF_EXP_RX_DN2")
	)
	(segment
		(start 131.946904 -108.706158)
		(end 131.947158 -108.706412)
		(width 0.1016)
		(layer "B.Cu")
		(net "SAS_GF_EXP_RX_DN2")
	)
	(segment
		(start 124.77242 -93.11259)
		(end 124.34697 -92.68714)
		(width 0.1016)
		(layer "B.Cu")
		(net "SAS_GF_EXP_RX_DN2")
	)
	(segment
		(start 123.47448 -92.535756)
		(end 123.473718 -92.535502)
		(width 0.1016)
		(layer "B.Cu")
		(net "SAS_GF_EXP_RX_DN2")
	)
	(segment
		(start 127.778764 -94.821756)
		(end 126.591822 -93.634814)
		(width 0.1016)
		(layer "B.Cu")
		(net "SAS_GF_EXP_RX_DN2")
	)
	(segment
		(start 141.15034 -248.586498)
		(end 141.15034 -248.281698)
		(width 0.1016)
		(layer "B.Cu")
		(net "SAS_GF_EXP_RX_DN2")
	)
	(segment
		(start 128.264158 -112.389412)
		(end 128.263904 -112.389158)
		(width 0.1016)
		(layer "B.Cu")
		(net "SAS_GF_EXP_RX_DN2")
	)
	(segment
		(start 132.70357 -106.880406)
		(end 132.70357 -98.8568)
		(width 0.1016)
		(layer "B.Cu")
		(net "SAS_GF_EXP_RX_DN2")
	)
	(segment
		(start 128.263904 -112.389158)
		(end 131.946904 -108.706158)
		(width 0.1016)
		(layer "B.Cu")
		(net "SAS_GF_EXP_RX_DN2")
	)
	(segment
		(start 140.594334 -160.776412)
		(end 127.703834 -147.885912)
		(width 0.1016)
		(layer "B.Cu")
		(net "SAS_GF_EXP_RX_DN2")
	)
	(segment
		(start 141.3891 -253.657608)
		(end 141.3891 -249.064018)
		(width 0.1016)
		(layer "B.Cu")
		(net "SAS_GF_EXP_RX_DN2")
	)
	(segment
		(start 141.097 -254)
		(end 141.134084 -253.962662)
		(width 0.1016)
		(layer "B.Cu")
		(net "SAS_GF_EXP_RX_DN2")
	)
	(segment
		(start 127.127 -146.49323)
		(end 127.127 -115.135406)
		(width 0.1016)
		(layer "B.Cu")
		(net "SAS_GF_EXP_RX_DN2")
	)
	(segment
		(start 124.140468 -92.601542)
		(end 123.80341 -92.601542)
		(width 0.1016)
		(layer "B.Cu")
		(net "SAS_GF_EXP_RX_DN2")
	)
	(arc
		(start 141.15034 -248.281698)
		(mid 141.180832 -248.147705)
		(end 141.26972 -248.042938)
		(width 0.1016)
		(layer "B.Cu")
		(net "SAS_GF_EXP_RX_DN2")
	)
	(arc
		(start 131.947158 -108.706412)
		(mid 132.506998 -107.868648)
		(end 132.70357 -106.880406)
		(width 0.1016)
		(layer "B.Cu")
		(net "SAS_GF_EXP_RX_DN2")
	)
	(arc
		(start 141.301978 -253.86792)
		(mid 141.366452 -253.771428)
		(end 141.3891 -253.657608)
		(width 0.1016)
		(layer "B.Cu")
		(net "SAS_GF_EXP_RX_DN2")
	)
	(arc
		(start 132.70357 -98.8568)
		(mid 132.622113 -98.44729)
		(end 132.390134 -98.100134)
		(width 0.1016)
		(layer "B.Cu")
		(net "SAS_GF_EXP_RX_DN2")
	)
	(arc
		(start 141.388846 -162.694874)
		(mid 141.182416 -161.65661)
		(end 140.594334 -160.776412)
		(width 0.1016)
		(layer "B.Cu")
		(net "SAS_GF_EXP_RX_DN2")
	)
	(arc
		(start 141.134084 -253.962662)
		(mid 141.180607 -253.924618)
		(end 141.233652 -253.896368)
		(width 0.1016)
		(layer "B.Cu")
		(net "SAS_GF_EXP_RX_DN2")
	)
	(arc
		(start 123.511056 -92.549472)
		(mid 123.492691 -92.54282)
		(end 123.47448 -92.535756)
		(width 0.1016)
		(layer "B.Cu")
		(net "SAS_GF_EXP_RX_DN2")
	)
	(arc
		(start 122.86107 -92.54236)
		(mid 122.830171 -92.684022)
		(end 122.850402 -92.827602)
		(width 0.1016)
		(layer "B.Cu")
		(net "SAS_GF_EXP_RX_DN2")
	)
	(arc
		(start 128.509776 -95.124524)
		(mid 128.114151 -95.045847)
		(end 127.778764 -94.821756)
		(width 0.1016)
		(layer "B.Cu")
		(net "SAS_GF_EXP_RX_DN2")
	)
	(arc
		(start 141.3891 -249.064018)
		(mid 141.358608 -248.930025)
		(end 141.26972 -248.825258)
		(width 0.1016)
		(layer "B.Cu")
		(net "SAS_GF_EXP_RX_DN2")
	)
	(arc
		(start 140.999972 -254.234188)
		(mid 141.025184 -254.107437)
		(end 141.097 -254)
		(width 0.1016)
		(layer "B.Cu")
		(net "SAS_GF_EXP_RX_DN2")
	)
	(arc
		(start 124.34697 -92.68714)
		(mid 124.252227 -92.623805)
		(end 124.140468 -92.601542)
		(width 0.1016)
		(layer "B.Cu")
		(net "SAS_GF_EXP_RX_DN2")
	)
	(arc
		(start 123.175014 -92.412058)
		(mid 122.991111 -92.412271)
		(end 122.86107 -92.54236)
		(width 0.1016)
		(layer "B.Cu")
		(net "SAS_GF_EXP_RX_DN2")
	)
	(arc
		(start 125.482604 -93.406722)
		(mid 125.098255 -93.330288)
		(end 124.77242 -93.11259)
		(width 0.1016)
		(layer "B.Cu")
		(net "SAS_GF_EXP_RX_DN2")
	)
	(arc
		(start 129.667 -95.377)
		(mid 129.387313 -95.190119)
		(end 129.0574 -95.124524)
		(width 0.1016)
		(layer "B.Cu")
		(net "SAS_GF_EXP_RX_DN2")
	)
	(arc
		(start 141.233652 -253.896368)
		(mid 141.270632 -253.888919)
		(end 141.301978 -253.86792)
		(width 0.1016)
		(layer "B.Cu")
		(net "SAS_GF_EXP_RX_DN2")
	)
	(arc
		(start 141.26972 -248.825258)
		(mid 141.180926 -248.720444)
		(end 141.15034 -248.586498)
		(width 0.1016)
		(layer "B.Cu")
		(net "SAS_GF_EXP_RX_DN2")
	)
	(arc
		(start 126.591822 -93.634814)
		(mid 126.339172 -93.465998)
		(end 126.04115 -93.406722)
		(width 0.1016)
		(layer "B.Cu")
		(net "SAS_GF_EXP_RX_DN2")
	)
	(arc
		(start 123.80341 -92.601288)
		(mid 123.655014 -92.587906)
		(end 123.511056 -92.549472)
		(width 0.1016)
		(layer "B.Cu")
		(net "SAS_GF_EXP_RX_DN2")
	)
	(arc
		(start 127.127 -115.135406)
		(mid 127.422436 -113.649295)
		(end 128.264158 -112.389412)
		(width 0.1016)
		(layer "B.Cu")
		(net "SAS_GF_EXP_RX_DN2")
	)
	(arc
		(start 141.26972 -248.042938)
		(mid 141.358514 -247.938124)
		(end 141.3891 -247.804178)
		(width 0.1016)
		(layer "B.Cu")
		(net "SAS_GF_EXP_RX_DN2")
	)
	(arc
		(start 127.703834 -147.885912)
		(mid 127.276943 -147.24693)
		(end 127.127 -146.49323)
		(width 0.1016)
		(layer "B.Cu")
		(net "SAS_GF_EXP_RX_DN2")
	)
	(segment
		(start 275.2852 -35.814)
		(end 273.812 -35.814)
		(width 0.508)
		(layer "F.Cu")
		(net "P1V8_STBY_SNB")
	)
	(segment
		(start 272.669 -35.814)
		(end 273.812 -35.814)
		(width 0.508)
		(layer "F.Cu")
		(net "P1V8_STBY_SNB")
	)
	(segment
		(start 275.336 -35.8648)
		(end 275.2852 -35.814)
		(width 0.508)
		(layer "F.Cu")
		(net "P1V8_STBY_SNB")
	)
	(via
		(at 273.812 -35.814)
		(size 0.7112)
		(drill 0.3556)
		(layers "F.Cu" "B.Cu")
		(net "P1V8_STBY_SNB")
	)
	(segment
		(start 295.5544 -163.2458)
		(end 294.894 -163.9062)
		(width 0.1143)
		(layer "F.Cu")
		(net "RMII0_PHY_BMC_C_RXD1")
	)
	(segment
		(start 296.037 -162.7632)
		(end 295.5544 -163.2458)
		(width 0.1143)
		(layer "F.Cu")
		(net "RMII0_PHY_BMC_C_RXD1")
	)
	(segment
		(start 294.032432 -167.686736)
		(end 293.634922 -168.084246)
		(width 0.1143)
		(layer "F.Cu")
		(net "RMII0_PHY_BMC_C_RXD1")
	)
	(segment
		(start 294.894 -165.238938)
		(end 294.032432 -166.100506)
		(width 0.1143)
		(layer "F.Cu")
		(net "RMII0_PHY_BMC_C_RXD1")
	)
	(segment
		(start 294.894 -163.9062)
		(end 294.894 -165.238938)
		(width 0.1143)
		(layer "F.Cu")
		(net "RMII0_PHY_BMC_C_RXD1")
	)
	(segment
		(start 296.545 -161.9885)
		(end 296.037 -162.4965)
		(width 0.1143)
		(layer "F.Cu")
		(net "RMII0_PHY_BMC_C_RXD1")
	)
	(segment
		(start 293.634922 -168.084246)
		(end 293.634922 -168.240202)
		(width 0.1143)
		(layer "F.Cu")
		(net "RMII0_PHY_BMC_C_RXD1")
	)
	(segment
		(start 296.037 -162.4965)
		(end 296.037 -162.7632)
		(width 0.1143)
		(layer "F.Cu")
		(net "RMII0_PHY_BMC_C_RXD1")
	)
	(segment
		(start 294.032432 -166.100506)
		(end 294.032432 -167.686736)
		(width 0.1143)
		(layer "F.Cu")
		(net "RMII0_PHY_BMC_C_RXD1")
	)
	(via
		(at 295.5544 -163.2458)
		(size 0.7112)
		(drill 0.3556)
		(layers "F.Cu" "B.Cu")
		(net "RMII0_PHY_BMC_C_RXD1")
	)
	(segment
		(start 96.529398 -29.727652)
		(end 96.393 -29.591)
		(width 0.1397)
		(layer "B.Cu")
		(net "PCIE_SAS_CPU_RX_P2")
	)
	(segment
		(start 129.460752 -10.344912)
		(end 150.210012 -31.094172)
		(width 0.1397)
		(layer "B.Cu")
		(net "PCIE_SAS_CPU_RX_P2")
	)
	(segment
		(start 106.855768 -14.401292)
		(end 113.986564 -14.401292)
		(width 0.1397)
		(layer "B.Cu")
		(net "PCIE_SAS_CPU_RX_P2")
	)
	(segment
		(start 96.524572 -24.327358)
		(end 106.164126 -14.687804)
		(width 0.1397)
		(layer "B.Cu")
		(net "PCIE_SAS_CPU_RX_P2")
	)
	(segment
		(start 150.659084 -31.2801)
		(end 155.284424 -31.2801)
		(width 0.1397)
		(layer "B.Cu")
		(net "PCIE_SAS_CPU_RX_P2")
	)
	(segment
		(start 96.23806 -29.216858)
		(end 96.23806 -25.019)
		(width 0.1397)
		(layer "B.Cu")
		(net "PCIE_SAS_CPU_RX_P2")
	)
	(segment
		(start 155.976066 -31.566612)
		(end 195.32981 -70.920356)
		(width 0.1397)
		(layer "B.Cu")
		(net "PCIE_SAS_CPU_RX_P2")
	)
	(segment
		(start 195.616322 -71.611998)
		(end 195.616322 -74.408792)
		(width 0.1397)
		(layer "B.Cu")
		(net "PCIE_SAS_CPU_RX_P2")
	)
	(segment
		(start 114.435636 -14.215364)
		(end 118.306088 -10.344912)
		(width 0.1397)
		(layer "B.Cu")
		(net "PCIE_SAS_CPU_RX_P2")
	)
	(segment
		(start 195.453 -74.803)
		(end 195.450206 -74.805794)
		(width 0.1397)
		(layer "B.Cu")
		(net "PCIE_SAS_CPU_RX_P2")
	)
	(segment
		(start 96.40316 -31.3436)
		(end 96.541082 -31.205678)
		(width 0.1397)
		(layer "B.Cu")
		(net "PCIE_SAS_CPU_RX_P2")
	)
	(segment
		(start 118.99773 -10.0584)
		(end 128.76911 -10.0584)
		(width 0.1397)
		(layer "B.Cu")
		(net "PCIE_SAS_CPU_RX_P2")
	)
	(segment
		(start 96.578166 -31.116016)
		(end 96.578166 -29.845)
		(width 0.1397)
		(layer "B.Cu")
		(net "PCIE_SAS_CPU_RX_P2")
	)
	(arc
		(start 195.32981 -70.920356)
		(mid 195.541896 -71.23767)
		(end 195.616322 -71.611998)
		(width 0.1397)
		(layer "B.Cu")
		(net "PCIE_SAS_CPU_RX_P2")
	)
	(arc
		(start 96.541082 -31.205678)
		(mid 96.568515 -31.164527)
		(end 96.578166 -31.116016)
		(width 0.1397)
		(layer "B.Cu")
		(net "PCIE_SAS_CPU_RX_P2")
	)
	(arc
		(start 96.393 -29.591)
		(mid 96.278302 -29.419342)
		(end 96.23806 -29.216858)
		(width 0.1397)
		(layer "B.Cu")
		(net "PCIE_SAS_CPU_RX_P2")
	)
	(arc
		(start 195.450206 -74.805794)
		(mid 195.254515 -75.278144)
		(end 195.450206 -75.75042)
		(width 0.1397)
		(layer "B.Cu")
		(net "PCIE_SAS_CPU_RX_P2")
	)
	(arc
		(start 96.23806 -25.019)
		(mid 96.312533 -24.644691)
		(end 96.524572 -24.327358)
		(width 0.1397)
		(layer "B.Cu")
		(net "PCIE_SAS_CPU_RX_P2")
	)
	(arc
		(start 113.986564 -14.401292)
		(mid 114.229568 -14.352956)
		(end 114.435636 -14.215364)
		(width 0.1397)
		(layer "B.Cu")
		(net "PCIE_SAS_CPU_RX_P2")
	)
	(arc
		(start 128.76911 -10.0584)
		(mid 129.143419 -10.132873)
		(end 129.460752 -10.344912)
		(width 0.1397)
		(layer "B.Cu")
		(net "PCIE_SAS_CPU_RX_P2")
	)
	(arc
		(start 106.164126 -14.687804)
		(mid 106.48144 -14.475718)
		(end 106.855768 -14.401292)
		(width 0.1397)
		(layer "B.Cu")
		(net "PCIE_SAS_CPU_RX_P2")
	)
	(arc
		(start 155.284424 -31.2801)
		(mid 155.658733 -31.354573)
		(end 155.976066 -31.566612)
		(width 0.1397)
		(layer "B.Cu")
		(net "PCIE_SAS_CPU_RX_P2")
	)
	(arc
		(start 96.578166 -29.845)
		(mid 96.565438 -29.781484)
		(end 96.529398 -29.727652)
		(width 0.1397)
		(layer "B.Cu")
		(net "PCIE_SAS_CPU_RX_P2")
	)
	(arc
		(start 118.306088 -10.344912)
		(mid 118.623402 -10.132826)
		(end 118.99773 -10.0584)
		(width 0.1397)
		(layer "B.Cu")
		(net "PCIE_SAS_CPU_RX_P2")
	)
	(arc
		(start 195.616322 -74.408792)
		(mid 195.573883 -74.622149)
		(end 195.453 -74.803)
		(width 0.1397)
		(layer "B.Cu")
		(net "PCIE_SAS_CPU_RX_P2")
	)
	(arc
		(start 150.210012 -31.094172)
		(mid 150.416048 -31.231841)
		(end 150.659084 -31.2801)
		(width 0.1397)
		(layer "B.Cu")
		(net "PCIE_SAS_CPU_RX_P2")
	)
	(segment
		(start 259.588 -37.465)
		(end 260.731 -37.465)
		(width 0.254)
		(layer "F.Cu")
		(net "P1V8_STBY_VFB_R")
	)
	(segment
		(start 261.0485 -37.7825)
		(end 260.731 -37.465)
		(width 0.254)
		(layer "F.Cu")
		(net "P1V8_STBY_VFB_R")
	)
	(segment
		(start 261.874 -37.7825)
		(end 261.0485 -37.7825)
		(width 0.254)
		(layer "F.Cu")
		(net "P1V8_STBY_VFB_R")
	)
	(via
		(at 259.588 -37.465)
		(size 0.7112)
		(drill 0.3556)
		(layers "F.Cu" "B.Cu")
		(net "P1V8_STBY_VFB_R")
	)
	(segment
		(start 288.034984 -177.840132)
		(end 287.63976 -178.235356)
		(width 0.1143)
		(layer "F.Cu")
		(net "ROMA3")
	)
	(segment
		(start 267.147548 -179.07)
		(end 267.380212 -178.837336)
		(width 0.1143)
		(layer "F.Cu")
		(net "ROMA3")
	)
	(segment
		(start 266.5095 -179.07)
		(end 267.147548 -179.07)
		(width 0.1143)
		(layer "F.Cu")
		(net "ROMA3")
	)
	(segment
		(start 267.528548 -178.689)
		(end 267.380212 -178.837336)
		(width 0.1143)
		(layer "F.Cu")
		(net "ROMA3")
	)
	(segment
		(start 268.1986 -178.689)
		(end 267.528548 -178.689)
		(width 0.1143)
		(layer "F.Cu")
		(net "ROMA3")
	)
	(via
		(at 267.380212 -178.837336)
		(size 0.5588)
		(drill 0.3048)
		(layers "F.Cu" "B.Cu")
		(net "ROMA3")
	)
	(via
		(at 268.1986 -178.689)
		(size 0.7112)
		(drill 0.3556)
		(layers "F.Cu" "B.Cu")
		(net "ROMA3")
	)
	(via
		(at 287.63976 -178.235356)
		(size 0.508)
		(drill 0.254)
		(layers "F.Cu" "B.Cu")
		(net "ROMA3")
	)
	(segment
		(start 272.590768 -178.1937)
		(end 272.178272 -178.606196)
		(width 0.127)
		(layer "In2.Cu")
		(net "ROMA3")
	)
	(segment
		(start 284.48762 -178.65598)
		(end 283.838396 -178.006756)
		(width 0.127)
		(layer "In2.Cu")
		(net "ROMA3")
	)
	(segment
		(start 272.178272 -178.606196)
		(end 267.611352 -178.606196)
		(width 0.127)
		(layer "In2.Cu")
		(net "ROMA3")
	)
	(segment
		(start 273.351244 -178.006756)
		(end 273.1643 -178.1937)
		(width 0.127)
		(layer "In2.Cu")
		(net "ROMA3")
	)
	(segment
		(start 287.23971 -178.635406)
		(end 284.508194 -178.635406)
		(width 0.0889)
		(layer "In2.Cu")
		(net "ROMA3")
	)
	(segment
		(start 273.1643 -178.1937)
		(end 272.590768 -178.1937)
		(width 0.127)
		(layer "In2.Cu")
		(net "ROMA3")
	)
	(segment
		(start 283.838396 -178.006756)
		(end 273.351244 -178.006756)
		(width 0.127)
		(layer "In2.Cu")
		(net "ROMA3")
	)
	(segment
		(start 287.63976 -178.235356)
		(end 287.23971 -178.635406)
		(width 0.0889)
		(layer "In2.Cu")
		(net "ROMA3")
	)
	(segment
		(start 267.611352 -178.606196)
		(end 267.380212 -178.837336)
		(width 0.127)
		(layer "In2.Cu")
		(net "ROMA3")
	)
	(segment
		(start 284.508194 -178.635406)
		(end 284.48762 -178.65598)
		(width 0.0889)
		(layer "In2.Cu")
		(net "ROMA3")
	)
	(segment
		(start 264.033 -45.4025)
		(end 262.89 -45.4025)
		(width 0.254)
		(layer "F.Cu")
		(net "AGND_P1V8_STBY")
	)
	(segment
		(start 263.5885 -31.496)
		(end 262.509 -31.496)
		(width 0.254)
		(layer "F.Cu")
		(net "AGND_P1V8_STBY")
	)
	(segment
		(start 260.8326 -39.37)
		(end 259.842 -39.37)
		(width 0.254)
		(layer "F.Cu")
		(net "AGND_P1V8_STBY")
	)
	(segment
		(start 262.89 -45.4025)
		(end 260.9215 -45.4025)
		(width 0.254)
		(layer "F.Cu")
		(net "AGND_P1V8_STBY")
	)
	(segment
		(start 260.7945 -43.942)
		(end 259.9944 -43.942)
		(width 0.254)
		(layer "F.Cu")
		(net "AGND_P1V8_STBY")
	)
	(segment
		(start 260.5405 -33.782)
		(end 260.477 -33.8455)
		(width 0.254)
		(layer "F.Cu")
		(net "AGND_P1V8_STBY")
	)
	(segment
		(start 259.9944 -44.4754)
		(end 259.9944 -43.942)
		(width 0.254)
		(layer "F.Cu")
		(net "AGND_P1V8_STBY")
	)
	(segment
		(start 260.9215 -45.4025)
		(end 259.9944 -44.4754)
		(width 0.254)
		(layer "F.Cu")
		(net "AGND_P1V8_STBY")
	)
	(segment
		(start 263.5885 -32.639)
		(end 263.5885 -31.496)
		(width 0.254)
		(layer "F.Cu")
		(net "AGND_P1V8_STBY")
	)
	(segment
		(start 261.5565 -33.782)
		(end 260.5405 -33.782)
		(width 0.254)
		(layer "F.Cu")
		(net "AGND_P1V8_STBY")
	)
	(segment
		(start 260.477 -32.893)
		(end 260.477 -33.8455)
		(width 0.254)
		(layer "F.Cu")
		(net "AGND_P1V8_STBY")
	)
	(via
		(at 260.477 -32.893)
		(size 0.5588)
		(drill 0.3048)
		(layers "F.Cu" "B.Cu")
		(net "AGND_P1V8_STBY")
	)
	(via
		(at 262.509 -31.496)
		(size 0.5588)
		(drill 0.3048)
		(layers "F.Cu" "B.Cu")
		(net "AGND_P1V8_STBY")
	)
	(via
		(at 260.477 -35.687)
		(size 0.7112)
		(drill 0.3556)
		(layers "F.Cu" "B.Cu")
		(net "AGND_P1V8_STBY")
	)
	(via
		(at 259.9944 -43.942)
		(size 0.5588)
		(drill 0.3048)
		(layers "F.Cu" "B.Cu")
		(net "AGND_P1V8_STBY")
	)
	(via
		(at 259.842 -39.37)
		(size 0.5588)
		(drill 0.3048)
		(layers "F.Cu" "B.Cu")
		(net "AGND_P1V8_STBY")
	)
	(segment
		(start 261.62 -31.496)
		(end 262.509 -31.496)
		(width 0.254)
		(layer "B.Cu")
		(net "AGND_P1V8_STBY")
	)
	(segment
		(start 259.842 -39.37)
		(end 259.842 -43.561)
		(width 0.254)
		(layer "B.Cu")
		(net "AGND_P1V8_STBY")
	)
	(segment
		(start 259.9944 -43.7134)
		(end 259.9944 -43.942)
		(width 0.254)
		(layer "B.Cu")
		(net "AGND_P1V8_STBY")
	)
	(segment
		(start 259.842 -38.1)
		(end 260.477 -37.465)
		(width 0.254)
		(layer "B.Cu")
		(net "AGND_P1V8_STBY")
	)
	(segment
		(start 260.477 -37.465)
		(end 260.477 -35.687)
		(width 0.254)
		(layer "B.Cu")
		(net "AGND_P1V8_STBY")
	)
	(segment
		(start 259.842 -43.561)
		(end 259.9944 -43.7134)
		(width 0.254)
		(layer "B.Cu")
		(net "AGND_P1V8_STBY")
	)
	(segment
		(start 260.477 -32.893)
		(end 260.477 -32.639)
		(width 0.254)
		(layer "B.Cu")
		(net "AGND_P1V8_STBY")
	)
	(segment
		(start 260.477 -32.639)
		(end 261.62 -31.496)
		(width 0.254)
		(layer "B.Cu")
		(net "AGND_P1V8_STBY")
	)
	(segment
		(start 259.842 -39.37)
		(end 259.842 -38.1)
		(width 0.254)
		(layer "B.Cu")
		(net "AGND_P1V8_STBY")
	)
	(segment
		(start 260.477 -35.687)
		(end 260.477 -32.893)
		(width 0.254)
		(layer "B.Cu")
		(net "AGND_P1V8_STBY")
	)
	(segment
		(start 264.033 -43.053)
		(end 263.525 -43.053)
		(width 0.254)
		(layer "F.Cu")
		(net "P1V8_STBY_TRIP")
	)
	(segment
		(start 262.89 -43.688)
		(end 263.144 -43.434)
		(width 0.254)
		(layer "F.Cu")
		(net "P1V8_STBY_TRIP")
	)
	(segment
		(start 264.437876 -41.891458)
		(end 264.437876 -42.648124)
		(width 0.254)
		(layer "F.Cu")
		(net "P1V8_STBY_TRIP")
	)
	(segment
		(start 264.437876 -42.648124)
		(end 264.033 -43.053)
		(width 0.254)
		(layer "F.Cu")
		(net "P1V8_STBY_TRIP")
	)
	(segment
		(start 262.89 -44.5135)
		(end 262.89 -43.688)
		(width 0.254)
		(layer "F.Cu")
		(net "P1V8_STBY_TRIP")
	)
	(segment
		(start 263.525 -43.053)
		(end 263.144 -43.434)
		(width 0.254)
		(layer "F.Cu")
		(net "P1V8_STBY_TRIP")
	)
	(via
		(at 263.144 -43.434)
		(size 0.7112)
		(drill 0.3556)
		(layers "F.Cu" "B.Cu")
		(net "P1V8_STBY_TRIP")
	)
	(segment
		(start 293.95039 -165.840918)
		(end 293.95039 -164.8714)
		(width 0.1143)
		(layer "F.Cu")
		(net "RMII0_BMC_C_CRS_DV")
	)
	(segment
		(start 295.3258 -162.1917)
		(end 295.3258 -162.5854)
		(width 0.1143)
		(layer "F.Cu")
		(net "RMII0_BMC_C_CRS_DV")
	)
	(segment
		(start 293.634922 -166.156386)
		(end 293.95039 -165.840918)
		(width 0.1143)
		(layer "F.Cu")
		(net "RMII0_BMC_C_CRS_DV")
	)
	(segment
		(start 293.95039 -163.96081)
		(end 293.95039 -164.8714)
		(width 0.1143)
		(layer "F.Cu")
		(net "RMII0_BMC_C_CRS_DV")
	)
	(segment
		(start 295.529 -161.9885)
		(end 295.3258 -162.1917)
		(width 0.1143)
		(layer "F.Cu")
		(net "RMII0_BMC_C_CRS_DV")
	)
	(segment
		(start 295.3258 -162.5854)
		(end 293.95039 -163.96081)
		(width 0.1143)
		(layer "F.Cu")
		(net "RMII0_BMC_C_CRS_DV")
	)
	(segment
		(start 293.634922 -167.440102)
		(end 293.634922 -166.156386)
		(width 0.1143)
		(layer "F.Cu")
		(net "RMII0_BMC_C_CRS_DV")
	)
	(via
		(at 293.95039 -164.8714)
		(size 0.7112)
		(drill 0.3556)
		(layers "F.Cu" "B.Cu")
		(net "RMII0_BMC_C_CRS_DV")
	)
	(segment
		(start 333.375 -219.644468)
		(end 333.375 -218.948)
		(width 0.1143)
		(layer "F.Cu")
		(net "VOL_SEN_SDA")
	)
	(segment
		(start 333.375 -217.805)
		(end 333.375 -218.948)
		(width 0.1143)
		(layer "F.Cu")
		(net "VOL_SEN_SDA")
	)
	(segment
		(start 334.518 -217.805)
		(end 333.375 -217.805)
		(width 0.1143)
		(layer "F.Cu")
		(net "VOL_SEN_SDA")
	)
	(segment
		(start 332.597252 -222.157036)
		(end 332.597252 -220.422216)
		(width 0.1143)
		(layer "F.Cu")
		(net "VOL_SEN_SDA")
	)
	(segment
		(start 332.597252 -220.422216)
		(end 333.375 -219.644468)
		(width 0.1143)
		(layer "F.Cu")
		(net "VOL_SEN_SDA")
	)
	(via
		(at 333.375 -218.948)
		(size 0.7112)
		(drill 0.3556)
		(layers "F.Cu" "B.Cu")
		(net "VOL_SEN_SDA")
	)
	(segment
		(start 264.5664 -45.0469)
		(end 264.033 -44.5135)
		(width 0.254)
		(layer "F.Cu")
		(net "P1V8_STBY_MODE")
	)
	(segment
		(start 264.5664 -45.8216)
		(end 264.5664 -45.0469)
		(width 0.254)
		(layer "F.Cu")
		(net "P1V8_STBY_MODE")
	)
	(segment
		(start 264.16 -46.228)
		(end 264.5664 -45.8216)
		(width 0.254)
		(layer "F.Cu")
		(net "P1V8_STBY_MODE")
	)
	(segment
		(start 264.937748 -42.96156)
		(end 264.937748 -41.891458)
		(width 0.254)
		(layer "F.Cu")
		(net "P1V8_STBY_MODE")
	)
	(segment
		(start 264.033 -44.5135)
		(end 264.033 -43.866308)
		(width 0.254)
		(layer "F.Cu")
		(net "P1V8_STBY_MODE")
	)
	(segment
		(start 264.033 -43.866308)
		(end 264.937748 -42.96156)
		(width 0.254)
		(layer "F.Cu")
		(net "P1V8_STBY_MODE")
	)
	(via
		(at 263.144 -45.212)
		(size 0.7112)
		(drill 0.3556)
		(layers "F.Cu" "B.Cu")
		(net "P1V8_STBY_MODE")
	)
	(via
		(at 264.16 -46.228)
		(size 0.5588)
		(drill 0.3048)
		(layers "F.Cu" "B.Cu")
		(net "P1V8_STBY_MODE")
	)
	(segment
		(start 260.5532 -38.4048)
		(end 260.5532 -42.6212)
		(width 0.254)
		(layer "B.Cu")
		(net "P1V8_STBY_MODE")
	)
	(segment
		(start 263.0805 -35.8775)
		(end 260.5532 -38.4048)
		(width 0.254)
		(layer "B.Cu")
		(net "P1V8_STBY_MODE")
	)
	(segment
		(start 263.0805 -35.814)
		(end 263.0805 -35.8775)
		(width 0.254)
		(layer "B.Cu")
		(net "P1V8_STBY_MODE")
	)
	(segment
		(start 264.16 -46.228)
		(end 263.144 -45.212)
		(width 0.254)
		(layer "B.Cu")
		(net "P1V8_STBY_MODE")
	)
	(segment
		(start 260.5532 -42.6212)
		(end 263.144 -45.212)
		(width 0.254)
		(layer "B.Cu")
		(net "P1V8_STBY_MODE")
	)
	(segment
		(start 343.683336 -81.256378)
		(end 343.683336 -81.435194)
		(width 0.1143)
		(layer "F.Cu")
		(net "FLA_CS_R")
	)
	(segment
		(start 337.058 -83.5025)
		(end 342.984836 -83.5025)
		(width 0.1143)
		(layer "F.Cu")
		(net "FLA_CS_R")
	)
	(segment
		(start 342.984836 -83.5025)
		(end 343.683336 -82.804)
		(width 0.1143)
		(layer "F.Cu")
		(net "FLA_CS_R")
	)
	(segment
		(start 335.915 -83.5025)
		(end 337.058 -83.5025)
		(width 0.1143)
		(layer "F.Cu")
		(net "FLA_CS_R")
	)
	(segment
		(start 343.683336 -82.804)
		(end 343.683336 -81.435194)
		(width 0.1143)
		(layer "F.Cu")
		(net "FLA_CS_R")
	)
	(segment
		(start 179.7685 -15.113)
		(end 179.7685 -15.0495)
		(width 0.1143)
		(layer "F.Cu")
		(net "TEMP_SENSOR_C")
	)
	(segment
		(start 174.56785 -14.42085)
		(end 174.121826 -13.974826)
		(width 0.1143)
		(layer "F.Cu")
		(net "TEMP_SENSOR_C")
	)
	(segment
		(start 179.7685 -16.129)
		(end 179.7685 -15.113)
		(width 0.1143)
		(layer "F.Cu")
		(net "TEMP_SENSOR_C")
	)
	(segment
		(start 177.673 -14.42085)
		(end 174.56785 -14.42085)
		(width 0.1143)
		(layer "F.Cu")
		(net "TEMP_SENSOR_C")
	)
	(segment
		(start 179.7685 -15.0495)
		(end 179.13985 -14.42085)
		(width 0.1143)
		(layer "F.Cu")
		(net "TEMP_SENSOR_C")
	)
	(segment
		(start 179.13985 -14.42085)
		(end 177.673 -14.42085)
		(width 0.1143)
		(layer "F.Cu")
		(net "TEMP_SENSOR_C")
	)
	(via
		(at 177.673 -14.42085)
		(size 0.7112)
		(drill 0.3556)
		(layers "F.Cu" "B.Cu")
		(net "TEMP_SENSOR_C")
	)
	(via
		(at 174.121826 -13.974826)
		(size 0.5588)
		(drill 0.3048)
		(layers "F.Cu" "B.Cu")
		(net "TEMP_SENSOR_C")
	)
	(segment
		(start 107.54995 -5.999988)
		(end 114.050064 -5.999988)
		(width 0.127)
		(layer "In2.Cu")
		(net "TEMP_SENSOR_C")
	)
	(segment
		(start 163.78428 -24.8412)
		(end 163.84778 -24.7777)
		(width 0.127)
		(layer "In2.Cu")
		(net "TEMP_SENSOR_C")
	)
	(segment
		(start 136.779 -15.875)
		(end 145.7452 -24.8412)
		(width 0.127)
		(layer "In2.Cu")
		(net "TEMP_SENSOR_C")
	)
	(segment
		(start 173.228 -15.748)
		(end 173.228 -14.906498)
		(width 0.127)
		(layer "In2.Cu")
		(net "TEMP_SENSOR_C")
	)
	(segment
		(start 174.121826 -14.012672)
		(end 174.121826 -13.974826)
		(width 0.127)
		(layer "In2.Cu")
		(net "TEMP_SENSOR_C")
	)
	(segment
		(start 114.050064 -5.999988)
		(end 123.925076 -15.875)
		(width 0.127)
		(layer "In2.Cu")
		(net "TEMP_SENSOR_C")
	)
	(segment
		(start 163.84778 -24.7777)
		(end 164.1983 -24.7777)
		(width 0.127)
		(layer "In2.Cu")
		(net "TEMP_SENSOR_C")
	)
	(segment
		(start 173.228 -14.906498)
		(end 174.121826 -14.012672)
		(width 0.127)
		(layer "In2.Cu")
		(net "TEMP_SENSOR_C")
	)
	(segment
		(start 145.7452 -24.8412)
		(end 163.78428 -24.8412)
		(width 0.127)
		(layer "In2.Cu")
		(net "TEMP_SENSOR_C")
	)
	(segment
		(start 164.1983 -24.7777)
		(end 173.228 -15.748)
		(width 0.127)
		(layer "In2.Cu")
		(net "TEMP_SENSOR_C")
	)
	(segment
		(start 123.925076 -15.875)
		(end 136.779 -15.875)
		(width 0.127)
		(layer "In2.Cu")
		(net "TEMP_SENSOR_C")
	)
	(segment
		(start 265.937746 -36.992814)
		(end 265.937746 -35.81654)
		(width 0.254)
		(layer "F.Cu")
		(net "P1V8_STBY_ROVP")
	)
	(segment
		(start 264.4775 -32.639)
		(end 264.4775 -31.496)
		(width 0.254)
		(layer "F.Cu")
		(net "P1V8_STBY_ROVP")
	)
	(segment
		(start 266.065 -35.689286)
		(end 266.065 -33.274)
		(width 0.254)
		(layer "F.Cu")
		(net "P1V8_STBY_ROVP")
	)
	(segment
		(start 264.4775 -31.496)
		(end 264.4775 -30.353)
		(width 0.254)
		(layer "F.Cu")
		(net "P1V8_STBY_ROVP")
	)
	(segment
		(start 266.065 -33.274)
		(end 265.43 -32.639)
		(width 0.254)
		(layer "F.Cu")
		(net "P1V8_STBY_ROVP")
	)
	(segment
		(start 265.937746 -35.81654)
		(end 266.065 -35.689286)
		(width 0.254)
		(layer "F.Cu")
		(net "P1V8_STBY_ROVP")
	)
	(segment
		(start 264.4775 -32.639)
		(end 265.43 -32.639)
		(width 0.254)
		(layer "F.Cu")
		(net "P1V8_STBY_ROVP")
	)
	(via
		(at 265.43 -32.639)
		(size 0.7112)
		(drill 0.3556)
		(layers "F.Cu" "B.Cu")
		(net "P1V8_STBY_ROVP")
	)
	(segment
		(start 335.915 -84.3915)
		(end 335.915 -85.598)
		(width 0.1143)
		(layer "F.Cu")
		(net "FLA_CS")
	)
	(segment
		(start 287.234884 -178.640232)
		(end 287.225232 -178.640232)
		(width 0.1143)
		(layer "F.Cu")
		(net "FLA_CS")
	)
	(segment
		(start 287.225232 -178.640232)
		(end 286.826452 -179.039012)
		(width 0.1143)
		(layer "F.Cu")
		(net "FLA_CS")
	)
	(via
		(at 335.915 -85.598)
		(size 0.5588)
		(drill 0.3048)
		(layers "F.Cu" "B.Cu")
		(net "FLA_CS")
	)
	(via
		(at 276.925278 -183.960262)
		(size 0.5588)
		(drill 0.3048)
		(layers "F.Cu" "B.Cu")
		(net "FLA_CS")
	)
	(via
		(at 286.826452 -179.039012)
		(size 0.508)
		(drill 0.254)
		(layers "F.Cu" "B.Cu")
		(net "FLA_CS")
	)
	(via
		(at 298.48175 -93.98)
		(size 0.5588)
		(drill 0.3048)
		(layers "F.Cu" "B.Cu")
		(net "FLA_CS")
	)
	(via
		(at 284.3276 -179.37734)
		(size 0.7112)
		(drill 0.3556)
		(layers "F.Cu" "B.Cu")
		(net "FLA_CS")
	)
	(segment
		(start 286.387794 -179.438046)
		(end 285.112206 -179.438046)
		(width 0.0889)
		(layer "B.Cu")
		(net "FLA_CS")
	)
	(segment
		(start 285.112206 -179.438046)
		(end 285.0515 -179.37734)
		(width 0.0889)
		(layer "B.Cu")
		(net "FLA_CS")
	)
	(segment
		(start 277.141178 -183.960262)
		(end 276.925278 -183.960262)
		(width 0.1143)
		(layer "B.Cu")
		(net "FLA_CS")
	)
	(segment
		(start 284.3276 -179.37734)
		(end 281.7241 -179.37734)
		(width 0.1143)
		(layer "B.Cu")
		(net "FLA_CS")
	)
	(segment
		(start 333.501746 -85.979)
		(end 331.850746 -87.63)
		(width 0.1143)
		(layer "B.Cu")
		(net "FLA_CS")
	)
	(segment
		(start 335.915 -85.598)
		(end 335.534 -85.979)
		(width 0.1143)
		(layer "B.Cu")
		(net "FLA_CS")
	)
	(segment
		(start 286.786828 -179.039012)
		(end 286.387794 -179.438046)
		(width 0.0889)
		(layer "B.Cu")
		(net "FLA_CS")
	)
	(segment
		(start 281.7241 -179.37734)
		(end 277.141178 -183.960262)
		(width 0.1143)
		(layer "B.Cu")
		(net "FLA_CS")
	)
	(segment
		(start 285.0515 -179.37734)
		(end 284.3276 -179.37734)
		(width 0.1143)
		(layer "B.Cu")
		(net "FLA_CS")
	)
	(segment
		(start 298.577 -93.98)
		(end 298.48175 -93.98)
		(width 0.1143)
		(layer "B.Cu")
		(net "FLA_CS")
	)
	(segment
		(start 303.461928 -93.539818)
		(end 299.017182 -93.539818)
		(width 0.1143)
		(layer "B.Cu")
		(net "FLA_CS")
	)
	(segment
		(start 299.017182 -93.539818)
		(end 298.577 -93.98)
		(width 0.1143)
		(layer "B.Cu")
		(net "FLA_CS")
	)
	(segment
		(start 309.371746 -87.63)
		(end 303.461928 -93.539818)
		(width 0.1143)
		(layer "B.Cu")
		(net "FLA_CS")
	)
	(segment
		(start 286.826452 -179.039012)
		(end 286.786828 -179.039012)
		(width 0.0889)
		(layer "B.Cu")
		(net "FLA_CS")
	)
	(segment
		(start 335.534 -85.979)
		(end 333.501746 -85.979)
		(width 0.1143)
		(layer "B.Cu")
		(net "FLA_CS")
	)
	(segment
		(start 331.850746 -87.63)
		(end 309.371746 -87.63)
		(width 0.1143)
		(layer "B.Cu")
		(net "FLA_CS")
	)
	(segment
		(start 295.051734 -114.2492)
		(end 284.002734 -125.2982)
		(width 0.127)
		(layer "In5.Cu")
		(net "FLA_CS")
	)
	(segment
		(start 281.823668 -133.253734)
		(end 278.897334 -133.253734)
		(width 0.127)
		(layer "In5.Cu")
		(net "FLA_CS")
	)
	(segment
		(start 274.0787 -138.072368)
		(end 274.0787 -148.990558)
		(width 0.127)
		(layer "In5.Cu")
		(net "FLA_CS")
	)
	(segment
		(start 278.897334 -133.253734)
		(end 274.0787 -138.072368)
		(width 0.127)
		(layer "In5.Cu")
		(net "FLA_CS")
	)
	(segment
		(start 284.002734 -131.074668)
		(end 281.823668 -133.253734)
		(width 0.127)
		(layer "In5.Cu")
		(net "FLA_CS")
	)
	(segment
		(start 274.0787 -148.990558)
		(end 278.4983 -153.410158)
		(width 0.127)
		(layer "In5.Cu")
		(net "FLA_CS")
	)
	(segment
		(start 298.39285 -93.98)
		(end 295.051734 -97.321116)
		(width 0.127)
		(layer "In5.Cu")
		(net "FLA_CS")
	)
	(segment
		(start 295.051734 -97.321116)
		(end 295.051734 -114.2492)
		(width 0.127)
		(layer "In5.Cu")
		(net "FLA_CS")
	)
	(segment
		(start 278.4983 -182.38724)
		(end 276.925278 -183.960262)
		(width 0.127)
		(layer "In5.Cu")
		(net "FLA_CS")
	)
	(segment
		(start 284.002734 -125.2982)
		(end 284.002734 -131.074668)
		(width 0.127)
		(layer "In5.Cu")
		(net "FLA_CS")
	)
	(segment
		(start 278.4983 -153.410158)
		(end 278.4983 -182.38724)
		(width 0.127)
		(layer "In5.Cu")
		(net "FLA_CS")
	)
	(segment
		(start 298.48175 -93.98)
		(end 298.39285 -93.98)
		(width 0.127)
		(layer "In5.Cu")
		(net "FLA_CS")
	)
	(segment
		(start 330.454 -200.025)
		(end 330.454 -198.517764)
		(width 0.127)
		(layer "F.Cu")
		(net "EEPROM_A0_R")
	)
	(segment
		(start 330.454 -198.517764)
		(end 331.161136 -197.810628)
		(width 0.127)
		(layer "F.Cu")
		(net "EEPROM_A0_R")
	)
	(segment
		(start 330.906628 -200.477628)
		(end 330.454 -200.025)
		(width 0.127)
		(layer "F.Cu")
		(net "EEPROM_A0_R")
	)
	(segment
		(start 331.161136 -201.748136)
		(end 331.161136 -200.477628)
		(width 0.127)
		(layer "F.Cu")
		(net "EEPROM_A0_R")
	)
	(segment
		(start 331.161136 -200.477628)
		(end 330.906628 -200.477628)
		(width 0.127)
		(layer "F.Cu")
		(net "EEPROM_A0_R")
	)
	(segment
		(start 331.161136 -201.748136)
		(end 331.161136 -203.462128)
		(width 0.127)
		(layer "F.Cu")
		(net "EEPROM_A0_R")
	)
	(via
		(at 331.161136 -201.748136)
		(size 0.7112)
		(drill 0.3556)
		(layers "F.Cu" "B.Cu")
		(net "EEPROM_A0_R")
	)
	(segment
		(start 110.533688 -18.013172)
		(end 117.871748 -10.675112)
		(width 0.1397)
		(layer "F.Cu")
		(net "PCIE_SAS_CPU_TX_P4")
	)
	(segment
		(start 100.375466 -33.33877)
		(end 100.375466 -31.579312)
		(width 0.1397)
		(layer "F.Cu")
		(net "PCIE_SAS_CPU_TX_P4")
	)
	(segment
		(start 167.63746 -51.36134)
		(end 167.63746 -73.9394)
		(width 0.1397)
		(layer "F.Cu")
		(net "PCIE_SAS_CPU_TX_P4")
	)
	(segment
		(start 135.8519 -15.197836)
		(end 135.8519 -18.381726)
		(width 0.1397)
		(layer "F.Cu")
		(net "PCIE_SAS_CPU_TX_P4")
	)
	(segment
		(start 136.223756 -19.279616)
		(end 167.16502 -50.22088)
		(width 0.1397)
		(layer "F.Cu")
		(net "PCIE_SAS_CPU_TX_P4")
	)
	(segment
		(start 100.447856 -25.165304)
		(end 107.202224 -18.410936)
		(width 0.1397)
		(layer "F.Cu")
		(net "PCIE_SAS_CPU_TX_P4")
	)
	(segment
		(start 118.56339 -10.3886)
		(end 132.109718 -10.3886)
		(width 0.1397)
		(layer "F.Cu")
		(net "PCIE_SAS_CPU_TX_P4")
	)
	(segment
		(start 168.63187 -75.553824)
		(end 168.63187 -76.30922)
		(width 0.1397)
		(layer "F.Cu")
		(net "PCIE_SAS_CPU_TX_P4")
	)
	(segment
		(start 132.80136 -10.675112)
		(end 134.81177 -12.68603)
		(width 0.1397)
		(layer "F.Cu")
		(net "PCIE_SAS_CPU_TX_P4")
	)
	(segment
		(start 99.975416 -30.61335)
		(end 99.975416 -26.305764)
		(width 0.1397)
		(layer "F.Cu")
		(net "PCIE_SAS_CPU_TX_P4")
	)
	(segment
		(start 167.796464 -74.323194)
		(end 168.35247 -74.8792)
		(width 0.1397)
		(layer "F.Cu")
		(net "PCIE_SAS_CPU_TX_P4")
	)
	(segment
		(start 107.71378 -18.1991)
		(end 110.084616 -18.1991)
		(width 0.1397)
		(layer "F.Cu")
		(net "PCIE_SAS_CPU_TX_P4")
	)
	(via
		(at 168.928542 -77.0255)
		(size 0.5588)
		(drill 0.3048)
		(layers "F.Cu" "B.Cu")
		(net "PCIE_SAS_CPU_TX_P4")
	)
	(arc
		(start 100.350066 -33.399984)
		(mid 100.368832 -33.371899)
		(end 100.375466 -33.33877)
		(width 0.1397)
		(layer "F.Cu")
		(net "PCIE_SAS_CPU_TX_P4")
	)
	(arc
		(start 134.81177 -12.68603)
		(mid 135.581684 -13.838472)
		(end 135.8519 -15.197836)
		(width 0.1397)
		(layer "F.Cu")
		(net "PCIE_SAS_CPU_TX_P4")
	)
	(arc
		(start 168.63187 -76.30922)
		(mid 168.708976 -76.69686)
		(end 168.928542 -77.0255)
		(width 0.1397)
		(layer "F.Cu")
		(net "PCIE_SAS_CPU_TX_P4")
	)
	(arc
		(start 100.375466 -31.579312)
		(mid 100.325621 -31.328726)
		(end 100.183696 -31.11627)
		(width 0.1397)
		(layer "F.Cu")
		(net "PCIE_SAS_CPU_TX_P4")
	)
	(arc
		(start 135.8519 -18.381726)
		(mid 135.948539 -18.867651)
		(end 136.223756 -19.279616)
		(width 0.1397)
		(layer "F.Cu")
		(net "PCIE_SAS_CPU_TX_P4")
	)
	(arc
		(start 107.202224 -18.410936)
		(mid 107.436941 -18.254136)
		(end 107.71378 -18.1991)
		(width 0.1397)
		(layer "F.Cu")
		(net "PCIE_SAS_CPU_TX_P4")
	)
	(arc
		(start 168.35247 -74.8792)
		(mid 168.559285 -75.18872)
		(end 168.63187 -75.553824)
		(width 0.1397)
		(layer "F.Cu")
		(net "PCIE_SAS_CPU_TX_P4")
	)
	(arc
		(start 117.871748 -10.675112)
		(mid 118.189062 -10.463026)
		(end 118.56339 -10.3886)
		(width 0.1397)
		(layer "F.Cu")
		(net "PCIE_SAS_CPU_TX_P4")
	)
	(arc
		(start 132.109718 -10.3886)
		(mid 132.484027 -10.463073)
		(end 132.80136 -10.675112)
		(width 0.1397)
		(layer "F.Cu")
		(net "PCIE_SAS_CPU_TX_P4")
	)
	(arc
		(start 110.084616 -18.1991)
		(mid 110.32762 -18.150764)
		(end 110.533688 -18.013172)
		(width 0.1397)
		(layer "F.Cu")
		(net "PCIE_SAS_CPU_TX_P4")
	)
	(arc
		(start 99.975416 -26.305764)
		(mid 100.098191 -25.688534)
		(end 100.447856 -25.165304)
		(width 0.1397)
		(layer "F.Cu")
		(net "PCIE_SAS_CPU_TX_P4")
	)
	(arc
		(start 167.16502 -50.22088)
		(mid 167.514643 -50.744127)
		(end 167.63746 -51.36134)
		(width 0.1397)
		(layer "F.Cu")
		(net "PCIE_SAS_CPU_TX_P4")
	)
	(arc
		(start 167.63746 -73.9394)
		(mid 167.678778 -74.14712)
		(end 167.796464 -74.323194)
		(width 0.1397)
		(layer "F.Cu")
		(net "PCIE_SAS_CPU_TX_P4")
	)
	(arc
		(start 100.183696 -31.11627)
		(mid 100.029519 -30.885528)
		(end 99.975416 -30.61335)
		(width 0.1397)
		(layer "F.Cu")
		(net "PCIE_SAS_CPU_TX_P4")
	)
	(segment
		(start 169.449496 -78.24978)
		(end 169.449496 -78.673706)
		(width 0.1397)
		(layer "B.Cu")
		(net "PCIE_SAS_CPU_TX_P4")
	)
	(segment
		(start 168.668954 -77.285088)
		(end 168.928542 -77.0255)
		(width 0.1397)
		(layer "B.Cu")
		(net "PCIE_SAS_CPU_TX_P4")
	)
	(segment
		(start 169.089578 -79.033624)
		(end 168.927272 -79.033624)
		(width 0.1397)
		(layer "B.Cu")
		(net "PCIE_SAS_CPU_TX_P4")
	)
	(segment
		(start 168.60393 -78.55331)
		(end 168.60393 -77.44206)
		(width 0.1397)
		(layer "B.Cu")
		(net "PCIE_SAS_CPU_TX_P4")
	)
	(arc
		(start 168.777158 -78.971394)
		(mid 168.648989 -78.779575)
		(end 168.60393 -78.55331)
		(width 0.1397)
		(layer "B.Cu")
		(net "PCIE_SAS_CPU_TX_P4")
	)
	(arc
		(start 168.60393 -77.44206)
		(mid 168.620828 -77.357106)
		(end 168.668954 -77.285088)
		(width 0.1397)
		(layer "B.Cu")
		(net "PCIE_SAS_CPU_TX_P4")
	)
	(arc
		(start 169.449496 -78.673706)
		(mid 169.344078 -78.928206)
		(end 169.089578 -79.033624)
		(width 0.1397)
		(layer "B.Cu")
		(net "PCIE_SAS_CPU_TX_P4")
	)
	(arc
		(start 168.927272 -79.033624)
		(mid 168.846011 -79.01746)
		(end 168.777158 -78.971394)
		(width 0.1397)
		(layer "B.Cu")
		(net "PCIE_SAS_CPU_TX_P4")
	)
	(segment
		(start 261.6835 -42.799)
		(end 261.6835 -42.4815)
		(width 0.254)
		(layer "F.Cu")
		(net "P1V8_STBY_RF")
	)
	(segment
		(start 263.93775 -41.891458)
		(end 262.273542 -41.891458)
		(width 0.254)
		(layer "F.Cu")
		(net "P1V8_STBY_RF")
	)
	(segment
		(start 261.6835 -42.4815)
		(end 262.255 -41.91)
		(width 0.254)
		(layer "F.Cu")
		(net "P1V8_STBY_RF")
	)
	(segment
		(start 261.6835 -43.942)
		(end 261.6835 -42.799)
		(width 0.254)
		(layer "F.Cu")
		(net "P1V8_STBY_RF")
	)
	(segment
		(start 262.273542 -41.891458)
		(end 262.255 -41.91)
		(width 0.254)
		(layer "F.Cu")
		(net "P1V8_STBY_RF")
	)
	(via
		(at 262.255 -41.91)
		(size 0.7112)
		(drill 0.3556)
		(layers "F.Cu" "B.Cu")
		(net "P1V8_STBY_RF")
	)
	(segment
		(start 294.033702 -171.041314)
		(end 294.033702 -171.048172)
		(width 0.1143)
		(layer "F.Cu")
		(net "RMII0_BMC_C_RX_ER")
	)
	(segment
		(start 294.434768 -170.640248)
		(end 294.033702 -171.041314)
		(width 0.1143)
		(layer "F.Cu")
		(net "RMII0_BMC_C_RX_ER")
	)
	(via
		(at 294.033702 -171.048172)
		(size 0.508)
		(drill 0.254)
		(layers "F.Cu" "B.Cu")
		(net "RMII0_BMC_C_RX_ER")
	)
	(via
		(at 294.386 -165.652704)
		(size 0.7112)
		(drill 0.3556)
		(layers "F.Cu" "B.Cu")
		(net "RMII0_BMC_C_RX_ER")
	)
	(segment
		(start 294.303958 -165.652704)
		(end 293.18585 -166.770812)
		(width 0.1143)
		(layer "B.Cu")
		(net "RMII0_BMC_C_RX_ER")
	)
	(segment
		(start 294.386 -165.652704)
		(end 294.303958 -165.652704)
		(width 0.1143)
		(layer "B.Cu")
		(net "RMII0_BMC_C_RX_ER")
	)
	(segment
		(start 293.18585 -167.281098)
		(end 293.3446 -167.439848)
		(width 0.1143)
		(layer "B.Cu")
		(net "RMII0_BMC_C_RX_ER")
	)
	(segment
		(start 293.18585 -166.770812)
		(end 293.18585 -167.281098)
		(width 0.1143)
		(layer "B.Cu")
		(net "RMII0_BMC_C_RX_ER")
	)
	(segment
		(start 293.3446 -168.912794)
		(end 293.642034 -169.210228)
		(width 0.0889)
		(layer "B.Cu")
		(net "RMII0_BMC_C_RX_ER")
	)
	(segment
		(start 295.148 -165.225222)
		(end 294.720518 -165.652704)
		(width 0.1143)
		(layer "B.Cu")
		(net "RMII0_BMC_C_RX_ER")
	)
	(segment
		(start 295.148 -164.6555)
		(end 295.148 -165.225222)
		(width 0.1143)
		(layer "B.Cu")
		(net "RMII0_BMC_C_RX_ER")
	)
	(segment
		(start 293.642034 -169.210228)
		(end 293.642034 -170.656504)
		(width 0.0889)
		(layer "B.Cu")
		(net "RMII0_BMC_C_RX_ER")
	)
	(segment
		(start 294.132 -164.6555)
		(end 295.148 -164.6555)
		(width 0.1143)
		(layer "B.Cu")
		(net "RMII0_BMC_C_RX_ER")
	)
	(segment
		(start 294.720518 -165.652704)
		(end 294.386 -165.652704)
		(width 0.1143)
		(layer "B.Cu")
		(net "RMII0_BMC_C_RX_ER")
	)
	(segment
		(start 293.3446 -167.439848)
		(end 293.3446 -168.912794)
		(width 0.1143)
		(layer "B.Cu")
		(net "RMII0_BMC_C_RX_ER")
	)
	(segment
		(start 293.642034 -170.656504)
		(end 294.033702 -171.048172)
		(width 0.0889)
		(layer "B.Cu")
		(net "RMII0_BMC_C_RX_ER")
	)
	(segment
		(start 276.903434 -178.481228)
		(end 275.841968 -179.542694)
		(width 0.1143)
		(layer "F.Cu")
		(net "ROMA2")
	)
	(segment
		(start 275.795486 -179.606702)
		(end 275.841968 -179.606702)
		(width 0.1143)
		(layer "F.Cu")
		(net "ROMA2")
	)
	(segment
		(start 274.6375 -180.721)
		(end 275.795486 -179.606702)
		(width 0.1143)
		(layer "F.Cu")
		(net "ROMA2")
	)
	(segment
		(start 275.841968 -179.542694)
		(end 275.841968 -179.606702)
		(width 0.1143)
		(layer "F.Cu")
		(net "ROMA2")
	)
	(segment
		(start 284.675834 -178.481228)
		(end 276.903434 -178.481228)
		(width 0.1143)
		(layer "F.Cu")
		(net "ROMA2")
	)
	(segment
		(start 284.834838 -178.640232)
		(end 284.675834 -178.481228)
		(width 0.1143)
		(layer "F.Cu")
		(net "ROMA2")
	)
	(via
		(at 275.841968 -179.606702)
		(size 0.7112)
		(drill 0.3556)
		(layers "F.Cu" "B.Cu")
		(net "ROMA2")
	)
	(segment
		(start 108.564426 -20.355052)
		(end 110.303818 -20.355052)
		(width 0.1397)
		(layer "F.Cu")
		(net "PCIE_SAS_CPU_TX_N5")
	)
	(segment
		(start 163.29406 -49.901094)
		(end 163.29406 -73.9394)
		(width 0.1397)
		(layer "F.Cu")
		(net "PCIE_SAS_CPU_TX_N5")
	)
	(segment
		(start 164.28847 -75.55357)
		(end 164.28847 -76.198984)
		(width 0.1397)
		(layer "F.Cu")
		(net "PCIE_SAS_CPU_TX_N5")
	)
	(segment
		(start 134.05104 -20.13204)
		(end 162.922204 -49.003204)
		(width 0.1397)
		(layer "F.Cu")
		(net "PCIE_SAS_CPU_TX_N5")
	)
	(segment
		(start 102.506272 -26.150316)
		(end 108.115354 -20.541234)
		(width 0.1397)
		(layer "F.Cu")
		(net "PCIE_SAS_CPU_TX_N5")
	)
	(segment
		(start 163.553394 -74.565764)
		(end 164.1094 -75.12177)
		(width 0.1397)
		(layer "F.Cu")
		(net "PCIE_SAS_CPU_TX_N5")
	)
	(segment
		(start 101.575362 -33.55975)
		(end 101.575362 -32.15132)
		(width 0.1397)
		(layer "F.Cu")
		(net "PCIE_SAS_CPU_TX_N5")
	)
	(segment
		(start 131.615688 -12.847828)
		(end 133.08203 -14.31417)
		(width 0.1397)
		(layer "F.Cu")
		(net "PCIE_SAS_CPU_TX_N5")
	)
	(segment
		(start 101.679756 -31.899606)
		(end 101.929692 -31.64967)
		(width 0.1397)
		(layer "F.Cu")
		(net "PCIE_SAS_CPU_TX_N5")
	)
	(segment
		(start 118.665244 -12.6619)
		(end 131.166616 -12.6619)
		(width 0.1397)
		(layer "F.Cu")
		(net "PCIE_SAS_CPU_TX_N5")
	)
	(segment
		(start 164.288216 -75.553824)
		(end 164.28847 -75.55357)
		(width 0.1397)
		(layer "F.Cu")
		(net "PCIE_SAS_CPU_TX_N5")
	)
	(segment
		(start 110.99546 -20.06854)
		(end 118.216172 -12.847828)
		(width 0.1397)
		(layer "F.Cu")
		(net "PCIE_SAS_CPU_TX_N5")
	)
	(segment
		(start 102.134416 -31.15564)
		(end 102.134416 -27.048206)
		(width 0.1397)
		(layer "F.Cu")
		(net "PCIE_SAS_CPU_TX_N5")
	)
	(segment
		(start 101.19233 -34.19983)
		(end 101.393498 -33.998662)
		(width 0.1397)
		(layer "F.Cu")
		(net "PCIE_SAS_CPU_TX_N5")
	)
	(segment
		(start 101.150166 -34.19983)
		(end 101.19233 -34.19983)
		(width 0.1397)
		(layer "F.Cu")
		(net "PCIE_SAS_CPU_TX_N5")
	)
	(segment
		(start 133.5786 -15.512796)
		(end 133.5786 -18.99158)
		(width 0.1397)
		(layer "F.Cu")
		(net "PCIE_SAS_CPU_TX_N5")
	)
	(via
		(at 163.946078 -77.0255)
		(size 0.5588)
		(drill 0.3048)
		(layers "F.Cu" "B.Cu")
		(net "PCIE_SAS_CPU_TX_N5")
	)
	(arc
		(start 131.166616 -12.6619)
		(mid 131.40962 -12.710236)
		(end 131.615688 -12.847828)
		(width 0.1397)
		(layer "F.Cu")
		(net "PCIE_SAS_CPU_TX_N5")
	)
	(arc
		(start 101.393498 -33.998662)
		(mid 101.528106 -33.797302)
		(end 101.575362 -33.55975)
		(width 0.1397)
		(layer "F.Cu")
		(net "PCIE_SAS_CPU_TX_N5")
	)
	(arc
		(start 133.08203 -14.31417)
		(mid 133.449538 -14.86409)
		(end 133.5786 -15.512796)
		(width 0.1397)
		(layer "F.Cu")
		(net "PCIE_SAS_CPU_TX_N5")
	)
	(arc
		(start 164.1094 -75.12177)
		(mid 164.241769 -75.320013)
		(end 164.288216 -75.553824)
		(width 0.1397)
		(layer "F.Cu")
		(net "PCIE_SAS_CPU_TX_N5")
	)
	(arc
		(start 118.216172 -12.847828)
		(mid 118.422208 -12.710159)
		(end 118.665244 -12.6619)
		(width 0.1397)
		(layer "F.Cu")
		(net "PCIE_SAS_CPU_TX_N5")
	)
	(arc
		(start 110.303818 -20.355052)
		(mid 110.678127 -20.280579)
		(end 110.99546 -20.06854)
		(width 0.1397)
		(layer "F.Cu")
		(net "PCIE_SAS_CPU_TX_N5")
	)
	(arc
		(start 133.5786 -18.99158)
		(mid 133.701375 -19.60881)
		(end 134.05104 -20.13204)
		(width 0.1397)
		(layer "F.Cu")
		(net "PCIE_SAS_CPU_TX_N5")
	)
	(arc
		(start 101.575362 -32.15132)
		(mid 101.602552 -32.015097)
		(end 101.679756 -31.899606)
		(width 0.1397)
		(layer "F.Cu")
		(net "PCIE_SAS_CPU_TX_N5")
	)
	(arc
		(start 162.922204 -49.003204)
		(mid 163.19741 -49.415174)
		(end 163.29406 -49.901094)
		(width 0.1397)
		(layer "F.Cu")
		(net "PCIE_SAS_CPU_TX_N5")
	)
	(arc
		(start 101.929692 -31.64967)
		(mid 102.081173 -31.423008)
		(end 102.134416 -31.15564)
		(width 0.1397)
		(layer "F.Cu")
		(net "PCIE_SAS_CPU_TX_N5")
	)
	(arc
		(start 163.29406 -73.9394)
		(mid 163.361397 -74.278396)
		(end 163.553394 -74.565764)
		(width 0.1397)
		(layer "F.Cu")
		(net "PCIE_SAS_CPU_TX_N5")
	)
	(arc
		(start 164.28847 -76.198984)
		(mid 164.199492 -76.646306)
		(end 163.946078 -77.0255)
		(width 0.1397)
		(layer "F.Cu")
		(net "PCIE_SAS_CPU_TX_N5")
	)
	(arc
		(start 102.134416 -27.048206)
		(mid 102.231055 -26.562281)
		(end 102.506272 -26.150316)
		(width 0.1397)
		(layer "F.Cu")
		(net "PCIE_SAS_CPU_TX_N5")
	)
	(arc
		(start 108.115354 -20.541234)
		(mid 108.321376 -20.403511)
		(end 108.564426 -20.355052)
		(width 0.1397)
		(layer "F.Cu")
		(net "PCIE_SAS_CPU_TX_N5")
	)
	(segment
		(start 164.449506 -80.25003)
		(end 164.810948 -79.528416)
		(width 0.1397)
		(layer "B.Cu")
		(net "PCIE_SAS_CPU_TX_N5")
	)
	(segment
		(start 164.747448 -79.340202)
		(end 164.5793 -79.256128)
		(width 0.1397)
		(layer "B.Cu")
		(net "PCIE_SAS_CPU_TX_N5")
	)
	(segment
		(start 164.188394 -77.267562)
		(end 163.946078 -77.0255)
		(width 0.1397)
		(layer "B.Cu")
		(net "PCIE_SAS_CPU_TX_N5")
	)
	(segment
		(start 164.26053 -78.553564)
		(end 164.26053 -77.44206)
		(width 0.1397)
		(layer "B.Cu")
		(net "PCIE_SAS_CPU_TX_N5")
	)
	(segment
		(start 164.748464 -79.340964)
		(end 164.747956 -79.34071)
		(width 0.1397)
		(layer "B.Cu")
		(net "PCIE_SAS_CPU_TX_N5")
	)
	(segment
		(start 164.748718 -79.340964)
		(end 164.748464 -79.340964)
		(width 0.1397)
		(layer "B.Cu")
		(net "PCIE_SAS_CPU_TX_N5")
	)
	(segment
		(start 164.747956 -79.34071)
		(end 164.747956 -79.340964)
		(width 0.1397)
		(layer "B.Cu")
		(net "PCIE_SAS_CPU_TX_N5")
	)
	(arc
		(start 164.5793 -79.256128)
		(mid 164.344011 -78.939287)
		(end 164.26053 -78.553564)
		(width 0.1397)
		(layer "B.Cu")
		(net "PCIE_SAS_CPU_TX_N5")
	)
	(arc
		(start 164.810948 -79.528416)
		(mid 164.818564 -79.421857)
		(end 164.748718 -79.340964)
		(width 0.1397)
		(layer "B.Cu")
		(net "PCIE_SAS_CPU_TX_N5")
	)
	(arc
		(start 164.747956 -79.340964)
		(mid 164.747702 -79.340583)
		(end 164.747448 -79.340202)
		(width 0.1397)
		(layer "B.Cu")
		(net "PCIE_SAS_CPU_TX_N5")
	)
	(arc
		(start 164.26053 -77.44206)
		(mid 164.241839 -77.347624)
		(end 164.188394 -77.267562)
		(width 0.1397)
		(layer "B.Cu")
		(net "PCIE_SAS_CPU_TX_N5")
	)
	(segment
		(start 318.449452 -59.69)
		(end 317.121794 -59.69)
		(width 0.1143)
		(layer "F.Cu")
		(net "PMU_PLTRST_N_10G")
	)
	(segment
		(start 317.121794 -59.69)
		(end 316.52591 -60.285884)
		(width 0.1143)
		(layer "F.Cu")
		(net "PMU_PLTRST_N_10G")
	)
	(segment
		(start 314.59297 -61.20003)
		(end 315.256926 -60.536074)
		(width 0.1143)
		(layer "F.Cu")
		(net "PMU_PLTRST_N_10G")
	)
	(segment
		(start 316.479428 -60.285884)
		(end 316.229238 -60.536074)
		(width 0.1143)
		(layer "F.Cu")
		(net "PMU_PLTRST_N_10G")
	)
	(segment
		(start 316.52591 -60.285884)
		(end 316.479428 -60.285884)
		(width 0.1143)
		(layer "F.Cu")
		(net "PMU_PLTRST_N_10G")
	)
	(segment
		(start 313.125104 -61.20003)
		(end 314.59297 -61.20003)
		(width 0.1143)
		(layer "F.Cu")
		(net "PMU_PLTRST_N_10G")
	)
	(segment
		(start 315.256926 -60.536074)
		(end 316.229238 -60.536074)
		(width 0.1143)
		(layer "F.Cu")
		(net "PMU_PLTRST_N_10G")
	)
	(via
		(at 316.229238 -60.536074)
		(size 0.7112)
		(drill 0.3556)
		(layers "F.Cu" "B.Cu")
		(net "PMU_PLTRST_N_10G")
	)
	(segment
		(start 120.000522 -256.50444)
		(end 120.000522 -254.421386)
		(width 0.1016)
		(layer "B.Cu")
		(net "SAS_GF_EXP_RX_DP7")
	)
	(segment
		(start 118.624858 -222.4405)
		(end 118.688612 -222.4405)
		(width 0.1016)
		(layer "B.Cu")
		(net "SAS_GF_EXP_RX_DP7")
	)
	(segment
		(start 118.070884 -222.931736)
		(end 118.143782 -222.75546)
		(width 0.1016)
		(layer "B.Cu")
		(net "SAS_GF_EXP_RX_DP7")
	)
	(segment
		(start 118.028212 -225.6536)
		(end 118.028212 -223.146366)
		(width 0.1016)
		(layer "B.Cu")
		(net "SAS_GF_EXP_RX_DP7")
	)
	(segment
		(start 119.679212 -253.645924)
		(end 119.679212 -228.603302)
		(width 0.1016)
		(layer "B.Cu")
		(net "SAS_GF_EXP_RX_DP7")
	)
	(segment
		(start 118.356126 -222.543624)
		(end 118.58625 -222.44812)
		(width 0.1016)
		(layer "B.Cu")
		(net "SAS_GF_EXP_RX_DP7")
	)
	(segment
		(start 119.120412 -227.2538)
		(end 118.387368 -226.520756)
		(width 0.1016)
		(layer "B.Cu")
		(net "SAS_GF_EXP_RX_DP7")
	)
	(arc
		(start 118.228872 -222.62846)
		(mid 118.288317 -222.579768)
		(end 118.356126 -222.543624)
		(width 0.1016)
		(layer "B.Cu")
		(net "SAS_GF_EXP_RX_DP7")
	)
	(arc
		(start 118.58625 -222.44812)
		(mid 118.605178 -222.442394)
		(end 118.624858 -222.4405)
		(width 0.1016)
		(layer "B.Cu")
		(net "SAS_GF_EXP_RX_DP7")
	)
	(arc
		(start 120.000522 -254.421386)
		(mid 119.958729 -254.211459)
		(end 119.83974 -254.033528)
		(width 0.1016)
		(layer "B.Cu")
		(net "SAS_GF_EXP_RX_DP7")
	)
	(arc
		(start 119.83974 -254.033528)
		(mid 119.720915 -253.855694)
		(end 119.679212 -253.645924)
		(width 0.1016)
		(layer "B.Cu")
		(net "SAS_GF_EXP_RX_DP7")
	)
	(arc
		(start 118.143782 -222.75546)
		(mid 118.180074 -222.68777)
		(end 118.228872 -222.62846)
		(width 0.1016)
		(layer "B.Cu")
		(net "SAS_GF_EXP_RX_DP7")
	)
	(arc
		(start 119.679212 -228.603302)
		(mid 119.534034 -227.872973)
		(end 119.120412 -227.2538)
		(width 0.1016)
		(layer "B.Cu")
		(net "SAS_GF_EXP_RX_DP7")
	)
	(arc
		(start 118.387368 -226.520756)
		(mid 118.12153 -226.122901)
		(end 118.028212 -225.6536)
		(width 0.1016)
		(layer "B.Cu")
		(net "SAS_GF_EXP_RX_DP7")
	)
	(arc
		(start 118.028212 -223.146366)
		(mid 118.038984 -223.036951)
		(end 118.070884 -222.931736)
		(width 0.1016)
		(layer "B.Cu")
		(net "SAS_GF_EXP_RX_DP7")
	)
	(segment
		(start 261.366 -32.639)
		(end 260.35 -31.623)
		(width 0.508)
		(layer "F.Cu")
		(net "P5V_STBY")
	)
	(segment
		(start 50.9905 -107.2515)
		(end 50.8 -107.061)
		(width 0.508)
		(layer "F.Cu")
		(net "P5V_STBY")
	)
	(segment
		(start 54.991 -109.5375)
		(end 54.991 -107.061)
		(width 0.508)
		(layer "F.Cu")
		(net "P5V_STBY")
	)
	(segment
		(start 261.5565 -32.639)
		(end 261.366 -32.639)
		(width 0.508)
		(layer "F.Cu")
		(net "P5V_STBY")
	)
	(segment
		(start 309.1815 -111.8235)
		(end 308.991 -111.633)
		(width 0.508)
		(layer "F.Cu")
		(net "P5V_STBY")
	)
	(segment
		(start 50.9905 -109.601)
		(end 50.9905 -107.2515)
		(width 0.508)
		(layer "F.Cu")
		(net "P5V_STBY")
	)
	(segment
		(start 310.388 -111.8235)
		(end 309.1815 -111.8235)
		(width 0.508)
		(layer "F.Cu")
		(net "P5V_STBY")
	)
	(segment
		(start 149.305772 -141.270228)
		(end 152.654 -137.922)
		(width 1.016)
		(layer "F.Cu")
		(net "P5V_STBY")
	)
	(segment
		(start 131.191 -141.224)
		(end 131.237228 -141.270228)
		(width 1.016)
		(layer "F.Cu")
		(net "P5V_STBY")
	)
	(segment
		(start 191.316356 -120.913652)
		(end 191.964056 -120.913652)
		(width 0.508)
		(layer "F.Cu")
		(net "P5V_STBY")
	)
	(segment
		(start 347.2815 -90.551)
		(end 346.837 -90.551)
		(width 0.127)
		(layer "F.Cu")
		(net "P5V_STBY")
	)
	(segment
		(start 259.207 -31.623)
		(end 260.35 -31.623)
		(width 0.508)
		(layer "F.Cu")
		(net "P5V_STBY")
	)
	(segment
		(start 131.237228 -141.270228)
		(end 149.305772 -141.270228)
		(width 1.016)
		(layer "F.Cu")
		(net "P5V_STBY")
	)
	(segment
		(start 191.964056 -120.913652)
		(end 192.481708 -120.396)
		(width 0.508)
		(layer "F.Cu")
		(net "P5V_STBY")
	)
	(via
		(at 315.1378 -43.4848)
		(size 0.7112)
		(drill 0.4064)
		(layers "F.Cu" "B.Cu")
		(net "P5V_STBY")
	)
	(via
		(at 308.991 -111.633)
		(size 0.5588)
		(drill 0.3048)
		(layers "F.Cu" "B.Cu")
		(net "P5V_STBY")
	)
	(via
		(at 315.1124 -42.418)
		(size 0.7112)
		(drill 0.4064)
		(layers "F.Cu" "B.Cu")
		(net "P5V_STBY")
	)
	(via
		(at 343.916 -88.011)
		(size 0.7112)
		(drill 0.4064)
		(layers "F.Cu" "B.Cu")
		(net "P5V_STBY")
	)
	(via
		(at 315.1378 -46.736)
		(size 0.7112)
		(drill 0.4064)
		(layers "F.Cu" "B.Cu")
		(net "P5V_STBY")
	)
	(via
		(at 259.207 -31.623)
		(size 0.5588)
		(drill 0.3048)
		(layers "F.Cu" "B.Cu")
		(net "P5V_STBY")
	)
	(via
		(at 257.429 -21.336)
		(size 0.7112)
		(drill 0.4064)
		(layers "F.Cu" "B.Cu")
		(net "P5V_STBY")
	)
	(via
		(at 308.864 -99.06)
		(size 0.5588)
		(drill 0.3048)
		(layers "F.Cu" "B.Cu")
		(net "P5V_STBY")
	)
	(via
		(at 260.35 -31.623)
		(size 0.7112)
		(drill 0.3556)
		(layers "F.Cu" "B.Cu")
		(net "P5V_STBY")
	)
	(via
		(at 192.481708 -120.396)
		(size 0.7112)
		(drill 0.4064)
		(layers "F.Cu" "B.Cu")
		(net "P5V_STBY")
	)
	(via
		(at 250.063 -99.695)
		(size 0.7112)
		(drill 0.4064)
		(layers "F.Cu" "B.Cu")
		(net "P5V_STBY")
	)
	(via
		(at 253.492 -20.32)
		(size 0.7112)
		(drill 0.3556)
		(layers "F.Cu" "B.Cu")
		(net "P5V_STBY")
	)
	(via
		(at 315.1632 -45.6692)
		(size 0.7112)
		(drill 0.4064)
		(layers "F.Cu" "B.Cu")
		(net "P5V_STBY")
	)
	(via
		(at 228.473 -23.495)
		(size 0.7112)
		(drill 0.4064)
		(layers "F.Cu" "B.Cu")
		(net "P5V_STBY")
	)
	(via
		(at 131.191 -141.224)
		(size 0.7112)
		(drill 0.4064)
		(layers "F.Cu" "B.Cu")
		(net "P5V_STBY")
	)
	(via
		(at 345.059 -88.011)
		(size 0.7112)
		(drill 0.4064)
		(layers "F.Cu" "B.Cu")
		(net "P5V_STBY")
	)
	(via
		(at 250.19 -98.552)
		(size 0.7112)
		(drill 0.4064)
		(layers "F.Cu" "B.Cu")
		(net "P5V_STBY")
	)
	(via
		(at 255.143 -21.336)
		(size 0.7112)
		(drill 0.4064)
		(layers "F.Cu" "B.Cu")
		(net "P5V_STBY")
	)
	(via
		(at 152.654 -137.922)
		(size 0.7112)
		(drill 0.4064)
		(layers "F.Cu" "B.Cu")
		(net "P5V_STBY")
	)
	(via
		(at 315.1378 -44.577)
		(size 0.7112)
		(drill 0.4064)
		(layers "F.Cu" "B.Cu")
		(net "P5V_STBY")
	)
	(via
		(at 315.976 -50.927)
		(size 0.7112)
		(drill 0.3556)
		(layers "F.Cu" "B.Cu")
		(net "P5V_STBY")
	)
	(via
		(at 334.772 -176.911)
		(size 0.508)
		(drill 0.254)
		(layers "F.Cu" "B.Cu")
		(net "P5V_STBY")
	)
	(via
		(at 249.174 -98.171)
		(size 0.7112)
		(drill 0.4064)
		(layers "F.Cu" "B.Cu")
		(net "P5V_STBY")
	)
	(via
		(at 345.059 -89.154)
		(size 0.7112)
		(drill 0.4064)
		(layers "F.Cu" "B.Cu")
		(net "P5V_STBY")
	)
	(via
		(at 317.3222 -42.164)
		(size 0.7112)
		(drill 0.4064)
		(layers "F.Cu" "B.Cu")
		(net "P5V_STBY")
	)
	(via
		(at 343.916 -89.154)
		(size 0.7112)
		(drill 0.4064)
		(layers "F.Cu" "B.Cu")
		(net "P5V_STBY")
	)
	(via
		(at 227.33 -24.384)
		(size 0.7112)
		(drill 0.4064)
		(layers "F.Cu" "B.Cu")
		(net "P5V_STBY")
	)
	(via
		(at 343.662 -99.06)
		(size 0.5588)
		(drill 0.3048)
		(layers "F.Cu" "B.Cu")
		(net "P5V_STBY")
	)
	(via
		(at 45.212 -149.86)
		(size 0.7112)
		(drill 0.4064)
		(layers "F.Cu" "B.Cu")
		(net "P5V_STBY")
	)
	(via
		(at 256.286 -21.336)
		(size 0.7112)
		(drill 0.4064)
		(layers "F.Cu" "B.Cu")
		(net "P5V_STBY")
	)
	(via
		(at 249.047 -99.314)
		(size 0.7112)
		(drill 0.4064)
		(layers "F.Cu" "B.Cu")
		(net "P5V_STBY")
	)
	(segment
		(start 339.985604 -4.509516)
		(end 339.985604 -5.500624)
		(width 0.508)
		(layer "B.Cu")
		(net "P5V_STBY")
	)
	(segment
		(start 43.688 -125.984)
		(end 43.688 -132.842)
		(width 1.016)
		(layer "B.Cu")
		(net "P5V_STBY")
	)
	(segment
		(start 43.18 -144.907)
		(end 45.212 -146.939)
		(width 1.016)
		(layer "B.Cu")
		(net "P5V_STBY")
	)
	(segment
		(start 43.18 -138.176)
		(end 43.18 -144.907)
		(width 1.016)
		(layer "B.Cu")
		(net "P5V_STBY")
	)
	(segment
		(start 50.8 -118.872)
		(end 43.688 -125.984)
		(width 1.016)
		(layer "B.Cu")
		(net "P5V_STBY")
	)
	(segment
		(start 334.3275 -177.3555)
		(end 334.772 -176.911)
		(width 0.508)
		(layer "B.Cu")
		(net "P5V_STBY")
	)
	(segment
		(start 45.212 -146.939)
		(end 45.212 -149.86)
		(width 1.016)
		(layer "B.Cu")
		(net "P5V_STBY")
	)
	(segment
		(start 54.991 -107.061)
		(end 50.8 -107.061)
		(width 1.016)
		(layer "B.Cu")
		(net "P5V_STBY")
	)
	(segment
		(start 43.688 -132.842)
		(end 42.326306 -134.203694)
		(width 1.016)
		(layer "B.Cu")
		(net "P5V_STBY")
	)
	(segment
		(start 338.994496 -5.500624)
		(end 339.985604 -5.500624)
		(width 0.508)
		(layer "B.Cu")
		(net "P5V_STBY")
	)
	(segment
		(start 42.326306 -137.322306)
		(end 43.18 -138.176)
		(width 1.016)
		(layer "B.Cu")
		(net "P5V_STBY")
	)
	(segment
		(start 325.374 -177.3555)
		(end 334.3275 -177.3555)
		(width 0.508)
		(layer "B.Cu")
		(net "P5V_STBY")
	)
	(segment
		(start 341.757 -100.203)
		(end 342.519 -100.203)
		(width 0.508)
		(layer "B.Cu")
		(net "P5V_STBY")
	)
	(segment
		(start 42.326306 -134.203694)
		(end 42.326306 -137.322306)
		(width 1.016)
		(layer "B.Cu")
		(net "P5V_STBY")
	)
	(segment
		(start 342.519 -100.203)
		(end 343.662 -99.06)
		(width 0.508)
		(layer "B.Cu")
		(net "P5V_STBY")
	)
	(segment
		(start 50.8 -107.061)
		(end 50.8 -118.872)
		(width 1.016)
		(layer "B.Cu")
		(net "P5V_STBY")
	)
	(segment
		(start 335.1149 -138.895074)
		(end 335.1149 -145.973292)
		(width 0.508)
		(layer "In2.Cu")
		(net "P5V_STBY")
	)
	(segment
		(start 339.195918 -153.770838)
		(end 335.026 -157.940756)
		(width 0.508)
		(layer "In2.Cu")
		(net "P5V_STBY")
	)
	(segment
		(start 174.752 -137.922)
		(end 192.278 -120.396)
		(width 1.016)
		(layer "In2.Cu")
		(net "P5V_STBY")
	)
	(segment
		(start 335.1149 -145.973292)
		(end 339.195918 -150.05431)
		(width 0.508)
		(layer "In2.Cu")
		(net "P5V_STBY")
	)
	(segment
		(start 329.6158 -123.0376)
		(end 329.6158 -133.395974)
		(width 0.508)
		(layer "In2.Cu")
		(net "P5V_STBY")
	)
	(segment
		(start 329.6158 -133.395974)
		(end 335.1149 -138.895074)
		(width 0.508)
		(layer "In2.Cu")
		(net "P5V_STBY")
	)
	(segment
		(start 327.279 -118.237)
		(end 327.279 -120.7008)
		(width 0.508)
		(layer "In2.Cu")
		(net "P5V_STBY")
	)
	(segment
		(start 335.026 -176.657)
		(end 334.772 -176.911)
		(width 0.508)
		(layer "In2.Cu")
		(net "P5V_STBY")
	)
	(segment
		(start 332.994 -88.9)
		(end 326.263 -95.631)
		(width 0.508)
		(layer "In2.Cu")
		(net "P5V_STBY")
	)
	(segment
		(start 326.263 -95.631)
		(end 326.263 -117.221)
		(width 0.508)
		(layer "In2.Cu")
		(net "P5V_STBY")
	)
	(segment
		(start 339.195918 -150.05431)
		(end 339.195918 -153.770838)
		(width 0.508)
		(layer "In2.Cu")
		(net "P5V_STBY")
	)
	(segment
		(start 327.279 -120.7008)
		(end 329.6158 -123.0376)
		(width 0.508)
		(layer "In2.Cu")
		(net "P5V_STBY")
	)
	(segment
		(start 192.278 -120.396)
		(end 192.481708 -120.396)
		(width 1.016)
		(layer "In2.Cu")
		(net "P5V_STBY")
	)
	(segment
		(start 326.263 -117.221)
		(end 327.279 -118.237)
		(width 0.508)
		(layer "In2.Cu")
		(net "P5V_STBY")
	)
	(segment
		(start 335.026 -157.940756)
		(end 335.026 -176.657)
		(width 0.508)
		(layer "In2.Cu")
		(net "P5V_STBY")
	)
	(segment
		(start 152.654 -137.922)
		(end 174.752 -137.922)
		(width 1.016)
		(layer "In2.Cu")
		(net "P5V_STBY")
	)
	(segment
		(start 308.864 -99.822)
		(end 308.61 -100.076)
		(width 0.508)
		(layer "In5.Cu")
		(net "P5V_STBY")
	)
	(segment
		(start 308.864 -99.06)
		(end 308.864 -99.822)
		(width 0.508)
		(layer "In5.Cu")
		(net "P5V_STBY")
	)
	(segment
		(start 308.61 -100.076)
		(end 308.61 -107.061)
		(width 0.508)
		(layer "In5.Cu")
		(net "P5V_STBY")
	)
	(segment
		(start 45.847 -150.495)
		(end 121.92 -150.495)
		(width 1.016)
		(layer "In5.Cu")
		(net "P5V_STBY")
	)
	(segment
		(start 121.92 -150.495)
		(end 131.191 -141.224)
		(width 1.016)
		(layer "In5.Cu")
		(net "P5V_STBY")
	)
	(segment
		(start 309.245 -107.696)
		(end 309.245 -111.252)
		(width 0.508)
		(layer "In5.Cu")
		(net "P5V_STBY")
	)
	(segment
		(start 45.212 -149.86)
		(end 45.847 -150.495)
		(width 1.016)
		(layer "In5.Cu")
		(net "P5V_STBY")
	)
	(segment
		(start 308.991 -111.506)
		(end 308.991 -111.633)
		(width 0.508)
		(layer "In5.Cu")
		(net "P5V_STBY")
	)
	(segment
		(start 308.61 -107.061)
		(end 309.245 -107.696)
		(width 0.508)
		(layer "In5.Cu")
		(net "P5V_STBY")
	)
	(segment
		(start 309.245 -111.252)
		(end 308.991 -111.506)
		(width 0.508)
		(layer "In5.Cu")
		(net "P5V_STBY")
	)
	(segment
		(start 266.37615 -119.71655)
		(end 267.3731 -120.7135)
		(width 0.1143)
		(layer "F.Cu")
		(net "RMII_BMC_TX_EN")
	)
	(segment
		(start 198.247 -33.274)
		(end 194.564 -33.274)
		(width 0.1143)
		(layer "F.Cu")
		(net "RMII_BMC_TX_EN")
	)
	(segment
		(start 198.882 -33.909)
		(end 198.247 -33.274)
		(width 0.1143)
		(layer "F.Cu")
		(net "RMII_BMC_TX_EN")
	)
	(segment
		(start 187.833762 -31.137098)
		(end 188.480192 -31.783528)
		(width 0.1143)
		(layer "F.Cu")
		(net "RMII_BMC_TX_EN")
	)
	(segment
		(start 260.2484 -92.566744)
		(end 260.2484 -94.045278)
		(width 0.1143)
		(layer "F.Cu")
		(net "RMII_BMC_TX_EN")
	)
	(segment
		(start 284.988 -149.83841)
		(end 285.077662 -149.928072)
		(width 0.1143)
		(layer "F.Cu")
		(net "RMII_BMC_TX_EN")
	)
	(segment
		(start 293.497 -160.416494)
		(end 293.331138 -160.250632)
		(width 0.1143)
		(layer "F.Cu")
		(net "RMII_BMC_TX_EN")
	)
	(segment
		(start 201.590656 -33.909)
		(end 260.2484 -92.566744)
		(width 0.1143)
		(layer "F.Cu")
		(net "RMII_BMC_TX_EN")
	)
	(segment
		(start 266.37615 -100.173028)
		(end 266.37615 -119.71655)
		(width 0.1143)
		(layer "F.Cu")
		(net "RMII_BMC_TX_EN")
	)
	(segment
		(start 280.54935 -144.0942)
		(end 284.988 -148.53285)
		(width 0.1143)
		(layer "F.Cu")
		(net "RMII_BMC_TX_EN")
	)
	(segment
		(start 260.2484 -94.045278)
		(end 266.37615 -100.173028)
		(width 0.1143)
		(layer "F.Cu")
		(net "RMII_BMC_TX_EN")
	)
	(segment
		(start 193.6115 -33.909)
		(end 193.7385 -34.036)
		(width 0.1143)
		(layer "F.Cu")
		(net "RMII_BMC_TX_EN")
	)
	(segment
		(start 187.81522 -31.137098)
		(end 187.833762 -31.137098)
		(width 0.1143)
		(layer "F.Cu")
		(net "RMII_BMC_TX_EN")
	)
	(segment
		(start 194.564 -33.274)
		(end 193.802 -34.036)
		(width 0.1143)
		(layer "F.Cu")
		(net "RMII_BMC_TX_EN")
	)
	(segment
		(start 193.802 -34.036)
		(end 193.7385 -34.036)
		(width 0.1143)
		(layer "F.Cu")
		(net "RMII_BMC_TX_EN")
	)
	(segment
		(start 267.3731 -120.7135)
		(end 267.3731 -135.22325)
		(width 0.1143)
		(layer "F.Cu")
		(net "RMII_BMC_TX_EN")
	)
	(segment
		(start 293.497 -161.0995)
		(end 293.497 -160.416494)
		(width 0.1143)
		(layer "F.Cu")
		(net "RMII_BMC_TX_EN")
	)
	(segment
		(start 267.3731 -135.22325)
		(end 276.24405 -144.0942)
		(width 0.1143)
		(layer "F.Cu")
		(net "RMII_BMC_TX_EN")
	)
	(segment
		(start 198.882 -33.909)
		(end 201.590656 -33.909)
		(width 0.1143)
		(layer "F.Cu")
		(net "RMII_BMC_TX_EN")
	)
	(segment
		(start 276.24405 -144.0942)
		(end 280.54935 -144.0942)
		(width 0.1143)
		(layer "F.Cu")
		(net "RMII_BMC_TX_EN")
	)
	(segment
		(start 187.734194 -31.056072)
		(end 187.81522 -31.137098)
		(width 0.1143)
		(layer "F.Cu")
		(net "RMII_BMC_TX_EN")
	)
	(segment
		(start 188.480192 -32.694118)
		(end 189.695074 -33.909)
		(width 0.1143)
		(layer "F.Cu")
		(net "RMII_BMC_TX_EN")
	)
	(segment
		(start 189.695074 -33.909)
		(end 193.6115 -33.909)
		(width 0.1143)
		(layer "F.Cu")
		(net "RMII_BMC_TX_EN")
	)
	(segment
		(start 188.480192 -31.783528)
		(end 188.480192 -32.694118)
		(width 0.1143)
		(layer "F.Cu")
		(net "RMII_BMC_TX_EN")
	)
	(segment
		(start 284.988 -148.53285)
		(end 284.988 -149.83841)
		(width 0.1143)
		(layer "F.Cu")
		(net "RMII_BMC_TX_EN")
	)
	(segment
		(start 186.744864 -31.056072)
		(end 187.734194 -31.056072)
		(width 0.1143)
		(layer "F.Cu")
		(net "RMII_BMC_TX_EN")
	)
	(via
		(at 285.077662 -149.928072)
		(size 0.5588)
		(drill 0.3048)
		(layers "F.Cu" "B.Cu")
		(net "RMII_BMC_TX_EN")
	)
	(via
		(at 198.882 -33.909)
		(size 0.7112)
		(drill 0.3556)
		(layers "F.Cu" "B.Cu")
		(net "RMII_BMC_TX_EN")
	)
	(via
		(at 293.331138 -160.250632)
		(size 0.5588)
		(drill 0.3048)
		(layers "F.Cu" "B.Cu")
		(net "RMII_BMC_TX_EN")
	)
	(segment
		(start 286.2453 -153.164794)
		(end 286.2453 -152.969468)
		(width 0.127)
		(layer "In2.Cu")
		(net "RMII_BMC_TX_EN")
	)
	(segment
		(start 286.2453 -152.969468)
		(end 285.077662 -151.80183)
		(width 0.127)
		(layer "In2.Cu")
		(net "RMII_BMC_TX_EN")
	)
	(segment
		(start 293.331138 -160.250632)
		(end 286.2453 -153.164794)
		(width 0.127)
		(layer "In2.Cu")
		(net "RMII_BMC_TX_EN")
	)
	(segment
		(start 285.077662 -151.80183)
		(end 285.077662 -149.928072)
		(width 0.127)
		(layer "In2.Cu")
		(net "RMII_BMC_TX_EN")
	)
	(segment
		(start 193.7385 -35.179)
		(end 192.975992 -35.179)
		(width 0.1143)
		(layer "F.Cu")
		(net "RMII_BMC_PHY_TXD0")
	)
	(segment
		(start 276.070314 -144.5133)
		(end 280.375614 -144.5133)
		(width 0.1143)
		(layer "F.Cu")
		(net "RMII_BMC_PHY_TXD0")
	)
	(segment
		(start 194.4751 -35.9156)
		(end 203.00442 -35.9156)
		(width 0.1143)
		(layer "F.Cu")
		(net "RMII_BMC_PHY_TXD0")
	)
	(segment
		(start 188.061092 -31.957264)
		(end 188.061092 -32.867854)
		(width 0.1143)
		(layer "F.Cu")
		(net "RMII_BMC_PHY_TXD0")
	)
	(segment
		(start 265.95705 -100.346764)
		(end 265.95705 -119.92483)
		(width 0.1143)
		(layer "F.Cu")
		(net "RMII_BMC_PHY_TXD0")
	)
	(segment
		(start 266.954 -135.396986)
		(end 276.070314 -144.5133)
		(width 0.1143)
		(layer "F.Cu")
		(net "RMII_BMC_PHY_TXD0")
	)
	(segment
		(start 266.954 -120.92178)
		(end 266.954 -135.396986)
		(width 0.1143)
		(layer "F.Cu")
		(net "RMII_BMC_PHY_TXD0")
	)
	(segment
		(start 189.895988 -34.70275)
		(end 192.499742 -34.70275)
		(width 0.1143)
		(layer "F.Cu")
		(net "RMII_BMC_PHY_TXD0")
	)
	(segment
		(start 283.819346 -148.844)
		(end 284.349698 -149.374352)
		(width 0.1143)
		(layer "F.Cu")
		(net "RMII_BMC_PHY_TXD0")
	)
	(segment
		(start 294.513 -160.28035)
		(end 294.40505 -160.1724)
		(width 0.1143)
		(layer "F.Cu")
		(net "RMII_BMC_PHY_TXD0")
	)
	(segment
		(start 192.975992 -35.179)
		(end 192.721992 -34.925)
		(width 0.1143)
		(layer "F.Cu")
		(net "RMII_BMC_PHY_TXD0")
	)
	(segment
		(start 192.499742 -34.70275)
		(end 192.721992 -34.925)
		(width 0.1143)
		(layer "F.Cu")
		(net "RMII_BMC_PHY_TXD0")
	)
	(segment
		(start 203.00442 -35.9156)
		(end 259.8293 -92.74048)
		(width 0.1143)
		(layer "F.Cu")
		(net "RMII_BMC_PHY_TXD0")
	)
	(segment
		(start 186.744864 -31.556198)
		(end 187.660026 -31.556198)
		(width 0.1143)
		(layer "F.Cu")
		(net "RMII_BMC_PHY_TXD0")
	)
	(segment
		(start 294.513 -161.0995)
		(end 294.513 -160.28035)
		(width 0.1143)
		(layer "F.Cu")
		(net "RMII_BMC_PHY_TXD0")
	)
	(segment
		(start 280.375614 -144.5133)
		(end 283.819346 -147.957032)
		(width 0.1143)
		(layer "F.Cu")
		(net "RMII_BMC_PHY_TXD0")
	)
	(segment
		(start 187.660026 -31.556198)
		(end 188.061092 -31.957264)
		(width 0.1143)
		(layer "F.Cu")
		(net "RMII_BMC_PHY_TXD0")
	)
	(segment
		(start 259.8293 -94.219014)
		(end 265.95705 -100.346764)
		(width 0.1143)
		(layer "F.Cu")
		(net "RMII_BMC_PHY_TXD0")
	)
	(segment
		(start 188.061092 -32.867854)
		(end 189.895988 -34.70275)
		(width 0.1143)
		(layer "F.Cu")
		(net "RMII_BMC_PHY_TXD0")
	)
	(segment
		(start 283.819346 -147.957032)
		(end 283.819346 -148.844)
		(width 0.1143)
		(layer "F.Cu")
		(net "RMII_BMC_PHY_TXD0")
	)
	(segment
		(start 259.8293 -92.74048)
		(end 259.8293 -94.219014)
		(width 0.1143)
		(layer "F.Cu")
		(net "RMII_BMC_PHY_TXD0")
	)
	(segment
		(start 265.95705 -119.92483)
		(end 266.954 -120.92178)
		(width 0.1143)
		(layer "F.Cu")
		(net "RMII_BMC_PHY_TXD0")
	)
	(segment
		(start 193.7385 -35.179)
		(end 194.4751 -35.9156)
		(width 0.1143)
		(layer "F.Cu")
		(net "RMII_BMC_PHY_TXD0")
	)
	(via
		(at 192.721992 -34.925)
		(size 0.7112)
		(drill 0.3556)
		(layers "F.Cu" "B.Cu")
		(net "RMII_BMC_PHY_TXD0")
	)
	(via
		(at 284.349698 -149.374352)
		(size 0.5588)
		(drill 0.3048)
		(layers "F.Cu" "B.Cu")
		(net "RMII_BMC_PHY_TXD0")
	)
	(via
		(at 294.40505 -160.1724)
		(size 0.5588)
		(drill 0.3048)
		(layers "F.Cu" "B.Cu")
		(net "RMII_BMC_PHY_TXD0")
	)
	(segment
		(start 285.877 -150.026878)
		(end 285.224474 -149.374352)
		(width 0.127)
		(layer "In2.Cu")
		(net "RMII_BMC_PHY_TXD0")
	)
	(segment
		(start 285.877 -150.872698)
		(end 285.877 -150.026878)
		(width 0.127)
		(layer "In2.Cu")
		(net "RMII_BMC_PHY_TXD0")
	)
	(segment
		(start 294.40505 -159.400748)
		(end 285.877 -150.872698)
		(width 0.127)
		(layer "In2.Cu")
		(net "RMII_BMC_PHY_TXD0")
	)
	(segment
		(start 294.40505 -160.1724)
		(end 294.40505 -159.400748)
		(width 0.127)
		(layer "In2.Cu")
		(net "RMII_BMC_PHY_TXD0")
	)
	(segment
		(start 285.224474 -149.374352)
		(end 284.349698 -149.374352)
		(width 0.127)
		(layer "In2.Cu")
		(net "RMII_BMC_PHY_TXD0")
	)
	(segment
		(start 88.4555 -226.06)
		(end 84.520532 -226.06)
		(width 0.127)
		(layer "F.Cu")
		(net "I2C_IO_EXP_RESET#")
	)
	(segment
		(start 26.67 -211.963)
		(end 30.48 -215.773)
		(width 0.127)
		(layer "F.Cu")
		(net "I2C_IO_EXP_RESET#")
	)
	(segment
		(start 30.48 -215.773)
		(end 30.48 -219.075)
		(width 0.127)
		(layer "F.Cu")
		(net "I2C_IO_EXP_RESET#")
	)
	(segment
		(start 18.9865 -210.6295)
		(end 25.3365 -210.6295)
		(width 0.127)
		(layer "F.Cu")
		(net "I2C_IO_EXP_RESET#")
	)
	(segment
		(start 18.873216 -213.35238)
		(end 18.873216 -210.742784)
		(width 0.127)
		(layer "F.Cu")
		(net "I2C_IO_EXP_RESET#")
	)
	(segment
		(start 22.611588 -195.708016)
		(end 22.611588 -196.113908)
		(width 0.127)
		(layer "F.Cu")
		(net "I2C_IO_EXP_RESET#")
	)
	(segment
		(start 84.520532 -226.06)
		(end 84.360766 -225.900234)
		(width 0.127)
		(layer "F.Cu")
		(net "I2C_IO_EXP_RESET#")
	)
	(segment
		(start 25.3365 -210.6295)
		(end 26.67 -211.963)
		(width 0.127)
		(layer "F.Cu")
		(net "I2C_IO_EXP_RESET#")
	)
	(segment
		(start 18.873216 -210.742784)
		(end 18.9865 -210.6295)
		(width 0.127)
		(layer "F.Cu")
		(net "I2C_IO_EXP_RESET#")
	)
	(segment
		(start 30.48 -219.075)
		(end 32.512 -221.107)
		(width 0.127)
		(layer "F.Cu")
		(net "I2C_IO_EXP_RESET#")
	)
	(segment
		(start 22.611588 -196.113908)
		(end 21.946616 -196.77888)
		(width 0.127)
		(layer "F.Cu")
		(net "I2C_IO_EXP_RESET#")
	)
	(segment
		(start 89.2175 -226.822)
		(end 88.4555 -226.06)
		(width 0.127)
		(layer "F.Cu")
		(net "I2C_IO_EXP_RESET#")
	)
	(via
		(at 81.661 -174.752)
		(size 0.5588)
		(drill 0.3048)
		(layers "F.Cu" "B.Cu")
		(net "I2C_IO_EXP_RESET#")
	)
	(via
		(at 70.231 -225.679)
		(size 0.5588)
		(drill 0.3048)
		(layers "F.Cu" "B.Cu")
		(net "I2C_IO_EXP_RESET#")
	)
	(via
		(at 315.214 -185.5216)
		(size 0.7112)
		(drill 0.3556)
		(layers "F.Cu" "B.Cu")
		(net "I2C_IO_EXP_RESET#")
	)
	(via
		(at 316.070234 -186.214766)
		(size 0.5588)
		(drill 0.3048)
		(layers "F.Cu" "B.Cu")
		(net "I2C_IO_EXP_RESET#")
	)
	(via
		(at 32.512 -221.107)
		(size 0.5588)
		(drill 0.3048)
		(layers "F.Cu" "B.Cu")
		(net "I2C_IO_EXP_RESET#")
	)
	(via
		(at 26.67 -211.963)
		(size 0.5588)
		(drill 0.3048)
		(layers "F.Cu" "B.Cu")
		(net "I2C_IO_EXP_RESET#")
	)
	(via
		(at 84.360766 -225.900234)
		(size 0.5588)
		(drill 0.3048)
		(layers "F.Cu" "B.Cu")
		(net "I2C_IO_EXP_RESET#")
	)
	(via
		(at 21.946616 -196.77888)
		(size 0.5588)
		(drill 0.3048)
		(layers "F.Cu" "B.Cu")
		(net "I2C_IO_EXP_RESET#")
	)
	(segment
		(start 81.661 -208.28)
		(end 81.661 -174.752)
		(width 0.127)
		(layer "B.Cu")
		(net "I2C_IO_EXP_RESET#")
	)
	(segment
		(start 315.42101 -185.72861)
		(end 315.214 -185.5216)
		(width 0.127)
		(layer "B.Cu")
		(net "I2C_IO_EXP_RESET#")
	)
	(segment
		(start 70.231 -225.679)
		(end 69.723 -225.171)
		(width 0.127)
		(layer "B.Cu")
		(net "I2C_IO_EXP_RESET#")
	)
	(segment
		(start 316.070234 -186.214766)
		(end 315.584078 -185.72861)
		(width 0.127)
		(layer "B.Cu")
		(net "I2C_IO_EXP_RESET#")
	)
	(segment
		(start 315.584078 -185.72861)
		(end 315.42101 -185.72861)
		(width 0.127)
		(layer "B.Cu")
		(net "I2C_IO_EXP_RESET#")
	)
	(segment
		(start 312.0136 -185.5216)
		(end 315.214 -185.5216)
		(width 0.127)
		(layer "B.Cu")
		(net "I2C_IO_EXP_RESET#")
	)
	(segment
		(start 69.723 -225.171)
		(end 69.723 -223.585532)
		(width 0.127)
		(layer "B.Cu")
		(net "I2C_IO_EXP_RESET#")
	)
	(segment
		(start 69.7738 -220.1672)
		(end 81.661 -208.28)
		(width 0.127)
		(layer "B.Cu")
		(net "I2C_IO_EXP_RESET#")
	)
	(segment
		(start 311.3405 -184.8485)
		(end 312.0136 -185.5216)
		(width 0.127)
		(layer "B.Cu")
		(net "I2C_IO_EXP_RESET#")
	)
	(segment
		(start 311.3405 -184.658)
		(end 311.3405 -184.8485)
		(width 0.127)
		(layer "B.Cu")
		(net "I2C_IO_EXP_RESET#")
	)
	(segment
		(start 69.723 -223.585532)
		(end 69.7738 -223.534732)
		(width 0.127)
		(layer "B.Cu")
		(net "I2C_IO_EXP_RESET#")
	)
	(segment
		(start 69.7738 -223.534732)
		(end 69.7738 -220.1672)
		(width 0.127)
		(layer "B.Cu")
		(net "I2C_IO_EXP_RESET#")
	)
	(segment
		(start 196.942964 -182.88)
		(end 206.071724 -182.88)
		(width 0.127)
		(layer "In2.Cu")
		(net "I2C_IO_EXP_RESET#")
	)
	(segment
		(start 316.2173 -186.361832)
		(end 316.070234 -186.214766)
		(width 0.127)
		(layer "In2.Cu")
		(net "I2C_IO_EXP_RESET#")
	)
	(segment
		(start 217.26652 -179.959)
		(end 222.91548 -179.959)
		(width 0.127)
		(layer "In2.Cu")
		(net "I2C_IO_EXP_RESET#")
	)
	(segment
		(start 214.15248 -179.959)
		(end 214.64778 -179.4637)
		(width 0.127)
		(layer "In2.Cu")
		(net "I2C_IO_EXP_RESET#")
	)
	(segment
		(start 263.887712 -192.397126)
		(end 263.887712 -198.904352)
		(width 0.127)
		(layer "In2.Cu")
		(net "I2C_IO_EXP_RESET#")
	)
	(segment
		(start 83.119468 -226.441)
		(end 70.993 -226.441)
		(width 0.127)
		(layer "In2.Cu")
		(net "I2C_IO_EXP_RESET#")
	)
	(segment
		(start 276.092412 -208.2546)
		(end 276.093936 -208.253076)
		(width 0.127)
		(layer "In2.Cu")
		(net "I2C_IO_EXP_RESET#")
	)
	(segment
		(start 223.41078 -179.4637)
		(end 224.13722 -179.4637)
		(width 0.127)
		(layer "In2.Cu")
		(net "I2C_IO_EXP_RESET#")
	)
	(segment
		(start 298.2849 -208.6229)
		(end 298.6405 -208.9785)
		(width 0.127)
		(layer "In2.Cu")
		(net "I2C_IO_EXP_RESET#")
	)
	(segment
		(start 196.434964 -182.372)
		(end 196.942964 -182.88)
		(width 0.127)
		(layer "In2.Cu")
		(net "I2C_IO_EXP_RESET#")
	)
	(segment
		(start 288.7218 -208.8261)
		(end 288.925 -208.6229)
		(width 0.127)
		(layer "In2.Cu")
		(net "I2C_IO_EXP_RESET#")
	)
	(segment
		(start 70.993 -226.441)
		(end 70.231 -225.679)
		(width 0.127)
		(layer "In2.Cu")
		(net "I2C_IO_EXP_RESET#")
	)
	(segment
		(start 298.6405 -208.9785)
		(end 301.500032 -208.9785)
		(width 0.127)
		(layer "In2.Cu")
		(net "I2C_IO_EXP_RESET#")
	)
	(segment
		(start 54.102 -222.25)
		(end 33.655 -222.25)
		(width 0.127)
		(layer "In2.Cu")
		(net "I2C_IO_EXP_RESET#")
	)
	(segment
		(start 313.182 -194.437)
		(end 316.2173 -191.4017)
		(width 0.127)
		(layer "In2.Cu")
		(net "I2C_IO_EXP_RESET#")
	)
	(segment
		(start 301.500032 -208.9785)
		(end 313.182 -197.296532)
		(width 0.127)
		(layer "In2.Cu")
		(net "I2C_IO_EXP_RESET#")
	)
	(segment
		(start 215.50122 -179.5907)
		(end 216.89822 -179.5907)
		(width 0.127)
		(layer "In2.Cu")
		(net "I2C_IO_EXP_RESET#")
	)
	(segment
		(start 70.231 -225.679)
		(end 68.961 -225.679)
		(width 0.127)
		(layer "In2.Cu")
		(net "I2C_IO_EXP_RESET#")
	)
	(segment
		(start 287.331912 -208.8261)
		(end 288.7218 -208.8261)
		(width 0.127)
		(layer "In2.Cu")
		(net "I2C_IO_EXP_RESET#")
	)
	(segment
		(start 163.957 -174.752)
		(end 171.577 -182.372)
		(width 0.127)
		(layer "In2.Cu")
		(net "I2C_IO_EXP_RESET#")
	)
	(segment
		(start 313.182 -197.296532)
		(end 313.182 -194.437)
		(width 0.127)
		(layer "In2.Cu")
		(net "I2C_IO_EXP_RESET#")
	)
	(segment
		(start 224.13722 -179.4637)
		(end 224.63252 -179.959)
		(width 0.127)
		(layer "In2.Cu")
		(net "I2C_IO_EXP_RESET#")
	)
	(segment
		(start 216.89822 -179.5907)
		(end 217.26652 -179.959)
		(width 0.127)
		(layer "In2.Cu")
		(net "I2C_IO_EXP_RESET#")
	)
	(segment
		(start 288.925 -208.6229)
		(end 298.2849 -208.6229)
		(width 0.127)
		(layer "In2.Cu")
		(net "I2C_IO_EXP_RESET#")
	)
	(segment
		(start 33.655 -222.25)
		(end 32.512 -221.107)
		(width 0.127)
		(layer "In2.Cu")
		(net "I2C_IO_EXP_RESET#")
	)
	(segment
		(start 222.91548 -179.959)
		(end 223.41078 -179.4637)
		(width 0.127)
		(layer "In2.Cu")
		(net "I2C_IO_EXP_RESET#")
	)
	(segment
		(start 84.360766 -225.900234)
		(end 83.660234 -225.900234)
		(width 0.127)
		(layer "In2.Cu")
		(net "I2C_IO_EXP_RESET#")
	)
	(segment
		(start 286.796988 -208.915)
		(end 287.243012 -208.915)
		(width 0.127)
		(layer "In2.Cu")
		(net "I2C_IO_EXP_RESET#")
	)
	(segment
		(start 263.887712 -198.904352)
		(end 273.23796 -208.2546)
		(width 0.127)
		(layer "In2.Cu")
		(net "I2C_IO_EXP_RESET#")
	)
	(segment
		(start 224.63252 -179.959)
		(end 251.449586 -179.959)
		(width 0.127)
		(layer "In2.Cu")
		(net "I2C_IO_EXP_RESET#")
	)
	(segment
		(start 214.64778 -179.4637)
		(end 215.37422 -179.4637)
		(width 0.127)
		(layer "In2.Cu")
		(net "I2C_IO_EXP_RESET#")
	)
	(segment
		(start 215.37422 -179.4637)
		(end 215.50122 -179.5907)
		(width 0.127)
		(layer "In2.Cu")
		(net "I2C_IO_EXP_RESET#")
	)
	(segment
		(start 206.071724 -182.88)
		(end 208.992724 -179.959)
		(width 0.127)
		(layer "In2.Cu")
		(net "I2C_IO_EXP_RESET#")
	)
	(segment
		(start 171.577 -182.372)
		(end 196.434964 -182.372)
		(width 0.127)
		(layer "In2.Cu")
		(net "I2C_IO_EXP_RESET#")
	)
	(segment
		(start 68.834 -225.552)
		(end 57.404 -225.552)
		(width 0.127)
		(layer "In2.Cu")
		(net "I2C_IO_EXP_RESET#")
	)
	(segment
		(start 68.961 -225.679)
		(end 68.834 -225.552)
		(width 0.127)
		(layer "In2.Cu")
		(net "I2C_IO_EXP_RESET#")
	)
	(segment
		(start 273.23796 -208.2546)
		(end 276.092412 -208.2546)
		(width 0.127)
		(layer "In2.Cu")
		(net "I2C_IO_EXP_RESET#")
	)
	(segment
		(start 251.449586 -179.959)
		(end 263.887712 -192.397126)
		(width 0.127)
		(layer "In2.Cu")
		(net "I2C_IO_EXP_RESET#")
	)
	(segment
		(start 286.135064 -208.253076)
		(end 286.796988 -208.915)
		(width 0.127)
		(layer "In2.Cu")
		(net "I2C_IO_EXP_RESET#")
	)
	(segment
		(start 83.660234 -225.900234)
		(end 83.119468 -226.441)
		(width 0.127)
		(layer "In2.Cu")
		(net "I2C_IO_EXP_RESET#")
	)
	(segment
		(start 287.243012 -208.915)
		(end 287.331912 -208.8261)
		(width 0.127)
		(layer "In2.Cu")
		(net "I2C_IO_EXP_RESET#")
	)
	(segment
		(start 57.404 -225.552)
		(end 54.102 -222.25)
		(width 0.127)
		(layer "In2.Cu")
		(net "I2C_IO_EXP_RESET#")
	)
	(segment
		(start 81.661 -174.752)
		(end 163.957 -174.752)
		(width 0.127)
		(layer "In2.Cu")
		(net "I2C_IO_EXP_RESET#")
	)
	(segment
		(start 276.093936 -208.253076)
		(end 286.135064 -208.253076)
		(width 0.127)
		(layer "In2.Cu")
		(net "I2C_IO_EXP_RESET#")
	)
	(segment
		(start 316.2173 -191.4017)
		(end 316.2173 -186.361832)
		(width 0.127)
		(layer "In2.Cu")
		(net "I2C_IO_EXP_RESET#")
	)
	(segment
		(start 208.992724 -179.959)
		(end 214.15248 -179.959)
		(width 0.127)
		(layer "In2.Cu")
		(net "I2C_IO_EXP_RESET#")
	)
	(segment
		(start 22.479 -208.28)
		(end 22.479 -197.311264)
		(width 0.127)
		(layer "In5.Cu")
		(net "I2C_IO_EXP_RESET#")
	)
	(segment
		(start 26.162 -211.963)
		(end 22.479 -208.28)
		(width 0.127)
		(layer "In5.Cu")
		(net "I2C_IO_EXP_RESET#")
	)
	(segment
		(start 26.67 -211.963)
		(end 26.162 -211.963)
		(width 0.127)
		(layer "In5.Cu")
		(net "I2C_IO_EXP_RESET#")
	)
	(segment
		(start 22.479 -197.311264)
		(end 21.946616 -196.77888)
		(width 0.127)
		(layer "In5.Cu")
		(net "I2C_IO_EXP_RESET#")
	)
	(segment
		(start 121.000012 -256.25044)
		(end 121.000012 -254.646176)
		(width 0.1016)
		(layer "F.Cu")
		(net "SAS_EXP_GF_TX_DN6")
	)
	(segment
		(start 123.120912 -232.6513)
		(end 125.909578 -229.862634)
		(width 0.1016)
		(layer "F.Cu")
		(net "SAS_EXP_GF_TX_DN6")
	)
	(segment
		(start 131.56438 -220.621352)
		(end 131.56438 -178.630326)
		(width 0.1016)
		(layer "F.Cu")
		(net "SAS_EXP_GF_TX_DN6")
	)
	(segment
		(start 117.88902 -160.642046)
		(end 117.88902 -114.931952)
		(width 0.1016)
		(layer "F.Cu")
		(net "SAS_EXP_GF_TX_DN6")
	)
	(segment
		(start 121.447052 -253.566676)
		(end 121.447052 -236.69244)
		(width 0.1016)
		(layer "F.Cu")
		(net "SAS_EXP_GF_TX_DN6")
	)
	(segment
		(start 129.355342 -173.297596)
		(end 129.16154 -173.10354)
		(width 0.1016)
		(layer "F.Cu")
		(net "SAS_EXP_GF_TX_DN6")
	)
	(segment
		(start 129.16154 -173.10354)
		(end 118.72976 -162.67176)
		(width 0.1016)
		(layer "F.Cu")
		(net "SAS_EXP_GF_TX_DN6")
	)
	(segment
		(start 125.909578 -229.862634)
		(end 129.028444 -226.744022)
		(width 0.1016)
		(layer "F.Cu")
		(net "SAS_EXP_GF_TX_DN6")
	)
	(arc
		(start 117.80139 -114.72037)
		(mid 117.758174 -114.655692)
		(end 117.74297 -114.5794)
		(width 0.1016)
		(layer "F.Cu")
		(net "SAS_EXP_GF_TX_DN6")
	)
	(arc
		(start 121.447052 -236.69244)
		(mid 121.882065 -234.50539)
		(end 123.120912 -232.6513)
		(width 0.1016)
		(layer "F.Cu")
		(net "SAS_EXP_GF_TX_DN6")
	)
	(arc
		(start 117.88902 -114.931952)
		(mid 117.866244 -114.817449)
		(end 117.80139 -114.72037)
		(width 0.1016)
		(layer "F.Cu")
		(net "SAS_EXP_GF_TX_DN6")
	)
	(arc
		(start 121.000012 -254.646176)
		(mid 121.062733 -254.330854)
		(end 121.241312 -254.0635)
		(width 0.1016)
		(layer "F.Cu")
		(net "SAS_EXP_GF_TX_DN6")
	)
	(arc
		(start 131.56438 -178.630326)
		(mid 130.990214 -175.74427)
		(end 129.355342 -173.297596)
		(width 0.1016)
		(layer "F.Cu")
		(net "SAS_EXP_GF_TX_DN6")
	)
	(arc
		(start 121.241312 -254.0635)
		(mid 121.39362 -253.835555)
		(end 121.447052 -253.566676)
		(width 0.1016)
		(layer "F.Cu")
		(net "SAS_EXP_GF_TX_DN6")
	)
	(arc
		(start 118.72976 -162.67176)
		(mid 118.107496 -161.74052)
		(end 117.88902 -160.642046)
		(width 0.1016)
		(layer "F.Cu")
		(net "SAS_EXP_GF_TX_DN6")
	)
	(arc
		(start 129.028444 -226.744022)
		(mid 130.905345 -223.934902)
		(end 131.56438 -220.621352)
		(width 0.1016)
		(layer "F.Cu")
		(net "SAS_EXP_GF_TX_DN6")
	)
	(segment
		(start 275.4122 -188.435996)
		(end 276.348952 -188.435996)
		(width 0.1143)
		(layer "F.Cu")
		(net "OSC2_CONT")
	)
	(segment
		(start 276.348952 -188.435996)
		(end 277.102824 -187.682124)
		(width 0.1143)
		(layer "F.Cu")
		(net "OSC2_CONT")
	)
	(segment
		(start 277.102824 -187.682124)
		(end 278.131524 -187.682124)
		(width 0.1143)
		(layer "F.Cu")
		(net "OSC2_CONT")
	)
	(via
		(at 275.4122 -188.435996)
		(size 0.5588)
		(drill 0.3048)
		(layers "F.Cu" "B.Cu")
		(net "OSC2_CONT")
	)
	(via
		(at 276.098 -187.7568)
		(size 0.7112)
		(drill 0.3556)
		(layers "F.Cu" "B.Cu")
		(net "OSC2_CONT")
	)
	(segment
		(start 276.098 -187.7568)
		(end 276.091396 -187.7568)
		(width 0.1143)
		(layer "B.Cu")
		(net "OSC2_CONT")
	)
	(segment
		(start 276.091396 -187.7568)
		(end 275.4122 -188.435996)
		(width 0.1143)
		(layer "B.Cu")
		(net "OSC2_CONT")
	)
	(segment
		(start 187.567062 -32.31007)
		(end 187.567062 -32.96666)
		(width 0.1143)
		(layer "F.Cu")
		(net "RMII_BMC_PHY_TXD1")
	)
	(segment
		(start 280.201878 -144.9324)
		(end 275.896578 -144.9324)
		(width 0.1143)
		(layer "F.Cu")
		(net "RMII_BMC_PHY_TXD1")
	)
	(segment
		(start 265.53795 -120.098566)
		(end 265.53795 -100.5205)
		(width 0.1143)
		(layer "F.Cu")
		(net "RMII_BMC_PHY_TXD1")
	)
	(segment
		(start 287.584388 -150.692612)
		(end 284.976316 -150.692612)
		(width 0.1143)
		(layer "F.Cu")
		(net "RMII_BMC_PHY_TXD1")
	)
	(segment
		(start 259.4102 -94.39275)
		(end 259.4102 -92.914216)
		(width 0.1143)
		(layer "F.Cu")
		(net "RMII_BMC_PHY_TXD1")
	)
	(segment
		(start 186.744864 -32.05607)
		(end 187.313062 -32.05607)
		(width 0.1143)
		(layer "F.Cu")
		(net "RMII_BMC_PHY_TXD1")
	)
	(segment
		(start 283.400246 -148.130768)
		(end 280.201878 -144.9324)
		(width 0.1143)
		(layer "F.Cu")
		(net "RMII_BMC_PHY_TXD1")
	)
	(segment
		(start 259.4102 -92.914216)
		(end 203.960984 -37.465)
		(width 0.1143)
		(layer "F.Cu")
		(net "RMII_BMC_PHY_TXD1")
	)
	(segment
		(start 283.400246 -149.116542)
		(end 283.400246 -148.130768)
		(width 0.1143)
		(layer "F.Cu")
		(net "RMII_BMC_PHY_TXD1")
	)
	(segment
		(start 187.567062 -32.96666)
		(end 191.049402 -36.449)
		(width 0.1143)
		(layer "F.Cu")
		(net "RMII_BMC_PHY_TXD1")
	)
	(segment
		(start 191.049402 -36.449)
		(end 193.5099 -36.449)
		(width 0.1143)
		(layer "F.Cu")
		(net "RMII_BMC_PHY_TXD1")
	)
	(segment
		(start 265.53795 -100.5205)
		(end 259.4102 -94.39275)
		(width 0.1143)
		(layer "F.Cu")
		(net "RMII_BMC_PHY_TXD1")
	)
	(segment
		(start 203.960984 -37.465)
		(end 194.5259 -37.465)
		(width 0.1143)
		(layer "F.Cu")
		(net "RMII_BMC_PHY_TXD1")
	)
	(segment
		(start 266.5349 -135.570722)
		(end 266.5349 -121.095516)
		(width 0.1143)
		(layer "F.Cu")
		(net "RMII_BMC_PHY_TXD1")
	)
	(segment
		(start 193.5099 -36.449)
		(end 193.7131 -36.6522)
		(width 0.1143)
		(layer "F.Cu")
		(net "RMII_BMC_PHY_TXD1")
	)
	(segment
		(start 284.976316 -150.692612)
		(end 283.400246 -149.116542)
		(width 0.1143)
		(layer "F.Cu")
		(net "RMII_BMC_PHY_TXD1")
	)
	(segment
		(start 275.896578 -144.9324)
		(end 266.5349 -135.570722)
		(width 0.1143)
		(layer "F.Cu")
		(net "RMII_BMC_PHY_TXD1")
	)
	(segment
		(start 194.5259 -37.465)
		(end 193.7131 -36.6522)
		(width 0.1143)
		(layer "F.Cu")
		(net "RMII_BMC_PHY_TXD1")
	)
	(segment
		(start 187.313062 -32.05607)
		(end 187.567062 -32.31007)
		(width 0.1143)
		(layer "F.Cu")
		(net "RMII_BMC_PHY_TXD1")
	)
	(segment
		(start 266.5349 -121.095516)
		(end 265.53795 -120.098566)
		(width 0.1143)
		(layer "F.Cu")
		(net "RMII_BMC_PHY_TXD1")
	)
	(via
		(at 287.584388 -150.692612)
		(size 0.5588)
		(drill 0.3048)
		(layers "F.Cu" "B.Cu")
		(net "RMII_BMC_PHY_TXD1")
	)
	(via
		(at 292.7604 -161.1884)
		(size 0.7112)
		(drill 0.3556)
		(layers "F.Cu" "B.Cu")
		(net "RMII_BMC_PHY_TXD1")
	)
	(segment
		(start 287.655 -151.765)
		(end 292.73627 -156.84627)
		(width 0.1143)
		(layer "B.Cu")
		(net "RMII_BMC_PHY_TXD1")
	)
	(segment
		(start 287.655 -150.763224)
		(end 287.655 -151.765)
		(width 0.1143)
		(layer "B.Cu")
		(net "RMII_BMC_PHY_TXD1")
	)
	(segment
		(start 292.7604 -163.6649)
		(end 292.862 -163.7665)
		(width 0.1143)
		(layer "B.Cu")
		(net "RMII_BMC_PHY_TXD1")
	)
	(segment
		(start 292.7604 -161.1884)
		(end 292.7604 -163.6649)
		(width 0.1143)
		(layer "B.Cu")
		(net "RMII_BMC_PHY_TXD1")
	)
	(segment
		(start 287.584388 -150.692612)
		(end 287.655 -150.763224)
		(width 0.1143)
		(layer "B.Cu")
		(net "RMII_BMC_PHY_TXD1")
	)
	(segment
		(start 292.73627 -157.312106)
		(end 292.7604 -157.336236)
		(width 0.1143)
		(layer "B.Cu")
		(net "RMII_BMC_PHY_TXD1")
	)
	(segment
		(start 292.7604 -157.336236)
		(end 292.7604 -161.1884)
		(width 0.1143)
		(layer "B.Cu")
		(net "RMII_BMC_PHY_TXD1")
	)
	(segment
		(start 292.73627 -156.84627)
		(end 292.73627 -157.312106)
		(width 0.1143)
		(layer "B.Cu")
		(net "RMII_BMC_PHY_TXD1")
	)
	(segment
		(start 123.35002 -91.34983)
		(end 123.850146 -90.849704)
		(width 0.1016)
		(layer "F.Cu")
		(net "SAS_GF_EXP_RX_DP1")
	)
	(via
		(at 123.850146 -90.849704)
		(size 0.508)
		(drill 0.254)
		(layers "F.Cu" "B.Cu")
		(net "SAS_GF_EXP_RX_DP1")
	)
	(segment
		(start 129.2479 -140.544042)
		(end 129.2479 -124.4727)
		(width 0.1016)
		(layer "B.Cu")
		(net "SAS_GF_EXP_RX_DP1")
	)
	(segment
		(start 145.034 -162.306)
		(end 129.849626 -147.121626)
		(width 0.1016)
		(layer "B.Cu")
		(net "SAS_GF_EXP_RX_DP1")
	)
	(segment
		(start 129.2479 -120.08358)
		(end 129.2479 -115.316)
		(width 0.1016)
		(layer "B.Cu")
		(net "SAS_GF_EXP_RX_DP1")
	)
	(segment
		(start 127.544068 -92.527628)
		(end 126.306834 -91.290394)
		(width 0.1016)
		(layer "B.Cu")
		(net "SAS_GF_EXP_RX_DP1")
	)
	(segment
		(start 145.999962 -256.50444)
		(end 145.999962 -254.733806)
		(width 0.1016)
		(layer "B.Cu")
		(net "SAS_GF_EXP_RX_DP1")
	)
	(segment
		(start 129.2479 -121.64822)
		(end 129.2479 -121.34342)
		(width 0.1016)
		(layer "B.Cu")
		(net "SAS_GF_EXP_RX_DP1")
	)
	(segment
		(start 128.651 -92.878402)
		(end 128.390904 -92.878402)
		(width 0.1016)
		(layer "B.Cu")
		(net "SAS_GF_EXP_RX_DP1")
	)
	(segment
		(start 129.48666 -122.43054)
		(end 129.48666 -122.12574)
		(width 0.1016)
		(layer "B.Cu")
		(net "SAS_GF_EXP_RX_DP1")
	)
	(segment
		(start 130.163824 -113.399824)
		(end 134.037324 -109.526324)
		(width 0.1016)
		(layer "B.Cu")
		(net "SAS_GF_EXP_RX_DP1")
	)
	(segment
		(start 125.53315 -90.9701)
		(end 124.26696 -90.9701)
		(width 0.1016)
		(layer "B.Cu")
		(net "SAS_GF_EXP_RX_DP1")
	)
	(segment
		(start 129.95529 -113.608612)
		(end 130.163824 -113.399824)
		(width 0.1016)
		(layer "B.Cu")
		(net "SAS_GF_EXP_RX_DP1")
	)
	(segment
		(start 127.991362 -92.809822)
		(end 127.991362 -92.809568)
		(width 0.1016)
		(layer "B.Cu")
		(net "SAS_GF_EXP_RX_DP1")
	)
	(segment
		(start 129.48666 -120.8659)
		(end 129.48666 -120.5611)
		(width 0.1016)
		(layer "B.Cu")
		(net "SAS_GF_EXP_RX_DP1")
	)
	(segment
		(start 134.76097 -107.779312)
		(end 134.76097 -99.135946)
		(width 0.1016)
		(layer "B.Cu")
		(net "SAS_GF_EXP_RX_DP1")
	)
	(segment
		(start 129.2479 -145.669)
		(end 129.2479 -141.803882)
		(width 0.1016)
		(layer "B.Cu")
		(net "SAS_GF_EXP_RX_DP1")
	)
	(segment
		(start 129.48666 -141.326362)
		(end 129.48666 -141.021562)
		(width 0.1016)
		(layer "B.Cu")
		(net "SAS_GF_EXP_RX_DP1")
	)
	(segment
		(start 124.023882 -90.92184)
		(end 123.850146 -90.849704)
		(width 0.1016)
		(layer "B.Cu")
		(net "SAS_GF_EXP_RX_DP1")
	)
	(segment
		(start 129.48666 -123.99518)
		(end 129.48666 -123.69038)
		(width 0.1016)
		(layer "B.Cu")
		(net "SAS_GF_EXP_RX_DP1")
	)
	(segment
		(start 145.951702 -254.490982)
		(end 145.8976 -254.360172)
		(width 0.1016)
		(layer "B.Cu")
		(net "SAS_GF_EXP_RX_DP1")
	)
	(segment
		(start 129.2479 -123.21286)
		(end 129.2479 -122.90806)
		(width 0.1016)
		(layer "B.Cu")
		(net "SAS_GF_EXP_RX_DP1")
	)
	(segment
		(start 134.284466 -97.985326)
		(end 129.549652 -93.250512)
		(width 0.1016)
		(layer "B.Cu")
		(net "SAS_GF_EXP_RX_DP1")
	)
	(segment
		(start 145.639282 -253.0094)
		(end 145.639282 -163.767262)
		(width 0.1016)
		(layer "B.Cu")
		(net "SAS_GF_EXP_RX_DP1")
	)
	(arc
		(start 129.36728 -124.23394)
		(mid 129.456168 -124.129145)
		(end 129.48666 -123.99518)
		(width 0.1016)
		(layer "B.Cu")
		(net "SAS_GF_EXP_RX_DP1")
	)
	(arc
		(start 129.36728 -121.88698)
		(mid 129.278392 -121.782185)
		(end 129.2479 -121.64822)
		(width 0.1016)
		(layer "B.Cu")
		(net "SAS_GF_EXP_RX_DP1")
	)
	(arc
		(start 129.36728 -123.45162)
		(mid 129.278392 -123.346825)
		(end 129.2479 -123.21286)
		(width 0.1016)
		(layer "B.Cu")
		(net "SAS_GF_EXP_RX_DP1")
	)
	(arc
		(start 129.849626 -147.121626)
		(mid 129.404305 -146.455156)
		(end 129.2479 -145.669)
		(width 0.1016)
		(layer "B.Cu")
		(net "SAS_GF_EXP_RX_DP1")
	)
	(arc
		(start 129.48666 -120.5611)
		(mid 129.456168 -120.427107)
		(end 129.36728 -120.32234)
		(width 0.1016)
		(layer "B.Cu")
		(net "SAS_GF_EXP_RX_DP1")
	)
	(arc
		(start 127.991362 -92.809568)
		(mid 127.751946 -92.693611)
		(end 127.544068 -92.527628)
		(width 0.1016)
		(layer "B.Cu")
		(net "SAS_GF_EXP_RX_DP1")
	)
	(arc
		(start 128.390904 -92.878402)
		(mid 128.188214 -92.861125)
		(end 127.991362 -92.809822)
		(width 0.1016)
		(layer "B.Cu")
		(net "SAS_GF_EXP_RX_DP1")
	)
	(arc
		(start 134.037324 -109.526324)
		(mid 134.572922 -108.724789)
		(end 134.76097 -107.779312)
		(width 0.1016)
		(layer "B.Cu")
		(net "SAS_GF_EXP_RX_DP1")
	)
	(arc
		(start 134.76097 -99.135946)
		(mid 134.637143 -98.513244)
		(end 134.284466 -97.985326)
		(width 0.1016)
		(layer "B.Cu")
		(net "SAS_GF_EXP_RX_DP1")
	)
	(arc
		(start 129.549652 -93.250512)
		(mid 129.137332 -92.975102)
		(end 128.651 -92.878402)
		(width 0.1016)
		(layer "B.Cu")
		(net "SAS_GF_EXP_RX_DP1")
	)
	(arc
		(start 129.2479 -122.90806)
		(mid 129.278392 -122.774067)
		(end 129.36728 -122.6693)
		(width 0.1016)
		(layer "B.Cu")
		(net "SAS_GF_EXP_RX_DP1")
	)
	(arc
		(start 126.306834 -91.290394)
		(mid 125.951836 -91.053348)
		(end 125.53315 -90.9701)
		(width 0.1016)
		(layer "B.Cu")
		(net "SAS_GF_EXP_RX_DP1")
	)
	(arc
		(start 129.2479 -115.316)
		(mid 129.431797 -114.391958)
		(end 129.95529 -113.608612)
		(width 0.1016)
		(layer "B.Cu")
		(net "SAS_GF_EXP_RX_DP1")
	)
	(arc
		(start 129.36728 -122.6693)
		(mid 129.456168 -122.564505)
		(end 129.48666 -122.43054)
		(width 0.1016)
		(layer "B.Cu")
		(net "SAS_GF_EXP_RX_DP1")
	)
	(arc
		(start 129.2479 -141.803882)
		(mid 129.278392 -141.669889)
		(end 129.36728 -141.565122)
		(width 0.1016)
		(layer "B.Cu")
		(net "SAS_GF_EXP_RX_DP1")
	)
	(arc
		(start 145.639282 -163.767262)
		(mid 145.481908 -162.976469)
		(end 145.034 -162.306)
		(width 0.1016)
		(layer "B.Cu")
		(net "SAS_GF_EXP_RX_DP1")
	)
	(arc
		(start 145.999962 -254.733806)
		(mid 145.98778 -254.61002)
		(end 145.951702 -254.490982)
		(width 0.1016)
		(layer "B.Cu")
		(net "SAS_GF_EXP_RX_DP1")
	)
	(arc
		(start 129.36728 -121.10466)
		(mid 129.456168 -120.999865)
		(end 129.48666 -120.8659)
		(width 0.1016)
		(layer "B.Cu")
		(net "SAS_GF_EXP_RX_DP1")
	)
	(arc
		(start 129.2479 -121.34342)
		(mid 129.278392 -121.209427)
		(end 129.36728 -121.10466)
		(width 0.1016)
		(layer "B.Cu")
		(net "SAS_GF_EXP_RX_DP1")
	)
	(arc
		(start 129.2479 -124.4727)
		(mid 129.278392 -124.338707)
		(end 129.36728 -124.23394)
		(width 0.1016)
		(layer "B.Cu")
		(net "SAS_GF_EXP_RX_DP1")
	)
	(arc
		(start 129.36728 -141.565122)
		(mid 129.456074 -141.460308)
		(end 129.48666 -141.326362)
		(width 0.1016)
		(layer "B.Cu")
		(net "SAS_GF_EXP_RX_DP1")
	)
	(arc
		(start 124.26696 -90.9701)
		(mid 124.143044 -90.957943)
		(end 124.023882 -90.92184)
		(width 0.1016)
		(layer "B.Cu")
		(net "SAS_GF_EXP_RX_DP1")
	)
	(arc
		(start 129.48666 -141.021562)
		(mid 129.456168 -140.887569)
		(end 129.36728 -140.782802)
		(width 0.1016)
		(layer "B.Cu")
		(net "SAS_GF_EXP_RX_DP1")
	)
	(arc
		(start 129.36728 -120.32234)
		(mid 129.278392 -120.217545)
		(end 129.2479 -120.08358)
		(width 0.1016)
		(layer "B.Cu")
		(net "SAS_GF_EXP_RX_DP1")
	)
	(arc
		(start 129.36728 -140.782802)
		(mid 129.278486 -140.677988)
		(end 129.2479 -140.544042)
		(width 0.1016)
		(layer "B.Cu")
		(net "SAS_GF_EXP_RX_DP1")
	)
	(arc
		(start 145.8976 -254.360172)
		(mid 145.704446 -253.697025)
		(end 145.639282 -253.0094)
		(width 0.1016)
		(layer "B.Cu")
		(net "SAS_GF_EXP_RX_DP1")
	)
	(arc
		(start 129.48666 -123.69038)
		(mid 129.456168 -123.556387)
		(end 129.36728 -123.45162)
		(width 0.1016)
		(layer "B.Cu")
		(net "SAS_GF_EXP_RX_DP1")
	)
	(arc
		(start 129.48666 -122.12574)
		(mid 129.456168 -121.991747)
		(end 129.36728 -121.88698)
		(width 0.1016)
		(layer "B.Cu")
		(net "SAS_GF_EXP_RX_DP1")
	)
	(segment
		(start 280.915872 -216.035636)
		(end 279.772872 -216.035636)
		(width 0.254)
		(layer "F.Cu")
		(net "TPS74801_1V53_STBY_EN")
	)
	(segment
		(start 282.2829 -216.259664)
		(end 282.2829 -218.577414)
		(width 0.254)
		(layer "F.Cu")
		(net "TPS74801_1V53_STBY_EN")
	)
	(segment
		(start 279.772872 -216.755472)
		(end 279.772872 -216.035636)
		(width 0.254)
		(layer "F.Cu")
		(net "TPS74801_1V53_STBY_EN")
	)
	(segment
		(start 279.8318 -216.8144)
		(end 279.772872 -216.755472)
		(width 0.254)
		(layer "F.Cu")
		(net "TPS74801_1V53_STBY_EN")
	)
	(segment
		(start 280.915872 -216.035636)
		(end 282.058872 -216.035636)
		(width 0.254)
		(layer "F.Cu")
		(net "TPS74801_1V53_STBY_EN")
	)
	(segment
		(start 282.058872 -216.035636)
		(end 282.2829 -216.259664)
		(width 0.254)
		(layer "F.Cu")
		(net "TPS74801_1V53_STBY_EN")
	)
	(segment
		(start 279.8318 -216.9414)
		(end 279.8318 -216.8144)
		(width 0.254)
		(layer "F.Cu")
		(net "TPS74801_1V53_STBY_EN")
	)
	(via
		(at 279.8318 -216.9414)
		(size 0.7112)
		(drill 0.3556)
		(layers "F.Cu" "B.Cu")
		(net "TPS74801_1V53_STBY_EN")
	)
	(segment
		(start 129.979928 -8.834628)
		(end 150.729188 -29.583888)
		(width 0.1397)
		(layer "B.Cu")
		(net "PCIE_SAS_CPU_RX_N1")
	)
	(segment
		(start 95.377254 -31.013146)
		(end 95.377254 -30.082998)
		(width 0.1397)
		(layer "B.Cu")
		(net "PCIE_SAS_CPU_RX_N1")
	)
	(segment
		(start 113.78692 -12.70508)
		(end 117.657372 -8.834628)
		(width 0.1397)
		(layer "B.Cu")
		(net "PCIE_SAS_CPU_RX_N1")
	)
	(segment
		(start 198.37527 -74.42327)
		(end 198.276464 -74.324464)
		(width 0.1397)
		(layer "B.Cu")
		(net "PCIE_SAS_CPU_RX_N1")
	)
	(segment
		(start 151.42083 -29.8704)
		(end 156.380688 -29.8704)
		(width 0.1397)
		(layer "B.Cu")
		(net "PCIE_SAS_CPU_RX_N1")
	)
	(segment
		(start 199.276462 -73.025)
		(end 199.276462 -74.08545)
		(width 0.1397)
		(layer "B.Cu")
		(net "PCIE_SAS_CPU_RX_N1")
	)
	(segment
		(start 156.82976 -30.056328)
		(end 198.9074 -72.133968)
		(width 0.1397)
		(layer "B.Cu")
		(net "PCIE_SAS_CPU_RX_N1")
	)
	(segment
		(start 95.014288 -23.843996)
		(end 105.680764 -13.17752)
		(width 0.1397)
		(layer "B.Cu")
		(net "PCIE_SAS_CPU_RX_N1")
	)
	(segment
		(start 106.129836 -12.991592)
		(end 113.095278 -12.991592)
		(width 0.1397)
		(layer "B.Cu")
		(net "PCIE_SAS_CPU_RX_N1")
	)
	(segment
		(start 118.106444 -8.6487)
		(end 129.530856 -8.6487)
		(width 0.1397)
		(layer "B.Cu")
		(net "PCIE_SAS_CPU_RX_N1")
	)
	(segment
		(start 198.276464 -73.923652)
		(end 198.449946 -73.75017)
		(width 0.1397)
		(layer "B.Cu")
		(net "PCIE_SAS_CPU_RX_N1")
	)
	(segment
		(start 94.82836 -28.758134)
		(end 94.82836 -24.293068)
		(width 0.1397)
		(layer "B.Cu")
		(net "PCIE_SAS_CPU_RX_N1")
	)
	(arc
		(start 95.51416 -31.3436)
		(mid 95.412855 -31.191986)
		(end 95.377254 -31.013146)
		(width 0.1397)
		(layer "B.Cu")
		(net "PCIE_SAS_CPU_RX_N1")
	)
	(arc
		(start 94.932754 -29.009848)
		(mid 94.855505 -28.894376)
		(end 94.82836 -28.758134)
		(width 0.1397)
		(layer "B.Cu")
		(net "PCIE_SAS_CPU_RX_N1")
	)
	(arc
		(start 150.729188 -29.583888)
		(mid 151.046502 -29.795974)
		(end 151.42083 -29.8704)
		(width 0.1397)
		(layer "B.Cu")
		(net "PCIE_SAS_CPU_RX_N1")
	)
	(arc
		(start 156.380688 -29.8704)
		(mid 156.623692 -29.918736)
		(end 156.82976 -30.056328)
		(width 0.1397)
		(layer "B.Cu")
		(net "PCIE_SAS_CPU_RX_N1")
	)
	(arc
		(start 105.680764 -13.17752)
		(mid 105.8868 -13.039851)
		(end 106.129836 -12.991592)
		(width 0.1397)
		(layer "B.Cu")
		(net "PCIE_SAS_CPU_RX_N1")
	)
	(arc
		(start 199.276462 -74.08545)
		(mid 199.240094 -74.268286)
		(end 199.136508 -74.42327)
		(width 0.1397)
		(layer "B.Cu")
		(net "PCIE_SAS_CPU_RX_N1")
	)
	(arc
		(start 113.095278 -12.991592)
		(mid 113.469587 -12.917119)
		(end 113.78692 -12.70508)
		(width 0.1397)
		(layer "B.Cu")
		(net "PCIE_SAS_CPU_RX_N1")
	)
	(arc
		(start 198.9074 -72.133968)
		(mid 199.180557 -72.542777)
		(end 199.276462 -73.025)
		(width 0.1397)
		(layer "B.Cu")
		(net "PCIE_SAS_CPU_RX_N1")
	)
	(arc
		(start 129.530856 -8.6487)
		(mid 129.77386 -8.697036)
		(end 129.979928 -8.834628)
		(width 0.1397)
		(layer "B.Cu")
		(net "PCIE_SAS_CPU_RX_N1")
	)
	(arc
		(start 95.377254 -30.082998)
		(mid 95.261745 -29.502204)
		(end 94.932754 -29.009848)
		(width 0.1397)
		(layer "B.Cu")
		(net "PCIE_SAS_CPU_RX_N1")
	)
	(arc
		(start 198.276464 -74.324464)
		(mid 198.193453 -74.124058)
		(end 198.276464 -73.923652)
		(width 0.1397)
		(layer "B.Cu")
		(net "PCIE_SAS_CPU_RX_N1")
	)
	(arc
		(start 94.82836 -24.293068)
		(mid 94.876696 -24.050064)
		(end 95.014288 -23.843996)
		(width 0.1397)
		(layer "B.Cu")
		(net "PCIE_SAS_CPU_RX_N1")
	)
	(arc
		(start 117.657372 -8.834628)
		(mid 117.863408 -8.696959)
		(end 118.106444 -8.6487)
		(width 0.1397)
		(layer "B.Cu")
		(net "PCIE_SAS_CPU_RX_N1")
	)
	(arc
		(start 199.136508 -74.42327)
		(mid 198.755926 -74.580875)
		(end 198.37527 -74.42327)
		(width 0.1397)
		(layer "B.Cu")
		(net "PCIE_SAS_CPU_RX_N1")
	)
	(via
		(at 279.146 -222.885)
		(size 0.7112)
		(drill 0.3556)
		(layers "F.Cu" "B.Cu")
		(net "TPS74801_P1V53_STBY_IN")
	)
	(segment
		(start 122.350022 -91.34983)
		(end 122.850148 -90.849704)
		(width 0.1016)
		(layer "F.Cu")
		(net "SAS_GF_EXP_RX_DN1")
	)
	(via
		(at 122.850148 -90.849704)
		(size 0.508)
		(drill 0.254)
		(layers "F.Cu" "B.Cu")
		(net "SAS_GF_EXP_RX_DN1")
	)
	(segment
		(start 123.360942 -91.127072)
		(end 123.166124 -90.932254)
		(width 0.1016)
		(layer "B.Cu")
		(net "SAS_GF_EXP_RX_DN1")
	)
	(segment
		(start 145.296382 -253.793244)
		(end 145.296382 -163.767516)
		(width 0.1016)
		(layer "B.Cu")
		(net "SAS_GF_EXP_RX_DN1")
	)
	(segment
		(start 145.000472 -256.50444)
		(end 145.000472 -254.465836)
		(width 0.1016)
		(layer "B.Cu")
		(net "SAS_GF_EXP_RX_DN1")
	)
	(segment
		(start 134.41807 -107.779058)
		(end 134.41807 -99.1362)
		(width 0.1016)
		(layer "B.Cu")
		(net "SAS_GF_EXP_RX_DN1")
	)
	(segment
		(start 125.53315 -91.313)
		(end 123.810014 -91.313)
		(width 0.1016)
		(layer "B.Cu")
		(net "SAS_GF_EXP_RX_DN1")
	)
	(segment
		(start 128.651 -93.221302)
		(end 128.39065 -93.221302)
		(width 0.1016)
		(layer "B.Cu")
		(net "SAS_GF_EXP_RX_DN1")
	)
	(segment
		(start 134.041896 -98.227896)
		(end 129.307082 -93.493082)
		(width 0.1016)
		(layer "B.Cu")
		(net "SAS_GF_EXP_RX_DN1")
	)
	(segment
		(start 129.712466 -113.366042)
		(end 133.794754 -109.283754)
		(width 0.1016)
		(layer "B.Cu")
		(net "SAS_GF_EXP_RX_DN1")
	)
	(segment
		(start 145.1483 -254.108458)
		(end 145.178018 -254.078994)
		(width 0.1016)
		(layer "B.Cu")
		(net "SAS_GF_EXP_RX_DN1")
	)
	(segment
		(start 144.79143 -162.54857)
		(end 129.607056 -147.364196)
		(width 0.1016)
		(layer "B.Cu")
		(net "SAS_GF_EXP_RX_DN1")
	)
	(segment
		(start 122.966734 -90.849704)
		(end 122.850148 -90.849704)
		(width 0.1016)
		(layer "B.Cu")
		(net "SAS_GF_EXP_RX_DN1")
	)
	(segment
		(start 127.301498 -92.770198)
		(end 126.064264 -91.532964)
		(width 0.1016)
		(layer "B.Cu")
		(net "SAS_GF_EXP_RX_DN1")
	)
	(segment
		(start 128.905 -145.669)
		(end 128.905 -115.315746)
		(width 0.1016)
		(layer "B.Cu")
		(net "SAS_GF_EXP_RX_DN1")
	)
	(arc
		(start 134.41807 -99.1362)
		(mid 134.32031 -98.644637)
		(end 134.041896 -98.227896)
		(width 0.1016)
		(layer "B.Cu")
		(net "SAS_GF_EXP_RX_DN1")
	)
	(arc
		(start 145.000472 -254.465836)
		(mid 145.038846 -254.272448)
		(end 145.1483 -254.108458)
		(width 0.1016)
		(layer "B.Cu")
		(net "SAS_GF_EXP_RX_DN1")
	)
	(arc
		(start 128.39065 -93.221302)
		(mid 128.130102 -93.199109)
		(end 127.877062 -93.133164)
		(width 0.1016)
		(layer "B.Cu")
		(net "SAS_GF_EXP_RX_DN1")
	)
	(arc
		(start 126.064264 -91.532964)
		(mid 125.820587 -91.370144)
		(end 125.53315 -91.313)
		(width 0.1016)
		(layer "B.Cu")
		(net "SAS_GF_EXP_RX_DN1")
	)
	(arc
		(start 123.166124 -90.932254)
		(mid 123.074642 -90.871158)
		(end 122.966734 -90.849704)
		(width 0.1016)
		(layer "B.Cu")
		(net "SAS_GF_EXP_RX_DN1")
	)
	(arc
		(start 145.296382 -163.767516)
		(mid 145.165158 -163.107809)
		(end 144.79143 -162.54857)
		(width 0.1016)
		(layer "B.Cu")
		(net "SAS_GF_EXP_RX_DN1")
	)
	(arc
		(start 127.877062 -93.133164)
		(mid 127.568978 -92.98387)
		(end 127.301498 -92.770198)
		(width 0.1016)
		(layer "B.Cu")
		(net "SAS_GF_EXP_RX_DN1")
	)
	(arc
		(start 129.307082 -93.493082)
		(mid 129.006069 -93.291952)
		(end 128.651 -93.221302)
		(width 0.1016)
		(layer "B.Cu")
		(net "SAS_GF_EXP_RX_DN1")
	)
	(arc
		(start 123.810014 -91.313)
		(mid 123.566996 -91.264679)
		(end 123.360942 -91.127072)
		(width 0.1016)
		(layer "B.Cu")
		(net "SAS_GF_EXP_RX_DN1")
	)
	(arc
		(start 145.178018 -254.078994)
		(mid 145.265643 -253.947904)
		(end 145.296382 -253.793244)
		(width 0.1016)
		(layer "B.Cu")
		(net "SAS_GF_EXP_RX_DN1")
	)
	(arc
		(start 129.607056 -147.364196)
		(mid 129.087455 -146.586418)
		(end 128.905 -145.669)
		(width 0.1016)
		(layer "B.Cu")
		(net "SAS_GF_EXP_RX_DN1")
	)
	(arc
		(start 128.905 -115.315746)
		(mid 129.114847 -114.260594)
		(end 129.712466 -113.366042)
		(width 0.1016)
		(layer "B.Cu")
		(net "SAS_GF_EXP_RX_DN1")
	)
	(arc
		(start 133.794754 -109.283754)
		(mid 134.256038 -108.593394)
		(end 134.41807 -107.779058)
		(width 0.1016)
		(layer "B.Cu")
		(net "SAS_GF_EXP_RX_DN1")
	)
	(segment
		(start 290.3855 -218.012264)
		(end 290.377372 -218.004136)
		(width 0.508)
		(layer "F.Cu")
		(net "TPS74801_1V53_STBY_OUT")
	)
	(segment
		(start 290.3855 -218.948)
		(end 290.3855 -218.012264)
		(width 0.508)
		(layer "F.Cu")
		(net "TPS74801_1V53_STBY_OUT")
	)
	(via
		(at 293.624 -219.964)
		(size 0.7112)
		(drill 0.3556)
		(layers "F.Cu" "B.Cu")
		(net "TPS74801_1V53_STBY_OUT")
	)
	(segment
		(start 294.894254 -201.34834)
		(end 294.906954 -201.33564)
		(width 0.3556)
		(layer "F.Cu")
		(net "P1V53_STBY")
	)
	(segment
		(start 299.72 -198.8058)
		(end 297.9928 -200.533)
		(width 0.508)
		(layer "F.Cu")
		(net "P1V53_STBY")
	)
	(segment
		(start 295.7322 -202.11034)
		(end 295.705784 -202.136756)
		(width 0.3556)
		(layer "F.Cu")
		(net "P1V53_STBY")
	)
	(segment
		(start 289.698176 -201.735182)
		(end 289.698176 -201.740516)
		(width 0.3048)
		(layer "F.Cu")
		(net "P1V53_STBY")
	)
	(segment
		(start 295.298114 -195.674234)
		(end 295.2623 -195.63842)
		(width 0.3556)
		(layer "F.Cu")
		(net "P1V53_STBY")
	)
	(segment
		(start 287.2486 -195.0212)
		(end 287.2486 -194.7418)
		(width 0.3556)
		(layer "F.Cu")
		(net "P1V53_STBY")
	)
	(segment
		(start 286.95904 -210.04784)
		(end 286.639 -209.7278)
		(width 0.6096)
		(layer "F.Cu")
		(net "P1V53_STBY")
	)
	(segment
		(start 291.298122 -201.741278)
		(end 290.89858 -202.14082)
		(width 0.3048)
		(layer "F.Cu")
		(net "P1V53_STBY")
	)
	(segment
		(start 295.2623 -195.63842)
		(end 295.2623 -195.37426)
		(width 0.3556)
		(layer "F.Cu")
		(net "P1V53_STBY")
	)
	(segment
		(start 289.1155 -208.915)
		(end 289.1155 -210.058)
		(width 0.6096)
		(layer "F.Cu")
		(net "P1V53_STBY")
	)
	(segment
		(start 292.903148 -202.535028)
		(end 293.31412 -202.946)
		(width 0.3556)
		(layer "F.Cu")
		(net "P1V53_STBY")
	)
	(segment
		(start 289.698176 -201.740516)
		(end 290.09848 -202.14082)
		(width 0.3048)
		(layer "F.Cu")
		(net "P1V53_STBY")
	)
	(segment
		(start 290.07816 -196.552566)
		(end 290.09213 -196.538596)
		(width 0.3556)
		(layer "F.Cu")
		(net "P1V53_STBY")
	)
	(segment
		(start 291.298122 -195.524882)
		(end 291.20592 -195.43268)
		(width 0.3556)
		(layer "F.Cu")
		(net "P1V53_STBY")
	)
	(segment
		(start 297.060112 -202.535028)
		(end 297.4213 -202.17384)
		(width 0.3048)
		(layer "F.Cu")
		(net "P1V53_STBY")
	)
	(segment
		(start 295.298114 -196.135244)
		(end 295.298114 -195.674234)
		(width 0.3556)
		(layer "F.Cu")
		(net "P1V53_STBY")
	)
	(segment
		(start 285.1912 -192.2145)
		(end 287.21304 -194.23634)
		(width 0.3556)
		(layer "F.Cu")
		(net "P1V53_STBY")
	)
	(segment
		(start 299.73778 -198.8058)
		(end 299.72 -198.8058)
		(width 0.508)
		(layer "F.Cu")
		(net "P1V53_STBY")
	)
	(segment
		(start 294.498014 -196.135244)
		(end 294.498014 -195.7832)
		(width 0.3556)
		(layer "F.Cu")
		(net "P1V53_STBY")
	)
	(segment
		(start 285.698184 -202.535028)
		(end 285.698184 -203.2381)
		(width 0.3556)
		(layer "F.Cu")
		(net "P1V53_STBY")
	)
	(segment
		(start 293.634922 -180.240178)
		(end 293.634922 -180.235098)
		(width 0.3556)
		(layer "F.Cu")
		(net "P1V53_STBY")
	)
	(segment
		(start 292.097968 -198.06666)
		(end 292.17874 -198.147432)
		(width 0.3556)
		(layer "F.Cu")
		(net "P1V53_STBY")
	)
	(segment
		(start 293.634922 -180.235098)
		(end 294.04818 -179.82184)
		(width 0.3556)
		(layer "F.Cu")
		(net "P1V53_STBY")
	)
	(segment
		(start 284.0482 -193.002662)
		(end 285.61284 -194.567302)
		(width 0.3556)
		(layer "F.Cu")
		(net "P1V53_STBY")
	)
	(segment
		(start 292.165532 -192.263776)
		(end 292.165532 -194.625468)
		(width 0.6096)
		(layer "F.Cu")
		(net "P1V53_STBY")
	)
	(segment
		(start 286.639 -208.534)
		(end 286.639 -209.7278)
		(width 0.508)
		(layer "F.Cu")
		(net "P1V53_STBY")
	)
	(segment
		(start 287.21304 -194.23634)
		(end 287.21304 -194.70624)
		(width 0.3556)
		(layer "F.Cu")
		(net "P1V53_STBY")
	)
	(segment
		(start 290.434776 -180.125624)
		(end 290.79952 -179.76088)
		(width 0.3556)
		(layer "F.Cu")
		(net "P1V53_STBY")
	)
	(segment
		(start 285.61284 -194.567302)
		(end 285.61284 -195.10756)
		(width 0.3556)
		(layer "F.Cu")
		(net "P1V53_STBY")
	)
	(segment
		(start 295.7068 -192.2653)
		(end 295.7068 -194.480688)
		(width 0.6096)
		(layer "F.Cu")
		(net "P1V53_STBY")
	)
	(segment
		(start 299.99178 -197.358)
		(end 298.97578 -196.342)
		(width 0.3048)
		(layer "F.Cu")
		(net "P1V53_STBY")
	)
	(segment
		(start 291.298122 -201.735182)
		(end 291.298122 -201.741278)
		(width 0.3048)
		(layer "F.Cu")
		(net "P1V53_STBY")
	)
	(segment
		(start 290.07816 -196.555106)
		(end 290.07816 -196.552566)
		(width 0.3556)
		(layer "F.Cu")
		(net "P1V53_STBY")
	)
	(segment
		(start 294.498014 -195.7832)
		(end 294.218614 -195.5038)
		(width 0.3556)
		(layer "F.Cu")
		(net "P1V53_STBY")
	)
	(segment
		(start 287.02762 -208.28)
		(end 286.893 -208.28)
		(width 0.508)
		(layer "F.Cu")
		(net "P1V53_STBY")
	)
	(segment
		(start 287.29813 -202.535028)
		(end 287.29813 -203.19111)
		(width 0.3556)
		(layer "F.Cu")
		(net "P1V53_STBY")
	)
	(segment
		(start 292.097968 -197.73519)
		(end 292.097968 -198.06666)
		(width 0.3556)
		(layer "F.Cu")
		(net "P1V53_STBY")
	)
	(segment
		(start 287.29813 -196.135244)
		(end 287.29813 -195.07073)
		(width 0.3556)
		(layer "F.Cu")
		(net "P1V53_STBY")
	)
	(segment
		(start 293.819072 -192.286636)
		(end 293.819072 -195.117212)
		(width 0.6096)
		(layer "F.Cu")
		(net "P1V53_STBY")
	)
	(segment
		(start 290.434776 -180.240178)
		(end 290.434776 -180.125624)
		(width 0.3556)
		(layer "F.Cu")
		(net "P1V53_STBY")
	)
	(segment
		(start 289.698176 -196.93509)
		(end 290.07816 -196.555106)
		(width 0.3556)
		(layer "F.Cu")
		(net "P1V53_STBY")
	)
	(segment
		(start 295.298114 -202.535028)
		(end 295.669716 -202.163426)
		(width 0.3556)
		(layer "F.Cu")
		(net "P1V53_STBY")
	)
	(segment
		(start 291.20592 -195.43268)
		(end 291.17798 -195.40474)
		(width 0.6096)
		(layer "F.Cu")
		(net "P1V53_STBY")
	)
	(segment
		(start 285.698184 -196.135244)
		(end 285.698184 -195.192904)
		(width 0.3556)
		(layer "F.Cu")
		(net "P1V53_STBY")
	)
	(segment
		(start 294.498014 -201.735182)
		(end 294.884856 -201.34834)
		(width 0.3556)
		(layer "F.Cu")
		(net "P1V53_STBY")
	)
	(segment
		(start 293.31412 -202.946)
		(end 293.3192 -202.946)
		(width 0.3556)
		(layer "F.Cu")
		(net "P1V53_STBY")
	)
	(segment
		(start 299.99178 -197.358)
		(end 299.99178 -198.5518)
		(width 0.508)
		(layer "F.Cu")
		(net "P1V53_STBY")
	)
	(segment
		(start 295.7322 -202.100942)
		(end 295.7322 -202.11034)
		(width 0.3556)
		(layer "F.Cu")
		(net "P1V53_STBY")
	)
	(segment
		(start 298.97578 -196.342)
		(end 297.49115 -196.342)
		(width 0.3048)
		(layer "F.Cu")
		(net "P1V53_STBY")
	)
	(segment
		(start 296.09796 -201.735182)
		(end 295.7322 -202.100942)
		(width 0.3556)
		(layer "F.Cu")
		(net "P1V53_STBY")
	)
	(segment
		(start 289.10534 -210.04784)
		(end 288.163 -210.04784)
		(width 0.6096)
		(layer "F.Cu")
		(net "P1V53_STBY")
	)
	(segment
		(start 291.298122 -196.135244)
		(end 291.298122 -195.524882)
		(width 0.3556)
		(layer "F.Cu")
		(net "P1V53_STBY")
	)
	(segment
		(start 299.99178 -198.5518)
		(end 299.73778 -198.8058)
		(width 0.508)
		(layer "F.Cu")
		(net "P1V53_STBY")
	)
	(segment
		(start 294.884856 -201.34834)
		(end 294.894254 -201.34834)
		(width 0.3556)
		(layer "F.Cu")
		(net "P1V53_STBY")
	)
	(segment
		(start 293.698168 -195.785232)
		(end 293.9796 -195.5038)
		(width 0.3556)
		(layer "F.Cu")
		(net "P1V53_STBY")
	)
	(segment
		(start 294.434768 -180.240178)
		(end 294.434768 -180.208428)
		(width 0.3556)
		(layer "F.Cu")
		(net "P1V53_STBY")
	)
	(segment
		(start 286.893 -208.28)
		(end 286.639 -208.534)
		(width 0.508)
		(layer "F.Cu")
		(net "P1V53_STBY")
	)
	(segment
		(start 297.49115 -196.342)
		(end 296.89806 -196.93509)
		(width 0.3048)
		(layer "F.Cu")
		(net "P1V53_STBY")
	)
	(segment
		(start 292.898068 -202.535028)
		(end 292.903148 -202.535028)
		(width 0.3556)
		(layer "F.Cu")
		(net "P1V53_STBY")
	)
	(segment
		(start 292.17874 -198.147432)
		(end 292.17874 -199.09536)
		(width 0.3556)
		(layer "F.Cu")
		(net "P1V53_STBY")
	)
	(segment
		(start 294.1574 -195.45554)
		(end 294.1574 -195.5038)
		(width 0.6096)
		(layer "F.Cu")
		(net "P1V53_STBY")
	)
	(segment
		(start 295.679114 -202.163426)
		(end 295.705784 -202.136756)
		(width 0.3556)
		(layer "F.Cu")
		(net "P1V53_STBY")
	)
	(segment
		(start 294.434768 -180.208428)
		(end 294.04818 -179.82184)
		(width 0.3556)
		(layer "F.Cu")
		(net "P1V53_STBY")
	)
	(segment
		(start 293.698168 -196.135244)
		(end 293.698168 -195.785232)
		(width 0.3556)
		(layer "F.Cu")
		(net "P1V53_STBY")
	)
	(segment
		(start 287.21304 -194.70624)
		(end 287.2486 -194.7418)
		(width 0.3556)
		(layer "F.Cu")
		(net "P1V53_STBY")
	)
	(segment
		(start 287.29813 -195.07073)
		(end 287.2486 -195.0212)
		(width 0.3556)
		(layer "F.Cu")
		(net "P1V53_STBY")
	)
	(segment
		(start 291.234876 -180.196236)
		(end 290.79952 -179.76088)
		(width 0.3556)
		(layer "F.Cu")
		(net "P1V53_STBY")
	)
	(segment
		(start 293.819072 -195.117212)
		(end 294.1574 -195.45554)
		(width 0.6096)
		(layer "F.Cu")
		(net "P1V53_STBY")
	)
	(segment
		(start 281.296872 -205.697836)
		(end 282.405836 -206.586836)
		(width 0.508)
		(layer "F.Cu")
		(net "P1V53_STBY")
	)
	(segment
		(start 296.89806 -202.535028)
		(end 297.060112 -202.535028)
		(width 0.3048)
		(layer "F.Cu")
		(net "P1V53_STBY")
	)
	(segment
		(start 294.218614 -195.5038)
		(end 294.1574 -195.5038)
		(width 0.3556)
		(layer "F.Cu")
		(net "P1V53_STBY")
	)
	(segment
		(start 295.669716 -202.163426)
		(end 295.679114 -202.163426)
		(width 0.3556)
		(layer "F.Cu")
		(net "P1V53_STBY")
	)
	(segment
		(start 284.0482 -192.2145)
		(end 284.0482 -193.002662)
		(width 0.3556)
		(layer "F.Cu")
		(net "P1V53_STBY")
	)
	(segment
		(start 295.7068 -194.480688)
		(end 295.2623 -194.925188)
		(width 0.6096)
		(layer "F.Cu")
		(net "P1V53_STBY")
	)
	(segment
		(start 293.9796 -195.5038)
		(end 294.1574 -195.5038)
		(width 0.3556)
		(layer "F.Cu")
		(net "P1V53_STBY")
	)
	(segment
		(start 289.1155 -210.058)
		(end 289.10534 -210.04784)
		(width 0.6096)
		(layer "F.Cu")
		(net "P1V53_STBY")
	)
	(segment
		(start 285.698184 -195.192904)
		(end 285.61284 -195.10756)
		(width 0.3556)
		(layer "F.Cu")
		(net "P1V53_STBY")
	)
	(segment
		(start 291.234876 -180.240178)
		(end 291.234876 -180.196236)
		(width 0.3556)
		(layer "F.Cu")
		(net "P1V53_STBY")
	)
	(segment
		(start 291.35832 -195.43268)
		(end 291.20592 -195.43268)
		(width 0.6096)
		(layer "F.Cu")
		(net "P1V53_STBY")
	)
	(segment
		(start 292.165532 -194.625468)
		(end 291.35832 -195.43268)
		(width 0.6096)
		(layer "F.Cu")
		(net "P1V53_STBY")
	)
	(segment
		(start 295.2623 -194.925188)
		(end 295.2623 -195.37426)
		(width 0.6096)
		(layer "F.Cu")
		(net "P1V53_STBY")
	)
	(segment
		(start 288.163 -210.04784)
		(end 286.95904 -210.04784)
		(width 0.6096)
		(layer "F.Cu")
		(net "P1V53_STBY")
	)
	(via
		(at 287.02762 -208.28)
		(size 0.5588)
		(drill 0.3048)
		(layers "F.Cu" "B.Cu")
		(net "P1V53_STBY")
	)
	(via
		(at 294.1574 -195.5038)
		(size 0.508)
		(drill 0.254)
		(layers "F.Cu" "B.Cu")
		(net "P1V53_STBY")
	)
	(via
		(at 287.2486 -194.7418)
		(size 0.508)
		(drill 0.254)
		(layers "F.Cu" "B.Cu")
		(net "P1V53_STBY")
	)
	(via
		(at 290.89858 -202.14082)
		(size 0.508)
		(drill 0.254)
		(layers "F.Cu" "B.Cu")
		(net "P1V53_STBY")
	)
	(via
		(at 297.4213 -202.17384)
		(size 0.508)
		(drill 0.254)
		(layers "F.Cu" "B.Cu")
		(net "P1V53_STBY")
	)
	(via
		(at 300.228 -207.264)
		(size 0.7112)
		(drill 0.4064)
		(layers "F.Cu" "B.Cu")
		(net "P1V53_STBY")
	)
	(via
		(at 297.9928 -200.533)
		(size 0.5588)
		(drill 0.3048)
		(layers "F.Cu" "B.Cu")
		(net "P1V53_STBY")
	)
	(via
		(at 290.09848 -202.14082)
		(size 0.508)
		(drill 0.254)
		(layers "F.Cu" "B.Cu")
		(net "P1V53_STBY")
	)
	(via
		(at 285.61284 -195.10756)
		(size 0.508)
		(drill 0.254)
		(layers "F.Cu" "B.Cu")
		(net "P1V53_STBY")
	)
	(via
		(at 290.79952 -179.76088)
		(size 0.508)
		(drill 0.254)
		(layers "F.Cu" "B.Cu")
		(net "P1V53_STBY")
	)
	(via
		(at 295.2623 -195.37426)
		(size 0.508)
		(drill 0.254)
		(layers "F.Cu" "B.Cu")
		(net "P1V53_STBY")
	)
	(via
		(at 298.958 -208.407)
		(size 0.7112)
		(drill 0.4064)
		(layers "F.Cu" "B.Cu")
		(net "P1V53_STBY")
	)
	(via
		(at 300.101 -208.407)
		(size 0.7112)
		(drill 0.4064)
		(layers "F.Cu" "B.Cu")
		(net "P1V53_STBY")
	)
	(via
		(at 294.04818 -179.82184)
		(size 0.508)
		(drill 0.254)
		(layers "F.Cu" "B.Cu")
		(net "P1V53_STBY")
	)
	(via
		(at 285.698184 -203.2381)
		(size 0.508)
		(drill 0.254)
		(layers "F.Cu" "B.Cu")
		(net "P1V53_STBY")
	)
	(via
		(at 294.906954 -201.33564)
		(size 0.508)
		(drill 0.254)
		(layers "F.Cu" "B.Cu")
		(net "P1V53_STBY")
	)
	(via
		(at 298.323 -191.262)
		(size 0.7112)
		(drill 0.3556)
		(layers "F.Cu" "B.Cu")
		(net "P1V53_STBY")
	)
	(via
		(at 290.09213 -196.538596)
		(size 0.508)
		(drill 0.254)
		(layers "F.Cu" "B.Cu")
		(net "P1V53_STBY")
	)
	(via
		(at 295.705784 -202.136756)
		(size 0.508)
		(drill 0.254)
		(layers "F.Cu" "B.Cu")
		(net "P1V53_STBY")
	)
	(via
		(at 291.0332 -207.264)
		(size 0.7112)
		(drill 0.3556)
		(layers "F.Cu" "B.Cu")
		(net "P1V53_STBY")
	)
	(via
		(at 291.17798 -195.40474)
		(size 0.508)
		(drill 0.254)
		(layers "F.Cu" "B.Cu")
		(net "P1V53_STBY")
	)
	(via
		(at 292.17874 -199.09536)
		(size 0.508)
		(drill 0.254)
		(layers "F.Cu" "B.Cu")
		(net "P1V53_STBY")
	)
	(via
		(at 287.29813 -203.19111)
		(size 0.508)
		(drill 0.254)
		(layers "F.Cu" "B.Cu")
		(net "P1V53_STBY")
	)
	(via
		(at 282.405836 -206.586836)
		(size 0.5588)
		(drill 0.3048)
		(layers "F.Cu" "B.Cu")
		(net "P1V53_STBY")
	)
	(via
		(at 293.3192 -202.946)
		(size 0.508)
		(drill 0.254)
		(layers "F.Cu" "B.Cu")
		(net "P1V53_STBY")
	)
	(segment
		(start 285.698184 -204.214984)
		(end 285.698184 -203.2381)
		(width 0.508)
		(layer "B.Cu")
		(net "P1V53_STBY")
	)
	(segment
		(start 287.3502 -204.216)
		(end 287.29813 -204.16393)
		(width 0.508)
		(layer "B.Cu")
		(net "P1V53_STBY")
	)
	(segment
		(start 285.6992 -204.216)
		(end 285.698184 -204.214984)
		(width 0.508)
		(layer "B.Cu")
		(net "P1V53_STBY")
	)
	(segment
		(start 287.29813 -204.16393)
		(end 287.29813 -203.19111)
		(width 0.508)
		(layer "B.Cu")
		(net "P1V53_STBY")
	)
	(segment
		(start 281.258518 -143.6751)
		(end 288.18205 -150.598632)
		(width 0.1143)
		(layer "F.Cu")
		(net "RMII_BMC_RX_ER")
	)
	(segment
		(start 192.142364 -28.520136)
		(end 192.451228 -28.829)
		(width 0.1143)
		(layer "F.Cu")
		(net "RMII_BMC_RX_ER")
	)
	(segment
		(start 267.7922 -135.049514)
		(end 276.417786 -143.6751)
		(width 0.1143)
		(layer "F.Cu")
		(net "RMII_BMC_RX_ER")
	)
	(segment
		(start 267.7922 -120.523)
		(end 267.7922 -135.049514)
		(width 0.1143)
		(layer "F.Cu")
		(net "RMII_BMC_RX_ER")
	)
	(segment
		(start 192.451228 -28.829)
		(end 197.103492 -28.829)
		(width 0.1143)
		(layer "F.Cu")
		(net "RMII_BMC_RX_ER")
	)
	(segment
		(start 260.6675 -92.393008)
		(end 260.6675 -93.871542)
		(width 0.1143)
		(layer "F.Cu")
		(net "RMII_BMC_RX_ER")
	)
	(segment
		(start 288.18205 -150.598632)
		(end 288.18205 -150.697692)
		(width 0.1143)
		(layer "F.Cu")
		(net "RMII_BMC_RX_ER")
	)
	(segment
		(start 260.6675 -93.871542)
		(end 266.79525 -99.999292)
		(width 0.1143)
		(layer "F.Cu")
		(net "RMII_BMC_RX_ER")
	)
	(segment
		(start 266.79525 -99.999292)
		(end 266.79525 -119.52605)
		(width 0.1143)
		(layer "F.Cu")
		(net "RMII_BMC_RX_ER")
	)
	(segment
		(start 288.18205 -150.697692)
		(end 288.29 -150.805642)
		(width 0.1143)
		(layer "F.Cu")
		(net "RMII_BMC_RX_ER")
	)
	(segment
		(start 288.29 -150.805642)
		(end 288.29 -151.638)
		(width 0.1143)
		(layer "F.Cu")
		(net "RMII_BMC_RX_ER")
	)
	(segment
		(start 197.103492 -28.829)
		(end 260.6675 -92.393008)
		(width 0.1143)
		(layer "F.Cu")
		(net "RMII_BMC_RX_ER")
	)
	(segment
		(start 276.417786 -143.6751)
		(end 281.258518 -143.6751)
		(width 0.1143)
		(layer "F.Cu")
		(net "RMII_BMC_RX_ER")
	)
	(segment
		(start 266.79525 -119.52605)
		(end 267.7922 -120.523)
		(width 0.1143)
		(layer "F.Cu")
		(net "RMII_BMC_RX_ER")
	)
	(via
		(at 294.513 -158.496)
		(size 0.7112)
		(drill 0.3556)
		(layers "F.Cu" "B.Cu")
		(net "RMII_BMC_RX_ER")
	)
	(via
		(at 288.29 -151.638)
		(size 0.5588)
		(drill 0.3048)
		(layers "F.Cu" "B.Cu")
		(net "RMII_BMC_RX_ER")
	)
	(segment
		(start 293.82085 -163.151566)
		(end 293.82085 -162.374834)
		(width 0.1143)
		(layer "B.Cu")
		(net "RMII_BMC_RX_ER")
	)
	(segment
		(start 293.15537 -157.13837)
		(end 294.513 -158.496)
		(width 0.1143)
		(layer "B.Cu")
		(net "RMII_BMC_RX_ER")
	)
	(segment
		(start 288.29 -151.638)
		(end 293.15537 -156.50337)
		(width 0.1143)
		(layer "B.Cu")
		(net "RMII_BMC_RX_ER")
	)
	(segment
		(start 293.865808 -163.196524)
		(end 293.82085 -163.151566)
		(width 0.1143)
		(layer "B.Cu")
		(net "RMII_BMC_RX_ER")
	)
	(segment
		(start 293.15537 -156.50337)
		(end 293.15537 -157.13837)
		(width 0.1143)
		(layer "B.Cu")
		(net "RMII_BMC_RX_ER")
	)
	(segment
		(start 293.865808 -163.500308)
		(end 293.865808 -163.196524)
		(width 0.1143)
		(layer "B.Cu")
		(net "RMII_BMC_RX_ER")
	)
	(segment
		(start 293.82085 -162.374834)
		(end 294.894 -161.301684)
		(width 0.1143)
		(layer "B.Cu")
		(net "RMII_BMC_RX_ER")
	)
	(segment
		(start 294.894 -161.301684)
		(end 294.894 -159.05226)
		(width 0.1143)
		(layer "B.Cu")
		(net "RMII_BMC_RX_ER")
	)
	(segment
		(start 294.894 -159.05226)
		(end 294.513 -158.67126)
		(width 0.1143)
		(layer "B.Cu")
		(net "RMII_BMC_RX_ER")
	)
	(segment
		(start 294.513 -158.67126)
		(end 294.513 -158.496)
		(width 0.1143)
		(layer "B.Cu")
		(net "RMII_BMC_RX_ER")
	)
	(segment
		(start 294.132 -163.7665)
		(end 293.865808 -163.500308)
		(width 0.1143)
		(layer "B.Cu")
		(net "RMII_BMC_RX_ER")
	)
	(segment
		(start 284.882844 -216.132664)
		(end 284.882844 -218.577414)
		(width 0.254)
		(layer "F.Cu")
		(net "TPS74801_1V53_STBY_SS")
	)
	(segment
		(start 284.979872 -216.035636)
		(end 284.882844 -216.132664)
		(width 0.254)
		(layer "F.Cu")
		(net "TPS74801_1V53_STBY_SS")
	)
	(segment
		(start 286.004 -216.035636)
		(end 284.979872 -216.035636)
		(width 0.254)
		(layer "F.Cu")
		(net "TPS74801_1V53_STBY_SS")
	)
	(via
		(at 286.004 -216.035636)
		(size 0.7112)
		(drill 0.3556)
		(layers "F.Cu" "B.Cu")
		(net "TPS74801_1V53_STBY_SS")
	)
	(segment
		(start 295.02862 -84.08162)
		(end 295.02862 -91.54922)
		(width 0.1143)
		(layer "F.Cu")
		(net "PMU_WAKE_N")
	)
	(segment
		(start 292.24605 -73.546462)
		(end 292.24605 -81.29905)
		(width 0.1143)
		(layer "F.Cu")
		(net "PMU_WAKE_N")
	)
	(segment
		(start 292.24605 -81.29905)
		(end 295.02862 -84.08162)
		(width 0.1143)
		(layer "F.Cu")
		(net "PMU_WAKE_N")
	)
	(segment
		(start 288.034984 -172.240194)
		(end 287.63976 -171.84497)
		(width 0.1143)
		(layer "F.Cu")
		(net "PMU_WAKE_N")
	)
	(segment
		(start 300.0375 -61.976)
		(end 299.847 -61.976)
		(width 0.1143)
		(layer "F.Cu")
		(net "PMU_WAKE_N")
	)
	(segment
		(start 298.9326 -62.8904)
		(end 298.9326 -66.859912)
		(width 0.1143)
		(layer "F.Cu")
		(net "PMU_WAKE_N")
	)
	(segment
		(start 298.9326 -66.859912)
		(end 292.24605 -73.546462)
		(width 0.1143)
		(layer "F.Cu")
		(net "PMU_WAKE_N")
	)
	(segment
		(start 299.847 -61.976)
		(end 298.9326 -62.8904)
		(width 0.1143)
		(layer "F.Cu")
		(net "PMU_WAKE_N")
	)
	(via
		(at 268.732 -172.085)
		(size 0.7112)
		(drill 0.3556)
		(layers "F.Cu" "B.Cu")
		(net "PMU_WAKE_N")
	)
	(via
		(at 287.63976 -171.84497)
		(size 0.508)
		(drill 0.254)
		(layers "F.Cu" "B.Cu")
		(net "PMU_WAKE_N")
	)
	(via
		(at 268.8209 -173.0883)
		(size 0.5588)
		(drill 0.3048)
		(layers "F.Cu" "B.Cu")
		(net "PMU_WAKE_N")
	)
	(via
		(at 295.02862 -91.54922)
		(size 0.5588)
		(drill 0.3048)
		(layers "F.Cu" "B.Cu")
		(net "PMU_WAKE_N")
	)
	(segment
		(start 268.732 -172.9994)
		(end 268.8209 -173.0883)
		(width 0.1143)
		(layer "B.Cu")
		(net "PMU_WAKE_N")
	)
	(segment
		(start 268.732 -172.085)
		(end 268.732 -172.9994)
		(width 0.1143)
		(layer "B.Cu")
		(net "PMU_WAKE_N")
	)
	(segment
		(start 286.453834 -172.823124)
		(end 286.20847 -173.068488)
		(width 0.127)
		(layer "In2.Cu")
		(net "PMU_WAKE_N")
	)
	(segment
		(start 285.648146 -172.855636)
		(end 272.406364 -172.855636)
		(width 0.127)
		(layer "In2.Cu")
		(net "PMU_WAKE_N")
	)
	(segment
		(start 287.63976 -171.84497)
		(end 287.432496 -171.84497)
		(width 0.127)
		(layer "In2.Cu")
		(net "PMU_WAKE_N")
	)
	(segment
		(start 286.20847 -173.068488)
		(end 285.860998 -173.068488)
		(width 0.127)
		(layer "In2.Cu")
		(net "PMU_WAKE_N")
	)
	(segment
		(start 269.317216 -173.584616)
		(end 268.8209 -173.0883)
		(width 0.127)
		(layer "In2.Cu")
		(net "PMU_WAKE_N")
	)
	(segment
		(start 272.406364 -172.855636)
		(end 271.677384 -173.584616)
		(width 0.127)
		(layer "In2.Cu")
		(net "PMU_WAKE_N")
	)
	(segment
		(start 286.454342 -172.823124)
		(end 286.453834 -172.823124)
		(width 0.127)
		(layer "In2.Cu")
		(net "PMU_WAKE_N")
	)
	(segment
		(start 285.860998 -173.068488)
		(end 285.648146 -172.855636)
		(width 0.127)
		(layer "In2.Cu")
		(net "PMU_WAKE_N")
	)
	(segment
		(start 287.432496 -171.84497)
		(end 286.454342 -172.823124)
		(width 0.127)
		(layer "In2.Cu")
		(net "PMU_WAKE_N")
	)
	(segment
		(start 271.677384 -173.584616)
		(end 269.317216 -173.584616)
		(width 0.127)
		(layer "In2.Cu")
		(net "PMU_WAKE_N")
	)
	(segment
		(start 270.96974 -167.10406)
		(end 270.96974 -165.892988)
		(width 0.127)
		(layer "In5.Cu")
		(net "PMU_WAKE_N")
	)
	(segment
		(start 268.8209 -169.2529)
		(end 270.96974 -167.10406)
		(width 0.127)
		(layer "In5.Cu")
		(net "PMU_WAKE_N")
	)
	(segment
		(start 272.415 -159.639)
		(end 272.415 -152.146)
		(width 0.127)
		(layer "In5.Cu")
		(net "PMU_WAKE_N")
	)
	(segment
		(start 286.004 -119.126)
		(end 290.703 -114.427)
		(width 0.127)
		(layer "In5.Cu")
		(net "PMU_WAKE_N")
	)
	(segment
		(start 294.83558 -91.35618)
		(end 295.02862 -91.54922)
		(width 0.127)
		(layer "In5.Cu")
		(net "PMU_WAKE_N")
	)
	(segment
		(start 273.177 -162.433)
		(end 273.177 -160.401)
		(width 0.127)
		(layer "In5.Cu")
		(net "PMU_WAKE_N")
	)
	(segment
		(start 279.573482 -124.968)
		(end 280.043382 -124.4981)
		(width 0.127)
		(layer "In5.Cu")
		(net "PMU_WAKE_N")
	)
	(segment
		(start 272.415 -152.146)
		(end 270.637 -150.368)
		(width 0.127)
		(layer "In5.Cu")
		(net "PMU_WAKE_N")
	)
	(segment
		(start 273.177 -160.401)
		(end 272.415 -159.639)
		(width 0.127)
		(layer "In5.Cu")
		(net "PMU_WAKE_N")
	)
	(segment
		(start 270.637 -150.368)
		(end 270.637 -148.844)
		(width 0.127)
		(layer "In5.Cu")
		(net "PMU_WAKE_N")
	)
	(segment
		(start 271.145 -148.336)
		(end 271.145 -132.758434)
		(width 0.127)
		(layer "In5.Cu")
		(net "PMU_WAKE_N")
	)
	(segment
		(start 270.7767 -164.8333)
		(end 273.177 -162.433)
		(width 0.127)
		(layer "In5.Cu")
		(net "PMU_WAKE_N")
	)
	(segment
		(start 270.96974 -165.892988)
		(end 270.7767 -165.699948)
		(width 0.127)
		(layer "In5.Cu")
		(net "PMU_WAKE_N")
	)
	(segment
		(start 290.703 -114.427)
		(end 290.703 -93.726)
		(width 0.127)
		(layer "In5.Cu")
		(net "PMU_WAKE_N")
	)
	(segment
		(start 270.7767 -165.699948)
		(end 270.7767 -164.8333)
		(width 0.127)
		(layer "In5.Cu")
		(net "PMU_WAKE_N")
	)
	(segment
		(start 290.703 -93.726)
		(end 293.07282 -91.35618)
		(width 0.127)
		(layer "In5.Cu")
		(net "PMU_WAKE_N")
	)
	(segment
		(start 293.07282 -91.35618)
		(end 294.83558 -91.35618)
		(width 0.127)
		(layer "In5.Cu")
		(net "PMU_WAKE_N")
	)
	(segment
		(start 280.043382 -124.4981)
		(end 280.758646 -124.4981)
		(width 0.127)
		(layer "In5.Cu")
		(net "PMU_WAKE_N")
	)
	(segment
		(start 270.637 -148.844)
		(end 271.145 -148.336)
		(width 0.127)
		(layer "In5.Cu")
		(net "PMU_WAKE_N")
	)
	(segment
		(start 268.8209 -173.0883)
		(end 268.8209 -169.2529)
		(width 0.127)
		(layer "In5.Cu")
		(net "PMU_WAKE_N")
	)
	(segment
		(start 280.758646 -124.4981)
		(end 286.004 -119.253)
		(width 0.127)
		(layer "In5.Cu")
		(net "PMU_WAKE_N")
	)
	(segment
		(start 271.145 -132.758434)
		(end 278.935434 -124.968)
		(width 0.127)
		(layer "In5.Cu")
		(net "PMU_WAKE_N")
	)
	(segment
		(start 286.004 -119.253)
		(end 286.004 -119.126)
		(width 0.127)
		(layer "In5.Cu")
		(net "PMU_WAKE_N")
	)
	(segment
		(start 278.935434 -124.968)
		(end 279.573482 -124.968)
		(width 0.127)
		(layer "In5.Cu")
		(net "PMU_WAKE_N")
	)
	(segment
		(start 103.61041 -27.156664)
		(end 109.068362 -21.698712)
		(width 0.1397)
		(layer "B.Cu")
		(net "PCIE_SAS_CPU_RX_P6")
	)
	(segment
		(start 102.570788 -31.271972)
		(end 102.616254 -31.164022)
		(width 0.1397)
		(layer "B.Cu")
		(net "PCIE_SAS_CPU_RX_P6")
	)
	(segment
		(start 154.049222 -39.847012)
		(end 163.209478 -49.007268)
		(width 0.1397)
		(layer "B.Cu")
		(net "PCIE_SAS_CPU_RX_P6")
	)
	(segment
		(start 124.12853 -24.8158)
		(end 133.1468 -24.8158)
		(width 0.1397)
		(layer "B.Cu")
		(net "PCIE_SAS_CPU_RX_P6")
	)
	(segment
		(start 119.83593 -21.616924)
		(end 122.261376 -24.04237)
		(width 0.1397)
		(layer "B.Cu")
		(net "PCIE_SAS_CPU_RX_P6")
	)
	(segment
		(start 109.760004 -21.4122)
		(end 119.3419 -21.4122)
		(width 0.1397)
		(layer "B.Cu")
		(net "PCIE_SAS_CPU_RX_P6")
	)
	(segment
		(start 133.758178 -25.069038)
		(end 148.063712 -39.374572)
		(width 0.1397)
		(layer "B.Cu")
		(net "PCIE_SAS_CPU_RX_P6")
	)
	(segment
		(start 163.391342 -75.691746)
		(end 163.450016 -75.75042)
		(width 0.1397)
		(layer "B.Cu")
		(net "PCIE_SAS_CPU_RX_P6")
	)
	(segment
		(start 102.62616 -31.114746)
		(end 102.62616 -29.93263)
		(width 0.1397)
		(layer "B.Cu")
		(net "PCIE_SAS_CPU_RX_P6")
	)
	(segment
		(start 163.622482 -50.004472)
		(end 163.622482 -74.327258)
		(width 0.1397)
		(layer "B.Cu")
		(net "PCIE_SAS_CPU_RX_P6")
	)
	(segment
		(start 148.512784 -39.5605)
		(end 153.35758 -39.5605)
		(width 0.1397)
		(layer "B.Cu")
		(net "PCIE_SAS_CPU_RX_P6")
	)
	(segment
		(start 102.49916 -31.3436)
		(end 102.570788 -31.271972)
		(width 0.1397)
		(layer "B.Cu")
		(net "PCIE_SAS_CPU_RX_P6")
	)
	(segment
		(start 103.24846 -28.4988)
		(end 103.24846 -28.030932)
		(width 0.1397)
		(layer "B.Cu")
		(net "PCIE_SAS_CPU_RX_P6")
	)
	(segment
		(start 102.912418 -29.241496)
		(end 102.960678 -29.193236)
		(width 0.1397)
		(layer "B.Cu")
		(net "PCIE_SAS_CPU_RX_P6")
	)
	(arc
		(start 103.24846 -28.030932)
		(mid 103.342479 -27.557798)
		(end 103.61041 -27.156664)
		(width 0.1397)
		(layer "B.Cu")
		(net "PCIE_SAS_CPU_RX_P6")
	)
	(arc
		(start 163.622482 -74.327258)
		(mid 163.565718 -74.601918)
		(end 163.40455 -74.831448)
		(width 0.1397)
		(layer "B.Cu")
		(net "PCIE_SAS_CPU_RX_P6")
	)
	(arc
		(start 102.960678 -29.193236)
		(mid 103.173649 -28.874641)
		(end 103.24846 -28.4988)
		(width 0.1397)
		(layer "B.Cu")
		(net "PCIE_SAS_CPU_RX_P6")
	)
	(arc
		(start 163.209478 -49.007268)
		(mid 163.515184 -49.464789)
		(end 163.622482 -50.004472)
		(width 0.1397)
		(layer "B.Cu")
		(net "PCIE_SAS_CPU_RX_P6")
	)
	(arc
		(start 122.261376 -24.04237)
		(mid 123.118034 -24.61477)
		(end 124.12853 -24.8158)
		(width 0.1397)
		(layer "B.Cu")
		(net "PCIE_SAS_CPU_RX_P6")
	)
	(arc
		(start 119.3419 -21.4122)
		(mid 119.609262 -21.465457)
		(end 119.83593 -21.616924)
		(width 0.1397)
		(layer "B.Cu")
		(net "PCIE_SAS_CPU_RX_P6")
	)
	(arc
		(start 102.61854 -31.157672)
		(mid 102.624223 -31.13654)
		(end 102.62616 -31.114746)
		(width 0.1397)
		(layer "B.Cu")
		(net "PCIE_SAS_CPU_RX_P6")
	)
	(arc
		(start 153.35758 -39.5605)
		(mid 153.731889 -39.634973)
		(end 154.049222 -39.847012)
		(width 0.1397)
		(layer "B.Cu")
		(net "PCIE_SAS_CPU_RX_P6")
	)
	(arc
		(start 102.62616 -29.93263)
		(mid 102.700545 -29.558584)
		(end 102.912418 -29.241496)
		(width 0.1397)
		(layer "B.Cu")
		(net "PCIE_SAS_CPU_RX_P6")
	)
	(arc
		(start 133.1468 -24.8158)
		(mid 133.477674 -24.881615)
		(end 133.758178 -25.069038)
		(width 0.1397)
		(layer "B.Cu")
		(net "PCIE_SAS_CPU_RX_P6")
	)
	(arc
		(start 109.068362 -21.698712)
		(mid 109.385676 -21.486626)
		(end 109.760004 -21.4122)
		(width 0.1397)
		(layer "B.Cu")
		(net "PCIE_SAS_CPU_RX_P6")
	)
	(arc
		(start 163.40455 -74.831448)
		(mid 163.215817 -75.258823)
		(end 163.391342 -75.691746)
		(width 0.1397)
		(layer "B.Cu")
		(net "PCIE_SAS_CPU_RX_P6")
	)
	(arc
		(start 148.063712 -39.374572)
		(mid 148.269748 -39.512241)
		(end 148.512784 -39.5605)
		(width 0.1397)
		(layer "B.Cu")
		(net "PCIE_SAS_CPU_RX_P6")
	)
	(arc
		(start 102.616254 -31.164022)
		(mid 102.617442 -31.160863)
		(end 102.61854 -31.157672)
		(width 0.1397)
		(layer "B.Cu")
		(net "PCIE_SAS_CPU_RX_P6")
	)
	(segment
		(start 279.599136 -219.274136)
		(end 279.908 -219.583)
		(width 0.508)
		(layer "F.Cu")
		(net "TPS74801_1V53_STBY_BIAS")
	)
	(segment
		(start 278.439372 -218.313)
		(end 278.439372 -219.274136)
		(width 0.508)
		(layer "F.Cu")
		(net "TPS74801_1V53_STBY_BIAS")
	)
	(segment
		(start 279.908 -219.583)
		(end 280.077164 -219.752164)
		(width 0.3556)
		(layer "F.Cu")
		(net "TPS74801_1V53_STBY_BIAS")
	)
	(segment
		(start 278.439372 -220.290136)
		(end 278.439372 -219.274136)
		(width 0.508)
		(layer "F.Cu")
		(net "TPS74801_1V53_STBY_BIAS")
	)
	(segment
		(start 280.077164 -219.752164)
		(end 281.10815 -219.752164)
		(width 0.3556)
		(layer "F.Cu")
		(net "TPS74801_1V53_STBY_BIAS")
	)
	(segment
		(start 278.439372 -219.274136)
		(end 279.599136 -219.274136)
		(width 0.508)
		(layer "F.Cu")
		(net "TPS74801_1V53_STBY_BIAS")
	)
	(via
		(at 278.439372 -218.313)
		(size 0.7112)
		(drill 0.3556)
		(layers "F.Cu" "B.Cu")
		(net "TPS74801_1V53_STBY_BIAS")
	)
	(segment
		(start 289.4965 -218.012264)
		(end 289.488372 -218.004136)
		(width 0.254)
		(layer "F.Cu")
		(net "TPS74801_1V53_STBY_FB")
	)
	(segment
		(start 286.057594 -219.752164)
		(end 287.613344 -219.752164)
		(width 0.254)
		(layer "F.Cu")
		(net "TPS74801_1V53_STBY_FB")
	)
	(segment
		(start 288.417508 -218.948)
		(end 289.4965 -218.948)
		(width 0.254)
		(layer "F.Cu")
		(net "TPS74801_1V53_STBY_FB")
	)
	(segment
		(start 289.488372 -216.971372)
		(end 289.488372 -218.004136)
		(width 0.254)
		(layer "F.Cu")
		(net "TPS74801_1V53_STBY_FB")
	)
	(segment
		(start 288.408872 -218.956636)
		(end 288.417508 -218.948)
		(width 0.254)
		(layer "F.Cu")
		(net "TPS74801_1V53_STBY_FB")
	)
	(segment
		(start 289.4965 -218.948)
		(end 289.4965 -218.012264)
		(width 0.254)
		(layer "F.Cu")
		(net "TPS74801_1V53_STBY_FB")
	)
	(segment
		(start 287.613344 -219.752164)
		(end 288.408872 -218.956636)
		(width 0.254)
		(layer "F.Cu")
		(net "TPS74801_1V53_STBY_FB")
	)
	(via
		(at 289.488372 -216.971372)
		(size 0.7112)
		(drill 0.3556)
		(layers "F.Cu" "B.Cu")
		(net "TPS74801_1V53_STBY_FB")
	)
	(segment
		(start 157.072584 -29.814012)
		(end 199.14997 -71.891398)
		(width 0.1397)
		(layer "B.Cu")
		(net "PCIE_SAS_CPU_RX_P1")
	)
	(segment
		(start 106.129582 -12.648692)
		(end 113.095024 -12.648692)
		(width 0.1397)
		(layer "B.Cu")
		(net "PCIE_SAS_CPU_RX_P1")
	)
	(segment
		(start 94.771972 -23.601172)
		(end 105.43794 -12.935204)
		(width 0.1397)
		(layer "B.Cu")
		(net "PCIE_SAS_CPU_RX_P1")
	)
	(segment
		(start 95.034354 -30.96895)
		(end 95.034354 -30.083252)
		(width 0.1397)
		(layer "B.Cu")
		(net "PCIE_SAS_CPU_RX_P1")
	)
	(segment
		(start 130.222752 -8.592312)
		(end 150.972012 -29.341572)
		(width 0.1397)
		(layer "B.Cu")
		(net "PCIE_SAS_CPU_RX_P1")
	)
	(segment
		(start 199.619362 -73.025)
		(end 199.619362 -75.34021)
		(width 0.1397)
		(layer "B.Cu")
		(net "PCIE_SAS_CPU_RX_P1")
	)
	(segment
		(start 94.48546 -28.758388)
		(end 94.48546 -24.292814)
		(width 0.1397)
		(layer "B.Cu")
		(net "PCIE_SAS_CPU_RX_P1")
	)
	(segment
		(start 151.421084 -29.5275)
		(end 156.380942 -29.5275)
		(width 0.1397)
		(layer "B.Cu")
		(net "PCIE_SAS_CPU_RX_P1")
	)
	(segment
		(start 118.10619 -8.3058)
		(end 129.53111 -8.3058)
		(width 0.1397)
		(layer "B.Cu")
		(net "PCIE_SAS_CPU_RX_P1")
	)
	(segment
		(start 113.544096 -12.462764)
		(end 117.414548 -8.592312)
		(width 0.1397)
		(layer "B.Cu")
		(net "PCIE_SAS_CPU_RX_P1")
	)
	(arc
		(start 199.14997 -71.891398)
		(mid 199.497407 -72.411514)
		(end 199.619362 -73.025)
		(width 0.1397)
		(layer "B.Cu")
		(net "PCIE_SAS_CPU_RX_P1")
	)
	(arc
		(start 150.972012 -29.341572)
		(mid 151.178048 -29.479241)
		(end 151.421084 -29.5275)
		(width 0.1397)
		(layer "B.Cu")
		(net "PCIE_SAS_CPU_RX_P1")
	)
	(arc
		(start 95.034354 -30.083252)
		(mid 94.944912 -29.633597)
		(end 94.690184 -29.252418)
		(width 0.1397)
		(layer "B.Cu")
		(net "PCIE_SAS_CPU_RX_P1")
	)
	(arc
		(start 129.53111 -8.3058)
		(mid 129.905419 -8.380273)
		(end 130.222752 -8.592312)
		(width 0.1397)
		(layer "B.Cu")
		(net "PCIE_SAS_CPU_RX_P1")
	)
	(arc
		(start 105.43794 -12.935204)
		(mid 105.755254 -12.723118)
		(end 106.129582 -12.648692)
		(width 0.1397)
		(layer "B.Cu")
		(net "PCIE_SAS_CPU_RX_P1")
	)
	(arc
		(start 94.48546 -24.292814)
		(mid 94.559933 -23.918505)
		(end 94.771972 -23.601172)
		(width 0.1397)
		(layer "B.Cu")
		(net "PCIE_SAS_CPU_RX_P1")
	)
	(arc
		(start 156.380942 -29.5275)
		(mid 156.755251 -29.601973)
		(end 157.072584 -29.814012)
		(width 0.1397)
		(layer "B.Cu")
		(net "PCIE_SAS_CPU_RX_P1")
	)
	(arc
		(start 199.619362 -75.34021)
		(mid 199.575202 -75.562218)
		(end 199.449436 -75.75042)
		(width 0.1397)
		(layer "B.Cu")
		(net "PCIE_SAS_CPU_RX_P1")
	)
	(arc
		(start 117.414548 -8.592312)
		(mid 117.731862 -8.380226)
		(end 118.10619 -8.3058)
		(width 0.1397)
		(layer "B.Cu")
		(net "PCIE_SAS_CPU_RX_P1")
	)
	(arc
		(start 94.690184 -29.252418)
		(mid 94.538703 -29.025756)
		(end 94.48546 -28.758388)
		(width 0.1397)
		(layer "B.Cu")
		(net "PCIE_SAS_CPU_RX_P1")
	)
	(arc
		(start 94.87916 -31.3436)
		(mid 94.994014 -31.171709)
		(end 95.034354 -30.96895)
		(width 0.1397)
		(layer "B.Cu")
		(net "PCIE_SAS_CPU_RX_P1")
	)
	(arc
		(start 113.095024 -12.648692)
		(mid 113.338028 -12.600356)
		(end 113.544096 -12.462764)
		(width 0.1397)
		(layer "B.Cu")
		(net "PCIE_SAS_CPU_RX_P1")
	)
	(segment
		(start 261.230364 -219.066872)
		(end 261.230364 -220.209872)
		(width 0.254)
		(layer "F.Cu")
		(net "TPS74801_1V26_STBY_FB")
	)
	(segment
		(start 260.277864 -219.003372)
		(end 259.207 -219.003372)
		(width 0.254)
		(layer "F.Cu")
		(net "TPS74801_1V26_STBY_FB")
	)
	(segment
		(start 261.293864 -219.003372)
		(end 261.230364 -219.066872)
		(width 0.254)
		(layer "F.Cu")
		(net "TPS74801_1V26_STBY_FB")
	)
	(segment
		(start 261.644892 -220.6244)
		(end 261.644892 -222.18015)
		(width 0.254)
		(layer "F.Cu")
		(net "TPS74801_1V26_STBY_FB")
	)
	(segment
		(start 261.230364 -220.209872)
		(end 261.644892 -220.6244)
		(width 0.254)
		(layer "F.Cu")
		(net "TPS74801_1V26_STBY_FB")
	)
	(segment
		(start 261.293864 -219.003372)
		(end 260.277864 -219.003372)
		(width 0.254)
		(layer "F.Cu")
		(net "TPS74801_1V26_STBY_FB")
	)
	(via
		(at 259.207 -219.003372)
		(size 0.7112)
		(drill 0.3556)
		(layers "F.Cu" "B.Cu")
		(net "TPS74801_1V26_STBY_FB")
	)
	(segment
		(start 285.242 -184.345072)
		(end 284.984952 -184.60212)
		(width 0.1143)
		(layer "F.Cu")
		(net "PD_USB2VRES")
	)
	(segment
		(start 285.242 -184.121044)
		(end 285.242 -184.345072)
		(width 0.1143)
		(layer "F.Cu")
		(net "PD_USB2VRES")
	)
	(segment
		(start 283.972 -187.706)
		(end 283.972 -189.611)
		(width 0.1143)
		(layer "F.Cu")
		(net "PD_USB2VRES")
	)
	(segment
		(start 285.484824 -183.87822)
		(end 285.242 -184.121044)
		(width 0.1143)
		(layer "F.Cu")
		(net "PD_USB2VRES")
	)
	(segment
		(start 277.621746 -190.44285)
		(end 277.56866 -190.495936)
		(width 0.1143)
		(layer "F.Cu")
		(net "PD_USB2VRES")
	)
	(segment
		(start 284.67812 -184.60212)
		(end 284.021022 -185.259218)
		(width 0.1143)
		(layer "F.Cu")
		(net "PD_USB2VRES")
	)
	(segment
		(start 278.69134 -190.495936)
		(end 278.638254 -190.44285)
		(width 0.1143)
		(layer "F.Cu")
		(net "PD_USB2VRES")
	)
	(segment
		(start 284.021022 -185.259218)
		(end 284.021022 -187.656978)
		(width 0.1143)
		(layer "F.Cu")
		(net "PD_USB2VRES")
	)
	(segment
		(start 283.972 -189.611)
		(end 283.087064 -190.495936)
		(width 0.1143)
		(layer "F.Cu")
		(net "PD_USB2VRES")
	)
	(segment
		(start 284.984952 -184.60212)
		(end 284.67812 -184.60212)
		(width 0.1143)
		(layer "F.Cu")
		(net "PD_USB2VRES")
	)
	(segment
		(start 284.021022 -187.656978)
		(end 283.972 -187.706)
		(width 0.1143)
		(layer "F.Cu")
		(net "PD_USB2VRES")
	)
	(segment
		(start 275.123148 -190.495936)
		(end 274.240752 -190.495936)
		(width 0.1143)
		(layer "F.Cu")
		(net "PD_USB2VRES")
	)
	(segment
		(start 275.538692 -190.506096)
		(end 275.133308 -190.506096)
		(width 0.1143)
		(layer "F.Cu")
		(net "PD_USB2VRES")
	)
	(segment
		(start 277.56866 -190.495936)
		(end 275.548852 -190.495936)
		(width 0.1143)
		(layer "F.Cu")
		(net "PD_USB2VRES")
	)
	(segment
		(start 283.087064 -190.495936)
		(end 278.69134 -190.495936)
		(width 0.1143)
		(layer "F.Cu")
		(net "PD_USB2VRES")
	)
	(segment
		(start 278.638254 -190.44285)
		(end 277.621746 -190.44285)
		(width 0.1143)
		(layer "F.Cu")
		(net "PD_USB2VRES")
	)
	(segment
		(start 286.434784 -183.44007)
		(end 286.42437 -183.44007)
		(width 0.1143)
		(layer "F.Cu")
		(net "PD_USB2VRES")
	)
	(segment
		(start 275.133308 -190.506096)
		(end 275.123148 -190.495936)
		(width 0.1143)
		(layer "F.Cu")
		(net "PD_USB2VRES")
	)
	(segment
		(start 275.548852 -190.495936)
		(end 275.538692 -190.506096)
		(width 0.1143)
		(layer "F.Cu")
		(net "PD_USB2VRES")
	)
	(segment
		(start 286.42437 -183.44007)
		(end 285.98622 -183.87822)
		(width 0.1143)
		(layer "F.Cu")
		(net "PD_USB2VRES")
	)
	(segment
		(start 285.98622 -183.87822)
		(end 285.484824 -183.87822)
		(width 0.1143)
		(layer "F.Cu")
		(net "PD_USB2VRES")
	)
	(via
		(at 283.972 -187.706)
		(size 0.7112)
		(drill 0.3556)
		(layers "F.Cu" "B.Cu")
		(net "PD_USB2VRES")
	)
	(segment
		(start 261.644892 -227.994972)
		(end 261.039864 -228.6)
		(width 0.381)
		(layer "F.Cu")
		(net "TPS74801_1V26_STBY_BIAS")
	)
	(segment
		(start 261.644892 -227.129594)
		(end 261.644892 -227.994972)
		(width 0.3556)
		(layer "F.Cu")
		(net "TPS74801_1V26_STBY_BIAS")
	)
	(segment
		(start 261.039864 -230.560372)
		(end 261.039864 -229.235)
		(width 0.508)
		(layer "F.Cu")
		(net "TPS74801_1V26_STBY_BIAS")
	)
	(segment
		(start 261.039864 -228.6)
		(end 261.039864 -229.235)
		(width 0.508)
		(layer "F.Cu")
		(net "TPS74801_1V26_STBY_BIAS")
	)
	(segment
		(start 260.023864 -230.560372)
		(end 261.039864 -230.560372)
		(width 0.508)
		(layer "F.Cu")
		(net "TPS74801_1V26_STBY_BIAS")
	)
	(via
		(at 261.039864 -229.235)
		(size 0.7112)
		(drill 0.3556)
		(layers "F.Cu" "B.Cu")
		(net "TPS74801_1V26_STBY_BIAS")
	)
	(via
		(at 263.779 -232.283)
		(size 0.7112)
		(drill 0.3556)
		(layers "F.Cu" "B.Cu")
		(net "TPS74801_P1V26_STBY_IN")
	)
	(via
		(at 263.779 -217.17)
		(size 0.7112)
		(drill 0.3556)
		(layers "F.Cu" "B.Cu")
		(net "TPS74801_1V26_STBY_OUT")
	)
	(segment
		(start 302.598328 -59.9821)
		(end 302.530764 -59.9821)
		(width 0.127)
		(layer "F.Cu")
		(net "SMB_LAN_ALERT_N")
	)
	(segment
		(start 302.530764 -59.9821)
		(end 302.192436 -60.320428)
		(width 0.127)
		(layer "F.Cu")
		(net "SMB_LAN_ALERT_N")
	)
	(segment
		(start 305.53025 -59.97575)
		(end 302.604678 -59.97575)
		(width 0.127)
		(layer "F.Cu")
		(net "SMB_LAN_ALERT_N")
	)
	(segment
		(start 301.752 -60.198)
		(end 301.874428 -60.320428)
		(width 0.127)
		(layer "F.Cu")
		(net "SMB_LAN_ALERT_N")
	)
	(segment
		(start 302.604678 -59.97575)
		(end 302.598328 -59.9821)
		(width 0.127)
		(layer "F.Cu")
		(net "SMB_LAN_ALERT_N")
	)
	(segment
		(start 306.197 -59.309)
		(end 305.53025 -59.97575)
		(width 0.127)
		(layer "F.Cu")
		(net "SMB_LAN_ALERT_N")
	)
	(segment
		(start 307.595016 -58.799984)
		(end 307.086 -59.309)
		(width 0.127)
		(layer "F.Cu")
		(net "SMB_LAN_ALERT_N")
	)
	(segment
		(start 301.874428 -60.320428)
		(end 301.879 -60.320428)
		(width 0.127)
		(layer "F.Cu")
		(net "SMB_LAN_ALERT_N")
	)
	(segment
		(start 307.086 -59.309)
		(end 306.197 -59.309)
		(width 0.127)
		(layer "F.Cu")
		(net "SMB_LAN_ALERT_N")
	)
	(segment
		(start 308.675024 -58.799984)
		(end 307.595016 -58.799984)
		(width 0.127)
		(layer "F.Cu")
		(net "SMB_LAN_ALERT_N")
	)
	(segment
		(start 302.192436 -60.320428)
		(end 301.879 -60.320428)
		(width 0.127)
		(layer "F.Cu")
		(net "SMB_LAN_ALERT_N")
	)
	(segment
		(start 300.9265 -60.198)
		(end 301.752 -60.198)
		(width 0.127)
		(layer "F.Cu")
		(net "SMB_LAN_ALERT_N")
	)
	(via
		(at 301.879 -60.320428)
		(size 0.7112)
		(drill 0.3556)
		(layers "F.Cu" "B.Cu")
		(net "SMB_LAN_ALERT_N")
	)
	(segment
		(start 257.937 -222.504)
		(end 257.937 -223.503236)
		(width 0.254)
		(layer "F.Cu")
		(net "TPS74801_1V26_STBY_SS")
	)
	(segment
		(start 259.69341 -223.3549)
		(end 259.62864 -223.3422)
		(width 0.254)
		(layer "F.Cu")
		(net "TPS74801_1V26_STBY_SS")
	)
	(segment
		(start 259.62864 -223.3422)
		(end 258.098036 -223.3422)
		(width 0.254)
		(layer "F.Cu")
		(net "TPS74801_1V26_STBY_SS")
	)
	(segment
		(start 260.470142 -223.3549)
		(end 259.69341 -223.3549)
		(width 0.254)
		(layer "F.Cu")
		(net "TPS74801_1V26_STBY_SS")
	)
	(segment
		(start 258.098036 -223.3422)
		(end 257.937 -223.503236)
		(width 0.254)
		(layer "F.Cu")
		(net "TPS74801_1V26_STBY_SS")
	)
	(segment
		(start 257.937 -223.503236)
		(end 257.928364 -223.511872)
		(width 0.254)
		(layer "F.Cu")
		(net "TPS74801_1V26_STBY_SS")
	)
	(via
		(at 257.937 -222.504)
		(size 0.7112)
		(drill 0.3556)
		(layers "F.Cu" "B.Cu")
		(net "TPS74801_1V26_STBY_SS")
	)
	(segment
		(start 286.434784 -174.64024)
		(end 286.033718 -174.239174)
		(width 0.1143)
		(layer "F.Cu")
		(net "MB0_PRESNET#")
	)
	(segment
		(start 286.033718 -174.239174)
		(end 286.033718 -174.231808)
		(width 0.1143)
		(layer "F.Cu")
		(net "MB0_PRESNET#")
	)
	(via
		(at 278.257 -173.153324)
		(size 0.7112)
		(drill 0.3556)
		(layers "F.Cu" "B.Cu")
		(net "MB0_PRESNET#")
	)
	(via
		(at 286.033718 -174.231808)
		(size 0.508)
		(drill 0.254)
		(layers "F.Cu" "B.Cu")
		(net "MB0_PRESNET#")
	)
	(segment
		(start 279.973024 -174.4345)
		(end 278.691848 -173.153324)
		(width 0.1143)
		(layer "B.Cu")
		(net "MB0_PRESNET#")
	)
	(segment
		(start 285.029656 -174.231808)
		(end 284.664658 -174.596806)
		(width 0.1143)
		(layer "B.Cu")
		(net "MB0_PRESNET#")
	)
	(segment
		(start 286.033718 -174.231808)
		(end 285.029656 -174.231808)
		(width 0.1143)
		(layer "B.Cu")
		(net "MB0_PRESNET#")
	)
	(segment
		(start 278.257 -173.153324)
		(end 277.659084 -173.153324)
		(width 0.1143)
		(layer "B.Cu")
		(net "MB0_PRESNET#")
	)
	(segment
		(start 277.60676 -173.101)
		(end 275.209 -173.101)
		(width 0.1143)
		(layer "B.Cu")
		(net "MB0_PRESNET#")
	)
	(segment
		(start 283.759656 -174.4345)
		(end 279.973024 -174.4345)
		(width 0.1143)
		(layer "B.Cu")
		(net "MB0_PRESNET#")
	)
	(segment
		(start 277.659084 -173.153324)
		(end 277.60676 -173.101)
		(width 0.1143)
		(layer "B.Cu")
		(net "MB0_PRESNET#")
	)
	(segment
		(start 274.701 -173.609)
		(end 274.6375 -173.609)
		(width 0.1143)
		(layer "B.Cu")
		(net "MB0_PRESNET#")
	)
	(segment
		(start 278.691848 -173.153324)
		(end 278.257 -173.153324)
		(width 0.1143)
		(layer "B.Cu")
		(net "MB0_PRESNET#")
	)
	(segment
		(start 275.209 -173.101)
		(end 274.701 -173.609)
		(width 0.1143)
		(layer "B.Cu")
		(net "MB0_PRESNET#")
	)
	(segment
		(start 284.664658 -174.596806)
		(end 283.921962 -174.596806)
		(width 0.1143)
		(layer "B.Cu")
		(net "MB0_PRESNET#")
	)
	(segment
		(start 283.921962 -174.596806)
		(end 283.759656 -174.4345)
		(width 0.1143)
		(layer "B.Cu")
		(net "MB0_PRESNET#")
	)
	(segment
		(start 46.594522 -125.97384)
		(end 54.394862 -118.1735)
		(width 0.254)
		(layer "F.Cu")
		(net "P1V26_STBY_PG")
	)
	(segment
		(start 30.7848 -141.5542)
		(end 31.623 -140.716)
		(width 0.254)
		(layer "F.Cu")
		(net "P1V26_STBY_PG")
	)
	(segment
		(start 281.051 -212.6615)
		(end 281.8765 -212.6615)
		(width 0.254)
		(layer "F.Cu")
		(net "P1V26_STBY_PG")
	)
	(segment
		(start 54.394862 -118.1735)
		(end 56.219598 -118.1735)
		(width 0.254)
		(layer "F.Cu")
		(net "P1V26_STBY_PG")
	)
	(segment
		(start 281.8765 -212.6615)
		(end 282.194 -212.344)
		(width 0.254)
		(layer "F.Cu")
		(net "P1V26_STBY_PG")
	)
	(segment
		(start 31.623 -140.716)
		(end 31.623 -135.130794)
		(width 0.254)
		(layer "F.Cu")
		(net "P1V26_STBY_PG")
	)
	(segment
		(start 262.294878 -227.129594)
		(end 262.294878 -228.981)
		(width 0.254)
		(layer "F.Cu")
		(net "P1V26_STBY_PG")
	)
	(segment
		(start 40.779954 -125.97384)
		(end 46.594522 -125.97384)
		(width 0.254)
		(layer "F.Cu")
		(net "P1V26_STBY_PG")
	)
	(segment
		(start 31.623 -135.130794)
		(end 40.779954 -125.97384)
		(width 0.254)
		(layer "F.Cu")
		(net "P1V26_STBY_PG")
	)
	(segment
		(start 30.7848 -148.406612)
		(end 30.7848 -141.5542)
		(width 0.254)
		(layer "F.Cu")
		(net "P1V26_STBY_PG")
	)
	(segment
		(start 262.294878 -230.448358)
		(end 262.294878 -228.981)
		(width 0.254)
		(layer "F.Cu")
		(net "P1V26_STBY_PG")
	)
	(segment
		(start 262.182864 -230.560372)
		(end 262.294878 -230.448358)
		(width 0.254)
		(layer "F.Cu")
		(net "P1V26_STBY_PG")
	)
	(segment
		(start 56.219598 -118.1735)
		(end 66.270886 -108.122212)
		(width 0.254)
		(layer "F.Cu")
		(net "P1V26_STBY_PG")
	)
	(via
		(at 260.986016 -216.754964)
		(size 0.508)
		(drill 0.254)
		(layers "F.Cu" "B.Cu")
		(net "P1V26_STBY_PG")
	)
	(via
		(at 262.294878 -228.981)
		(size 0.5588)
		(drill 0.3048)
		(layers "F.Cu" "B.Cu")
		(net "P1V26_STBY_PG")
	)
	(via
		(at 44.942252 -172.83811)
		(size 0.508)
		(drill 0.254)
		(layers "F.Cu" "B.Cu")
		(net "P1V26_STBY_PG")
	)
	(via
		(at 257.937 -221.361)
		(size 0.7112)
		(drill 0.3556)
		(layers "F.Cu" "B.Cu")
		(net "P1V26_STBY_PG")
	)
	(via
		(at 282.194 -212.344)
		(size 0.5588)
		(drill 0.3048)
		(layers "F.Cu" "B.Cu")
		(net "P1V26_STBY_PG")
	)
	(via
		(at 30.7848 -148.406612)
		(size 0.508)
		(drill 0.254)
		(layers "F.Cu" "B.Cu")
		(net "P1V26_STBY_PG")
	)
	(segment
		(start 44.942252 -172.83811)
		(end 41.105328 -169.001186)
		(width 0.254)
		(layer "B.Cu")
		(net "P1V26_STBY_PG")
	)
	(segment
		(start 257.937 -224.926144)
		(end 261.991856 -228.981)
		(width 0.254)
		(layer "B.Cu")
		(net "P1V26_STBY_PG")
	)
	(segment
		(start 41.105328 -169.001186)
		(end 41.105328 -159.088328)
		(width 0.254)
		(layer "B.Cu")
		(net "P1V26_STBY_PG")
	)
	(segment
		(start 31.496 -149.479)
		(end 31.496 -149.117812)
		(width 0.254)
		(layer "B.Cu")
		(net "P1V26_STBY_PG")
	)
	(segment
		(start 264.90803 -212.83295)
		(end 281.70505 -212.83295)
		(width 0.254)
		(layer "B.Cu")
		(net "P1V26_STBY_PG")
	)
	(segment
		(start 257.937 -221.361)
		(end 257.937 -224.926144)
		(width 0.254)
		(layer "B.Cu")
		(net "P1V26_STBY_PG")
	)
	(segment
		(start 260.986016 -216.754964)
		(end 257.937 -219.80398)
		(width 0.254)
		(layer "B.Cu")
		(net "P1V26_STBY_PG")
	)
	(segment
		(start 257.937 -219.80398)
		(end 257.937 -221.361)
		(width 0.254)
		(layer "B.Cu")
		(net "P1V26_STBY_PG")
	)
	(segment
		(start 260.986016 -216.754964)
		(end 264.90803 -212.83295)
		(width 0.254)
		(layer "B.Cu")
		(net "P1V26_STBY_PG")
	)
	(segment
		(start 31.496 -149.117812)
		(end 30.7848 -148.406612)
		(width 0.254)
		(layer "B.Cu")
		(net "P1V26_STBY_PG")
	)
	(segment
		(start 281.70505 -212.83295)
		(end 282.194 -212.344)
		(width 0.254)
		(layer "B.Cu")
		(net "P1V26_STBY_PG")
	)
	(segment
		(start 261.991856 -228.981)
		(end 262.294878 -228.981)
		(width 0.254)
		(layer "B.Cu")
		(net "P1V26_STBY_PG")
	)
	(segment
		(start 41.105328 -159.088328)
		(end 31.496 -149.479)
		(width 0.254)
		(layer "B.Cu")
		(net "P1V26_STBY_PG")
	)
	(segment
		(start 65.784222 -179.959)
		(end 161.844228 -179.959)
		(width 0.254)
		(layer "In2.Cu")
		(net "P1V26_STBY_PG")
	)
	(segment
		(start 161.844228 -179.959)
		(end 169.261028 -187.3758)
		(width 0.254)
		(layer "In2.Cu")
		(net "P1V26_STBY_PG")
	)
	(segment
		(start 169.261028 -187.3758)
		(end 218.417648 -187.3758)
		(width 0.254)
		(layer "In2.Cu")
		(net "P1V26_STBY_PG")
	)
	(segment
		(start 219.700348 -186.0931)
		(end 253.54153 -186.0931)
		(width 0.254)
		(layer "In2.Cu")
		(net "P1V26_STBY_PG")
	)
	(segment
		(start 50.344578 -177.926746)
		(end 63.751968 -177.926746)
		(width 0.254)
		(layer "In2.Cu")
		(net "P1V26_STBY_PG")
	)
	(segment
		(start 260.866128 -193.417698)
		(end 260.866128 -216.635076)
		(width 0.254)
		(layer "In2.Cu")
		(net "P1V26_STBY_PG")
	)
	(segment
		(start 45.255942 -172.83811)
		(end 50.344578 -177.926746)
		(width 0.254)
		(layer "In2.Cu")
		(net "P1V26_STBY_PG")
	)
	(segment
		(start 218.417648 -187.3758)
		(end 219.700348 -186.0931)
		(width 0.254)
		(layer "In2.Cu")
		(net "P1V26_STBY_PG")
	)
	(segment
		(start 63.751968 -177.926746)
		(end 65.784222 -179.959)
		(width 0.254)
		(layer "In2.Cu")
		(net "P1V26_STBY_PG")
	)
	(segment
		(start 260.866128 -216.635076)
		(end 260.986016 -216.754964)
		(width 0.254)
		(layer "In2.Cu")
		(net "P1V26_STBY_PG")
	)
	(segment
		(start 253.54153 -186.0931)
		(end 260.866128 -193.417698)
		(width 0.254)
		(layer "In2.Cu")
		(net "P1V26_STBY_PG")
	)
	(segment
		(start 44.942252 -172.83811)
		(end 45.255942 -172.83811)
		(width 0.254)
		(layer "In2.Cu")
		(net "P1V26_STBY_PG")
	)
	(segment
		(start 100.08616 -31.3436)
		(end 100.08616 -26.471626)
		(width 0.1397)
		(layer "B.Cu")
		(net "PCIE_SAS_CPU_RX_N4")
	)
	(segment
		(start 127.721614 -14.117828)
		(end 148.445474 -34.841688)
		(width 0.1397)
		(layer "B.Cu")
		(net "PCIE_SAS_CPU_RX_N4")
	)
	(segment
		(start 171.256452 -52.552854)
		(end 171.256452 -74.168)
		(width 0.1397)
		(layer "B.Cu")
		(net "PCIE_SAS_CPU_RX_N4")
	)
	(segment
		(start 154.28087 -35.314128)
		(end 171.070524 -52.103782)
		(width 0.1397)
		(layer "B.Cu")
		(net "PCIE_SAS_CPU_RX_N4")
	)
	(segment
		(start 170.482514 -74.597514)
		(end 170.383708 -74.498708)
		(width 0.1397)
		(layer "B.Cu")
		(net "PCIE_SAS_CPU_RX_N4")
	)
	(segment
		(start 149.137116 -35.1282)
		(end 153.831798 -35.1282)
		(width 0.1397)
		(layer "B.Cu")
		(net "PCIE_SAS_CPU_RX_N4")
	)
	(segment
		(start 108.308394 -18.249392)
		(end 116.219478 -18.249392)
		(width 0.1397)
		(layer "B.Cu")
		(net "PCIE_SAS_CPU_RX_N4")
	)
	(segment
		(start 100.272088 -26.022554)
		(end 107.859322 -18.43532)
		(width 0.1397)
		(layer "B.Cu")
		(net "PCIE_SAS_CPU_RX_N4")
	)
	(segment
		(start 116.91112 -17.96288)
		(end 120.756172 -14.117828)
		(width 0.1397)
		(layer "B.Cu")
		(net "PCIE_SAS_CPU_RX_N4")
	)
	(segment
		(start 170.383708 -73.816718)
		(end 170.450256 -73.75017)
		(width 0.1397)
		(layer "B.Cu")
		(net "PCIE_SAS_CPU_RX_N4")
	)
	(segment
		(start 171.119546 -74.498454)
		(end 171.020486 -74.597514)
		(width 0.1397)
		(layer "B.Cu")
		(net "PCIE_SAS_CPU_RX_N4")
	)
	(segment
		(start 121.205244 -13.9319)
		(end 127.272542 -13.9319)
		(width 0.1397)
		(layer "B.Cu")
		(net "PCIE_SAS_CPU_RX_N4")
	)
	(arc
		(start 153.831798 -35.1282)
		(mid 154.074802 -35.176536)
		(end 154.28087 -35.314128)
		(width 0.1397)
		(layer "B.Cu")
		(net "PCIE_SAS_CPU_RX_N4")
	)
	(arc
		(start 100.08616 -26.471626)
		(mid 100.134496 -26.228622)
		(end 100.272088 -26.022554)
		(width 0.1397)
		(layer "B.Cu")
		(net "PCIE_SAS_CPU_RX_N4")
	)
	(arc
		(start 171.070524 -52.103782)
		(mid 171.208193 -52.309818)
		(end 171.256452 -52.552854)
		(width 0.1397)
		(layer "B.Cu")
		(net "PCIE_SAS_CPU_RX_N4")
	)
	(arc
		(start 171.020486 -74.597514)
		(mid 170.7515 -74.708932)
		(end 170.482514 -74.597514)
		(width 0.1397)
		(layer "B.Cu")
		(net "PCIE_SAS_CPU_RX_N4")
	)
	(arc
		(start 171.256452 -74.168)
		(mid 171.220876 -74.346851)
		(end 171.119546 -74.498454)
		(width 0.1397)
		(layer "B.Cu")
		(net "PCIE_SAS_CPU_RX_N4")
	)
	(arc
		(start 107.859322 -18.43532)
		(mid 108.065358 -18.297651)
		(end 108.308394 -18.249392)
		(width 0.1397)
		(layer "B.Cu")
		(net "PCIE_SAS_CPU_RX_N4")
	)
	(arc
		(start 127.272542 -13.9319)
		(mid 127.515546 -13.980236)
		(end 127.721614 -14.117828)
		(width 0.1397)
		(layer "B.Cu")
		(net "PCIE_SAS_CPU_RX_N4")
	)
	(arc
		(start 148.445474 -34.841688)
		(mid 148.762788 -35.053774)
		(end 149.137116 -35.1282)
		(width 0.1397)
		(layer "B.Cu")
		(net "PCIE_SAS_CPU_RX_N4")
	)
	(arc
		(start 170.383708 -74.498708)
		(mid 170.24259 -74.15775)
		(end 170.383708 -73.816718)
		(width 0.1397)
		(layer "B.Cu")
		(net "PCIE_SAS_CPU_RX_N4")
	)
	(arc
		(start 116.219478 -18.249392)
		(mid 116.593787 -18.174919)
		(end 116.91112 -17.96288)
		(width 0.1397)
		(layer "B.Cu")
		(net "PCIE_SAS_CPU_RX_N4")
	)
	(arc
		(start 120.756172 -14.117828)
		(mid 120.962208 -13.980159)
		(end 121.205244 -13.9319)
		(width 0.1397)
		(layer "B.Cu")
		(net "PCIE_SAS_CPU_RX_N4")
	)
	(segment
		(start 260.096 -227.203)
		(end 257.937 -227.203)
		(width 0.254)
		(layer "F.Cu")
		(net "TPS74801_1V26_STBY_EN")
	)
	(segment
		(start 257.928364 -228.210872)
		(end 257.937 -228.202236)
		(width 0.254)
		(layer "F.Cu")
		(net "TPS74801_1V26_STBY_EN")
	)
	(segment
		(start 260.470142 -226.828858)
		(end 260.096 -227.203)
		(width 0.254)
		(layer "F.Cu")
		(net "TPS74801_1V26_STBY_EN")
	)
	(segment
		(start 257.928364 -229.226872)
		(end 257.928364 -230.323136)
		(width 0.254)
		(layer "F.Cu")
		(net "TPS74801_1V26_STBY_EN")
	)
	(segment
		(start 260.470142 -225.954844)
		(end 260.470142 -226.828858)
		(width 0.254)
		(layer "F.Cu")
		(net "TPS74801_1V26_STBY_EN")
	)
	(segment
		(start 257.928364 -230.323136)
		(end 257.8735 -230.378)
		(width 0.254)
		(layer "F.Cu")
		(net "TPS74801_1V26_STBY_EN")
	)
	(segment
		(start 257.928364 -229.226872)
		(end 257.928364 -228.210872)
		(width 0.254)
		(layer "F.Cu")
		(net "TPS74801_1V26_STBY_EN")
	)
	(segment
		(start 257.937 -228.202236)
		(end 257.937 -227.203)
		(width 0.254)
		(layer "F.Cu")
		(net "TPS74801_1V26_STBY_EN")
	)
	(via
		(at 257.937 -227.203)
		(size 0.7112)
		(drill 0.3556)
		(layers "F.Cu" "B.Cu")
		(net "TPS74801_1V26_STBY_EN")
	)
	(segment
		(start 299.597826 -174.19701)
		(end 299.634402 -174.233586)
		(width 0.1143)
		(layer "F.Cu")
		(net "LOW_HEX_1")
	)
	(segment
		(start 299.59173 -174.19701)
		(end 299.597826 -174.19701)
		(width 0.1143)
		(layer "F.Cu")
		(net "LOW_HEX_1")
	)
	(segment
		(start 299.23486 -173.84014)
		(end 299.59173 -174.19701)
		(width 0.1143)
		(layer "F.Cu")
		(net "LOW_HEX_1")
	)
	(via
		(at 303.767998 -173.697646)
		(size 0.5588)
		(drill 0.3048)
		(layers "F.Cu" "B.Cu")
		(net "LOW_HEX_1")
	)
	(via
		(at 299.634402 -174.233586)
		(size 0.508)
		(drill 0.254)
		(layers "F.Cu" "B.Cu")
		(net "LOW_HEX_1")
	)
	(segment
		(start 300.590712 -173.482)
		(end 299.839126 -174.233586)
		(width 0.127)
		(layer "In2.Cu")
		(net "LOW_HEX_1")
	)
	(segment
		(start 303.767998 -173.697646)
		(end 303.171352 -173.101)
		(width 0.127)
		(layer "In2.Cu")
		(net "LOW_HEX_1")
	)
	(segment
		(start 301.498 -173.482)
		(end 300.590712 -173.482)
		(width 0.127)
		(layer "In2.Cu")
		(net "LOW_HEX_1")
	)
	(segment
		(start 299.839126 -174.233586)
		(end 299.634402 -174.233586)
		(width 0.127)
		(layer "In2.Cu")
		(net "LOW_HEX_1")
	)
	(segment
		(start 301.879 -173.101)
		(end 301.498 -173.482)
		(width 0.127)
		(layer "In2.Cu")
		(net "LOW_HEX_1")
	)
	(segment
		(start 303.171352 -173.101)
		(end 301.879 -173.101)
		(width 0.127)
		(layer "In2.Cu")
		(net "LOW_HEX_1")
	)
	(segment
		(start 318.5541 -174.4726)
		(end 331.099668 -174.4726)
		(width 0.127)
		(layer "In5.Cu")
		(net "LOW_HEX_1")
	)
	(segment
		(start 331.099668 -174.4726)
		(end 332.966568 -172.6057)
		(width 0.127)
		(layer "In5.Cu")
		(net "LOW_HEX_1")
	)
	(segment
		(start 346.198698 -13.97)
		(end 347.446092 -13.97)
		(width 0.127)
		(layer "In5.Cu")
		(net "LOW_HEX_1")
	)
	(segment
		(start 352.810064 -6.326124)
		(end 351.984564 -5.500624)
		(width 0.127)
		(layer "In5.Cu")
		(net "LOW_HEX_1")
	)
	(segment
		(start 335.788 -169.936668)
		(end 335.788 -160.092898)
		(width 0.127)
		(layer "In5.Cu")
		(net "LOW_HEX_1")
	)
	(segment
		(start 336.7913 -81.5467)
		(end 336.7913 -23.377398)
		(width 0.127)
		(layer "In5.Cu")
		(net "LOW_HEX_1")
	)
	(segment
		(start 336.567018 -159.31388)
		(end 336.567018 -158.903416)
		(width 0.127)
		(layer "In5.Cu")
		(net "LOW_HEX_1")
	)
	(segment
		(start 333.756 -84.582)
		(end 336.7913 -81.5467)
		(width 0.127)
		(layer "In5.Cu")
		(net "LOW_HEX_1")
	)
	(segment
		(start 335.788 -143.34617)
		(end 327.6473 -135.20547)
		(width 0.127)
		(layer "In5.Cu")
		(net "LOW_HEX_1")
	)
	(segment
		(start 327.6473 -135.20547)
		(end 327.6473 -114.427)
		(width 0.127)
		(layer "In5.Cu")
		(net "LOW_HEX_1")
	)
	(segment
		(start 304.517298 -174.446946)
		(end 309.81777 -174.446946)
		(width 0.127)
		(layer "In5.Cu")
		(net "LOW_HEX_1")
	)
	(segment
		(start 335.788 -158.124398)
		(end 335.788 -143.34617)
		(width 0.127)
		(layer "In5.Cu")
		(net "LOW_HEX_1")
	)
	(segment
		(start 336.7913 -23.377398)
		(end 346.198698 -13.97)
		(width 0.127)
		(layer "In5.Cu")
		(net "LOW_HEX_1")
	)
	(segment
		(start 327.6473 -114.427)
		(end 326.517 -113.2967)
		(width 0.127)
		(layer "In5.Cu")
		(net "LOW_HEX_1")
	)
	(segment
		(start 309.81777 -174.446946)
		(end 310.630824 -175.26)
		(width 0.127)
		(layer "In5.Cu")
		(net "LOW_HEX_1")
	)
	(segment
		(start 352.810064 -8.606028)
		(end 352.810064 -6.326124)
		(width 0.127)
		(layer "In5.Cu")
		(net "LOW_HEX_1")
	)
	(segment
		(start 324.6247 -99.1743)
		(end 333.756 -90.043)
		(width 0.127)
		(layer "In5.Cu")
		(net "LOW_HEX_1")
	)
	(segment
		(start 335.788 -160.092898)
		(end 336.567018 -159.31388)
		(width 0.127)
		(layer "In5.Cu")
		(net "LOW_HEX_1")
	)
	(segment
		(start 303.767998 -173.697646)
		(end 304.517298 -174.446946)
		(width 0.127)
		(layer "In5.Cu")
		(net "LOW_HEX_1")
	)
	(segment
		(start 326.517 -110.617)
		(end 324.6247 -108.7247)
		(width 0.127)
		(layer "In5.Cu")
		(net "LOW_HEX_1")
	)
	(segment
		(start 317.7667 -175.26)
		(end 318.5541 -174.4726)
		(width 0.127)
		(layer "In5.Cu")
		(net "LOW_HEX_1")
	)
	(segment
		(start 324.6247 -108.7247)
		(end 324.6247 -99.1743)
		(width 0.127)
		(layer "In5.Cu")
		(net "LOW_HEX_1")
	)
	(segment
		(start 310.630824 -175.26)
		(end 317.7667 -175.26)
		(width 0.127)
		(layer "In5.Cu")
		(net "LOW_HEX_1")
	)
	(segment
		(start 332.966568 -172.6057)
		(end 333.118968 -172.6057)
		(width 0.127)
		(layer "In5.Cu")
		(net "LOW_HEX_1")
	)
	(segment
		(start 333.756 -90.043)
		(end 333.756 -84.582)
		(width 0.127)
		(layer "In5.Cu")
		(net "LOW_HEX_1")
	)
	(segment
		(start 336.567018 -158.903416)
		(end 335.788 -158.124398)
		(width 0.127)
		(layer "In5.Cu")
		(net "LOW_HEX_1")
	)
	(segment
		(start 333.118968 -172.6057)
		(end 335.788 -169.936668)
		(width 0.127)
		(layer "In5.Cu")
		(net "LOW_HEX_1")
	)
	(segment
		(start 347.446092 -13.97)
		(end 352.810064 -8.606028)
		(width 0.127)
		(layer "In5.Cu")
		(net "LOW_HEX_1")
	)
	(segment
		(start 326.517 -113.2967)
		(end 326.517 -110.617)
		(width 0.127)
		(layer "In5.Cu")
		(net "LOW_HEX_1")
	)
	(segment
		(start 298.78528 -174.28972)
		(end 298.78528 -174.28718)
		(width 0.1143)
		(layer "F.Cu")
		(net "LOW_HEX_2")
	)
	(segment
		(start 298.78528 -174.28718)
		(end 298.83608 -174.23638)
		(width 0.1143)
		(layer "F.Cu")
		(net "LOW_HEX_2")
	)
	(segment
		(start 298.43476 -174.64024)
		(end 298.78528 -174.28972)
		(width 0.1143)
		(layer "F.Cu")
		(net "LOW_HEX_2")
	)
	(via
		(at 304.685954 -173.727872)
		(size 0.5588)
		(drill 0.3048)
		(layers "F.Cu" "B.Cu")
		(net "LOW_HEX_2")
	)
	(via
		(at 298.83608 -174.23638)
		(size 0.508)
		(drill 0.254)
		(layers "F.Cu" "B.Cu")
		(net "LOW_HEX_2")
	)
	(segment
		(start 301.207424 -173.19752)
		(end 300.029372 -173.19752)
		(width 0.127)
		(layer "In2.Cu")
		(net "LOW_HEX_2")
	)
	(segment
		(start 304.685954 -173.727872)
		(end 303.805082 -172.847)
		(width 0.127)
		(layer "In2.Cu")
		(net "LOW_HEX_2")
	)
	(segment
		(start 303.805082 -172.847)
		(end 301.557944 -172.847)
		(width 0.127)
		(layer "In2.Cu")
		(net "LOW_HEX_2")
	)
	(segment
		(start 298.990512 -174.23638)
		(end 298.83608 -174.23638)
		(width 0.127)
		(layer "In2.Cu")
		(net "LOW_HEX_2")
	)
	(segment
		(start 300.029372 -173.19752)
		(end 298.990512 -174.23638)
		(width 0.127)
		(layer "In2.Cu")
		(net "LOW_HEX_2")
	)
	(segment
		(start 301.557944 -172.847)
		(end 301.207424 -173.19752)
		(width 0.127)
		(layer "In2.Cu")
		(net "LOW_HEX_2")
	)
	(segment
		(start 325.498206 -171.071794)
		(end 324.6247 -171.9453)
		(width 0.127)
		(layer "In5.Cu")
		(net "LOW_HEX_2")
	)
	(segment
		(start 334.2513 -166.95293)
		(end 330.132436 -171.071794)
		(width 0.127)
		(layer "In5.Cu")
		(net "LOW_HEX_2")
	)
	(segment
		(start 319.405 -130.222498)
		(end 328.184002 -139.0015)
		(width 0.127)
		(layer "In5.Cu")
		(net "LOW_HEX_2")
	)
	(segment
		(start 349.985584 -9.27481)
		(end 346.814394 -12.446)
		(width 0.127)
		(layer "In5.Cu")
		(net "LOW_HEX_2")
	)
	(segment
		(start 334.899 -32.258)
		(end 333.976218 -33.180782)
		(width 0.127)
		(layer "In5.Cu")
		(net "LOW_HEX_2")
	)
	(segment
		(start 316.073282 -173.736)
		(end 311.658 -173.736)
		(width 0.127)
		(layer "In5.Cu")
		(net "LOW_HEX_2")
	)
	(segment
		(start 345.560904 -12.446)
		(end 334.899 -23.107904)
		(width 0.127)
		(layer "In5.Cu")
		(net "LOW_HEX_2")
	)
	(segment
		(start 319.405 -127.932434)
		(end 319.405 -130.222498)
		(width 0.127)
		(layer "In5.Cu")
		(net "LOW_HEX_2")
	)
	(segment
		(start 314.2615 -116.1415)
		(end 314.2615 -122.788934)
		(width 0.127)
		(layer "In5.Cu")
		(net "LOW_HEX_2")
	)
	(segment
		(start 310.655462 -172.733462)
		(end 305.680364 -172.733462)
		(width 0.127)
		(layer "In5.Cu")
		(net "LOW_HEX_2")
	)
	(segment
		(start 332.232 -89.281)
		(end 320.675 -100.838)
		(width 0.127)
		(layer "In5.Cu")
		(net "LOW_HEX_2")
	)
	(segment
		(start 317.934848 -171.874434)
		(end 316.073282 -173.736)
		(width 0.127)
		(layer "In5.Cu")
		(net "LOW_HEX_2")
	)
	(segment
		(start 320.675 -100.838)
		(end 320.675 -107.569)
		(width 0.127)
		(layer "In5.Cu")
		(net "LOW_HEX_2")
	)
	(segment
		(start 318.262 -112.141)
		(end 314.2615 -116.1415)
		(width 0.127)
		(layer "In5.Cu")
		(net "LOW_HEX_2")
	)
	(segment
		(start 328.71156 -139.0015)
		(end 334.2513 -144.54124)
		(width 0.127)
		(layer "In5.Cu")
		(net "LOW_HEX_2")
	)
	(segment
		(start 320.675 -107.569)
		(end 318.262 -109.982)
		(width 0.127)
		(layer "In5.Cu")
		(net "LOW_HEX_2")
	)
	(segment
		(start 334.899 -23.107904)
		(end 334.899 -32.258)
		(width 0.127)
		(layer "In5.Cu")
		(net "LOW_HEX_2")
	)
	(segment
		(start 332.232 -82.339434)
		(end 332.232 -89.281)
		(width 0.127)
		(layer "In5.Cu")
		(net "LOW_HEX_2")
	)
	(segment
		(start 324.6247 -171.9453)
		(end 321.485514 -171.9453)
		(width 0.127)
		(layer "In5.Cu")
		(net "LOW_HEX_2")
	)
	(segment
		(start 349.985584 -7.499604)
		(end 349.985584 -9.27481)
		(width 0.127)
		(layer "In5.Cu")
		(net "LOW_HEX_2")
	)
	(segment
		(start 321.414648 -171.874434)
		(end 317.934848 -171.874434)
		(width 0.127)
		(layer "In5.Cu")
		(net "LOW_HEX_2")
	)
	(segment
		(start 334.2513 -144.54124)
		(end 334.2513 -166.95293)
		(width 0.127)
		(layer "In5.Cu")
		(net "LOW_HEX_2")
	)
	(segment
		(start 311.658 -173.736)
		(end 310.655462 -172.733462)
		(width 0.127)
		(layer "In5.Cu")
		(net "LOW_HEX_2")
	)
	(segment
		(start 346.814394 -12.446)
		(end 345.560904 -12.446)
		(width 0.127)
		(layer "In5.Cu")
		(net "LOW_HEX_2")
	)
	(segment
		(start 333.976218 -33.180782)
		(end 333.976218 -80.595216)
		(width 0.127)
		(layer "In5.Cu")
		(net "LOW_HEX_2")
	)
	(segment
		(start 318.262 -109.982)
		(end 318.262 -112.141)
		(width 0.127)
		(layer "In5.Cu")
		(net "LOW_HEX_2")
	)
	(segment
		(start 328.184002 -139.0015)
		(end 328.71156 -139.0015)
		(width 0.127)
		(layer "In5.Cu")
		(net "LOW_HEX_2")
	)
	(segment
		(start 305.680364 -172.733462)
		(end 304.685954 -173.727872)
		(width 0.127)
		(layer "In5.Cu")
		(net "LOW_HEX_2")
	)
	(segment
		(start 321.485514 -171.9453)
		(end 321.414648 -171.874434)
		(width 0.127)
		(layer "In5.Cu")
		(net "LOW_HEX_2")
	)
	(segment
		(start 330.132436 -171.071794)
		(end 325.498206 -171.071794)
		(width 0.127)
		(layer "In5.Cu")
		(net "LOW_HEX_2")
	)
	(segment
		(start 314.2615 -122.788934)
		(end 319.405 -127.932434)
		(width 0.127)
		(layer "In5.Cu")
		(net "LOW_HEX_2")
	)
	(segment
		(start 333.976218 -80.595216)
		(end 332.232 -82.339434)
		(width 0.127)
		(layer "In5.Cu")
		(net "LOW_HEX_2")
	)
	(segment
		(start 137.911078 -254.117602)
		(end 137.629392 -253.835916)
		(width 0.1016)
		(layer "F.Cu")
		(net "SAS_EXP_GF_TX_DP2")
	)
	(segment
		(start 138.000232 -256.25044)
		(end 138.000232 -254.332486)
		(width 0.1016)
		(layer "F.Cu")
		(net "SAS_EXP_GF_TX_DP2")
	)
	(segment
		(start 137.589006 -253.73838)
		(end 137.589006 -245.660164)
		(width 0.1016)
		(layer "F.Cu")
		(net "SAS_EXP_GF_TX_DP2")
	)
	(segment
		(start 138.126724 -168.248584)
		(end 126.58344 -156.7053)
		(width 0.1016)
		(layer "F.Cu")
		(net "SAS_EXP_GF_TX_DP2")
	)
	(segment
		(start 137.589006 -244.400324)
		(end 137.589006 -244.095524)
		(width 0.1016)
		(layer "F.Cu")
		(net "SAS_EXP_GF_TX_DP2")
	)
	(segment
		(start 133.247638 -99.527614)
		(end 133.334252 -99.441)
		(width 0.1016)
		(layer "F.Cu")
		(net "SAS_EXP_GF_TX_DP2")
	)
	(segment
		(start 126.128526 -116.418614)
		(end 132.530088 -110.017052)
		(width 0.1016)
		(layer "F.Cu")
		(net "SAS_EXP_GF_TX_DP2")
	)
	(segment
		(start 137.589006 -241.271044)
		(end 137.589006 -230.901748)
		(width 0.1016)
		(layer "F.Cu")
		(net "SAS_EXP_GF_TX_DP2")
	)
	(segment
		(start 138.19632 -168.318434)
		(end 138.126724 -168.248584)
		(width 0.1016)
		(layer "F.Cu")
		(net "SAS_EXP_GF_TX_DP2")
	)
	(segment
		(start 138.083036 -229.708964)
		(end 139.705588 -228.086412)
		(width 0.1016)
		(layer "F.Cu")
		(net "SAS_EXP_GF_TX_DP2")
	)
	(segment
		(start 140.6779 -225.73869)
		(end 140.6779 -174.309532)
		(width 0.1016)
		(layer "F.Cu")
		(net "SAS_EXP_GF_TX_DP2")
	)
	(segment
		(start 133.21792 -108.3564)
		(end 133.21792 -99.599496)
		(width 0.1016)
		(layer "F.Cu")
		(net "SAS_EXP_GF_TX_DP2")
	)
	(segment
		(start 137.827766 -245.182644)
		(end 137.827766 -244.877844)
		(width 0.1016)
		(layer "F.Cu")
		(net "SAS_EXP_GF_TX_DP2")
	)
	(segment
		(start 137.589006 -242.835684)
		(end 137.589006 -242.530884)
		(width 0.1016)
		(layer "F.Cu")
		(net "SAS_EXP_GF_TX_DP2")
	)
	(segment
		(start 137.827766 -243.618004)
		(end 137.827766 -243.313204)
		(width 0.1016)
		(layer "F.Cu")
		(net "SAS_EXP_GF_TX_DP2")
	)
	(segment
		(start 133.36397 -99.369118)
		(end 133.36397 -99.0854)
		(width 0.1016)
		(layer "F.Cu")
		(net "SAS_EXP_GF_TX_DP2")
	)
	(segment
		(start 125.8189 -154.859482)
		(end 125.8189 -117.166136)
		(width 0.1016)
		(layer "F.Cu")
		(net "SAS_EXP_GF_TX_DP2")
	)
	(segment
		(start 137.827766 -242.053364)
		(end 137.827766 -241.748564)
		(width 0.1016)
		(layer "F.Cu")
		(net "SAS_EXP_GF_TX_DP2")
	)
	(arc
		(start 137.708386 -243.074444)
		(mid 137.619592 -242.96963)
		(end 137.589006 -242.835684)
		(width 0.1016)
		(layer "F.Cu")
		(net "SAS_EXP_GF_TX_DP2")
	)
	(arc
		(start 137.708386 -244.639084)
		(mid 137.619592 -244.53427)
		(end 137.589006 -244.400324)
		(width 0.1016)
		(layer "F.Cu")
		(net "SAS_EXP_GF_TX_DP2")
	)
	(arc
		(start 137.708386 -245.421404)
		(mid 137.79718 -245.31659)
		(end 137.827766 -245.182644)
		(width 0.1016)
		(layer "F.Cu")
		(net "SAS_EXP_GF_TX_DP2")
	)
	(arc
		(start 133.334252 -99.441)
		(mid 133.356235 -99.408006)
		(end 133.36397 -99.369118)
		(width 0.1016)
		(layer "F.Cu")
		(net "SAS_EXP_GF_TX_DP2")
	)
	(arc
		(start 137.589006 -242.530884)
		(mid 137.619498 -242.396891)
		(end 137.708386 -242.292124)
		(width 0.1016)
		(layer "F.Cu")
		(net "SAS_EXP_GF_TX_DP2")
	)
	(arc
		(start 137.827766 -241.748564)
		(mid 137.797274 -241.614571)
		(end 137.708386 -241.509804)
		(width 0.1016)
		(layer "F.Cu")
		(net "SAS_EXP_GF_TX_DP2")
	)
	(arc
		(start 137.827766 -244.877844)
		(mid 137.797274 -244.743851)
		(end 137.708386 -244.639084)
		(width 0.1016)
		(layer "F.Cu")
		(net "SAS_EXP_GF_TX_DP2")
	)
	(arc
		(start 132.530088 -110.017052)
		(mid 133.039182 -109.255138)
		(end 133.21792 -108.3564)
		(width 0.1016)
		(layer "F.Cu")
		(net "SAS_EXP_GF_TX_DP2")
	)
	(arc
		(start 137.708386 -241.509804)
		(mid 137.619592 -241.40499)
		(end 137.589006 -241.271044)
		(width 0.1016)
		(layer "F.Cu")
		(net "SAS_EXP_GF_TX_DP2")
	)
	(arc
		(start 137.589006 -244.095524)
		(mid 137.619498 -243.961531)
		(end 137.708386 -243.856764)
		(width 0.1016)
		(layer "F.Cu")
		(net "SAS_EXP_GF_TX_DP2")
	)
	(arc
		(start 138.000232 -254.332486)
		(mid 137.977006 -254.216189)
		(end 137.911078 -254.117602)
		(width 0.1016)
		(layer "F.Cu")
		(net "SAS_EXP_GF_TX_DP2")
	)
	(arc
		(start 137.629392 -253.835916)
		(mid 137.599491 -253.791166)
		(end 137.589006 -253.73838)
		(width 0.1016)
		(layer "F.Cu")
		(net "SAS_EXP_GF_TX_DP2")
	)
	(arc
		(start 137.589006 -245.660164)
		(mid 137.619498 -245.526171)
		(end 137.708386 -245.421404)
		(width 0.1016)
		(layer "F.Cu")
		(net "SAS_EXP_GF_TX_DP2")
	)
	(arc
		(start 133.21792 -99.599496)
		(mid 133.225639 -99.560601)
		(end 133.247638 -99.527614)
		(width 0.1016)
		(layer "F.Cu")
		(net "SAS_EXP_GF_TX_DP2")
	)
	(arc
		(start 139.705588 -228.086412)
		(mid 140.42523 -227.009253)
		(end 140.6779 -225.73869)
		(width 0.1016)
		(layer "F.Cu")
		(net "SAS_EXP_GF_TX_DP2")
	)
	(arc
		(start 140.6779 -174.309532)
		(mid 140.032918 -171.067189)
		(end 138.19632 -168.318434)
		(width 0.1016)
		(layer "F.Cu")
		(net "SAS_EXP_GF_TX_DP2")
	)
	(arc
		(start 137.589006 -230.901748)
		(mid 137.717407 -230.256232)
		(end 138.083036 -229.708964)
		(width 0.1016)
		(layer "F.Cu")
		(net "SAS_EXP_GF_TX_DP2")
	)
	(arc
		(start 137.827766 -243.313204)
		(mid 137.797274 -243.179211)
		(end 137.708386 -243.074444)
		(width 0.1016)
		(layer "F.Cu")
		(net "SAS_EXP_GF_TX_DP2")
	)
	(arc
		(start 126.58344 -156.7053)
		(mid 126.017581 -155.858432)
		(end 125.8189 -154.859482)
		(width 0.1016)
		(layer "F.Cu")
		(net "SAS_EXP_GF_TX_DP2")
	)
	(arc
		(start 125.8189 -117.166136)
		(mid 125.899371 -116.761583)
		(end 126.128526 -116.418614)
		(width 0.1016)
		(layer "F.Cu")
		(net "SAS_EXP_GF_TX_DP2")
	)
	(arc
		(start 137.708386 -242.292124)
		(mid 137.79718 -242.18731)
		(end 137.827766 -242.053364)
		(width 0.1016)
		(layer "F.Cu")
		(net "SAS_EXP_GF_TX_DP2")
	)
	(arc
		(start 137.708386 -243.856764)
		(mid 137.79718 -243.75195)
		(end 137.827766 -243.618004)
		(width 0.1016)
		(layer "F.Cu")
		(net "SAS_EXP_GF_TX_DP2")
	)
	(segment
		(start 312.9915 -184.023)
		(end 311.912 -184.023)
		(width 0.1143)
		(layer "F.Cu")
		(net "BMC0_LED_DR_R_LED0")
	)
	(segment
		(start 306.832 -184.785)
		(end 306.197 -185.42)
		(width 0.1143)
		(layer "F.Cu")
		(net "BMC0_LED_DR_R_LED0")
	)
	(segment
		(start 302.09617 -184.24017)
		(end 301.634906 -184.24017)
		(width 0.1143)
		(layer "F.Cu")
		(net "BMC0_LED_DR_R_LED0")
	)
	(segment
		(start 303.276 -185.42)
		(end 302.09617 -184.24017)
		(width 0.1143)
		(layer "F.Cu")
		(net "BMC0_LED_DR_R_LED0")
	)
	(segment
		(start 307.086 -184.531)
		(end 306.832 -184.785)
		(width 0.1143)
		(layer "F.Cu")
		(net "BMC0_LED_DR_R_LED0")
	)
	(segment
		(start 306.197 -185.42)
		(end 303.276 -185.42)
		(width 0.1143)
		(layer "F.Cu")
		(net "BMC0_LED_DR_R_LED0")
	)
	(segment
		(start 311.404 -184.531)
		(end 307.086 -184.531)
		(width 0.1143)
		(layer "F.Cu")
		(net "BMC0_LED_DR_R_LED0")
	)
	(segment
		(start 311.912 -184.023)
		(end 311.404 -184.531)
		(width 0.1143)
		(layer "F.Cu")
		(net "BMC0_LED_DR_R_LED0")
	)
	(segment
		(start 314.2615 -185.293)
		(end 312.9915 -184.023)
		(width 0.1143)
		(layer "F.Cu")
		(net "BMC0_LED_DR_R_LED0")
	)
	(via
		(at 306.832 -184.785)
		(size 0.7112)
		(drill 0.3556)
		(layers "F.Cu" "B.Cu")
		(net "BMC0_LED_DR_R_LED0")
	)
	(segment
		(start 304.6603 -108.3437)
		(end 304.165 -108.839)
		(width 0.127)
		(layer "F.Cu")
		(net "CONN_10G_PRSNT2_N")
	)
	(segment
		(start 306.2605 -190.246)
		(end 306.2605 -189.71514)
		(width 0.127)
		(layer "F.Cu")
		(net "CONN_10G_PRSNT2_N")
	)
	(segment
		(start 299.593 -184.11317)
		(end 299.3771 -183.89727)
		(width 0.127)
		(layer "F.Cu")
		(net "CONN_10G_PRSNT2_N")
	)
	(segment
		(start 302.350932 -187.077096)
		(end 299.593 -184.319164)
		(width 0.127)
		(layer "F.Cu")
		(net "CONN_10G_PRSNT2_N")
	)
	(segment
		(start 312.166 -188.214)
		(end 310.134 -190.246)
		(width 0.127)
		(layer "F.Cu")
		(net "CONN_10G_PRSNT2_N")
	)
	(segment
		(start 299.339 -127.508)
		(end 294.259 -132.588)
		(width 0.127)
		(layer "F.Cu")
		(net "CONN_10G_PRSNT2_N")
	)
	(segment
		(start 313.125104 -48.400208)
		(end 313.549792 -48.400208)
		(width 0.127)
		(layer "F.Cu")
		(net "CONN_10G_PRSNT2_N")
	)
	(segment
		(start 307.5432 -101.49586)
		(end 304.6603 -104.37876)
		(width 0.127)
		(layer "F.Cu")
		(net "CONN_10G_PRSNT2_N")
	)
	(segment
		(start 298.918122 -183.89727)
		(end 298.676822 -183.65597)
		(width 0.127)
		(layer "F.Cu")
		(net "CONN_10G_PRSNT2_N")
	)
	(segment
		(start 308.386988 -95.600012)
		(end 307.5432 -96.4438)
		(width 0.127)
		(layer "F.Cu")
		(net "CONN_10G_PRSNT2_N")
	)
	(segment
		(start 302.53051 -187.077096)
		(end 302.350932 -187.077096)
		(width 0.127)
		(layer "F.Cu")
		(net "CONN_10G_PRSNT2_N")
	)
	(segment
		(start 313.549792 -48.400208)
		(end 313.563 -48.387)
		(width 0.127)
		(layer "F.Cu")
		(net "CONN_10G_PRSNT2_N")
	)
	(segment
		(start 304.165762 -187.620402)
		(end 303.073816 -187.620402)
		(width 0.127)
		(layer "F.Cu")
		(net "CONN_10G_PRSNT2_N")
	)
	(segment
		(start 298.676822 -183.65597)
		(end 298.65066 -183.65597)
		(width 0.127)
		(layer "F.Cu")
		(net "CONN_10G_PRSNT2_N")
	)
	(segment
		(start 312.166 -187.96)
		(end 312.166 -188.214)
		(width 0.127)
		(layer "F.Cu")
		(net "CONN_10G_PRSNT2_N")
	)
	(segment
		(start 298.65066 -183.65597)
		(end 298.43476 -183.44007)
		(width 0.127)
		(layer "F.Cu")
		(net "CONN_10G_PRSNT2_N")
	)
	(segment
		(start 299.339 -121.158)
		(end 299.339 -127.508)
		(width 0.127)
		(layer "F.Cu")
		(net "CONN_10G_PRSNT2_N")
	)
	(segment
		(start 299.593 -184.319164)
		(end 299.593 -184.11317)
		(width 0.127)
		(layer "F.Cu")
		(net "CONN_10G_PRSNT2_N")
	)
	(segment
		(start 304.6603 -104.37876)
		(end 304.6603 -108.3437)
		(width 0.127)
		(layer "F.Cu")
		(net "CONN_10G_PRSNT2_N")
	)
	(segment
		(start 308.675024 -95.600012)
		(end 308.386988 -95.600012)
		(width 0.127)
		(layer "F.Cu")
		(net "CONN_10G_PRSNT2_N")
	)
	(segment
		(start 303.073816 -187.620402)
		(end 302.53051 -187.077096)
		(width 0.127)
		(layer "F.Cu")
		(net "CONN_10G_PRSNT2_N")
	)
	(segment
		(start 306.2605 -189.71514)
		(end 304.165762 -187.620402)
		(width 0.127)
		(layer "F.Cu")
		(net "CONN_10G_PRSNT2_N")
	)
	(segment
		(start 313.563 -48.387)
		(end 314.706 -48.387)
		(width 0.127)
		(layer "F.Cu")
		(net "CONN_10G_PRSNT2_N")
	)
	(segment
		(start 299.3771 -183.89727)
		(end 298.918122 -183.89727)
		(width 0.127)
		(layer "F.Cu")
		(net "CONN_10G_PRSNT2_N")
	)
	(segment
		(start 304.165 -108.839)
		(end 304.165 -116.332)
		(width 0.127)
		(layer "F.Cu")
		(net "CONN_10G_PRSNT2_N")
	)
	(segment
		(start 307.5432 -96.4438)
		(end 307.5432 -101.49586)
		(width 0.127)
		(layer "F.Cu")
		(net "CONN_10G_PRSNT2_N")
	)
	(segment
		(start 310.134 -190.246)
		(end 306.2605 -190.246)
		(width 0.127)
		(layer "F.Cu")
		(net "CONN_10G_PRSNT2_N")
	)
	(segment
		(start 294.259 -132.588)
		(end 292.481 -132.588)
		(width 0.127)
		(layer "F.Cu")
		(net "CONN_10G_PRSNT2_N")
	)
	(segment
		(start 304.165 -116.332)
		(end 299.339 -121.158)
		(width 0.127)
		(layer "F.Cu")
		(net "CONN_10G_PRSNT2_N")
	)
	(via
		(at 304.20945 -135.41375)
		(size 0.5588)
		(drill 0.3048)
		(layers "F.Cu" "B.Cu")
		(net "CONN_10G_PRSNT2_N")
	)
	(via
		(at 294.0558 -134.1628)
		(size 0.7112)
		(drill 0.3556)
		(layers "F.Cu" "B.Cu")
		(net "CONN_10G_PRSNT2_N")
	)
	(via
		(at 312.166 -187.96)
		(size 0.5588)
		(drill 0.3048)
		(layers "F.Cu" "B.Cu")
		(net "CONN_10G_PRSNT2_N")
	)
	(via
		(at 307.5432 -96.4438)
		(size 0.5588)
		(drill 0.3048)
		(layers "F.Cu" "B.Cu")
		(net "CONN_10G_PRSNT2_N")
	)
	(via
		(at 292.481 -132.588)
		(size 0.5588)
		(drill 0.3048)
		(layers "F.Cu" "B.Cu")
		(net "CONN_10G_PRSNT2_N")
	)
	(via
		(at 314.706 -48.387)
		(size 0.5588)
		(drill 0.3048)
		(layers "F.Cu" "B.Cu")
		(net "CONN_10G_PRSNT2_N")
	)
	(segment
		(start 294.57015 -134.67715)
		(end 294.0558 -134.1628)
		(width 0.127)
		(layer "B.Cu")
		(net "CONN_10G_PRSNT2_N")
	)
	(segment
		(start 304.20945 -135.41375)
		(end 303.121568 -135.41375)
		(width 0.127)
		(layer "B.Cu")
		(net "CONN_10G_PRSNT2_N")
	)
	(segment
		(start 294.0558 -134.1628)
		(end 292.481 -132.588)
		(width 0.127)
		(layer "B.Cu")
		(net "CONN_10G_PRSNT2_N")
	)
	(segment
		(start 303.121568 -135.41375)
		(end 302.384968 -134.67715)
		(width 0.127)
		(layer "B.Cu")
		(net "CONN_10G_PRSNT2_N")
	)
	(segment
		(start 302.384968 -134.67715)
		(end 294.57015 -134.67715)
		(width 0.127)
		(layer "B.Cu")
		(net "CONN_10G_PRSNT2_N")
	)
	(segment
		(start 314.706 -49.53)
		(end 314.706 -48.387)
		(width 0.127)
		(layer "In2.Cu")
		(net "CONN_10G_PRSNT2_N")
	)
	(segment
		(start 310.515 -93.472)
		(end 310.515 -64.389)
		(width 0.127)
		(layer "In2.Cu")
		(net "CONN_10G_PRSNT2_N")
	)
	(segment
		(start 312.166 -186.120532)
		(end 313.4233 -184.863232)
		(width 0.127)
		(layer "In2.Cu")
		(net "CONN_10G_PRSNT2_N")
	)
	(segment
		(start 307.5432 -96.4438)
		(end 310.515 -93.472)
		(width 0.127)
		(layer "In2.Cu")
		(net "CONN_10G_PRSNT2_N")
	)
	(segment
		(start 313.4233 -184.863232)
		(end 313.4233 -177.9143)
		(width 0.127)
		(layer "In2.Cu")
		(net "CONN_10G_PRSNT2_N")
	)
	(segment
		(start 304.6857 -136.095232)
		(end 304.6857 -135.89)
		(width 0.127)
		(layer "In2.Cu")
		(net "CONN_10G_PRSNT2_N")
	)
	(segment
		(start 313.4233 -177.9143)
		(end 312.293 -176.784)
		(width 0.127)
		(layer "In2.Cu")
		(net "CONN_10G_PRSNT2_N")
	)
	(segment
		(start 316.738 -58.166)
		(end 316.738 -51.562)
		(width 0.127)
		(layer "In2.Cu")
		(net "CONN_10G_PRSNT2_N")
	)
	(segment
		(start 312.166 -187.96)
		(end 312.166 -186.120532)
		(width 0.127)
		(layer "In2.Cu")
		(net "CONN_10G_PRSNT2_N")
	)
	(segment
		(start 312.293 -143.702532)
		(end 304.6857 -136.095232)
		(width 0.127)
		(layer "In2.Cu")
		(net "CONN_10G_PRSNT2_N")
	)
	(segment
		(start 310.515 -64.389)
		(end 316.738 -58.166)
		(width 0.127)
		(layer "In2.Cu")
		(net "CONN_10G_PRSNT2_N")
	)
	(segment
		(start 304.6857 -135.89)
		(end 304.20945 -135.41375)
		(width 0.127)
		(layer "In2.Cu")
		(net "CONN_10G_PRSNT2_N")
	)
	(segment
		(start 312.293 -176.784)
		(end 312.293 -143.702532)
		(width 0.127)
		(layer "In2.Cu")
		(net "CONN_10G_PRSNT2_N")
	)
	(segment
		(start 316.738 -51.562)
		(end 314.706 -49.53)
		(width 0.127)
		(layer "In2.Cu")
		(net "CONN_10G_PRSNT2_N")
	)
	(segment
		(start 300.03496 -173.84014)
		(end 300.403768 -174.208948)
		(width 0.1143)
		(layer "F.Cu")
		(net "LOW_HEX_3")
	)
	(segment
		(start 300.403768 -174.214536)
		(end 300.42739 -174.238158)
		(width 0.1143)
		(layer "F.Cu")
		(net "LOW_HEX_3")
	)
	(segment
		(start 300.403768 -174.208948)
		(end 300.403768 -174.214536)
		(width 0.1143)
		(layer "F.Cu")
		(net "LOW_HEX_3")
	)
	(via
		(at 305.607974 -173.727872)
		(size 0.5588)
		(drill 0.3048)
		(layers "F.Cu" "B.Cu")
		(net "LOW_HEX_3")
	)
	(via
		(at 300.42739 -174.238158)
		(size 0.508)
		(drill 0.254)
		(layers "F.Cu" "B.Cu")
		(net "LOW_HEX_3")
	)
	(segment
		(start 305.103276 -174.23257)
		(end 303.653444 -174.23257)
		(width 0.127)
		(layer "In2.Cu")
		(net "LOW_HEX_3")
	)
	(segment
		(start 305.607974 -173.727872)
		(end 305.103276 -174.23257)
		(width 0.127)
		(layer "In2.Cu")
		(net "LOW_HEX_3")
	)
	(segment
		(start 303.653444 -174.23257)
		(end 303.647856 -174.238158)
		(width 0.127)
		(layer "In2.Cu")
		(net "LOW_HEX_3")
	)
	(segment
		(start 303.647856 -174.238158)
		(end 300.42739 -174.238158)
		(width 0.127)
		(layer "In2.Cu")
		(net "LOW_HEX_3")
	)
	(segment
		(start 332.74 -82.55)
		(end 332.74 -89.535)
		(width 0.127)
		(layer "In5.Cu")
		(net "LOW_HEX_3")
	)
	(segment
		(start 335.407 -23.324058)
		(end 335.407 -32.639)
		(width 0.127)
		(layer "In5.Cu")
		(net "LOW_HEX_3")
	)
	(segment
		(start 319.913 -130.011932)
		(end 328.394568 -138.4935)
		(width 0.127)
		(layer "In5.Cu")
		(net "LOW_HEX_3")
	)
	(segment
		(start 350.811084 -9.167876)
		(end 347.02496 -12.954)
		(width 0.127)
		(layer "In5.Cu")
		(net "LOW_HEX_3")
	)
	(segment
		(start 334.7593 -167.163496)
		(end 328.974196 -172.9486)
		(width 0.127)
		(layer "In5.Cu")
		(net "LOW_HEX_3")
	)
	(segment
		(start 314.7695 -122.578368)
		(end 319.913 -127.721868)
		(width 0.127)
		(layer "In5.Cu")
		(net "LOW_HEX_3")
	)
	(segment
		(start 310.274462 -173.241462)
		(end 306.094384 -173.241462)
		(width 0.127)
		(layer "In5.Cu")
		(net "LOW_HEX_3")
	)
	(segment
		(start 318.77 -111.571532)
		(end 318.77 -112.522)
		(width 0.127)
		(layer "In5.Cu")
		(net "LOW_HEX_3")
	)
	(segment
		(start 306.094384 -173.241462)
		(end 305.607974 -173.727872)
		(width 0.127)
		(layer "In5.Cu")
		(net "LOW_HEX_3")
	)
	(segment
		(start 345.777058 -12.954)
		(end 335.407 -23.324058)
		(width 0.127)
		(layer "In5.Cu")
		(net "LOW_HEX_3")
	)
	(segment
		(start 334.484218 -33.561782)
		(end 334.484218 -80.805782)
		(width 0.127)
		(layer "In5.Cu")
		(net "LOW_HEX_3")
	)
	(segment
		(start 311.277 -174.244)
		(end 310.274462 -173.241462)
		(width 0.127)
		(layer "In5.Cu")
		(net "LOW_HEX_3")
	)
	(segment
		(start 328.974196 -172.9486)
		(end 318.190118 -172.9486)
		(width 0.127)
		(layer "In5.Cu")
		(net "LOW_HEX_3")
	)
	(segment
		(start 318.190118 -172.9486)
		(end 316.894718 -174.244)
		(width 0.127)
		(layer "In5.Cu")
		(net "LOW_HEX_3")
	)
	(segment
		(start 319.913 -127.721868)
		(end 319.913 -130.011932)
		(width 0.127)
		(layer "In5.Cu")
		(net "LOW_HEX_3")
	)
	(segment
		(start 335.407 -32.639)
		(end 334.484218 -33.561782)
		(width 0.127)
		(layer "In5.Cu")
		(net "LOW_HEX_3")
	)
	(segment
		(start 334.7593 -144.330674)
		(end 334.7593 -167.163496)
		(width 0.127)
		(layer "In5.Cu")
		(net "LOW_HEX_3")
	)
	(segment
		(start 328.922126 -138.4935)
		(end 334.7593 -144.330674)
		(width 0.127)
		(layer "In5.Cu")
		(net "LOW_HEX_3")
	)
	(segment
		(start 349.985584 -5.500624)
		(end 350.811084 -6.326124)
		(width 0.127)
		(layer "In5.Cu")
		(net "LOW_HEX_3")
	)
	(segment
		(start 321.8053 -108.536232)
		(end 318.77 -111.571532)
		(width 0.127)
		(layer "In5.Cu")
		(net "LOW_HEX_3")
	)
	(segment
		(start 334.484218 -80.805782)
		(end 332.74 -82.55)
		(width 0.127)
		(layer "In5.Cu")
		(net "LOW_HEX_3")
	)
	(segment
		(start 347.02496 -12.954)
		(end 345.777058 -12.954)
		(width 0.127)
		(layer "In5.Cu")
		(net "LOW_HEX_3")
	)
	(segment
		(start 321.8053 -100.4697)
		(end 321.8053 -108.536232)
		(width 0.127)
		(layer "In5.Cu")
		(net "LOW_HEX_3")
	)
	(segment
		(start 350.811084 -6.326124)
		(end 350.811084 -9.167876)
		(width 0.127)
		(layer "In5.Cu")
		(net "LOW_HEX_3")
	)
	(segment
		(start 332.74 -89.535)
		(end 321.8053 -100.4697)
		(width 0.127)
		(layer "In5.Cu")
		(net "LOW_HEX_3")
	)
	(segment
		(start 316.894718 -174.244)
		(end 311.277 -174.244)
		(width 0.127)
		(layer "In5.Cu")
		(net "LOW_HEX_3")
	)
	(segment
		(start 328.394568 -138.4935)
		(end 328.922126 -138.4935)
		(width 0.127)
		(layer "In5.Cu")
		(net "LOW_HEX_3")
	)
	(segment
		(start 314.7695 -116.5225)
		(end 314.7695 -122.578368)
		(width 0.127)
		(layer "In5.Cu")
		(net "LOW_HEX_3")
	)
	(segment
		(start 318.77 -112.522)
		(end 314.7695 -116.5225)
		(width 0.127)
		(layer "In5.Cu")
		(net "LOW_HEX_3")
	)
	(segment
		(start 304.463958 -67.4751)
		(end 304.771806 -67.4751)
		(width 0.1397)
		(layer "F.Cu")
		(net "PCIE_10G_REFCLK_P")
	)
	(segment
		(start 305.502564 -67.028568)
		(end 307.226716 -67.028568)
		(width 0.1397)
		(layer "F.Cu")
		(net "PCIE_10G_REFCLK_P")
	)
	(segment
		(start 304.870612 -67.434206)
		(end 305.116484 -67.188334)
		(width 0.1397)
		(layer "F.Cu")
		(net "PCIE_10G_REFCLK_P")
	)
	(segment
		(start 303.763172 -67.07124)
		(end 303.957228 -67.265042)
		(width 0.1397)
		(layer "F.Cu")
		(net "PCIE_10G_REFCLK_P")
	)
	(segment
		(start 307.777896 -66.800222)
		(end 308.675024 -66.800222)
		(width 0.1397)
		(layer "F.Cu")
		(net "PCIE_10G_REFCLK_P")
	)
	(arc
		(start 303.957228 -67.265042)
		(mid 304.189703 -67.42047)
		(end 304.463958 -67.4751)
		(width 0.1397)
		(layer "F.Cu")
		(net "PCIE_10G_REFCLK_P")
	)
	(arc
		(start 304.771806 -67.4751)
		(mid 304.825267 -67.464466)
		(end 304.870612 -67.434206)
		(width 0.1397)
		(layer "F.Cu")
		(net "PCIE_10G_REFCLK_P")
	)
	(arc
		(start 307.467 -66.929)
		(mid 307.60964 -66.833691)
		(end 307.777896 -66.800222)
		(width 0.1397)
		(layer "F.Cu")
		(net "PCIE_10G_REFCLK_P")
	)
	(arc
		(start 305.116484 -67.188334)
		(mid 305.293634 -67.070059)
		(end 305.502564 -67.028568)
		(width 0.1397)
		(layer "F.Cu")
		(net "PCIE_10G_REFCLK_P")
	)
	(arc
		(start 307.226716 -67.028568)
		(mid 307.356772 -67.002698)
		(end 307.467 -66.929)
		(width 0.1397)
		(layer "F.Cu")
		(net "PCIE_10G_REFCLK_P")
	)
	(segment
		(start 123.35002 -93.349826)
		(end 123.352306 -93.349826)
		(width 0.1016)
		(layer "F.Cu")
		(net "SAS_GF_EXP_RX_DP3")
	)
	(segment
		(start 123.352306 -93.349826)
		(end 123.851162 -93.848682)
		(width 0.1016)
		(layer "F.Cu")
		(net "SAS_GF_EXP_RX_DP3")
	)
	(via
		(at 123.851162 -93.848682)
		(size 0.508)
		(drill 0.254)
		(layers "F.Cu" "B.Cu")
		(net "SAS_GF_EXP_RX_DP3")
	)
	(segment
		(start 135.736584 -253.965964)
		(end 135.632952 -253.715774)
		(width 0.1016)
		(layer "B.Cu")
		(net "SAS_GF_EXP_RX_DP3")
	)
	(segment
		(start 135.814054 -254.066802)
		(end 135.783574 -254.036322)
		(width 0.1016)
		(layer "B.Cu")
		(net "SAS_GF_EXP_RX_DP3")
	)
	(segment
		(start 128.85293 -96.015302)
		(end 128.531874 -96.015302)
		(width 0.1016)
		(layer "B.Cu")
		(net "SAS_GF_EXP_RX_DP3")
	)
	(segment
		(start 126.643638 -94.730062)
		(end 124.097034 -94.730062)
		(width 0.1016)
		(layer "B.Cu")
		(net "SAS_GF_EXP_RX_DP3")
	)
	(segment
		(start 130.98907 -97.63633)
		(end 129.73177 -96.37903)
		(width 0.1016)
		(layer "B.Cu")
		(net "SAS_GF_EXP_RX_DP3")
	)
	(segment
		(start 136.368282 -234.36707)
		(end 136.749282 -233.98607)
		(width 0.1016)
		(layer "B.Cu")
		(net "SAS_GF_EXP_RX_DP3")
	)
	(segment
		(start 135.594852 -253.524766)
		(end 135.594852 -236.234224)
		(width 0.1016)
		(layer "B.Cu")
		(net "SAS_GF_EXP_RX_DP3")
	)
	(segment
		(start 135.999982 -256.50444)
		(end 135.999982 -254.515874)
		(width 0.1016)
		(layer "B.Cu")
		(net "SAS_GF_EXP_RX_DP3")
	)
	(segment
		(start 123.58243 -94.374208)
		(end 123.58243 -94.117414)
		(width 0.1016)
		(layer "B.Cu")
		(net "SAS_GF_EXP_RX_DP3")
	)
	(segment
		(start 126.371858 -112.275112)
		(end 130.468624 -108.178346)
		(width 0.1016)
		(layer "B.Cu")
		(net "SAS_GF_EXP_RX_DP3")
	)
	(segment
		(start 137.293858 -168.394888)
		(end 127.641858 -158.742888)
		(width 0.1016)
		(layer "B.Cu")
		(net "SAS_GF_EXP_RX_DP3")
	)
	(segment
		(start 127.641858 -158.742888)
		(end 127.067056 -158.16834)
		(width 0.1016)
		(layer "B.Cu")
		(net "SAS_GF_EXP_RX_DP3")
	)
	(segment
		(start 131.33197 -106.094022)
		(end 131.33197 -98.464878)
		(width 0.1016)
		(layer "B.Cu")
		(net "SAS_GF_EXP_RX_DP3")
	)
	(segment
		(start 125.73 -154.94)
		(end 125.73 -113.824766)
		(width 0.1016)
		(layer "B.Cu")
		(net "SAS_GF_EXP_RX_DP3")
	)
	(segment
		(start 123.663456 -94.55912)
		(end 123.610116 -94.471998)
		(width 0.1016)
		(layer "B.Cu")
		(net "SAS_GF_EXP_RX_DP3")
	)
	(segment
		(start 137.959084 -231.065324)
		(end 137.959084 -170.00093)
		(width 0.1016)
		(layer "B.Cu")
		(net "SAS_GF_EXP_RX_DP3")
	)
	(segment
		(start 127.951738 -95.775018)
		(end 127.09271 -94.91599)
		(width 0.1016)
		(layer "B.Cu")
		(net "SAS_GF_EXP_RX_DP3")
	)
	(arc
		(start 135.594852 -236.234224)
		(mid 135.795854 -235.223716)
		(end 136.368282 -234.36707)
		(width 0.1016)
		(layer "B.Cu")
		(net "SAS_GF_EXP_RX_DP3")
	)
	(arc
		(start 129.73177 -96.37903)
		(mid 129.328539 -96.109722)
		(end 128.85293 -96.015302)
		(width 0.1016)
		(layer "B.Cu")
		(net "SAS_GF_EXP_RX_DP3")
	)
	(arc
		(start 127.09271 -94.91599)
		(mid 126.88666 -94.778375)
		(end 126.643638 -94.730062)
		(width 0.1016)
		(layer "B.Cu")
		(net "SAS_GF_EXP_RX_DP3")
	)
	(arc
		(start 135.999982 -254.515874)
		(mid 135.951661 -254.272856)
		(end 135.814054 -254.066802)
		(width 0.1016)
		(layer "B.Cu")
		(net "SAS_GF_EXP_RX_DP3")
	)
	(arc
		(start 124.097034 -94.730062)
		(mid 123.864008 -94.685779)
		(end 123.663456 -94.55912)
		(width 0.1016)
		(layer "B.Cu")
		(net "SAS_GF_EXP_RX_DP3")
	)
	(arc
		(start 131.33197 -98.464878)
		(mid 131.24295 -98.016491)
		(end 130.98907 -97.63633)
		(width 0.1016)
		(layer "B.Cu")
		(net "SAS_GF_EXP_RX_DP3")
	)
	(arc
		(start 130.468624 -108.178346)
		(mid 131.107601 -107.22205)
		(end 131.33197 -106.094022)
		(width 0.1016)
		(layer "B.Cu")
		(net "SAS_GF_EXP_RX_DP3")
	)
	(arc
		(start 135.632952 -253.715774)
		(mid 135.60448 -253.622148)
		(end 135.594852 -253.524766)
		(width 0.1016)
		(layer "B.Cu")
		(net "SAS_GF_EXP_RX_DP3")
	)
	(arc
		(start 135.783574 -254.036322)
		(mid 135.75661 -254.00346)
		(end 135.736584 -253.965964)
		(width 0.1016)
		(layer "B.Cu")
		(net "SAS_GF_EXP_RX_DP3")
	)
	(arc
		(start 137.959084 -170.00093)
		(mid 137.786209 -169.131739)
		(end 137.293858 -168.394888)
		(width 0.1016)
		(layer "B.Cu")
		(net "SAS_GF_EXP_RX_DP3")
	)
	(arc
		(start 136.749282 -233.98607)
		(mid 137.644621 -232.646006)
		(end 137.959084 -231.065324)
		(width 0.1016)
		(layer "B.Cu")
		(net "SAS_GF_EXP_RX_DP3")
	)
	(arc
		(start 128.531874 -96.015302)
		(mid 128.217913 -95.952851)
		(end 127.951738 -95.775018)
		(width 0.1016)
		(layer "B.Cu")
		(net "SAS_GF_EXP_RX_DP3")
	)
	(arc
		(start 125.73 -113.824766)
		(mid 125.896819 -112.986111)
		(end 126.371858 -112.275112)
		(width 0.1016)
		(layer "B.Cu")
		(net "SAS_GF_EXP_RX_DP3")
	)
	(arc
		(start 127.067056 -158.16834)
		(mid 126.077449 -156.68715)
		(end 125.73 -154.94)
		(width 0.1016)
		(layer "B.Cu")
		(net "SAS_GF_EXP_RX_DP3")
	)
	(arc
		(start 123.610116 -94.471998)
		(mid 123.589528 -94.425017)
		(end 123.58243 -94.374208)
		(width 0.1016)
		(layer "B.Cu")
		(net "SAS_GF_EXP_RX_DP3")
	)
	(arc
		(start 123.58243 -94.117414)
		(mid 123.66114 -93.927392)
		(end 123.851162 -93.848682)
		(width 0.1016)
		(layer "B.Cu")
		(net "SAS_GF_EXP_RX_DP3")
	)
	(segment
		(start 162.597338 -74.586084)
		(end 162.433 -74.422)
		(width 0.1397)
		(layer "B.Cu")
		(net "PCIE_SAS_CPU_RX_N6")
	)
	(segment
		(start 163.279328 -50.004472)
		(end 163.279582 -50.004218)
		(width 0.1397)
		(layer "B.Cu")
		(net "PCIE_SAS_CPU_RX_N6")
	)
	(segment
		(start 103.85298 -27.399234)
		(end 109.311186 -21.941028)
		(width 0.1397)
		(layer "B.Cu")
		(net "PCIE_SAS_CPU_RX_N6")
	)
	(segment
		(start 163.279582 -50.004218)
		(end 163.279582 -74.327258)
		(width 0.1397)
		(layer "B.Cu")
		(net "PCIE_SAS_CPU_RX_N6")
	)
	(segment
		(start 119.59336 -21.859494)
		(end 122.018806 -24.28494)
		(width 0.1397)
		(layer "B.Cu")
		(net "PCIE_SAS_CPU_RX_N6")
	)
	(segment
		(start 153.806398 -40.089328)
		(end 162.966908 -49.249838)
		(width 0.1397)
		(layer "B.Cu")
		(net "PCIE_SAS_CPU_RX_N6")
	)
	(segment
		(start 133.515608 -25.311608)
		(end 147.820888 -39.616888)
		(width 0.1397)
		(layer "B.Cu")
		(net "PCIE_SAS_CPU_RX_N6")
	)
	(segment
		(start 162.93084 -74.676)
		(end 162.814 -74.676)
		(width 0.1397)
		(layer "B.Cu")
		(net "PCIE_SAS_CPU_RX_N6")
	)
	(segment
		(start 103.154988 -29.484066)
		(end 103.203248 -29.435806)
		(width 0.1397)
		(layer "B.Cu")
		(net "PCIE_SAS_CPU_RX_N6")
	)
	(segment
		(start 148.51253 -39.9034)
		(end 153.357326 -39.9034)
		(width 0.1397)
		(layer "B.Cu")
		(net "PCIE_SAS_CPU_RX_N6")
	)
	(segment
		(start 124.128276 -25.1587)
		(end 133.1468 -25.1587)
		(width 0.1397)
		(layer "B.Cu")
		(net "PCIE_SAS_CPU_RX_N6")
	)
	(segment
		(start 102.96906 -30.945074)
		(end 102.96906 -29.932884)
		(width 0.1397)
		(layer "B.Cu")
		(net "PCIE_SAS_CPU_RX_N6")
	)
	(segment
		(start 109.760258 -21.7551)
		(end 119.3419 -21.7551)
		(width 0.1397)
		(layer "B.Cu")
		(net "PCIE_SAS_CPU_RX_N6")
	)
	(segment
		(start 162.433 -73.767696)
		(end 162.450526 -73.75017)
		(width 0.1397)
		(layer "B.Cu")
		(net "PCIE_SAS_CPU_RX_N6")
	)
	(segment
		(start 103.59136 -28.499054)
		(end 103.59136 -28.030932)
		(width 0.1397)
		(layer "B.Cu")
		(net "PCIE_SAS_CPU_RX_N6")
	)
	(arc
		(start 147.820888 -39.616888)
		(mid 148.138202 -39.828974)
		(end 148.51253 -39.9034)
		(width 0.1397)
		(layer "B.Cu")
		(net "PCIE_SAS_CPU_RX_N6")
	)
	(arc
		(start 122.018806 -24.28494)
		(mid 122.986653 -24.931572)
		(end 124.128276 -25.1587)
		(width 0.1397)
		(layer "B.Cu")
		(net "PCIE_SAS_CPU_RX_N6")
	)
	(arc
		(start 109.311186 -21.941028)
		(mid 109.517222 -21.803359)
		(end 109.760258 -21.7551)
		(width 0.1397)
		(layer "B.Cu")
		(net "PCIE_SAS_CPU_RX_N6")
	)
	(arc
		(start 162.814 -74.676)
		(mid 162.696731 -74.65258)
		(end 162.597338 -74.586084)
		(width 0.1397)
		(layer "B.Cu")
		(net "PCIE_SAS_CPU_RX_N6")
	)
	(arc
		(start 153.357326 -39.9034)
		(mid 153.60033 -39.951736)
		(end 153.806398 -40.089328)
		(width 0.1397)
		(layer "B.Cu")
		(net "PCIE_SAS_CPU_RX_N6")
	)
	(arc
		(start 163.279582 -74.327258)
		(mid 163.177438 -74.573856)
		(end 162.93084 -74.676)
		(width 0.1397)
		(layer "B.Cu")
		(net "PCIE_SAS_CPU_RX_N6")
	)
	(arc
		(start 103.13416 -31.3436)
		(mid 103.011987 -31.160755)
		(end 102.96906 -30.945074)
		(width 0.1397)
		(layer "B.Cu")
		(net "PCIE_SAS_CPU_RX_N6")
	)
	(arc
		(start 103.59136 -28.030932)
		(mid 103.65936 -27.689074)
		(end 103.85298 -27.399234)
		(width 0.1397)
		(layer "B.Cu")
		(net "PCIE_SAS_CPU_RX_N6")
	)
	(arc
		(start 103.203248 -29.435806)
		(mid 103.490451 -29.006021)
		(end 103.59136 -28.499054)
		(width 0.1397)
		(layer "B.Cu")
		(net "PCIE_SAS_CPU_RX_N6")
	)
	(arc
		(start 162.433 -74.422)
		(mid 162.297489 -74.094848)
		(end 162.433 -73.767696)
		(width 0.1397)
		(layer "B.Cu")
		(net "PCIE_SAS_CPU_RX_N6")
	)
	(arc
		(start 119.3419 -21.7551)
		(mid 119.477986 -21.782338)
		(end 119.59336 -21.859494)
		(width 0.1397)
		(layer "B.Cu")
		(net "PCIE_SAS_CPU_RX_N6")
	)
	(arc
		(start 162.966908 -49.249838)
		(mid 163.198114 -49.596096)
		(end 163.279328 -50.004472)
		(width 0.1397)
		(layer "B.Cu")
		(net "PCIE_SAS_CPU_RX_N6")
	)
	(arc
		(start 133.1468 -25.1587)
		(mid 133.346398 -25.198496)
		(end 133.515608 -25.311608)
		(width 0.1397)
		(layer "B.Cu")
		(net "PCIE_SAS_CPU_RX_N6")
	)
	(arc
		(start 102.96906 -29.932884)
		(mid 103.017377 -29.689977)
		(end 103.154988 -29.484066)
		(width 0.1397)
		(layer "B.Cu")
		(net "PCIE_SAS_CPU_RX_N6")
	)
	(segment
		(start 328.413872 -194.987672)
		(end 332.867 -190.534544)
		(width 0.1143)
		(layer "F.Cu")
		(net "ADC_P3V3_STBY")
	)
	(segment
		(start 328.413872 -214.257636)
		(end 328.413872 -194.987672)
		(width 0.1143)
		(layer "F.Cu")
		(net "ADC_P3V3_STBY")
	)
	(segment
		(start 332.867 -190.534544)
		(end 332.867 -187.325)
		(width 0.1143)
		(layer "F.Cu")
		(net "ADC_P3V3_STBY")
	)
	(via
		(at 328.676 -180.848)
		(size 0.7112)
		(drill 0.3556)
		(layers "F.Cu" "B.Cu")
		(net "ADC_P3V3_STBY")
	)
	(via
		(at 332.867 -187.325)
		(size 0.508)
		(drill 0.254)
		(layers "F.Cu" "B.Cu")
		(net "ADC_P3V3_STBY")
	)
	(segment
		(start 324.358 -179.2605)
		(end 325.374 -179.2605)
		(width 0.1143)
		(layer "B.Cu")
		(net "ADC_P3V3_STBY")
	)
	(segment
		(start 323.342 -179.2605)
		(end 322.7705 -178.689)
		(width 0.1143)
		(layer "B.Cu")
		(net "ADC_P3V3_STBY")
	)
	(segment
		(start 325.374 -179.2605)
		(end 325.57085 -179.45735)
		(width 0.1143)
		(layer "B.Cu")
		(net "ADC_P3V3_STBY")
	)
	(segment
		(start 323.342 -179.2605)
		(end 324.358 -179.2605)
		(width 0.1143)
		(layer "B.Cu")
		(net "ADC_P3V3_STBY")
	)
	(segment
		(start 332.867 -185.039)
		(end 328.676 -180.848)
		(width 0.1143)
		(layer "B.Cu")
		(net "ADC_P3V3_STBY")
	)
	(segment
		(start 325.57085 -179.45735)
		(end 327.41235 -179.45735)
		(width 0.1143)
		(layer "B.Cu")
		(net "ADC_P3V3_STBY")
	)
	(segment
		(start 322.7705 -178.689)
		(end 318.4525 -178.689)
		(width 0.1143)
		(layer "B.Cu")
		(net "ADC_P3V3_STBY")
	)
	(segment
		(start 328.676 -180.721)
		(end 328.676 -180.848)
		(width 0.1143)
		(layer "B.Cu")
		(net "ADC_P3V3_STBY")
	)
	(segment
		(start 327.41235 -179.45735)
		(end 328.676 -180.721)
		(width 0.1143)
		(layer "B.Cu")
		(net "ADC_P3V3_STBY")
	)
	(segment
		(start 332.867 -187.325)
		(end 332.867 -185.039)
		(width 0.1143)
		(layer "B.Cu")
		(net "ADC_P3V3_STBY")
	)
	(segment
		(start 280.562812 -189.4205)
		(end 280.47442 -189.332108)
		(width 0.1143)
		(layer "F.Cu")
		(net "OSC2_OUT")
	)
	(segment
		(start 283.2608 -189.3316)
		(end 282.2829 -189.3316)
		(width 0.1143)
		(layer "F.Cu")
		(net "OSC2_OUT")
	)
	(segment
		(start 282.194 -189.4205)
		(end 280.562812 -189.4205)
		(width 0.1143)
		(layer "F.Cu")
		(net "OSC2_OUT")
	)
	(segment
		(start 282.2829 -189.3316)
		(end 282.194 -189.4205)
		(width 0.1143)
		(layer "F.Cu")
		(net "OSC2_OUT")
	)
	(via
		(at 283.2608 -189.3316)
		(size 0.7112)
		(drill 0.3556)
		(layers "F.Cu" "B.Cu")
		(net "OSC2_OUT")
	)
	(segment
		(start 306.135532 -60.833)
		(end 306.705 -60.833)
		(width 0.1143)
		(layer "F.Cu")
		(net "SAS_I2C_C_10G_SDA")
	)
	(segment
		(start 304.225706 -61.134752)
		(end 304.582576 -61.134752)
		(width 0.1143)
		(layer "F.Cu")
		(net "SAS_I2C_C_10G_SDA")
	)
	(segment
		(start 304.582576 -61.134752)
		(end 304.744628 -60.9727)
		(width 0.1143)
		(layer "F.Cu")
		(net "SAS_I2C_C_10G_SDA")
	)
	(segment
		(start 308.675024 -60.400184)
		(end 307.518816 -60.400184)
		(width 0.1143)
		(layer "F.Cu")
		(net "SAS_I2C_C_10G_SDA")
	)
	(segment
		(start 305.995832 -60.9727)
		(end 306.135532 -60.833)
		(width 0.1143)
		(layer "F.Cu")
		(net "SAS_I2C_C_10G_SDA")
	)
	(segment
		(start 304.744628 -60.9727)
		(end 305.995832 -60.9727)
		(width 0.1143)
		(layer "F.Cu")
		(net "SAS_I2C_C_10G_SDA")
	)
	(segment
		(start 303.765458 -61.595)
		(end 304.225706 -61.134752)
		(width 0.1143)
		(layer "F.Cu")
		(net "SAS_I2C_C_10G_SDA")
	)
	(segment
		(start 307.518816 -60.400184)
		(end 307.086 -60.833)
		(width 0.1143)
		(layer "F.Cu")
		(net "SAS_I2C_C_10G_SDA")
	)
	(segment
		(start 307.086 -60.833)
		(end 306.705 -60.833)
		(width 0.1143)
		(layer "F.Cu")
		(net "SAS_I2C_C_10G_SDA")
	)
	(via
		(at 306.705 -60.833)
		(size 0.5588)
		(drill 0.3048)
		(layers "F.Cu" "B.Cu")
		(net "SAS_I2C_C_10G_SDA")
	)
	(segment
		(start 105.00106 -28.758134)
		(end 105.00106 -28.56992)
		(width 0.1397)
		(layer "B.Cu")
		(net "PCIE_SAS_CPU_RX_P7")
	)
	(segment
		(start 123.672854 -26.7843)
		(end 130.8862 -26.7843)
		(width 0.1397)
		(layer "B.Cu")
		(net "PCIE_SAS_CPU_RX_P7")
	)
	(segment
		(start 134.182612 -28.14955)
		(end 147.160234 -41.127172)
		(width 0.1397)
		(layer "B.Cu")
		(net "PCIE_SAS_CPU_RX_P7")
	)
	(segment
		(start 105.23093 -28.01493)
		(end 109.794548 -23.451312)
		(width 0.1397)
		(layer "B.Cu")
		(net "PCIE_SAS_CPU_RX_P7")
	)
	(segment
		(start 104.519984 -29.38653)
		(end 104.896666 -29.009848)
		(width 0.1397)
		(layer "B.Cu")
		(net "PCIE_SAS_CPU_RX_P7")
	)
	(segment
		(start 153.322782 -41.599358)
		(end 159.366712 -47.643288)
		(width 0.1397)
		(layer "B.Cu")
		(net "PCIE_SAS_CPU_RX_P7")
	)
	(segment
		(start 147.609306 -41.3131)
		(end 152.630886 -41.3131)
		(width 0.1397)
		(layer "B.Cu")
		(net "PCIE_SAS_CPU_RX_P7")
	)
	(segment
		(start 104.31526 -30.638496)
		(end 104.31526 -29.880814)
		(width 0.1397)
		(layer "B.Cu")
		(net "PCIE_SAS_CPU_RX_P7")
	)
	(segment
		(start 119.168418 -23.451312)
		(end 121.673112 -25.956006)
		(width 0.1397)
		(layer "B.Cu")
		(net "PCIE_SAS_CPU_RX_P7")
	)
	(segment
		(start 159.61741 -48.24857)
		(end 159.61741 -74.238358)
		(width 0.1397)
		(layer "B.Cu")
		(net "PCIE_SAS_CPU_RX_P7")
	)
	(segment
		(start 159.355536 -75.65644)
		(end 159.449516 -75.75042)
		(width 0.1397)
		(layer "B.Cu")
		(net "PCIE_SAS_CPU_RX_P7")
	)
	(segment
		(start 110.48619 -23.1648)
		(end 118.476776 -23.1648)
		(width 0.1397)
		(layer "B.Cu")
		(net "PCIE_SAS_CPU_RX_P7")
	)
	(arc
		(start 104.31526 -29.880814)
		(mid 104.368469 -29.613315)
		(end 104.519984 -29.38653)
		(width 0.1397)
		(layer "B.Cu")
		(net "PCIE_SAS_CPU_RX_P7")
	)
	(arc
		(start 104.896666 -29.009848)
		(mid 104.973915 -28.894376)
		(end 105.00106 -28.758134)
		(width 0.1397)
		(layer "B.Cu")
		(net "PCIE_SAS_CPU_RX_P7")
	)
	(arc
		(start 121.673112 -25.956006)
		(mid 122.590601 -26.569053)
		(end 123.672854 -26.7843)
		(width 0.1397)
		(layer "B.Cu")
		(net "PCIE_SAS_CPU_RX_P7")
	)
	(arc
		(start 159.61741 -74.238358)
		(mid 159.552889 -74.549352)
		(end 159.36976 -74.808842)
		(width 0.1397)
		(layer "B.Cu")
		(net "PCIE_SAS_CPU_RX_P7")
	)
	(arc
		(start 152.630886 -41.3131)
		(mid 153.005303 -41.387407)
		(end 153.322782 -41.599358)
		(width 0.1397)
		(layer "B.Cu")
		(net "PCIE_SAS_CPU_RX_P7")
	)
	(arc
		(start 130.8862 -26.7843)
		(mid 132.670209 -27.13905)
		(end 134.182612 -28.14955)
		(width 0.1397)
		(layer "B.Cu")
		(net "PCIE_SAS_CPU_RX_P7")
	)
	(arc
		(start 104.26827 -30.940248)
		(mid 104.303386 -30.791182)
		(end 104.31526 -30.638496)
		(width 0.1397)
		(layer "B.Cu")
		(net "PCIE_SAS_CPU_RX_P7")
	)
	(arc
		(start 147.160234 -41.127172)
		(mid 147.36627 -41.264841)
		(end 147.609306 -41.3131)
		(width 0.1397)
		(layer "B.Cu")
		(net "PCIE_SAS_CPU_RX_P7")
	)
	(arc
		(start 104.02316 -31.3436)
		(mid 104.169936 -31.156641)
		(end 104.26827 -30.940248)
		(width 0.1397)
		(layer "B.Cu")
		(net "PCIE_SAS_CPU_RX_P7")
	)
	(arc
		(start 105.00106 -28.56992)
		(mid 105.060789 -28.269553)
		(end 105.23093 -28.01493)
		(width 0.1397)
		(layer "B.Cu")
		(net "PCIE_SAS_CPU_RX_P7")
	)
	(arc
		(start 109.794548 -23.451312)
		(mid 110.111862 -23.239226)
		(end 110.48619 -23.1648)
		(width 0.1397)
		(layer "B.Cu")
		(net "PCIE_SAS_CPU_RX_P7")
	)
	(arc
		(start 159.36976 -74.808842)
		(mid 159.182813 -75.229656)
		(end 159.355536 -75.65644)
		(width 0.1397)
		(layer "B.Cu")
		(net "PCIE_SAS_CPU_RX_P7")
	)
	(arc
		(start 159.366712 -47.643288)
		(mid 159.552215 -47.921008)
		(end 159.61741 -48.24857)
		(width 0.1397)
		(layer "B.Cu")
		(net "PCIE_SAS_CPU_RX_P7")
	)
	(arc
		(start 118.476776 -23.1648)
		(mid 118.851085 -23.239273)
		(end 119.168418 -23.451312)
		(width 0.1397)
		(layer "B.Cu")
		(net "PCIE_SAS_CPU_RX_P7")
	)
	(segment
		(start 291.83965 -156.938472)
		(end 291.83965 -162.13709)
		(width 0.1143)
		(layer "F.Cu")
		(net "HIGH_HEX_0")
	)
	(segment
		(start 291.234876 -166.859458)
		(end 291.234876 -167.440102)
		(width 0.1143)
		(layer "F.Cu")
		(net "HIGH_HEX_0")
	)
	(segment
		(start 291.63645 -162.783012)
		(end 291.63645 -162.815778)
		(width 0.1143)
		(layer "F.Cu")
		(net "HIGH_HEX_0")
	)
	(segment
		(start 291.38499 -166.196518)
		(end 291.38499 -166.709344)
		(width 0.1143)
		(layer "F.Cu")
		(net "HIGH_HEX_0")
	)
	(segment
		(start 288.075878 -153.1747)
		(end 291.83965 -156.938472)
		(width 0.1143)
		(layer "F.Cu")
		(net "HIGH_HEX_0")
	)
	(segment
		(start 291.83965 -162.13709)
		(end 291.7063 -162.27044)
		(width 0.1143)
		(layer "F.Cu")
		(net "HIGH_HEX_0")
	)
	(segment
		(start 291.584126 -165.997382)
		(end 291.38499 -166.196518)
		(width 0.1143)
		(layer "F.Cu")
		(net "HIGH_HEX_0")
	)
	(segment
		(start 291.38499 -166.709344)
		(end 291.234876 -166.859458)
		(width 0.1143)
		(layer "F.Cu")
		(net "HIGH_HEX_0")
	)
	(segment
		(start 291.7063 -162.713162)
		(end 291.63645 -162.783012)
		(width 0.1143)
		(layer "F.Cu")
		(net "HIGH_HEX_0")
	)
	(segment
		(start 291.7063 -162.27044)
		(end 291.7063 -162.713162)
		(width 0.1143)
		(layer "F.Cu")
		(net "HIGH_HEX_0")
	)
	(segment
		(start 285.75 -153.1747)
		(end 288.075878 -153.1747)
		(width 0.1143)
		(layer "F.Cu")
		(net "HIGH_HEX_0")
	)
	(segment
		(start 291.63645 -162.815778)
		(end 291.584126 -162.868102)
		(width 0.1143)
		(layer "F.Cu")
		(net "HIGH_HEX_0")
	)
	(segment
		(start 291.584126 -162.868102)
		(end 291.584126 -165.997382)
		(width 0.1143)
		(layer "F.Cu")
		(net "HIGH_HEX_0")
	)
	(via
		(at 314.96 -137.8966)
		(size 0.5588)
		(drill 0.3048)
		(layers "F.Cu" "B.Cu")
		(net "HIGH_HEX_0")
	)
	(via
		(at 285.75 -153.1747)
		(size 0.5588)
		(drill 0.3048)
		(layers "F.Cu" "B.Cu")
		(net "HIGH_HEX_0")
	)
	(via
		(at 288.5948 -145.8214)
		(size 0.7112)
		(drill 0.3556)
		(layers "F.Cu" "B.Cu")
		(net "HIGH_HEX_0")
	)
	(segment
		(start 288.5948 -145.8214)
		(end 285.609538 -148.806662)
		(width 0.1143)
		(layer "B.Cu")
		(net "HIGH_HEX_0")
	)
	(segment
		(start 314.96 -137.8966)
		(end 314.6171 -137.5537)
		(width 0.1143)
		(layer "B.Cu")
		(net "HIGH_HEX_0")
	)
	(segment
		(start 285.609538 -152.903682)
		(end 285.75 -153.044144)
		(width 0.1143)
		(layer "B.Cu")
		(net "HIGH_HEX_0")
	)
	(segment
		(start 314.6171 -137.5537)
		(end 296.282872 -137.5537)
		(width 0.1143)
		(layer "B.Cu")
		(net "HIGH_HEX_0")
	)
	(segment
		(start 285.609538 -148.806662)
		(end 285.609538 -152.903682)
		(width 0.1143)
		(layer "B.Cu")
		(net "HIGH_HEX_0")
	)
	(segment
		(start 296.282872 -137.5537)
		(end 288.5948 -145.241772)
		(width 0.1143)
		(layer "B.Cu")
		(net "HIGH_HEX_0")
	)
	(segment
		(start 285.75 -153.044144)
		(end 285.75 -153.1747)
		(width 0.1143)
		(layer "B.Cu")
		(net "HIGH_HEX_0")
	)
	(segment
		(start 288.5948 -145.241772)
		(end 288.5948 -145.8214)
		(width 0.1143)
		(layer "B.Cu")
		(net "HIGH_HEX_0")
	)
	(segment
		(start 318.262 -99.905566)
		(end 318.262 -105.41)
		(width 0.127)
		(layer "In5.Cu")
		(net "HIGH_HEX_0")
	)
	(segment
		(start 347.985334 -7.724394)
		(end 343.916 -11.793728)
		(width 0.127)
		(layer "In5.Cu")
		(net "HIGH_HEX_0")
	)
	(segment
		(start 329.531218 -27.038554)
		(end 329.531218 -71.467218)
		(width 0.127)
		(layer "In5.Cu")
		(net "HIGH_HEX_0")
	)
	(segment
		(start 318.262 -105.41)
		(end 312.801 -110.871)
		(width 0.127)
		(layer "In5.Cu")
		(net "HIGH_HEX_0")
	)
	(segment
		(start 312.801 -112.685576)
		(end 312.0771 -113.409476)
		(width 0.127)
		(layer "In5.Cu")
		(net "HIGH_HEX_0")
	)
	(segment
		(start 329.531218 -71.467218)
		(end 330.5937 -72.5297)
		(width 0.127)
		(layer "In5.Cu")
		(net "HIGH_HEX_0")
	)
	(segment
		(start 329.057 -85.935566)
		(end 329.057 -89.110566)
		(width 0.127)
		(layer "In5.Cu")
		(net "HIGH_HEX_0")
	)
	(segment
		(start 343.916 -11.793728)
		(end 343.916 -12.653772)
		(width 0.127)
		(layer "In5.Cu")
		(net "HIGH_HEX_0")
	)
	(segment
		(start 312.0771 -113.409476)
		(end 312.0771 -124.4981)
		(width 0.127)
		(layer "In5.Cu")
		(net "HIGH_HEX_0")
	)
	(segment
		(start 312.0771 -124.4981)
		(end 314.96 -127.381)
		(width 0.127)
		(layer "In5.Cu")
		(net "HIGH_HEX_0")
	)
	(segment
		(start 330.5937 -72.5297)
		(end 330.5937 -84.398866)
		(width 0.127)
		(layer "In5.Cu")
		(net "HIGH_HEX_0")
	)
	(segment
		(start 312.801 -110.871)
		(end 312.801 -112.685576)
		(width 0.127)
		(layer "In5.Cu")
		(net "HIGH_HEX_0")
	)
	(segment
		(start 330.5937 -84.398866)
		(end 329.057 -85.935566)
		(width 0.127)
		(layer "In5.Cu")
		(net "HIGH_HEX_0")
	)
	(segment
		(start 314.96 -127.381)
		(end 314.96 -137.8966)
		(width 0.127)
		(layer "In5.Cu")
		(net "HIGH_HEX_0")
	)
	(segment
		(start 329.057 -89.110566)
		(end 318.262 -99.905566)
		(width 0.127)
		(layer "In5.Cu")
		(net "HIGH_HEX_0")
	)
	(segment
		(start 347.985334 -7.499604)
		(end 347.985334 -7.724394)
		(width 0.127)
		(layer "In5.Cu")
		(net "HIGH_HEX_0")
	)
	(segment
		(start 343.916 -12.653772)
		(end 329.531218 -27.038554)
		(width 0.127)
		(layer "In5.Cu")
		(net "HIGH_HEX_0")
	)
	(segment
		(start 306.3875 -59.8805)
		(end 306.705 -59.8805)
		(width 0.1143)
		(layer "F.Cu")
		(net "SAS_I2C_C_10G_SCL")
	)
	(segment
		(start 303.765458 -60.452)
		(end 303.790858 -60.4774)
		(width 0.1143)
		(layer "F.Cu")
		(net "SAS_I2C_C_10G_SCL")
	)
	(segment
		(start 307.556916 -59.600084)
		(end 307.2765 -59.8805)
		(width 0.1143)
		(layer "F.Cu")
		(net "SAS_I2C_C_10G_SCL")
	)
	(segment
		(start 308.675024 -59.600084)
		(end 307.556916 -59.600084)
		(width 0.1143)
		(layer "F.Cu")
		(net "SAS_I2C_C_10G_SCL")
	)
	(segment
		(start 303.790858 -60.4774)
		(end 305.7906 -60.4774)
		(width 0.1143)
		(layer "F.Cu")
		(net "SAS_I2C_C_10G_SCL")
	)
	(segment
		(start 305.7906 -60.4774)
		(end 306.3875 -59.8805)
		(width 0.1143)
		(layer "F.Cu")
		(net "SAS_I2C_C_10G_SCL")
	)
	(segment
		(start 307.2765 -59.8805)
		(end 306.705 -59.8805)
		(width 0.1143)
		(layer "F.Cu")
		(net "SAS_I2C_C_10G_SCL")
	)
	(via
		(at 306.705 -59.8805)
		(size 0.7112)
		(drill 0.3556)
		(layers "F.Cu" "B.Cu")
		(net "SAS_I2C_C_10G_SCL")
	)
	(segment
		(start 103.13797 -79.204312)
		(end 103.600504 -79.666846)
		(width 0.1143)
		(layer "F.Cu")
		(net "JTAG_EXP_TDI")
	)
	(segment
		(start 103.600504 -80.605376)
		(end 103.89997 -80.904842)
		(width 0.1143)
		(layer "F.Cu")
		(net "JTAG_EXP_TDI")
	)
	(segment
		(start 103.01097 -76.8985)
		(end 103.01097 -77.978)
		(width 0.1143)
		(layer "F.Cu")
		(net "JTAG_EXP_TDI")
	)
	(segment
		(start 103.89997 -80.904842)
		(end 103.89997 -82.900012)
		(width 0.1143)
		(layer "F.Cu")
		(net "JTAG_EXP_TDI")
	)
	(segment
		(start 103.01097 -77.978)
		(end 103.13797 -78.105)
		(width 0.1143)
		(layer "F.Cu")
		(net "JTAG_EXP_TDI")
	)
	(segment
		(start 103.13797 -78.105)
		(end 103.13797 -79.204312)
		(width 0.1143)
		(layer "F.Cu")
		(net "JTAG_EXP_TDI")
	)
	(segment
		(start 103.89997 -82.900012)
		(end 104.349804 -83.349846)
		(width 0.1143)
		(layer "F.Cu")
		(net "JTAG_EXP_TDI")
	)
	(segment
		(start 103.600504 -79.666846)
		(end 103.600504 -80.605376)
		(width 0.1143)
		(layer "F.Cu")
		(net "JTAG_EXP_TDI")
	)
	(segment
		(start 303.763172 -68.21424)
		(end 303.94402 -68.033392)
		(width 0.1397)
		(layer "F.Cu")
		(net "PCIE_10G_REFCLK_N")
	)
	(segment
		(start 305.502564 -67.371468)
		(end 307.181758 -67.371468)
		(width 0.1397)
		(layer "F.Cu")
		(net "PCIE_10G_REFCLK_N")
	)
	(segment
		(start 307.34 -67.437)
		(end 307.438806 -67.535806)
		(width 0.1397)
		(layer "F.Cu")
		(net "PCIE_10G_REFCLK_N")
	)
	(segment
		(start 307.594 -67.600068)
		(end 308.675024 -67.600068)
		(width 0.1397)
		(layer "F.Cu")
		(net "PCIE_10G_REFCLK_N")
	)
	(segment
		(start 305.031394 -67.758564)
		(end 305.359054 -67.430904)
		(width 0.1397)
		(layer "F.Cu")
		(net "PCIE_10G_REFCLK_N")
	)
	(segment
		(start 304.463958 -67.818)
		(end 304.887884 -67.818)
		(width 0.1397)
		(layer "F.Cu")
		(net "PCIE_10G_REFCLK_N")
	)
	(arc
		(start 305.359054 -67.430904)
		(mid 305.424897 -67.386909)
		(end 305.502564 -67.371468)
		(width 0.1397)
		(layer "F.Cu")
		(net "PCIE_10G_REFCLK_N")
	)
	(arc
		(start 307.181758 -67.371468)
		(mid 307.267393 -67.388502)
		(end 307.34 -67.437)
		(width 0.1397)
		(layer "F.Cu")
		(net "PCIE_10G_REFCLK_N")
	)
	(arc
		(start 303.94402 -68.033392)
		(mid 304.18257 -67.873998)
		(end 304.463958 -67.818)
		(width 0.1397)
		(layer "F.Cu")
		(net "PCIE_10G_REFCLK_N")
	)
	(arc
		(start 304.887884 -67.818)
		(mid 304.965548 -67.802552)
		(end 305.031394 -67.758564)
		(width 0.1397)
		(layer "F.Cu")
		(net "PCIE_10G_REFCLK_N")
	)
	(arc
		(start 307.438806 -67.535806)
		(mid 307.51001 -67.583383)
		(end 307.594 -67.600068)
		(width 0.1397)
		(layer "F.Cu")
		(net "PCIE_10G_REFCLK_N")
	)
	(segment
		(start 101.437186 -31.657036)
		(end 101.687122 -31.4071)
		(width 0.1397)
		(layer "F.Cu")
		(net "PCIE_SAS_CPU_TX_P5")
	)
	(segment
		(start 164.63137 -75.553824)
		(end 164.63137 -76.30922)
		(width 0.1397)
		(layer "F.Cu")
		(net "PCIE_SAS_CPU_TX_P5")
	)
	(segment
		(start 108.564172 -20.012152)
		(end 110.303564 -20.012152)
		(width 0.1397)
		(layer "F.Cu")
		(net "PCIE_SAS_CPU_TX_P5")
	)
	(segment
		(start 102.263956 -25.907492)
		(end 107.872784 -20.298664)
		(width 0.1397)
		(layer "F.Cu")
		(net "PCIE_SAS_CPU_TX_P5")
	)
	(segment
		(start 110.752636 -19.826224)
		(end 117.973348 -12.605512)
		(width 0.1397)
		(layer "F.Cu")
		(net "PCIE_SAS_CPU_TX_P5")
	)
	(segment
		(start 131.858258 -12.605258)
		(end 133.3246 -14.0716)
		(width 0.1397)
		(layer "F.Cu")
		(net "PCIE_SAS_CPU_TX_P5")
	)
	(segment
		(start 118.66499 -12.319)
		(end 131.166362 -12.319)
		(width 0.1397)
		(layer "F.Cu")
		(net "PCIE_SAS_CPU_TX_P5")
	)
	(segment
		(start 101.150166 -33.399984)
		(end 101.232462 -33.317688)
		(width 0.1397)
		(layer "F.Cu")
		(net "PCIE_SAS_CPU_TX_P5")
	)
	(segment
		(start 163.63696 -49.90084)
		(end 163.63696 -73.9394)
		(width 0.1397)
		(layer "F.Cu")
		(net "PCIE_SAS_CPU_TX_P5")
	)
	(segment
		(start 163.795964 -74.323194)
		(end 164.35197 -74.8792)
		(width 0.1397)
		(layer "F.Cu")
		(net "PCIE_SAS_CPU_TX_P5")
	)
	(segment
		(start 133.9215 -15.512542)
		(end 133.9215 -18.991326)
		(width 0.1397)
		(layer "F.Cu")
		(net "PCIE_SAS_CPU_TX_P5")
	)
	(segment
		(start 101.791516 -31.155386)
		(end 101.791516 -27.047952)
		(width 0.1397)
		(layer "F.Cu")
		(net "PCIE_SAS_CPU_TX_P5")
	)
	(segment
		(start 134.293356 -19.889216)
		(end 163.16452 -48.76038)
		(width 0.1397)
		(layer "F.Cu")
		(net "PCIE_SAS_CPU_TX_P5")
	)
	(segment
		(start 101.232462 -33.317688)
		(end 101.232462 -32.15132)
		(width 0.1397)
		(layer "F.Cu")
		(net "PCIE_SAS_CPU_TX_P5")
	)
	(via
		(at 164.928042 -77.0255)
		(size 0.5588)
		(drill 0.3048)
		(layers "F.Cu" "B.Cu")
		(net "PCIE_SAS_CPU_TX_P5")
	)
	(arc
		(start 164.35197 -74.8792)
		(mid 164.558785 -75.18872)
		(end 164.63137 -75.553824)
		(width 0.1397)
		(layer "F.Cu")
		(net "PCIE_SAS_CPU_TX_P5")
	)
	(arc
		(start 101.232462 -32.15132)
		(mid 101.285671 -31.883821)
		(end 101.437186 -31.657036)
		(width 0.1397)
		(layer "F.Cu")
		(net "PCIE_SAS_CPU_TX_P5")
	)
	(arc
		(start 133.3246 -14.0716)
		(mid 133.766339 -14.73271)
		(end 133.9215 -15.512542)
		(width 0.1397)
		(layer "F.Cu")
		(net "PCIE_SAS_CPU_TX_P5")
	)
	(arc
		(start 110.303564 -20.012152)
		(mid 110.546568 -19.963816)
		(end 110.752636 -19.826224)
		(width 0.1397)
		(layer "F.Cu")
		(net "PCIE_SAS_CPU_TX_P5")
	)
	(arc
		(start 133.9215 -18.991326)
		(mid 134.018139 -19.477251)
		(end 134.293356 -19.889216)
		(width 0.1397)
		(layer "F.Cu")
		(net "PCIE_SAS_CPU_TX_P5")
	)
	(arc
		(start 101.687122 -31.4071)
		(mid 101.764371 -31.291628)
		(end 101.791516 -31.155386)
		(width 0.1397)
		(layer "F.Cu")
		(net "PCIE_SAS_CPU_TX_P5")
	)
	(arc
		(start 101.791516 -27.047952)
		(mid 101.914291 -26.430722)
		(end 102.263956 -25.907492)
		(width 0.1397)
		(layer "F.Cu")
		(net "PCIE_SAS_CPU_TX_P5")
	)
	(arc
		(start 163.16452 -48.76038)
		(mid 163.514143 -49.283627)
		(end 163.63696 -49.90084)
		(width 0.1397)
		(layer "F.Cu")
		(net "PCIE_SAS_CPU_TX_P5")
	)
	(arc
		(start 117.973348 -12.605512)
		(mid 118.290662 -12.393426)
		(end 118.66499 -12.319)
		(width 0.1397)
		(layer "F.Cu")
		(net "PCIE_SAS_CPU_TX_P5")
	)
	(arc
		(start 107.872784 -20.298664)
		(mid 108.18998 -20.086627)
		(end 108.564172 -20.012152)
		(width 0.1397)
		(layer "F.Cu")
		(net "PCIE_SAS_CPU_TX_P5")
	)
	(arc
		(start 163.63696 -73.9394)
		(mid 163.678278 -74.14712)
		(end 163.795964 -74.323194)
		(width 0.1397)
		(layer "F.Cu")
		(net "PCIE_SAS_CPU_TX_P5")
	)
	(arc
		(start 131.166362 -12.319)
		(mid 131.540779 -12.393307)
		(end 131.858258 -12.605258)
		(width 0.1397)
		(layer "F.Cu")
		(net "PCIE_SAS_CPU_TX_P5")
	)
	(arc
		(start 164.63137 -76.30922)
		(mid 164.708476 -76.69686)
		(end 164.928042 -77.0255)
		(width 0.1397)
		(layer "F.Cu")
		(net "PCIE_SAS_CPU_TX_P5")
	)
	(segment
		(start 164.668454 -77.285088)
		(end 164.928042 -77.0255)
		(width 0.1397)
		(layer "B.Cu")
		(net "PCIE_SAS_CPU_TX_P5")
	)
	(segment
		(start 164.60343 -78.55331)
		(end 164.60343 -77.44206)
		(width 0.1397)
		(layer "B.Cu")
		(net "PCIE_SAS_CPU_TX_P5")
	)
	(segment
		(start 165.450266 -78.24978)
		(end 165.450266 -78.672436)
		(width 0.1397)
		(layer "B.Cu")
		(net "PCIE_SAS_CPU_TX_P5")
	)
	(segment
		(start 165.089078 -79.033624)
		(end 164.926772 -79.033624)
		(width 0.1397)
		(layer "B.Cu")
		(net "PCIE_SAS_CPU_TX_P5")
	)
	(arc
		(start 164.926772 -79.033624)
		(mid 164.845511 -79.01746)
		(end 164.776658 -78.971394)
		(width 0.1397)
		(layer "B.Cu")
		(net "PCIE_SAS_CPU_TX_P5")
	)
	(arc
		(start 164.776658 -78.971394)
		(mid 164.648489 -78.779575)
		(end 164.60343 -78.55331)
		(width 0.1397)
		(layer "B.Cu")
		(net "PCIE_SAS_CPU_TX_P5")
	)
	(arc
		(start 165.450266 -78.672436)
		(mid 165.344476 -78.927834)
		(end 165.089078 -79.033624)
		(width 0.1397)
		(layer "B.Cu")
		(net "PCIE_SAS_CPU_TX_P5")
	)
	(arc
		(start 164.60343 -77.44206)
		(mid 164.620328 -77.357106)
		(end 164.668454 -77.285088)
		(width 0.1397)
		(layer "B.Cu")
		(net "PCIE_SAS_CPU_TX_P5")
	)
	(segment
		(start 299.23486 -172.240194)
		(end 298.83735 -172.637704)
		(width 0.1143)
		(layer "F.Cu")
		(net "BMC0_JTAG_RTCK")
	)
	(via
		(at 298.83735 -172.637704)
		(size 0.508)
		(drill 0.254)
		(layers "F.Cu" "B.Cu")
		(net "BMC0_JTAG_RTCK")
	)
	(segment
		(start 298.814998 -172.736002)
		(end 298.814998 -172.660056)
		(width 0.1143)
		(layer "B.Cu")
		(net "BMC0_JTAG_RTCK")
	)
	(segment
		(start 298.069 -173.482)
		(end 298.814998 -172.736002)
		(width 0.1143)
		(layer "B.Cu")
		(net "BMC0_JTAG_RTCK")
	)
	(segment
		(start 298.814998 -172.660056)
		(end 298.83735 -172.637704)
		(width 0.1143)
		(layer "B.Cu")
		(net "BMC0_JTAG_RTCK")
	)
	(segment
		(start 297.6753 -173.0883)
		(end 298.069 -173.482)
		(width 0.1143)
		(layer "B.Cu")
		(net "BMC0_JTAG_RTCK")
	)
	(segment
		(start 297.6753 -172.5422)
		(end 297.6753 -173.0883)
		(width 0.1143)
		(layer "B.Cu")
		(net "BMC0_JTAG_RTCK")
	)
	(segment
		(start 292.034976 -170.640248)
		(end 291.639752 -170.245024)
		(width 0.1143)
		(layer "F.Cu")
		(net "HIGH_HEX_1")
	)
	(via
		(at 291.639752 -170.245024)
		(size 0.508)
		(drill 0.254)
		(layers "F.Cu" "B.Cu")
		(net "HIGH_HEX_1")
	)
	(via
		(at 314.96 -138.811)
		(size 0.5588)
		(drill 0.3048)
		(layers "F.Cu" "B.Cu")
		(net "HIGH_HEX_1")
	)
	(via
		(at 312.674 -138.11885)
		(size 0.7112)
		(drill 0.3556)
		(layers "F.Cu" "B.Cu")
		(net "HIGH_HEX_1")
	)
	(segment
		(start 290.1569 -156.750258)
		(end 290.1569 -157.486096)
		(width 0.1143)
		(layer "B.Cu")
		(net "HIGH_HEX_1")
	)
	(segment
		(start 291.233352 -169.246804)
		(end 291.233352 -169.765472)
		(width 0.1016)
		(layer "B.Cu")
		(net "HIGH_HEX_1")
	)
	(segment
		(start 314.26785 -138.11885)
		(end 312.674 -138.11885)
		(width 0.1143)
		(layer "B.Cu")
		(net "HIGH_HEX_1")
	)
	(segment
		(start 291.639752 -170.171872)
		(end 291.639752 -170.245024)
		(width 0.1016)
		(layer "B.Cu")
		(net "HIGH_HEX_1")
	)
	(segment
		(start 286.104838 -150.070566)
		(end 286.104838 -152.698196)
		(width 0.1143)
		(layer "B.Cu")
		(net "HIGH_HEX_1")
	)
	(segment
		(start 291.233352 -169.765472)
		(end 291.639752 -170.171872)
		(width 0.1016)
		(layer "B.Cu")
		(net "HIGH_HEX_1")
	)
	(segment
		(start 286.104838 -152.698196)
		(end 290.1569 -156.750258)
		(width 0.1143)
		(layer "B.Cu")
		(net "HIGH_HEX_1")
	)
	(segment
		(start 291.21735 -165.557962)
		(end 291.21735 -169.230802)
		(width 0.1143)
		(layer "B.Cu")
		(net "HIGH_HEX_1")
	)
	(segment
		(start 312.674 -138.11885)
		(end 296.418254 -138.11885)
		(width 0.1143)
		(layer "B.Cu")
		(net "HIGH_HEX_1")
	)
	(segment
		(start 290.91001 -165.250622)
		(end 291.21735 -165.557962)
		(width 0.1143)
		(layer "B.Cu")
		(net "HIGH_HEX_1")
	)
	(segment
		(start 289.210496 -145.326608)
		(end 289.210496 -146.964908)
		(width 0.1143)
		(layer "B.Cu")
		(net "HIGH_HEX_1")
	)
	(segment
		(start 314.96 -138.811)
		(end 314.26785 -138.11885)
		(width 0.1143)
		(layer "B.Cu")
		(net "HIGH_HEX_1")
	)
	(segment
		(start 290.1569 -157.486096)
		(end 290.91001 -158.239206)
		(width 0.1143)
		(layer "B.Cu")
		(net "HIGH_HEX_1")
	)
	(segment
		(start 290.91001 -158.239206)
		(end 290.91001 -165.250622)
		(width 0.1143)
		(layer "B.Cu")
		(net "HIGH_HEX_1")
	)
	(segment
		(start 289.210496 -146.964908)
		(end 286.104838 -150.070566)
		(width 0.1143)
		(layer "B.Cu")
		(net "HIGH_HEX_1")
	)
	(segment
		(start 291.21735 -169.230802)
		(end 291.233352 -169.246804)
		(width 0.1143)
		(layer "B.Cu")
		(net "HIGH_HEX_1")
	)
	(segment
		(start 296.418254 -138.11885)
		(end 289.210496 -145.326608)
		(width 0.1143)
		(layer "B.Cu")
		(net "HIGH_HEX_1")
	)
	(segment
		(start 315.468 -127.127)
		(end 315.468 -138.303)
		(width 0.127)
		(layer "In5.Cu")
		(net "HIGH_HEX_1")
	)
	(segment
		(start 313.309 -112.896142)
		(end 312.5851 -113.620042)
		(width 0.127)
		(layer "In5.Cu")
		(net "HIGH_HEX_1")
	)
	(segment
		(start 331.216 -79.121)
		(end 331.216 -84.495132)
		(width 0.127)
		(layer "In5.Cu")
		(net "HIGH_HEX_1")
	)
	(segment
		(start 333.468218 -76.868782)
		(end 331.216 -79.121)
		(width 0.127)
		(layer "In5.Cu")
		(net "HIGH_HEX_1")
	)
	(segment
		(start 312.5851 -124.2441)
		(end 315.468 -127.127)
		(width 0.127)
		(layer "In5.Cu")
		(net "HIGH_HEX_1")
	)
	(segment
		(start 318.77 -106.68)
		(end 316.2173 -109.2327)
		(width 0.127)
		(layer "In5.Cu")
		(net "HIGH_HEX_1")
	)
	(segment
		(start 318.77 -100.203)
		(end 318.77 -106.68)
		(width 0.127)
		(layer "In5.Cu")
		(net "HIGH_HEX_1")
	)
	(segment
		(start 329.565 -86.146132)
		(end 329.565 -89.408)
		(width 0.127)
		(layer "In5.Cu")
		(net "HIGH_HEX_1")
	)
	(segment
		(start 315.468 -138.303)
		(end 314.96 -138.811)
		(width 0.127)
		(layer "In5.Cu")
		(net "HIGH_HEX_1")
	)
	(segment
		(start 333.468218 -23.82012)
		(end 333.468218 -76.868782)
		(width 0.127)
		(layer "In5.Cu")
		(net "HIGH_HEX_1")
	)
	(segment
		(start 348.810834 -7.841742)
		(end 344.424 -12.228576)
		(width 0.127)
		(layer "In5.Cu")
		(net "HIGH_HEX_1")
	)
	(segment
		(start 344.424 -12.864338)
		(end 333.468218 -23.82012)
		(width 0.127)
		(layer "In5.Cu")
		(net "HIGH_HEX_1")
	)
	(segment
		(start 348.810834 -6.326124)
		(end 348.810834 -7.841742)
		(width 0.127)
		(layer "In5.Cu")
		(net "HIGH_HEX_1")
	)
	(segment
		(start 316.2173 -109.2327)
		(end 316.2173 -109.913928)
		(width 0.127)
		(layer "In5.Cu")
		(net "HIGH_HEX_1")
	)
	(segment
		(start 344.424 -12.228576)
		(end 344.424 -12.864338)
		(width 0.127)
		(layer "In5.Cu")
		(net "HIGH_HEX_1")
	)
	(segment
		(start 329.565 -89.408)
		(end 318.77 -100.203)
		(width 0.127)
		(layer "In5.Cu")
		(net "HIGH_HEX_1")
	)
	(segment
		(start 313.309 -112.822228)
		(end 313.309 -112.896142)
		(width 0.127)
		(layer "In5.Cu")
		(net "HIGH_HEX_1")
	)
	(segment
		(start 312.5851 -113.620042)
		(end 312.5851 -124.2441)
		(width 0.127)
		(layer "In5.Cu")
		(net "HIGH_HEX_1")
	)
	(segment
		(start 316.2173 -109.913928)
		(end 313.309 -112.822228)
		(width 0.127)
		(layer "In5.Cu")
		(net "HIGH_HEX_1")
	)
	(segment
		(start 347.985334 -5.500624)
		(end 348.810834 -6.326124)
		(width 0.127)
		(layer "In5.Cu")
		(net "HIGH_HEX_1")
	)
	(segment
		(start 331.216 -84.495132)
		(end 329.565 -86.146132)
		(width 0.127)
		(layer "In5.Cu")
		(net "HIGH_HEX_1")
	)
	(segment
		(start 292.034976 -169.840148)
		(end 291.639752 -169.444924)
		(width 0.1143)
		(layer "F.Cu")
		(net "HIGH_HEX_2")
	)
	(via
		(at 313.812428 -138.933428)
		(size 0.5588)
		(drill 0.3048)
		(layers "F.Cu" "B.Cu")
		(net "HIGH_HEX_2")
	)
	(via
		(at 291.639752 -169.444924)
		(size 0.508)
		(drill 0.254)
		(layers "F.Cu" "B.Cu")
		(net "HIGH_HEX_2")
	)
	(via
		(at 307.213 -138.684)
		(size 0.7112)
		(drill 0.3556)
		(layers "F.Cu" "B.Cu")
		(net "HIGH_HEX_2")
	)
	(segment
		(start 313.812428 -138.933428)
		(end 313.563 -138.684)
		(width 0.1143)
		(layer "B.Cu")
		(net "HIGH_HEX_2")
	)
	(segment
		(start 291.639752 -169.444924)
		(end 291.639752 -169.355008)
		(width 0.1016)
		(layer "B.Cu")
		(net "HIGH_HEX_2")
	)
	(segment
		(start 296.553636 -138.684)
		(end 307.213 -138.684)
		(width 0.1143)
		(layer "B.Cu")
		(net "HIGH_HEX_2")
	)
	(segment
		(start 290.6522 -157.280864)
		(end 290.6522 -156.536136)
		(width 0.1143)
		(layer "B.Cu")
		(net "HIGH_HEX_2")
	)
	(segment
		(start 313.563 -138.684)
		(end 307.213 -138.684)
		(width 0.1143)
		(layer "B.Cu")
		(net "HIGH_HEX_2")
	)
	(segment
		(start 292.0365 -168.476422)
		(end 291.465 -167.904922)
		(width 0.1016)
		(layer "B.Cu")
		(net "HIGH_HEX_2")
	)
	(segment
		(start 292.0365 -168.95826)
		(end 292.0365 -168.476422)
		(width 0.1016)
		(layer "B.Cu")
		(net "HIGH_HEX_2")
	)
	(segment
		(start 291.465 -165.310312)
		(end 291.40531 -165.250622)
		(width 0.1143)
		(layer "B.Cu")
		(net "HIGH_HEX_2")
	)
	(segment
		(start 291.40531 -165.250622)
		(end 291.40531 -158.033974)
		(width 0.1143)
		(layer "B.Cu")
		(net "HIGH_HEX_2")
	)
	(segment
		(start 290.6522 -156.536136)
		(end 286.600138 -152.484074)
		(width 0.1143)
		(layer "B.Cu")
		(net "HIGH_HEX_2")
	)
	(segment
		(start 291.639752 -169.355008)
		(end 292.0365 -168.95826)
		(width 0.1016)
		(layer "B.Cu")
		(net "HIGH_HEX_2")
	)
	(segment
		(start 289.705796 -145.53184)
		(end 296.553636 -138.684)
		(width 0.1143)
		(layer "B.Cu")
		(net "HIGH_HEX_2")
	)
	(segment
		(start 289.705796 -147.17014)
		(end 289.705796 -145.53184)
		(width 0.1143)
		(layer "B.Cu")
		(net "HIGH_HEX_2")
	)
	(segment
		(start 291.40531 -158.033974)
		(end 290.6522 -157.280864)
		(width 0.1143)
		(layer "B.Cu")
		(net "HIGH_HEX_2")
	)
	(segment
		(start 286.600138 -150.275798)
		(end 289.705796 -147.17014)
		(width 0.1143)
		(layer "B.Cu")
		(net "HIGH_HEX_2")
	)
	(segment
		(start 291.465 -167.759634)
		(end 291.465 -165.310312)
		(width 0.1143)
		(layer "B.Cu")
		(net "HIGH_HEX_2")
	)
	(segment
		(start 286.600138 -152.484074)
		(end 286.600138 -150.275798)
		(width 0.1143)
		(layer "B.Cu")
		(net "HIGH_HEX_2")
	)
	(segment
		(start 291.465 -167.904922)
		(end 291.465 -167.759634)
		(width 0.1016)
		(layer "B.Cu")
		(net "HIGH_HEX_2")
	)
	(segment
		(start 342.773 -11.499596)
		(end 345.985084 -8.287512)
		(width 0.127)
		(layer "In5.Cu")
		(net "HIGH_HEX_2")
	)
	(segment
		(start 339.282532 -15.748)
		(end 342.773 -12.257532)
		(width 0.127)
		(layer "In5.Cu")
		(net "HIGH_HEX_2")
	)
	(segment
		(start 313.812428 -138.933428)
		(end 313.812428 -136.529572)
		(width 0.127)
		(layer "In5.Cu")
		(net "HIGH_HEX_2")
	)
	(segment
		(start 328.041 -88.646)
		(end 328.041 -22.19325)
		(width 0.127)
		(layer "In5.Cu")
		(net "HIGH_HEX_2")
	)
	(segment
		(start 328.041 -22.19325)
		(end 334.48625 -15.748)
		(width 0.127)
		(layer "In5.Cu")
		(net "HIGH_HEX_2")
	)
	(segment
		(start 311.785 -112.264444)
		(end 311.785 -110.363)
		(width 0.127)
		(layer "In5.Cu")
		(net "HIGH_HEX_2")
	)
	(segment
		(start 313.817 -136.525)
		(end 313.817 -127.889)
		(width 0.127)
		(layer "In5.Cu")
		(net "HIGH_HEX_2")
	)
	(segment
		(start 317.246 -104.902)
		(end 317.246 -99.441)
		(width 0.127)
		(layer "In5.Cu")
		(net "HIGH_HEX_2")
	)
	(segment
		(start 342.773 -12.257532)
		(end 342.773 -11.499596)
		(width 0.127)
		(layer "In5.Cu")
		(net "HIGH_HEX_2")
	)
	(segment
		(start 311.0611 -125.1331)
		(end 311.0611 -112.988344)
		(width 0.127)
		(layer "In5.Cu")
		(net "HIGH_HEX_2")
	)
	(segment
		(start 334.48625 -15.748)
		(end 339.282532 -15.748)
		(width 0.127)
		(layer "In5.Cu")
		(net "HIGH_HEX_2")
	)
	(segment
		(start 317.246 -99.441)
		(end 328.041 -88.646)
		(width 0.127)
		(layer "In5.Cu")
		(net "HIGH_HEX_2")
	)
	(segment
		(start 311.0611 -112.988344)
		(end 311.785 -112.264444)
		(width 0.127)
		(layer "In5.Cu")
		(net "HIGH_HEX_2")
	)
	(segment
		(start 311.785 -110.363)
		(end 317.246 -104.902)
		(width 0.127)
		(layer "In5.Cu")
		(net "HIGH_HEX_2")
	)
	(segment
		(start 313.817 -127.889)
		(end 311.0611 -125.1331)
		(width 0.127)
		(layer "In5.Cu")
		(net "HIGH_HEX_2")
	)
	(segment
		(start 313.812428 -136.529572)
		(end 313.817 -136.525)
		(width 0.127)
		(layer "In5.Cu")
		(net "HIGH_HEX_2")
	)
	(segment
		(start 345.985084 -8.287512)
		(end 345.985084 -7.499604)
		(width 0.127)
		(layer "In5.Cu")
		(net "HIGH_HEX_2")
	)
	(segment
		(start 110.000542 -256.25044)
		(end 110.000542 -254.28194)
		(width 0.1016)
		(layer "F.Cu")
		(net "SAS_EXP_GF_TX_DP9")
	)
	(segment
		(start 112.89792 -193.877692)
		(end 112.89792 -114.931952)
		(width 0.1016)
		(layer "F.Cu")
		(net "SAS_EXP_GF_TX_DP9")
	)
	(segment
		(start 104.187752 -222.174054)
		(end 104.187752 -221.944692)
		(width 0.1016)
		(layer "F.Cu")
		(net "SAS_EXP_GF_TX_DP9")
	)
	(segment
		(start 110.98657 -197.287642)
		(end 111.838232 -196.43598)
		(width 0.1016)
		(layer "F.Cu")
		(net "SAS_EXP_GF_TX_DP9")
	)
	(segment
		(start 104.426512 -221.467172)
		(end 104.426512 -221.162372)
		(width 0.1016)
		(layer "F.Cu")
		(net "SAS_EXP_GF_TX_DP9")
	)
	(segment
		(start 109.495844 -199.115934)
		(end 109.71149 -198.900542)
		(width 0.1016)
		(layer "F.Cu")
		(net "SAS_EXP_GF_TX_DP9")
	)
	(segment
		(start 110.308136 -250.081542)
		(end 110.976918 -249.41276)
		(width 0.1016)
		(layer "F.Cu")
		(net "SAS_EXP_GF_TX_DP9")
	)
	(segment
		(start 110.602268 -198.00951)
		(end 110.817914 -197.794118)
		(width 0.1016)
		(layer "F.Cu")
		(net "SAS_EXP_GF_TX_DP9")
	)
	(segment
		(start 109.880146 -198.394066)
		(end 110.095792 -198.17842)
		(width 0.1016)
		(layer "F.Cu")
		(net "SAS_EXP_GF_TX_DP9")
	)
	(segment
		(start 111.805212 -247.413018)
		(end 111.805212 -230.494078)
		(width 0.1016)
		(layer "F.Cu")
		(net "SAS_EXP_GF_TX_DP9")
	)
	(segment
		(start 104.426512 -219.902532)
		(end 104.426512 -219.597732)
		(width 0.1016)
		(layer "F.Cu")
		(net "SAS_EXP_GF_TX_DP9")
	)
	(segment
		(start 108.773976 -199.500236)
		(end 108.989368 -199.284844)
		(width 0.1016)
		(layer "F.Cu")
		(net "SAS_EXP_GF_TX_DP9")
	)
	(segment
		(start 109.898942 -254.18034)
		(end 109.773212 -254.18034)
		(width 0.1016)
		(layer "F.Cu")
		(net "SAS_EXP_GF_TX_DP9")
	)
	(segment
		(start 109.671612 -254.07874)
		(end 109.671612 -251.618242)
		(width 0.1016)
		(layer "F.Cu")
		(net "SAS_EXP_GF_TX_DP9")
	)
	(segment
		(start 104.187752 -220.684852)
		(end 104.187752 -220.380052)
		(width 0.1016)
		(layer "F.Cu")
		(net "SAS_EXP_GF_TX_DP9")
	)
	(segment
		(start 104.187752 -217.555572)
		(end 104.187752 -217.250772)
		(width 0.1016)
		(layer "F.Cu")
		(net "SAS_EXP_GF_TX_DP9")
	)
	(segment
		(start 108.38942 -200.222358)
		(end 108.605066 -200.006712)
		(width 0.1016)
		(layer "F.Cu")
		(net "SAS_EXP_GF_TX_DP9")
	)
	(segment
		(start 111.450628 -229.638098)
		(end 104.329992 -222.517462)
		(width 0.1016)
		(layer "F.Cu")
		(net "SAS_EXP_GF_TX_DP9")
	)
	(segment
		(start 107.117134 -201.157078)
		(end 107.882944 -200.391268)
		(width 0.1016)
		(layer "F.Cu")
		(net "SAS_EXP_GF_TX_DP9")
	)
	(segment
		(start 104.187752 -215.990932)
		(end 104.187752 -208.2292)
		(width 0.1016)
		(layer "F.Cu")
		(net "SAS_EXP_GF_TX_DP9")
	)
	(segment
		(start 104.426512 -216.773252)
		(end 104.426512 -216.468452)
		(width 0.1016)
		(layer "F.Cu")
		(net "SAS_EXP_GF_TX_DP9")
	)
	(segment
		(start 104.187752 -219.120212)
		(end 104.187752 -218.815412)
		(width 0.1016)
		(layer "F.Cu")
		(net "SAS_EXP_GF_TX_DP9")
	)
	(segment
		(start 104.426512 -218.337892)
		(end 104.426512 -218.033092)
		(width 0.1016)
		(layer "F.Cu")
		(net "SAS_EXP_GF_TX_DP9")
	)
	(arc
		(start 104.187752 -208.2292)
		(mid 104.949071 -204.40179)
		(end 107.117134 -201.157078)
		(width 0.1016)
		(layer "F.Cu")
		(net "SAS_EXP_GF_TX_DP9")
	)
	(arc
		(start 104.187752 -220.380052)
		(mid 104.218244 -220.246059)
		(end 104.307132 -220.141292)
		(width 0.1016)
		(layer "F.Cu")
		(net "SAS_EXP_GF_TX_DP9")
	)
	(arc
		(start 104.307132 -221.705932)
		(mid 104.395926 -221.601118)
		(end 104.426512 -221.467172)
		(width 0.1016)
		(layer "F.Cu")
		(net "SAS_EXP_GF_TX_DP9")
	)
	(arc
		(start 104.426512 -216.468452)
		(mid 104.39602 -216.334459)
		(end 104.307132 -216.229692)
		(width 0.1016)
		(layer "F.Cu")
		(net "SAS_EXP_GF_TX_DP9")
	)
	(arc
		(start 111.805212 -230.494078)
		(mid 111.713063 -230.030815)
		(end 111.450628 -229.638098)
		(width 0.1016)
		(layer "F.Cu")
		(net "SAS_EXP_GF_TX_DP9")
	)
	(arc
		(start 109.773212 -254.18034)
		(mid 109.70137 -254.150582)
		(end 109.671612 -254.07874)
		(width 0.1016)
		(layer "F.Cu")
		(net "SAS_EXP_GF_TX_DP9")
	)
	(arc
		(start 104.329992 -222.517462)
		(mid 104.224716 -222.359905)
		(end 104.187752 -222.174054)
		(width 0.1016)
		(layer "F.Cu")
		(net "SAS_EXP_GF_TX_DP9")
	)
	(arc
		(start 104.187752 -221.944692)
		(mid 104.218244 -221.810699)
		(end 104.307132 -221.705932)
		(width 0.1016)
		(layer "F.Cu")
		(net "SAS_EXP_GF_TX_DP9")
	)
	(arc
		(start 112.98555 -114.72037)
		(mid 113.028766 -114.655692)
		(end 113.04397 -114.5794)
		(width 0.1016)
		(layer "F.Cu")
		(net "SAS_EXP_GF_TX_DP9")
	)
	(arc
		(start 104.307132 -218.576652)
		(mid 104.395926 -218.471838)
		(end 104.426512 -218.337892)
		(width 0.1016)
		(layer "F.Cu")
		(net "SAS_EXP_GF_TX_DP9")
	)
	(arc
		(start 104.307132 -220.923612)
		(mid 104.218338 -220.818798)
		(end 104.187752 -220.684852)
		(width 0.1016)
		(layer "F.Cu")
		(net "SAS_EXP_GF_TX_DP9")
	)
	(arc
		(start 110.817914 -197.794118)
		(mid 110.890974 -197.677793)
		(end 110.902242 -197.54088)
		(width 0.1016)
		(layer "F.Cu")
		(net "SAS_EXP_GF_TX_DP9")
	)
	(arc
		(start 112.89792 -114.931952)
		(mid 112.920696 -114.817449)
		(end 112.98555 -114.72037)
		(width 0.1016)
		(layer "F.Cu")
		(net "SAS_EXP_GF_TX_DP9")
	)
	(arc
		(start 104.426512 -218.033092)
		(mid 104.39602 -217.899099)
		(end 104.307132 -217.794332)
		(width 0.1016)
		(layer "F.Cu")
		(net "SAS_EXP_GF_TX_DP9")
	)
	(arc
		(start 104.307132 -217.794332)
		(mid 104.218338 -217.689518)
		(end 104.187752 -217.555572)
		(width 0.1016)
		(layer "F.Cu")
		(net "SAS_EXP_GF_TX_DP9")
	)
	(arc
		(start 108.136182 -200.306686)
		(mid 108.273107 -200.295456)
		(end 108.38942 -200.222358)
		(width 0.1016)
		(layer "F.Cu")
		(net "SAS_EXP_GF_TX_DP9")
	)
	(arc
		(start 104.307132 -216.229692)
		(mid 104.218338 -216.124878)
		(end 104.187752 -215.990932)
		(width 0.1016)
		(layer "F.Cu")
		(net "SAS_EXP_GF_TX_DP9")
	)
	(arc
		(start 104.307132 -217.012012)
		(mid 104.395926 -216.907198)
		(end 104.426512 -216.773252)
		(width 0.1016)
		(layer "F.Cu")
		(net "SAS_EXP_GF_TX_DP9")
	)
	(arc
		(start 104.187752 -217.250772)
		(mid 104.218244 -217.116779)
		(end 104.307132 -217.012012)
		(width 0.1016)
		(layer "F.Cu")
		(net "SAS_EXP_GF_TX_DP9")
	)
	(arc
		(start 108.989368 -199.284844)
		(mid 109.105656 -199.211621)
		(end 109.242606 -199.200262)
		(width 0.1016)
		(layer "F.Cu")
		(net "SAS_EXP_GF_TX_DP9")
	)
	(arc
		(start 109.795818 -198.647304)
		(mid 109.807048 -198.510379)
		(end 109.880146 -198.394066)
		(width 0.1016)
		(layer "F.Cu")
		(net "SAS_EXP_GF_TX_DP9")
	)
	(arc
		(start 108.605066 -200.006712)
		(mid 108.678126 -199.890387)
		(end 108.689394 -199.753474)
		(width 0.1016)
		(layer "F.Cu")
		(net "SAS_EXP_GF_TX_DP9")
	)
	(arc
		(start 108.689394 -199.753474)
		(mid 108.700758 -199.616526)
		(end 108.773976 -199.500236)
		(width 0.1016)
		(layer "F.Cu")
		(net "SAS_EXP_GF_TX_DP9")
	)
	(arc
		(start 104.426512 -219.597732)
		(mid 104.39602 -219.463739)
		(end 104.307132 -219.358972)
		(width 0.1016)
		(layer "F.Cu")
		(net "SAS_EXP_GF_TX_DP9")
	)
	(arc
		(start 104.426512 -221.162372)
		(mid 104.39602 -221.028379)
		(end 104.307132 -220.923612)
		(width 0.1016)
		(layer "F.Cu")
		(net "SAS_EXP_GF_TX_DP9")
	)
	(arc
		(start 110.902242 -197.54088)
		(mid 110.913472 -197.403955)
		(end 110.98657 -197.287642)
		(width 0.1016)
		(layer "F.Cu")
		(net "SAS_EXP_GF_TX_DP9")
	)
	(arc
		(start 110.095792 -198.17842)
		(mid 110.212117 -198.10536)
		(end 110.34903 -198.094092)
		(width 0.1016)
		(layer "F.Cu")
		(net "SAS_EXP_GF_TX_DP9")
	)
	(arc
		(start 107.882944 -200.391268)
		(mid 107.999232 -200.318045)
		(end 108.136182 -200.306686)
		(width 0.1016)
		(layer "F.Cu")
		(net "SAS_EXP_GF_TX_DP9")
	)
	(arc
		(start 104.307132 -220.141292)
		(mid 104.395926 -220.036478)
		(end 104.426512 -219.902532)
		(width 0.1016)
		(layer "F.Cu")
		(net "SAS_EXP_GF_TX_DP9")
	)
	(arc
		(start 104.307132 -219.358972)
		(mid 104.218338 -219.254158)
		(end 104.187752 -219.120212)
		(width 0.1016)
		(layer "F.Cu")
		(net "SAS_EXP_GF_TX_DP9")
	)
	(arc
		(start 110.976918 -249.41276)
		(mid 111.589911 -248.495256)
		(end 111.805212 -247.413018)
		(width 0.1016)
		(layer "F.Cu")
		(net "SAS_EXP_GF_TX_DP9")
	)
	(arc
		(start 111.838232 -196.43598)
		(mid 112.622538 -195.262228)
		(end 112.89792 -193.877692)
		(width 0.1016)
		(layer "F.Cu")
		(net "SAS_EXP_GF_TX_DP9")
	)
	(arc
		(start 109.242606 -199.200262)
		(mid 109.379531 -199.189032)
		(end 109.495844 -199.115934)
		(width 0.1016)
		(layer "F.Cu")
		(net "SAS_EXP_GF_TX_DP9")
	)
	(arc
		(start 110.34903 -198.094092)
		(mid 110.485978 -198.082728)
		(end 110.602268 -198.00951)
		(width 0.1016)
		(layer "F.Cu")
		(net "SAS_EXP_GF_TX_DP9")
	)
	(arc
		(start 104.187752 -218.815412)
		(mid 104.218244 -218.681419)
		(end 104.307132 -218.576652)
		(width 0.1016)
		(layer "F.Cu")
		(net "SAS_EXP_GF_TX_DP9")
	)
	(arc
		(start 109.671612 -251.618242)
		(mid 109.837039 -250.786585)
		(end 110.308136 -250.081542)
		(width 0.1016)
		(layer "F.Cu")
		(net "SAS_EXP_GF_TX_DP9")
	)
	(arc
		(start 109.71149 -198.900542)
		(mid 109.78455 -198.784217)
		(end 109.795818 -198.647304)
		(width 0.1016)
		(layer "F.Cu")
		(net "SAS_EXP_GF_TX_DP9")
	)
	(arc
		(start 110.000542 -254.28194)
		(mid 109.970784 -254.210098)
		(end 109.898942 -254.18034)
		(width 0.1016)
		(layer "F.Cu")
		(net "SAS_EXP_GF_TX_DP9")
	)
	(segment
		(start 143.001746 -10.536174)
		(end 143.002 -10.53592)
		(width 0.1397)
		(layer "F.Cu")
		(net "PCIE_SAS_CPU_TX_N0")
	)
	(segment
		(start 189.733428 -59.299856)
		(end 203.090018 -72.656446)
		(width 0.1397)
		(layer "F.Cu")
		(net "PCIE_SAS_CPU_TX_N0")
	)
	(segment
		(start 203.662534 -74.673714)
		(end 204.11059 -75.12177)
		(width 0.1397)
		(layer "F.Cu")
		(net "PCIE_SAS_CPU_TX_N0")
	)
	(segment
		(start 204.28966 -75.55357)
		(end 204.28966 -76.198984)
		(width 0.1397)
		(layer "F.Cu")
		(net "PCIE_SAS_CPU_TX_N0")
	)
	(segment
		(start 109.633512 -11.143488)
		(end 116.946172 -3.830828)
		(width 0.1397)
		(layer "F.Cu")
		(net "PCIE_SAS_CPU_TX_N0")
	)
	(segment
		(start 95.924624 -33.381696)
		(end 95.924624 -33.19526)
		(width 0.1397)
		(layer "F.Cu")
		(net "PCIE_SAS_CPU_TX_N0")
	)
	(segment
		(start 95.635572 -33.844484)
		(end 95.801688 -33.678368)
		(width 0.1397)
		(layer "F.Cu")
		(net "PCIE_SAS_CPU_TX_N0")
	)
	(segment
		(start 95.549974 -34.19983)
		(end 95.549974 -34.050986)
		(width 0.1397)
		(layer "F.Cu")
		(net "PCIE_SAS_CPU_TX_N0")
	)
	(segment
		(start 137.37463 -4.02717)
		(end 142.37843 -9.03097)
		(width 0.1397)
		(layer "F.Cu")
		(net "PCIE_SAS_CPU_TX_N0")
	)
	(segment
		(start 104.365044 -11.43)
		(end 108.94187 -11.43)
		(width 0.1397)
		(layer "F.Cu")
		(net "PCIE_SAS_CPU_TX_N0")
	)
	(segment
		(start 203.29525 -73.152)
		(end 203.29525 -73.787)
		(width 0.1397)
		(layer "F.Cu")
		(net "PCIE_SAS_CPU_TX_N0")
	)
	(segment
		(start 93.307916 -29.77134)
		(end 93.307916 -22.750018)
		(width 0.1397)
		(layer "F.Cu")
		(net "PCIE_SAS_CPU_TX_N0")
	)
	(segment
		(start 186.34202 -58.928)
		(end 188.835538 -58.928)
		(width 0.1397)
		(layer "F.Cu")
		(net "PCIE_SAS_CPU_TX_N0")
	)
	(segment
		(start 117.395244 -3.6449)
		(end 136.451848 -3.6449)
		(width 0.1397)
		(layer "F.Cu")
		(net "PCIE_SAS_CPU_TX_N0")
	)
	(segment
		(start 95.72625 -32.715962)
		(end 95.649542 -32.639)
		(width 0.1397)
		(layer "F.Cu")
		(net "PCIE_SAS_CPU_TX_N0")
	)
	(segment
		(start 143.474186 -16.728186)
		(end 185.20156 -58.45556)
		(width 0.1397)
		(layer "F.Cu")
		(net "PCIE_SAS_CPU_TX_N0")
	)
	(segment
		(start 204.289406 -75.553824)
		(end 204.28966 -75.55357)
		(width 0.1397)
		(layer "F.Cu")
		(net "PCIE_SAS_CPU_TX_N0")
	)
	(segment
		(start 143.002 -10.53592)
		(end 143.002 -15.58798)
		(width 0.1397)
		(layer "F.Cu")
		(net "PCIE_SAS_CPU_TX_N0")
	)
	(segment
		(start 93.679772 -21.852128)
		(end 103.915972 -11.615928)
		(width 0.1397)
		(layer "F.Cu")
		(net "PCIE_SAS_CPU_TX_N0")
	)
	(segment
		(start 95.649542 -32.639)
		(end 93.679772 -30.66923)
		(width 0.1397)
		(layer "F.Cu")
		(net "PCIE_SAS_CPU_TX_N0")
	)
	(via
		(at 203.947268 -77.0255)
		(size 0.5588)
		(drill 0.3048)
		(layers "F.Cu" "B.Cu")
		(net "PCIE_SAS_CPU_TX_N0")
	)
	(arc
		(start 204.11059 -75.12177)
		(mid 204.242959 -75.320013)
		(end 204.289406 -75.553824)
		(width 0.1397)
		(layer "F.Cu")
		(net "PCIE_SAS_CPU_TX_N0")
	)
	(arc
		(start 203.29525 -73.787)
		(mid 203.390705 -74.266884)
		(end 203.662534 -74.673714)
		(width 0.1397)
		(layer "F.Cu")
		(net "PCIE_SAS_CPU_TX_N0")
	)
	(arc
		(start 136.451848 -3.6449)
		(mid 136.951256 -3.744256)
		(end 137.37463 -4.02717)
		(width 0.1397)
		(layer "F.Cu")
		(net "PCIE_SAS_CPU_TX_N0")
	)
	(arc
		(start 116.946172 -3.830828)
		(mid 117.152208 -3.693159)
		(end 117.395244 -3.6449)
		(width 0.1397)
		(layer "F.Cu")
		(net "PCIE_SAS_CPU_TX_N0")
	)
	(arc
		(start 142.37843 -9.03097)
		(mid 142.839787 -9.721578)
		(end 143.001746 -10.536174)
		(width 0.1397)
		(layer "F.Cu")
		(net "PCIE_SAS_CPU_TX_N0")
	)
	(arc
		(start 103.915972 -11.615928)
		(mid 104.122008 -11.478259)
		(end 104.365044 -11.43)
		(width 0.1397)
		(layer "F.Cu")
		(net "PCIE_SAS_CPU_TX_N0")
	)
	(arc
		(start 185.20156 -58.45556)
		(mid 185.724807 -58.805183)
		(end 186.34202 -58.928)
		(width 0.1397)
		(layer "F.Cu")
		(net "PCIE_SAS_CPU_TX_N0")
	)
	(arc
		(start 93.679772 -30.66923)
		(mid 93.404566 -30.25726)
		(end 93.307916 -29.77134)
		(width 0.1397)
		(layer "F.Cu")
		(net "PCIE_SAS_CPU_TX_N0")
	)
	(arc
		(start 95.801688 -33.678368)
		(mid 95.89269 -33.542268)
		(end 95.924624 -33.381696)
		(width 0.1397)
		(layer "F.Cu")
		(net "PCIE_SAS_CPU_TX_N0")
	)
	(arc
		(start 93.307916 -22.750018)
		(mid 93.404555 -22.264093)
		(end 93.679772 -21.852128)
		(width 0.1397)
		(layer "F.Cu")
		(net "PCIE_SAS_CPU_TX_N0")
	)
	(arc
		(start 188.835538 -58.928)
		(mid 189.321463 -59.024639)
		(end 189.733428 -59.299856)
		(width 0.1397)
		(layer "F.Cu")
		(net "PCIE_SAS_CPU_TX_N0")
	)
	(arc
		(start 108.94187 -11.43)
		(mid 109.316179 -11.355527)
		(end 109.633512 -11.143488)
		(width 0.1397)
		(layer "F.Cu")
		(net "PCIE_SAS_CPU_TX_N0")
	)
	(arc
		(start 143.002 -15.58798)
		(mid 143.124706 -16.205044)
		(end 143.474186 -16.728186)
		(width 0.1397)
		(layer "F.Cu")
		(net "PCIE_SAS_CPU_TX_N0")
	)
	(arc
		(start 203.090018 -72.656446)
		(mid 203.241937 -72.883808)
		(end 203.29525 -73.152)
		(width 0.1397)
		(layer "F.Cu")
		(net "PCIE_SAS_CPU_TX_N0")
	)
	(arc
		(start 95.924624 -33.19526)
		(mid 95.873122 -32.935872)
		(end 95.72625 -32.715962)
		(width 0.1397)
		(layer "F.Cu")
		(net "PCIE_SAS_CPU_TX_N0")
	)
	(arc
		(start 95.549974 -34.050986)
		(mid 95.572224 -33.939218)
		(end 95.635572 -33.844484)
		(width 0.1397)
		(layer "F.Cu")
		(net "PCIE_SAS_CPU_TX_N0")
	)
	(arc
		(start 204.28966 -76.198984)
		(mid 204.200682 -76.646306)
		(end 203.947268 -77.0255)
		(width 0.1397)
		(layer "F.Cu")
		(net "PCIE_SAS_CPU_TX_N0")
	)
	(segment
		(start 204.449426 -80.25003)
		(end 204.45984 -80.25003)
		(width 0.1397)
		(layer "B.Cu")
		(net "PCIE_SAS_CPU_TX_N0")
	)
	(segment
		(start 204.785214 -79.435198)
		(end 204.58049 -79.256128)
		(width 0.1397)
		(layer "B.Cu")
		(net "PCIE_SAS_CPU_TX_N0")
	)
	(segment
		(start 204.189584 -77.267562)
		(end 203.947268 -77.0255)
		(width 0.1397)
		(layer "B.Cu")
		(net "PCIE_SAS_CPU_TX_N0")
	)
	(segment
		(start 204.82687 -79.883)
		(end 204.82687 -79.5274)
		(width 0.1397)
		(layer "B.Cu")
		(net "PCIE_SAS_CPU_TX_N0")
	)
	(segment
		(start 204.26172 -78.553564)
		(end 204.26172 -77.44206)
		(width 0.1397)
		(layer "B.Cu")
		(net "PCIE_SAS_CPU_TX_N0")
	)
	(arc
		(start 204.58049 -79.256128)
		(mid 204.557532 -79.235423)
		(end 204.535278 -79.213964)
		(width 0.1397)
		(layer "B.Cu")
		(net "PCIE_SAS_CPU_TX_N0")
	)
	(arc
		(start 204.26172 -77.44206)
		(mid 204.243029 -77.347624)
		(end 204.189584 -77.267562)
		(width 0.1397)
		(layer "B.Cu")
		(net "PCIE_SAS_CPU_TX_N0")
	)
	(arc
		(start 204.45984 -80.25003)
		(mid 204.719369 -80.142529)
		(end 204.82687 -79.883)
		(width 0.1397)
		(layer "B.Cu")
		(net "PCIE_SAS_CPU_TX_N0")
	)
	(arc
		(start 204.535278 -79.213964)
		(mid 204.332795 -78.910971)
		(end 204.26172 -78.553564)
		(width 0.1397)
		(layer "B.Cu")
		(net "PCIE_SAS_CPU_TX_N0")
	)
	(arc
		(start 204.82687 -79.5274)
		(mid 204.816031 -79.476781)
		(end 204.785214 -79.435198)
		(width 0.1397)
		(layer "B.Cu")
		(net "PCIE_SAS_CPU_TX_N0")
	)
	(segment
		(start 137.062972 -254.090932)
		(end 137.075418 -254.078232)
		(width 0.1016)
		(layer "F.Cu")
		(net "SAS_EXP_GF_TX_DN2")
	)
	(segment
		(start 136.999472 -256.25044)
		(end 136.999472 -254.24384)
		(width 0.1016)
		(layer "F.Cu")
		(net "SAS_EXP_GF_TX_DN2")
	)
	(segment
		(start 137.953496 -168.56075)
		(end 137.883646 -168.490646)
		(width 0.1016)
		(layer "F.Cu")
		(net "SAS_EXP_GF_TX_DN2")
	)
	(segment
		(start 132.874766 -108.3564)
		(end 132.87502 -108.356654)
		(width 0.1016)
		(layer "F.Cu")
		(net "SAS_EXP_GF_TX_DN2")
	)
	(segment
		(start 132.87502 -108.356654)
		(end 132.87502 -99.599496)
		(width 0.1016)
		(layer "F.Cu")
		(net "SAS_EXP_GF_TX_DN2")
	)
	(segment
		(start 125.476 -154.859482)
		(end 125.476 -117.166136)
		(width 0.1016)
		(layer "F.Cu")
		(net "SAS_EXP_GF_TX_DN2")
	)
	(segment
		(start 132.845302 -99.527614)
		(end 132.758688 -99.441)
		(width 0.1016)
		(layer "F.Cu")
		(net "SAS_EXP_GF_TX_DN2")
	)
	(segment
		(start 140.335 -225.73869)
		(end 140.335 -174.309786)
		(width 0.1016)
		(layer "F.Cu")
		(net "SAS_EXP_GF_TX_DN2")
	)
	(segment
		(start 137.840466 -229.466394)
		(end 139.463018 -227.843842)
		(width 0.1016)
		(layer "F.Cu")
		(net "SAS_EXP_GF_TX_DN2")
	)
	(segment
		(start 125.885956 -116.176044)
		(end 132.287518 -109.774482)
		(width 0.1016)
		(layer "F.Cu")
		(net "SAS_EXP_GF_TX_DN2")
	)
	(segment
		(start 137.246106 -253.822454)
		(end 137.246106 -230.901748)
		(width 0.1016)
		(layer "F.Cu")
		(net "SAS_EXP_GF_TX_DN2")
	)
	(segment
		(start 132.72897 -99.369118)
		(end 132.72897 -99.0854)
		(width 0.1016)
		(layer "F.Cu")
		(net "SAS_EXP_GF_TX_DN2")
	)
	(segment
		(start 137.075418 -254.078232)
		(end 137.185908 -253.967742)
		(width 0.1016)
		(layer "F.Cu")
		(net "SAS_EXP_GF_TX_DN2")
	)
	(segment
		(start 137.883646 -168.490646)
		(end 126.34087 -156.94787)
		(width 0.1016)
		(layer "F.Cu")
		(net "SAS_EXP_GF_TX_DN2")
	)
	(arc
		(start 137.246106 -230.901748)
		(mid 137.400526 -230.124956)
		(end 137.840466 -229.466394)
		(width 0.1016)
		(layer "F.Cu")
		(net "SAS_EXP_GF_TX_DN2")
	)
	(arc
		(start 136.999472 -254.24384)
		(mid 137.016028 -254.161078)
		(end 137.062972 -254.090932)
		(width 0.1016)
		(layer "F.Cu")
		(net "SAS_EXP_GF_TX_DN2")
	)
	(arc
		(start 137.221976 -253.91872)
		(mid 137.23994 -253.872067)
		(end 137.246106 -253.822454)
		(width 0.1016)
		(layer "F.Cu")
		(net "SAS_EXP_GF_TX_DN2")
	)
	(arc
		(start 137.185908 -253.967742)
		(mid 137.20576 -253.94457)
		(end 137.221976 -253.91872)
		(width 0.1016)
		(layer "F.Cu")
		(net "SAS_EXP_GF_TX_DN2")
	)
	(arc
		(start 126.34087 -156.94787)
		(mid 125.700731 -155.989694)
		(end 125.476 -154.859482)
		(width 0.1016)
		(layer "F.Cu")
		(net "SAS_EXP_GF_TX_DN2")
	)
	(arc
		(start 125.476 -117.166136)
		(mid 125.582489 -116.630307)
		(end 125.885956 -116.176044)
		(width 0.1016)
		(layer "F.Cu")
		(net "SAS_EXP_GF_TX_DN2")
	)
	(arc
		(start 139.463018 -227.843842)
		(mid 140.10838 -226.87799)
		(end 140.335 -225.73869)
		(width 0.1016)
		(layer "F.Cu")
		(net "SAS_EXP_GF_TX_DN2")
	)
	(arc
		(start 140.335 -174.309786)
		(mid 139.716017 -171.198417)
		(end 137.953496 -168.56075)
		(width 0.1016)
		(layer "F.Cu")
		(net "SAS_EXP_GF_TX_DN2")
	)
	(arc
		(start 132.87502 -99.599496)
		(mid 132.867301 -99.560601)
		(end 132.845302 -99.527614)
		(width 0.1016)
		(layer "F.Cu")
		(net "SAS_EXP_GF_TX_DN2")
	)
	(arc
		(start 132.758688 -99.441)
		(mid 132.736705 -99.408006)
		(end 132.72897 -99.369118)
		(width 0.1016)
		(layer "F.Cu")
		(net "SAS_EXP_GF_TX_DN2")
	)
	(arc
		(start 132.287518 -109.774482)
		(mid 132.722166 -109.123845)
		(end 132.874766 -108.3564)
		(width 0.1016)
		(layer "F.Cu")
		(net "SAS_EXP_GF_TX_DN2")
	)
	(segment
		(start 330.699872 -232.926636)
		(end 330.699872 -233.671872)
		(width 0.1143)
		(layer "F.Cu")
		(net "ADC_P5V_STBY")
	)
	(segment
		(start 331.94625 -234.91825)
		(end 334.52562 -234.91825)
		(width 0.1143)
		(layer "F.Cu")
		(net "ADC_P5V_STBY")
	)
	(segment
		(start 330.699872 -233.671872)
		(end 331.94625 -234.91825)
		(width 0.1143)
		(layer "F.Cu")
		(net "ADC_P5V_STBY")
	)
	(segment
		(start 337.6676 -231.77627)
		(end 337.6676 -193.3956)
		(width 0.1143)
		(layer "F.Cu")
		(net "ADC_P5V_STBY")
	)
	(segment
		(start 337.6676 -193.3956)
		(end 335.026 -190.754)
		(width 0.1143)
		(layer "F.Cu")
		(net "ADC_P5V_STBY")
	)
	(segment
		(start 335.026 -190.754)
		(end 335.026 -179.832)
		(width 0.1143)
		(layer "F.Cu")
		(net "ADC_P5V_STBY")
	)
	(segment
		(start 334.52562 -234.91825)
		(end 337.6676 -231.77627)
		(width 0.1143)
		(layer "F.Cu")
		(net "ADC_P5V_STBY")
	)
	(via
		(at 335.026 -179.832)
		(size 0.508)
		(drill 0.254)
		(layers "F.Cu" "B.Cu")
		(net "ADC_P5V_STBY")
	)
	(via
		(at 334.01 -178.816)
		(size 0.7112)
		(drill 0.3556)
		(layers "F.Cu" "B.Cu")
		(net "ADC_P5V_STBY")
	)
	(segment
		(start 319.024 -178.2445)
		(end 318.4525 -177.673)
		(width 0.1143)
		(layer "B.Cu")
		(net "ADC_P5V_STBY")
	)
	(segment
		(start 323.342 -178.2445)
		(end 324.358 -178.2445)
		(width 0.1143)
		(layer "B.Cu")
		(net "ADC_P5V_STBY")
	)
	(segment
		(start 335.026 -179.832)
		(end 334.01 -178.816)
		(width 0.1143)
		(layer "B.Cu")
		(net "ADC_P5V_STBY")
	)
	(segment
		(start 324.358 -178.2445)
		(end 325.374 -178.2445)
		(width 0.1143)
		(layer "B.Cu")
		(net "ADC_P5V_STBY")
	)
	(segment
		(start 333.4385 -178.2445)
		(end 334.01 -178.816)
		(width 0.1143)
		(layer "B.Cu")
		(net "ADC_P5V_STBY")
	)
	(segment
		(start 323.342 -178.2445)
		(end 319.024 -178.2445)
		(width 0.1143)
		(layer "B.Cu")
		(net "ADC_P5V_STBY")
	)
	(segment
		(start 325.374 -178.2445)
		(end 333.4385 -178.2445)
		(width 0.1143)
		(layer "B.Cu")
		(net "ADC_P5V_STBY")
	)
	(segment
		(start 258.9911 -94.566486)
		(end 258.9911 -93.087952)
		(width 0.1143)
		(layer "F.Cu")
		(net "RMII_BMC_CRS_DV")
	)
	(segment
		(start 265.11885 -120.272302)
		(end 265.11885 -100.694236)
		(width 0.1143)
		(layer "F.Cu")
		(net "RMII_BMC_CRS_DV")
	)
	(segment
		(start 258.9911 -93.087952)
		(end 204.574648 -38.6715)
		(width 0.1143)
		(layer "F.Cu")
		(net "RMII_BMC_CRS_DV")
	)
	(segment
		(start 283.180282 -150.169118)
		(end 282.491688 -149.480524)
		(width 0.1143)
		(layer "F.Cu")
		(net "RMII_BMC_CRS_DV")
	)
	(segment
		(start 189.357 -38.6715)
		(end 197.612 -38.6715)
		(width 0.1143)
		(layer "F.Cu")
		(net "RMII_BMC_CRS_DV")
	)
	(segment
		(start 295.529 -160.401)
		(end 295.783 -160.147)
		(width 0.1143)
		(layer "F.Cu")
		(net "RMII_BMC_CRS_DV")
	)
	(segment
		(start 280.028142 -145.3515)
		(end 275.722842 -145.3515)
		(width 0.1143)
		(layer "F.Cu")
		(net "RMII_BMC_CRS_DV")
	)
	(segment
		(start 295.529 -161.0995)
		(end 295.529 -160.401)
		(width 0.1143)
		(layer "F.Cu")
		(net "RMII_BMC_CRS_DV")
	)
	(segment
		(start 282.491688 -149.480524)
		(end 282.491688 -147.815046)
		(width 0.1143)
		(layer "F.Cu")
		(net "RMII_BMC_CRS_DV")
	)
	(segment
		(start 266.1158 -135.744458)
		(end 266.1158 -121.269252)
		(width 0.1143)
		(layer "F.Cu")
		(net "RMII_BMC_CRS_DV")
	)
	(segment
		(start 283.180282 -150.34895)
		(end 283.180282 -150.169118)
		(width 0.1143)
		(layer "F.Cu")
		(net "RMII_BMC_CRS_DV")
	)
	(segment
		(start 204.574648 -38.6715)
		(end 197.612 -38.6715)
		(width 0.1143)
		(layer "F.Cu")
		(net "RMII_BMC_CRS_DV")
	)
	(segment
		(start 266.1158 -121.269252)
		(end 265.11885 -120.272302)
		(width 0.1143)
		(layer "F.Cu")
		(net "RMII_BMC_CRS_DV")
	)
	(segment
		(start 275.722842 -145.3515)
		(end 266.1158 -135.744458)
		(width 0.1143)
		(layer "F.Cu")
		(net "RMII_BMC_CRS_DV")
	)
	(segment
		(start 188.149992 -38.6715)
		(end 189.357 -38.6715)
		(width 0.1143)
		(layer "F.Cu")
		(net "RMII_BMC_CRS_DV")
	)
	(segment
		(start 295.783 -160.147)
		(end 295.783 -159.695642)
		(width 0.1143)
		(layer "F.Cu")
		(net "RMII_BMC_CRS_DV")
	)
	(segment
		(start 282.491688 -147.815046)
		(end 280.028142 -145.3515)
		(width 0.1143)
		(layer "F.Cu")
		(net "RMII_BMC_CRS_DV")
	)
	(segment
		(start 265.11885 -100.694236)
		(end 258.9911 -94.566486)
		(width 0.1143)
		(layer "F.Cu")
		(net "RMII_BMC_CRS_DV")
	)
	(via
		(at 283.180282 -150.34895)
		(size 0.5588)
		(drill 0.3048)
		(layers "F.Cu" "B.Cu")
		(net "RMII_BMC_CRS_DV")
	)
	(via
		(at 197.612 -38.6715)
		(size 0.7112)
		(drill 0.3556)
		(layers "F.Cu" "B.Cu")
		(net "RMII_BMC_CRS_DV")
	)
	(via
		(at 295.783 -159.695642)
		(size 0.5588)
		(drill 0.3048)
		(layers "F.Cu" "B.Cu")
		(net "RMII_BMC_CRS_DV")
	)
	(segment
		(start 283.180282 -149.843236)
		(end 284.144466 -148.879052)
		(width 0.127)
		(layer "In2.Cu")
		(net "RMII_BMC_CRS_DV")
	)
	(segment
		(start 283.180282 -150.34895)
		(end 283.180282 -149.843236)
		(width 0.127)
		(layer "In2.Cu")
		(net "RMII_BMC_CRS_DV")
	)
	(segment
		(start 288.065972 -148.879052)
		(end 289.964368 -150.777448)
		(width 0.127)
		(layer "In2.Cu")
		(net "RMII_BMC_CRS_DV")
	)
	(segment
		(start 289.964368 -150.777448)
		(end 289.964368 -153.522934)
		(width 0.127)
		(layer "In2.Cu")
		(net "RMII_BMC_CRS_DV")
	)
	(segment
		(start 284.144466 -148.879052)
		(end 288.065972 -148.879052)
		(width 0.127)
		(layer "In2.Cu")
		(net "RMII_BMC_CRS_DV")
	)
	(segment
		(start 295.783 -159.341566)
		(end 295.783 -159.695642)
		(width 0.127)
		(layer "In2.Cu")
		(net "RMII_BMC_CRS_DV")
	)
	(segment
		(start 289.964368 -153.522934)
		(end 295.783 -159.341566)
		(width 0.127)
		(layer "In2.Cu")
		(net "RMII_BMC_CRS_DV")
	)
	(zone
		(layer "F.Cu")
		(hatch none 0.5)
		(connect_pads
			(clearance 0)
		)
		(min_thickness 0.25)
		(keepout
			(tracks not_allowed)
			(vias allowed)
			(pads allowed)
			(copperpour not_allowed)
			(footprints allowed)
		)
		(placement
			(enabled no)
			(sheetname "")
		)
		(fill
			(thermal_gap 0.5)
			(thermal_bridge_width 0.5)
			(island_removal_mode 0)
		)
		(polygon
			(pts
				(arc
					(start 134.11454 -87.11438)
					(mid 133.731127 -86.730586)
					(end 133.34746 -87.114126)
				)
				(xy 133.34746 -87.33155)
				(arc
					(start 133.400038 -87.33155)
					(mid 133.421908 -87.3272)
					(end 133.440424 -87.314786)
				)
				(arc
					(start 133.484366 -87.270844)
					(mid 133.937626 -86.9075)
					(end 133.574282 -87.36076)
				)
				(xy 133.53034 -87.404702) (xy 133.511798 -87.423244)
				(arc
					(start 133.508496 -87.423244)
					(mid 133.470463 -87.444539)
					(end 133.428486 -87.456264)
				)
				(xy 133.426454 -87.45855) (xy 133.34746 -87.45855) (xy 133.34746 -87.67445) (xy 133.376416 -87.67445)
				(arc
					(start 133.377432 -87.67572)
					(mid 133.466552 -87.697589)
					(end 133.545072 -87.745062)
				)
				(xy 133.54685 -87.745062) (xy 133.565392 -87.763604)
				(arc
					(start 133.574282 -87.772494)
					(mid 133.937626 -88.225754)
					(end 133.484366 -87.86241)
				)
				(arc
					(start 133.475476 -87.85352)
					(mid 133.417921 -87.815)
					(end 133.35 -87.80145)
				)
				(xy 133.34746 -87.80145)
				(arc
					(start 133.34746 -88.019128)
					(mid 133.731 -88.402668)
					(end 134.11454 -88.019128)
				)
			)
		)
	)
	(zone
		(net "GND")
		(layer "F.Cu")
		(hatch none 0.5)
		(connect_pads
			(clearance 0.5)
		)
		(min_thickness 0.25)
		(fill yes
			(thermal_gap 0.5)
			(thermal_bridge_width 0.5)
			(island_removal_mode 0)
		)
		(polygon
			(pts
				(xy 316.992 -183.007) (xy 316.484 -183.515) (xy 316.484 -185.293) (xy 317.119 -185.928) (xy 317.119 -194.437)
				(xy 320.294 -197.612) (xy 320.294 -203.835) (xy 321.818 -205.359) (xy 321.818 -214.63) (xy 321.437 -215.011)
				(xy 315.976 -215.011) (xy 315.087 -215.9) (xy 315.087 -221.488) (xy 306.07 -230.505) (xy 277.495 -230.505)
				(xy 277.241 -230.251) (xy 277.241 -229.489) (xy 277.495 -229.235) (xy 296.418 -229.235) (xy 297.053 -228.6)
				(xy 297.053 -224.155) (xy 296.799 -223.901) (xy 288.036 -223.901) (xy 287.528 -224.409) (xy 284.734 -224.409)
				(xy 284.48 -224.155) (xy 284.48 -223.139) (xy 284.353 -223.012) (xy 282.829 -223.012) (xy 282.702 -223.139)
				(xy 282.702 -224.79) (xy 282.194 -225.298) (xy 275.209 -225.298) (xy 274.955 -225.552) (xy 274.955 -233.934)
				(xy 276.225 -235.204) (xy 329.311 -235.204) (xy 330.073 -234.442) (xy 330.073 -222.758) (xy 327.279 -219.964)
				(xy 327.279 -188.214) (xy 322.072 -183.007)
			)
		)
		(polygon
			(pts
				(xy 279.696672 -225.751136) (xy 279.442672 -225.751136) (xy 279.442672 -226.005136) (xy 279.696672 -226.005136)
			)
		)
		(polygon
			(pts
				(xy 279.087072 -225.751136) (xy 278.833072 -225.751136) (xy 278.833072 -226.005136) (xy 279.087072 -226.005136)
			)
		)
		(polygon
			(pts
				(xy 288.840672 -224.354136) (xy 288.586672 -224.354136) (xy 288.586672 -224.608136) (xy 288.840672 -224.608136)
			)
		)
		(polygon
			(pts
				(xy 288.231072 -224.354136) (xy 287.977072 -224.354136) (xy 287.977072 -224.608136) (xy 288.231072 -224.608136)
			)
		)
		(polygon
			(pts
				(xy 321.1322 -197.4596) (xy 320.8782 -197.4596) (xy 320.8782 -197.7136) (xy 321.1322 -197.7136)
			)
		)
	)
	(zone
		(layer "F.Cu")
		(hatch none 0.5)
		(connect_pads
			(clearance 0)
		)
		(min_thickness 0.25)
		(keepout
			(tracks allowed)
			(vias allowed)
			(pads allowed)
			(copperpour allowed)
			(footprints allowed)
		)
		(placement
			(enabled no)
			(sheetname "")
		)
		(fill
			(thermal_gap 0.5)
			(thermal_bridge_width 0.5)
			(island_removal_mode 0)
		)
		(polygon
			(pts
				(xy 263.8806 -37.1094) (xy 263.8806 -34.8488) (xy 266.4206 -34.8488) (xy 266.4206 -37.1094)
			)
		)
	)
	(zone
		(layer "F.Cu")
		(hatch none 0.5)
		(connect_pads
			(clearance 0)
		)
		(min_thickness 0.25)
		(keepout
			(tracks not_allowed)
			(vias allowed)
			(pads allowed)
			(copperpour not_allowed)
			(footprints allowed)
		)
		(placement
			(enabled no)
			(sheetname "")
		)
		(fill
			(thermal_gap 0.5)
			(thermal_bridge_width 0.5)
			(island_removal_mode 0)
		)
		(polygon
			(pts
				(xy 182.699914 -82.350102) (xy 182.699914 -109.000036) (xy 195.699888 -109.000036) (xy 195.699888 -82.350102)
			)
		)
	)
	(zone
		(layer "F.Cu")
		(hatch none 0.5)
		(connect_pads
			(clearance 0)
		)
		(min_thickness 0.25)
		(keepout
			(tracks allowed)
			(vias allowed)
			(pads allowed)
			(copperpour allowed)
			(footprints allowed)
		)
		(placement
			(enabled no)
			(sheetname "")
		)
		(fill
			(thermal_gap 0.5)
			(thermal_bridge_width 0.5)
			(island_removal_mode 0)
		)
		(polygon
			(pts
				(xy 68.199 -258.826) (xy 68.199 -253.492) (xy 68.199 -252.095) (xy 99.695 -252.095) (xy 99.695 -250.698)
				(xy 102.616 -250.698) (xy 102.616 -252.095) (xy 150.241 -252.095) (xy 150.241 -253.492) (xy 150.241 -258.826)
			)
		)
	)
	(zone
		(net "GND")
		(layer "F.Cu")
		(hatch none 0.5)
		(connect_pads
			(clearance 0.5)
		)
		(min_thickness 0.25)
		(fill yes
			(thermal_gap 0.5)
			(thermal_bridge_width 0.5)
			(island_removal_mode 0)
		)
		(polygon
			(pts
				(xy 296.037 -58.42) (xy 295.783 -58.674) (xy 295.783 -59.182) (xy 295.91 -59.309) (xy 301.244 -59.309)
				(xy 301.752 -59.817) (xy 305.054 -59.817) (xy 305.181 -59.69) (xy 305.181 -59.182) (xy 305.054 -59.055)
				(xy 303.149 -59.055) (xy 302.895 -58.801) (xy 301.879 -58.801) (xy 301.498 -58.42)
			)
		)
	)
	(zone
		(layer "F.Cu")
		(hatch none 0.5)
		(connect_pads
			(clearance 0)
		)
		(min_thickness 0.25)
		(keepout
			(tracks allowed)
			(vias allowed)
			(pads allowed)
			(copperpour allowed)
			(footprints allowed)
		)
		(placement
			(enabled no)
			(sheetname "")
		)
		(fill
			(thermal_gap 0.5)
			(thermal_bridge_width 0.5)
			(island_removal_mode 0)
		)
		(polygon
			(pts
				(xy 253.873 -118.872) (xy 253.873 -117.475) (xy 255.143 -117.475) (xy 255.143 -118.872)
			)
		)
	)
	(zone
		(net "GND")
		(layer "F.Cu")
		(hatch none 0.5)
		(connect_pads
			(clearance 0.5)
		)
		(min_thickness 0.25)
		(fill yes
			(thermal_gap 0.5)
			(thermal_bridge_width 0.5)
			(island_removal_mode 0)
		)
		(polygon
			(pts
				(xy 64.008 -142.748) (xy 63.5 -143.256) (xy 60.452 -143.256) (xy 60.198 -143.51) (xy 60.198 -143.891)
				(xy 60.325 -144.018) (xy 61.341 -144.018) (xy 61.849 -144.526) (xy 61.849 -170.307) (xy 58.039 -174.117)
				(xy 58.039 -183.261) (xy 57.023 -184.277) (xy 57.023 -185.928) (xy 56.515 -186.436) (xy 47.498 -186.436)
				(xy 46.863 -187.071) (xy 46.863 -188.595) (xy 46.101 -189.357) (xy 44.323 -189.357) (xy 43.561 -188.595)
				(xy 43.561 -182.753) (xy 42.545 -181.737) (xy 33.782 -181.737) (xy 28.194 -187.325) (xy 28.194 -197.104)
				(xy 29.464 -198.374) (xy 38.1 -198.374) (xy 38.1635 -198.4375) (xy 39.751 -196.85) (xy 70.231 -196.85)
				(xy 71.501 -195.58) (xy 71.501 -190.5) (xy 84.709 -177.292) (xy 84.709 -154.051) (xy 80.518 -149.86)
				(xy 78.74 -149.86) (xy 76.835 -147.955) (xy 76.835 -144.399) (xy 75.184 -142.748)
			)
		)
	)
	(zone
		(layer "F.Cu")
		(hatch none 0.5)
		(connect_pads
			(clearance 0)
		)
		(min_thickness 0.25)
		(keepout
			(tracks not_allowed)
			(vias allowed)
			(pads allowed)
			(copperpour not_allowed)
			(footprints allowed)
		)
		(placement
			(enabled no)
			(sheetname "")
		)
		(fill
			(thermal_gap 0.5)
			(thermal_bridge_width 0.5)
			(island_removal_mode 0)
		)
		(polygon
			(pts
				(arc
					(start 351.11309 -151.97201)
					(mid 350.75495 -151.61387)
					(end 350.39681 -151.97201)
				)
				(xy 350.39681 -152.19045) (xy 350.41967 -152.19045)
				(arc
					(start 350.517206 -152.092914)
					(mid 350.94355 -151.78341)
					(end 350.634046 -152.209754)
				)
				(xy 350.53651 -152.30729) (xy 350.48825 -152.35555) (xy 350.41967 -152.35555) (xy 350.39681 -152.35555)
				(xy 350.39681 -152.53335) (xy 350.41967 -152.53335) (xy 350.48825 -152.53335) (xy 350.53651 -152.58161)
				(arc
					(start 350.634046 -152.679146)
					(mid 350.94355 -153.10549)
					(end 350.517206 -152.795986)
				)
				(xy 350.41967 -152.69845) (xy 350.39681 -152.69845)
				(arc
					(start 350.39681 -152.916636)
					(mid 350.754823 -153.27503)
					(end 351.11309 -152.91689)
				)
			)
		)
	)
	(zone
		(net "P1V5_E_VIN")
		(layer "F.Cu")
		(hatch none 0.5)
		(connect_pads
			(clearance 0.5)
		)
		(min_thickness 0.25)
		(fill yes
			(thermal_gap 0.5)
			(thermal_bridge_width 0.5)
			(island_removal_mode 0)
		)
		(polygon
			(pts
				(xy 203.454 -112.014) (xy 202.565 -112.903) (xy 202.565 -114.681) (xy 203.835 -115.951) (xy 211.201 -115.951)
				(xy 211.455 -115.697) (xy 211.455 -112.141) (xy 211.328 -112.014)
			)
		)
		(polygon
			(pts
				(xy 205.352396 -114.827812) (xy 205.098396 -114.827812) (xy 205.098396 -115.081812) (xy 205.352396 -115.081812)
			)
		)
		(polygon
			(pts
				(xy 204.488796 -114.827812) (xy 204.234796 -114.827812) (xy 204.234796 -115.081812) (xy 204.488796 -115.081812)
			)
		)
		(polygon
			(pts
				(xy 205.225396 -112.541812) (xy 204.971396 -112.541812) (xy 204.971396 -112.795812) (xy 205.225396 -112.795812)
			)
		)
		(polygon
			(pts
				(xy 204.615796 -112.541812) (xy 204.361796 -112.541812) (xy 204.361796 -112.795812) (xy 204.615796 -112.795812)
			)
		)
	)
	(zone
		(layer "F.Cu")
		(hatch none 0.5)
		(connect_pads
			(clearance 0)
		)
		(min_thickness 0.25)
		(keepout
			(tracks allowed)
			(vias allowed)
			(pads allowed)
			(copperpour allowed)
			(footprints allowed)
		)
		(placement
			(enabled no)
			(sheetname "")
		)
		(fill
			(thermal_gap 0.5)
			(thermal_bridge_width 0.5)
			(island_removal_mode 0)
		)
		(polygon
			(pts
				(xy 168.529 -113.665) (xy 168.529 -111.887) (xy 170.18 -111.887) (xy 170.18 -113.665)
			)
		)
	)
	(zone
		(layer "F.Cu")
		(hatch none 0.5)
		(connect_pads
			(clearance 0)
		)
		(min_thickness 0.25)
		(keepout
			(tracks not_allowed)
			(vias allowed)
			(pads allowed)
			(copperpour not_allowed)
			(footprints allowed)
		)
		(placement
			(enabled no)
			(sheetname "")
		)
		(fill
			(thermal_gap 0.5)
			(thermal_bridge_width 0.5)
			(island_removal_mode 0)
		)
		(polygon
			(pts
				(xy 326.300084 -61.237368) (xy 326.300084 -72.237346) (xy 337.799934 -72.237346) (xy 337.799934 -61.237368)
			)
		)
	)
	(zone
		(net "GND")
		(layer "F.Cu")
		(hatch none 0.5)
		(connect_pads
			(clearance 0.5)
		)
		(min_thickness 0.25)
		(fill yes
			(thermal_gap 0.5)
			(thermal_bridge_width 0.5)
			(island_removal_mode 0)
		)
		(polygon
			(pts
				(xy 75.565 -0.889) (xy 75.311 -1.143) (xy 75.311 -2.794) (xy 75.565 -3.048) (xy 79.121 -3.048) (xy 80.137 -2.032)
				(xy 81.661 -2.032) (xy 82.169 -2.54) (xy 82.169 -2.921) (xy 82.296 -3.048) (xy 82.931 -3.048) (xy 83.947 -4.064)
				(xy 97.155 -4.064) (xy 97.282 -3.937) (xy 97.282 -3.175) (xy 97.028 -2.921) (xy 95.377 -2.921) (xy 95.123 -2.667)
				(xy 95.123 -1.143) (xy 94.869 -0.889)
			)
		)
		(polygon
			(pts
				(xy 96.4692 -3.302) (xy 95.9358 -3.302) (xy 95.9358 -3.556) (xy 96.4692 -3.556)
			)
		)
		(polygon
			(pts
				(xy 95.5802 -3.302) (xy 95.0468 -3.302) (xy 95.0468 -3.556) (xy 95.5802 -3.556)
			)
		)
		(polygon
			(pts
				(xy 94.6912 -3.302) (xy 94.4372 -3.302) (xy 94.4372 -3.556) (xy 94.6912 -3.556)
			)
		)
	)
	(zone
		(net "P1V5_E_SW")
		(layer "F.Cu")
		(hatch none 0.5)
		(connect_pads
			(clearance 0.5)
		)
		(min_thickness 0.25)
		(fill yes
			(thermal_gap 0.5)
			(thermal_bridge_width 0.5)
			(island_removal_mode 0)
		)
		(polygon
			(pts
				(xy 196.215 -103.632) (xy 195.834 -104.013) (xy 195.834 -109.093) (xy 194.818 -110.109) (xy 194.818 -112.395)
				(xy 195.072 -112.649) (xy 198.12 -112.649) (xy 198.882 -113.411) (xy 200.025 -113.411) (xy 200.152 -113.284)
				(xy 200.152 -112.395) (xy 200.66 -111.887) (xy 200.66 -109.347) (xy 201.93 -108.077) (xy 201.93 -103.886)
				(xy 201.676 -103.632)
			)
		)
		(polygon
			(pts
				(xy 196.030596 -111.475012) (xy 195.776596 -111.475012) (xy 195.776596 -111.729012) (xy 196.030596 -111.729012)
			)
		)
		(polygon
			(pts
				(xy 199.840596 -110.560612) (xy 199.586596 -110.560612) (xy 199.586596 -110.814612) (xy 199.840596 -110.814612)
			)
		)
		(polygon
			(pts
				(xy 199.840596 -109.697012) (xy 199.586596 -109.697012) (xy 199.586596 -109.951012) (xy 199.840596 -109.951012)
			)
		)
	)
	(zone
		(layer "F.Cu")
		(hatch none 0.5)
		(connect_pads
			(clearance 0)
		)
		(min_thickness 0.25)
		(keepout
			(tracks not_allowed)
			(vias allowed)
			(pads allowed)
			(copperpour not_allowed)
			(footprints allowed)
		)
		(placement
			(enabled no)
			(sheetname "")
		)
		(fill
			(thermal_gap 0.5)
			(thermal_bridge_width 0.5)
			(island_removal_mode 0)
		)
		(polygon
			(pts
				(arc
					(start 32.334708 -89.712546)
					(mid 31.950914 -90.095959)
					(end 32.334454 -90.479626)
				)
				(arc
					(start 33.311338 -90.479626)
					(mid 33.694878 -90.096086)
					(end 33.311338 -89.712546)
				)
				(arc
					(start 33.153604 -89.712546)
					(mid 33.169497 -89.772073)
					(end 33.19145 -89.82964)
				)
				(arc
					(start 33.19145 -89.82964)
					(mid 33.48782 -90.328718)
					(end 33.088072 -89.907872)
				)
				(arc
					(start 33.088072 -89.907872)
					(mid 33.04922 -89.812485)
					(end 33.024318 -89.712546)
				)
				(arc
					(start 32.772858 -89.712546)
					(mid 32.750127 -89.757235)
					(end 32.720788 -89.79789)
				)
				(xy 32.720788 -89.799668) (xy 32.702246 -89.81821)
				(arc
					(start 32.581088 -89.939368)
					(mid 32.127828 -90.302712)
					(end 32.491172 -89.849452)
				)
				(xy 32.61233 -89.728294) (xy 32.626554 -89.712546)
			)
		)
	)
	(zone
		(net "GND")
		(layer "F.Cu")
		(hatch none 0.5)
		(connect_pads
			(clearance 0.5)
		)
		(min_thickness 0.25)
		(fill yes
			(thermal_gap 0.5)
			(thermal_bridge_width 0.5)
			(island_removal_mode 0)
		)
		(polygon
			(pts
				(xy 90.297 -10.795) (xy 90.043 -11.049) (xy 90.043 -14.605) (xy 92.329 -16.891) (xy 92.329 -17.526)
				(xy 92.583 -17.78) (xy 94.107 -17.78) (xy 94.488 -17.399) (xy 94.488 -12.7) (xy 94.996 -12.192)
				(xy 96.52 -12.192) (xy 96.647 -12.065) (xy 96.647 -10.922) (xy 96.52 -10.795)
			)
		)
	)
	(zone
		(layer "F.Cu")
		(hatch none 0.5)
		(connect_pads
			(clearance 0)
		)
		(min_thickness 0.25)
		(keepout
			(tracks allowed)
			(vias allowed)
			(pads allowed)
			(copperpour allowed)
			(footprints allowed)
		)
		(placement
			(enabled no)
			(sheetname "")
		)
		(fill
			(thermal_gap 0.5)
			(thermal_bridge_width 0.5)
			(island_removal_mode 0)
		)
		(polygon
			(pts
				(xy 330.835 -165.481) (xy 330.835 -163.195) (xy 332.486 -163.195) (xy 332.486 -165.481)
			)
		)
	)
	(zone
		(net "P5V_STBY")
		(layer "F.Cu")
		(hatch none 0.5)
		(connect_pads
			(clearance 0.5)
		)
		(min_thickness 0.25)
		(fill yes
			(thermal_gap 0.5)
			(thermal_bridge_width 0.5)
			(island_removal_mode 0)
		)
		(polygon
			(pts
				(xy 343.662 -87.249) (xy 343.281 -87.63) (xy 343.281 -88.773) (xy 338.836 -93.218) (xy 338.836 -99.187)
				(xy 339.217 -99.568) (xy 346.964 -99.568) (xy 347.345 -99.187) (xy 347.345 -87.884) (xy 346.71 -87.249)
			)
		)
	)
	(zone
		(net "P12V")
		(layer "F.Cu")
		(hatch none 0.5)
		(connect_pads
			(clearance 0.5)
		)
		(min_thickness 0.25)
		(fill yes
			(thermal_gap 0.5)
			(thermal_bridge_width 0.5)
			(island_removal_mode 0)
		)
		(polygon
			(pts
				(xy 330.073 -118.745) (xy 329.946 -118.872) (xy 329.946 -120.777) (xy 328.422 -122.301) (xy 322.072 -122.301)
				(xy 321.564 -121.793) (xy 321.564 -119.761) (xy 321.437 -119.634) (xy 320.675 -119.634) (xy 320.548 -119.761)
				(xy 320.548 -121.793) (xy 320.04 -122.301) (xy 316.738 -122.301) (xy 314.96 -120.523) (xy 301.879 -120.523)
				(xy 300.99 -121.412) (xy 300.99 -125.857) (xy 301.625 -126.492) (xy 312.039 -126.492) (xy 315.468 -129.921)
				(xy 317.627 -129.921) (xy 318.389 -129.159) (xy 334.645 -129.159) (xy 339.598 -124.206) (xy 345.694 -124.206)
				(xy 345.948 -123.952) (xy 345.948 -120.269) (xy 345.567 -119.888) (xy 341.63 -119.888) (xy 340.487 -118.745)
			)
		)
		(polygon
			(pts
				(xy 331.5335 -119.9007) (xy 331.2795 -119.9007) (xy 331.2795 -120.1547) (xy 331.5335 -120.1547)
			)
		)
	)
	(zone
		(layer "F.Cu")
		(hatch none 0.5)
		(connect_pads
			(clearance 0)
		)
		(min_thickness 0.25)
		(keepout
			(tracks not_allowed)
			(vias allowed)
			(pads allowed)
			(copperpour not_allowed)
			(footprints allowed)
		)
		(placement
			(enabled no)
			(sheetname "")
		)
		(fill
			(thermal_gap 0.5)
			(thermal_bridge_width 0.5)
			(island_removal_mode 0)
		)
		(polygon
			(pts
				(arc
					(start 297.076622 -73.40346)
					(mid 297.092946 -73.355417)
					(end 297.112182 -73.308464)
				)
				(arc
					(start 297.112182 -73.308464)
					(mid 296.73995 -73.697339)
					(end 297.123358 -74.07529)
				)
				(arc
					(start 298.139104 -74.07529)
					(mid 298.522898 -73.691877)
					(end 298.139358 -73.30821)
				)
				(xy 297.872658 -73.30821)
				(arc
					(start 297.999658 -73.43521)
					(mid 298.345912 -73.898304)
					(end 297.882818 -73.55205)
				)
				(xy 297.72102 -73.390252)
				(arc
					(start 297.72102 -73.385934)
					(mid 297.699027 -73.348768)
					(end 297.68419 -73.30821)
				)
				(arc
					(start 297.297602 -73.30821)
					(mid 297.267573 -73.365434)
					(end 297.243246 -73.425304)
				)
				(arc
					(start 297.243246 -73.425304)
					(mid 297.085685 -73.981349)
					(end 297.076622 -73.40346)
				)
			)
		)
	)
	(zone
		(net "GND")
		(layer "F.Cu")
		(hatch none 0.5)
		(connect_pads
			(clearance 0.5)
		)
		(min_thickness 0.25)
		(fill yes
			(thermal_gap 0.5)
			(thermal_bridge_width 0.5)
			(island_removal_mode 0)
		)
		(polygon
			(pts
				(xy 63.246 -44.577) (xy 62.738 -45.085) (xy 62.738 -67.056) (xy 63.119 -67.437) (xy 67.437 -67.437)
				(xy 69.723 -65.151) (xy 69.723 -54.864) (xy 69.088 -54.229) (xy 65.278 -54.229) (xy 64.77 -53.721)
				(xy 64.77 -50.546) (xy 65.151 -50.165) (xy 65.2272 -50.165) (xy 66.675 -48.7172) (xy 68.4784 -48.7172)
				(xy 68.58 -48.6156) (xy 68.58 -44.831) (xy 68.326 -44.577)
			)
		)
		(polygon
			(pts
				(xy 69.1388 -54.737) (xy 68.8848 -54.737) (xy 68.8848 -54.991) (xy 69.1388 -54.991)
			)
		)
		(polygon
			(pts
				(xy 68.5292 -54.737) (xy 68.2752 -54.737) (xy 68.2752 -54.991) (xy 68.5292 -54.991)
			)
		)
		(polygon
			(pts
				(xy 68.1228 -54.737) (xy 67.8688 -54.737) (xy 67.8688 -54.991) (xy 68.1228 -54.991)
			)
		)
		(polygon
			(pts
				(xy 67.5132 -54.737) (xy 67.2592 -54.737) (xy 67.2592 -54.991) (xy 67.5132 -54.991)
			)
		)
	)
	(zone
		(layer "F.Cu")
		(hatch none 0.5)
		(connect_pads
			(clearance 0)
		)
		(min_thickness 0.25)
		(keepout
			(tracks allowed)
			(vias allowed)
			(pads allowed)
			(copperpour allowed)
			(footprints not_allowed)
		)
		(placement
			(enabled no)
			(sheetname "")
		)
		(fill
			(thermal_gap 0.5)
			(thermal_bridge_width 0.5)
			(island_removal_mode 0)
		)
		(polygon
			(pts
				(xy 337.799934 -61.237368) (xy 326.300084 -61.237368) (xy 326.300084 -27.737308) (xy 337.799934 -27.737308)
			)
		)
	)
	(zone
		(net "SYSPLL_VDDA18")
		(layer "F.Cu")
		(hatch none 0.5)
		(connect_pads
			(clearance 0.5)
		)
		(min_thickness 0.25)
		(fill yes
			(thermal_gap 0.5)
			(thermal_bridge_width 0.5)
			(island_removal_mode 0)
		)
		(polygon
			(pts
				(xy 80.753966 -86.106) (xy 80.626966 -86.233) (xy 80.626966 -88.646) (xy 80.753966 -88.773) (xy 81.134966 -88.773)
				(xy 81.261966 -88.646) (xy 81.261966 -88.265) (xy 81.769966 -87.757) (xy 88.246966 -87.757) (xy 88.373966 -87.63)
				(xy 88.373966 -86.233) (xy 88.246966 -86.106)
			)
		)
	)
	(zone
		(layer "F.Cu")
		(hatch none 0.5)
		(connect_pads
			(clearance 0)
		)
		(min_thickness 0.25)
		(keepout
			(tracks allowed)
			(vias allowed)
			(pads allowed)
			(copperpour allowed)
			(footprints allowed)
		)
		(placement
			(enabled no)
			(sheetname "")
		)
		(fill
			(thermal_gap 0.5)
			(thermal_bridge_width 0.5)
			(island_removal_mode 0)
		)
		(polygon
			(pts
				(xy 40.64 -120.015) (xy 40.64 -118.872) (xy 42.418 -118.872) (xy 42.418 -120.015)
			)
		)
	)
	(zone
		(net "P12V")
		(layer "F.Cu")
		(hatch none 0.5)
		(connect_pads
			(clearance 0.5)
		)
		(min_thickness 0.25)
		(fill yes
			(thermal_gap 0.5)
			(thermal_bridge_width 0.5)
			(island_removal_mode 0)
		)
		(polygon
			(pts
				(xy 80.137 -2.286) (xy 79.756 -2.667) (xy 79.756 -5.334) (xy 80.01 -5.588) (xy 80.899 -5.588) (xy 81.915 -6.604)
				(xy 82.423 -6.604) (xy 82.677 -6.35) (xy 82.677 -3.556) (xy 82.55 -3.429) (xy 82.296 -3.429) (xy 82.042 -3.175)
				(xy 82.042 -2.54) (xy 81.788 -2.286)
			)
		)
	)
	(zone
		(layer "F.Cu")
		(hatch none 0.5)
		(connect_pads
			(clearance 0)
		)
		(min_thickness 0.25)
		(keepout
			(tracks allowed)
			(vias allowed)
			(pads allowed)
			(copperpour allowed)
			(footprints allowed)
		)
		(placement
			(enabled no)
			(sheetname "")
		)
		(fill
			(thermal_gap 0.5)
			(thermal_bridge_width 0.5)
			(island_removal_mode 0)
		)
		(polygon
			(pts
				(xy 9.19734 -107.757468) (xy 9.19734 -96.962468) (xy 21.38934 -96.962468) (xy 21.38934 -107.757468)
			)
		)
	)
	(zone
		(net "P0V955_C")
		(layer "F.Cu")
		(hatch none 0.5)
		(connect_pads
			(clearance 0.5)
		)
		(min_thickness 0.25)
		(fill yes
			(thermal_gap 0.5)
			(thermal_bridge_width 0.5)
			(island_removal_mode 0)
		)
		(polygon
			(pts
				(xy 74.93 -25.527) (xy 74.549 -25.908) (xy 74.549 -32.004) (xy 74.676 -32.131) (xy 75.438 -32.131)
				(xy 75.565 -32.004) (xy 75.565 -30.861) (xy 75.692 -30.734) (xy 76.581 -30.734) (xy 78.232 -29.083)
				(xy 78.232 -25.908) (xy 77.851 -25.527)
			)
		)
	)
	(zone
		(net "GB_VDDH2")
		(layer "F.Cu")
		(hatch none 0.5)
		(connect_pads
			(clearance 0.5)
		)
		(min_thickness 0.25)
		(fill yes
			(thermal_gap 0.5)
			(thermal_bridge_width 0.5)
			(island_removal_mode 0)
		)
		(polygon
			(pts
				(xy 196.088 -83.693) (xy 195.707 -84.074) (xy 195.707 -86.106) (xy 195.961 -86.36) (xy 205.994 -86.36)
				(xy 206.248 -86.106) (xy 206.248 -83.947) (xy 205.994 -83.693)
			)
		)
		(polygon
			(pts
				(xy 206.0448 -85.344) (xy 205.7908 -85.344) (xy 205.7908 -85.598) (xy 206.0448 -85.598)
			)
		)
		(polygon
			(pts
				(xy 205.1812 -85.344) (xy 204.9272 -85.344) (xy 204.9272 -85.598) (xy 205.1812 -85.598)
			)
		)
	)
	(zone
		(net "GND")
		(layer "F.Cu")
		(hatch none 0.5)
		(connect_pads
			(clearance 0.5)
		)
		(min_thickness 0.25)
		(fill yes
			(thermal_gap 0.5)
			(thermal_bridge_width 0.5)
			(island_removal_mode 0)
		)
		(polygon
			(pts
				(xy 82.658966 -84.455) (xy 82.531966 -84.582) (xy 82.531966 -85.725) (xy 82.658966 -85.852) (xy 88.246966 -85.852)
				(xy 88.373966 -85.725) (xy 88.373966 -84.582) (xy 88.246966 -84.455)
			)
		)
		(polygon
			(pts
				(xy 87.942166 -84.6836) (xy 87.688166 -84.6836) (xy 87.688166 -84.9376) (xy 87.942166 -84.9376)
			)
		)
		(polygon
			(pts
				(xy 87.281766 -84.6836) (xy 86.672166 -84.6836) (xy 86.672166 -84.9376) (xy 87.281766 -84.9376)
			)
		)
	)
	(zone
		(net "GND")
		(layer "F.Cu")
		(hatch none 0.5)
		(connect_pads
			(clearance 0.5)
		)
		(min_thickness 0.25)
		(fill yes
			(thermal_gap 0.5)
			(thermal_bridge_width 0.5)
			(island_removal_mode 0)
		)
		(polygon
			(pts
				(xy 92.056966 -42.037) (xy 91.929966 -42.164) (xy 91.929966 -42.926) (xy 91.294966 -43.561) (xy 91.294966 -43.815)
				(xy 91.548966 -44.069) (xy 93.199966 -44.069) (xy 93.326966 -43.942) (xy 93.326966 -43.561) (xy 92.691966 -42.926)
				(xy 92.691966 -42.291) (xy 92.437966 -42.037)
			)
		)
	)
	(zone
		(layer "F.Cu")
		(hatch none 0.5)
		(connect_pads
			(clearance 0)
		)
		(min_thickness 0.25)
		(keepout
			(tracks allowed)
			(vias allowed)
			(pads allowed)
			(copperpour allowed)
			(footprints allowed)
		)
		(placement
			(enabled no)
			(sheetname "")
		)
		(fill
			(thermal_gap 0.5)
			(thermal_bridge_width 0.5)
			(island_removal_mode 0)
		)
		(polygon
			(pts
				(xy 82.042 -131.826) (xy 82.042 -129.921) (xy 82.931 -129.921) (xy 82.931 -131.826)
			)
		)
	)
	(zone
		(layer "F.Cu")
		(hatch none 0.5)
		(connect_pads
			(clearance 0)
		)
		(min_thickness 0.25)
		(keepout
			(tracks allowed)
			(vias allowed)
			(pads allowed)
			(copperpour allowed)
			(footprints allowed)
		)
		(placement
			(enabled no)
			(sheetname "")
		)
		(fill
			(thermal_gap 0.5)
			(thermal_bridge_width 0.5)
			(island_removal_mode 0)
		)
		(polygon
			(pts
				(xy 192.405 -147.955) (xy 192.405 -146.812) (xy 194.564 -146.812) (xy 194.564 -147.955)
			)
		)
	)
	(zone
		(layer "F.Cu")
		(hatch none 0.5)
		(connect_pads
			(clearance 0)
		)
		(min_thickness 0.25)
		(keepout
			(tracks not_allowed)
			(vias allowed)
			(pads allowed)
			(copperpour not_allowed)
			(footprints allowed)
		)
		(placement
			(enabled no)
			(sheetname "")
		)
		(fill
			(thermal_gap 0.5)
			(thermal_bridge_width 0.5)
			(island_removal_mode 0)
		)
		(polygon
			(pts
				(arc
					(start 294.03294 -79.44993)
					(mid 293.6494 -79.06639)
					(end 293.26586 -79.44993)
				)
				(arc
					(start 293.26586 -80.366616)
					(mid 293.649273 -80.75041)
					(end 294.03294 -80.36687)
				)
				(arc
					(start 294.03294 -80.119982)
					(mid 294.000315 -80.137557)
					(end 293.971726 -80.16113)
				)
				(arc
					(start 293.90594 -80.226916)
					(mid 293.443409 -80.574014)
					(end 293.7891 -80.11033)
				)
				(xy 293.854886 -80.04429) (xy 293.879016 -80.02016)
				(arc
					(start 293.88181 -80.02016)
					(mid 293.953065 -79.974973)
					(end 294.03294 -79.94777)
				)
				(arc
					(start 294.03294 -79.758032)
					(mid 293.920778 -79.734325)
					(end 293.814754 -79.690722)
				)
				(arc
					(start 293.814754 -79.690722)
					(mid 293.42179 -79.266813)
					(end 293.920672 -79.558642)
				)
				(arc
					(start 293.920672 -79.558642)
					(mid 293.975777 -79.578549)
					(end 294.03294 -79.591408)
				)
			)
		)
	)
	(zone
		(net "P3V3_STBY_LL")
		(layer "F.Cu")
		(hatch none 0.5)
		(connect_pads
			(clearance 0.5)
		)
		(min_thickness 0.25)
		(fill yes
			(thermal_gap 0.5)
			(thermal_bridge_width 0.5)
			(island_removal_mode 0)
		)
		(polygon
			(pts
				(xy 323.977 -103.251) (xy 322.199 -105.029) (xy 322.199 -110.744) (xy 322.453 -110.998) (xy 327.025 -110.998)
				(xy 327.152 -110.871) (xy 327.152 -109.855) (xy 329.311 -107.696) (xy 331.978 -107.696) (xy 332.613 -107.061)
				(xy 332.613 -103.632) (xy 332.232 -103.251)
			)
		)
		(polygon
			(pts
				(xy 326.367648 -109.858048) (xy 326.113648 -109.858048) (xy 326.113648 -110.112048) (xy 326.367648 -110.112048)
			)
		)
	)
	(zone
		(net "GND")
		(layer "F.Cu")
		(hatch none 0.5)
		(connect_pads
			(clearance 0.5)
		)
		(min_thickness 0.25)
		(fill yes
			(thermal_gap 0.5)
			(thermal_bridge_width 0.5)
			(island_removal_mode 0)
		)
		(polygon
			(pts
				(xy 214.249 -97.409) (xy 214.122 -97.536) (xy 214.122 -100.076) (xy 213.995 -100.203) (xy 213.614 -100.203)
				(xy 213.36 -100.457) (xy 213.36 -103.378) (xy 213.614 -103.632) (xy 213.995 -103.632) (xy 214.122 -103.759)
				(xy 214.122 -104.902) (xy 214.249 -105.029) (xy 215.773 -105.029) (xy 215.9 -104.902) (xy 215.9 -103.886)
				(xy 216.154 -103.632) (xy 216.662 -103.632) (xy 216.789 -103.505) (xy 216.789 -100.457) (xy 216.662 -100.33)
				(xy 216.027 -100.33) (xy 215.9 -100.203) (xy 215.9 -97.536) (xy 215.773 -97.409)
			)
		)
		(polygon
			(pts
				(xy 215.519 -97.9678) (xy 215.265 -97.9678) (xy 215.265 -98.2218) (xy 215.519 -98.2218)
			)
		)
	)
	(zone
		(layer "F.Cu")
		(hatch none 0.5)
		(connect_pads
			(clearance 0)
		)
		(min_thickness 0.25)
		(keepout
			(tracks allowed)
			(vias allowed)
			(pads allowed)
			(copperpour allowed)
			(footprints allowed)
		)
		(placement
			(enabled no)
			(sheetname "")
		)
		(fill
			(thermal_gap 0.5)
			(thermal_bridge_width 0.5)
			(island_removal_mode 0)
		)
		(polygon
			(pts
				(xy 253.111 -135.128) (xy 253.111 -133.35) (xy 254.254 -133.35) (xy 254.254 -135.128)
			)
		)
	)
	(zone
		(net "P0V9_E")
		(layer "F.Cu")
		(hatch none 0.5)
		(connect_pads
			(clearance 0.5)
		)
		(min_thickness 0.25)
		(fill yes
			(thermal_gap 0.5)
			(thermal_bridge_width 0.5)
			(island_removal_mode 0)
		)
		(polygon
			(pts
				(xy 73.279 -78.105) (xy 71.755 -79.629) (xy 71.755 -92.075) (xy 72.136 -92.456) (xy 80.245966 -92.456)
				(xy 80.372966 -92.329) (xy 80.372966 -89.662) (xy 80.245966 -89.535) (xy 74.93 -89.535) (xy 74.168 -88.773)
				(xy 74.168 -83.693) (xy 75.819 -82.042) (xy 80.245966 -82.042) (xy 80.499966 -81.788) (xy 80.499966 -78.613)
				(xy 79.991966 -78.105)
			)
		)
		(polygon
			(pts
				(xy 79.788766 -90.0684) (xy 79.534766 -90.0684) (xy 79.534766 -90.3224) (xy 79.788766 -90.3224)
			)
		)
		(polygon
			(pts
				(xy 80.06207 -79.693008) (xy 79.80807 -79.693008) (xy 79.80807 -79.947008) (xy 80.06207 -79.947008)
			)
		)
		(polygon
			(pts
				(xy 80.06207 -79.134208) (xy 79.80807 -79.134208) (xy 79.80807 -79.388208) (xy 80.06207 -79.388208)
			)
		)
	)
	(zone
		(layer "F.Cu")
		(hatch none 0.5)
		(connect_pads
			(clearance 0)
		)
		(min_thickness 0.25)
		(keepout
			(tracks not_allowed)
			(vias allowed)
			(pads allowed)
			(copperpour not_allowed)
			(footprints allowed)
		)
		(placement
			(enabled no)
			(sheetname "")
		)
		(fill
			(thermal_gap 0.5)
			(thermal_bridge_width 0.5)
			(island_removal_mode 0)
		)
		(polygon
			(pts
				(arc
					(start 319.139316 -68.216272)
					(mid 318.755903 -67.832478)
					(end 318.372236 -68.216018)
				)
				(xy 318.372236 -68.453)
				(arc
					(start 318.378332 -68.453)
					(mid 318.400202 -68.44865)
					(end 318.418718 -68.436236)
				)
				(arc
					(start 318.499236 -68.355718)
					(mid 318.96233 -68.009464)
					(end 318.616076 -68.472558)
				)
				(xy 318.511428 -68.577206)
				(arc
					(start 318.506856 -68.577206)
					(mid 318.463393 -68.601265)
					(end 318.41567 -68.615052)
				)
				(xy 318.412622 -68.6181) (xy 318.372236 -68.6181) (xy 318.372236 -68.7959) (xy 318.412622 -68.7959)
				(arc
					(start 318.41567 -68.798948)
					(mid 318.463383 -68.812759)
					(end 318.506856 -68.836794)
				)
				(xy 318.511428 -68.836794)
				(arc
					(start 318.616076 -68.941442)
					(mid 318.96233 -69.404536)
					(end 318.499236 -69.058282)
				)
				(arc
					(start 318.418718 -68.977764)
					(mid 318.400189 -68.965383)
					(end 318.378332 -68.961)
				)
				(xy 318.372236 -68.961)
				(arc
					(start 318.372236 -69.197982)
					(mid 318.755776 -69.581522)
					(end 319.139316 -69.197982)
				)
			)
		)
	)
	(zone
		(net "GND")
		(layer "F.Cu")
		(hatch none 0.5)
		(connect_pads
			(clearance 0.5)
		)
		(min_thickness 0.25)
		(fill yes
			(thermal_gap 0.5)
			(thermal_bridge_width 0.5)
			(island_removal_mode 0)
		)
		(polygon
			(pts
				(xy 348.107 -90.424) (xy 347.726 -90.805) (xy 347.726 -103.251) (xy 344.805 -106.172) (xy 344.805 -107.95)
				(xy 344.932 -108.077) (xy 350.012 -108.077) (xy 350.393 -107.696) (xy 350.393 -90.805) (xy 350.012 -90.424)
			)
		)
		(polygon
			(pts
				(xy 345.9988 -107.061) (xy 345.7448 -107.061) (xy 345.7448 -107.315) (xy 345.9988 -107.315)
			)
		)
	)
	(zone
		(layer "F.Cu")
		(hatch none 0.5)
		(connect_pads
			(clearance 0)
		)
		(min_thickness 0.25)
		(keepout
			(tracks allowed)
			(vias allowed)
			(pads allowed)
			(copperpour allowed)
			(footprints allowed)
		)
		(placement
			(enabled no)
			(sheetname "")
		)
		(fill
			(thermal_gap 0.5)
			(thermal_bridge_width 0.5)
			(island_removal_mode 0)
		)
		(polygon
			(pts
				(xy 216.789 -103.251) (xy 216.789 -101.6) (xy 220.726 -101.6) (xy 220.726 -103.251)
			)
		)
	)
	(zone
		(layer "F.Cu")
		(hatch none 0.5)
		(connect_pads
			(clearance 0)
		)
		(min_thickness 0.25)
		(keepout
			(tracks not_allowed)
			(vias allowed)
			(pads allowed)
			(copperpour not_allowed)
			(footprints allowed)
		)
		(placement
			(enabled no)
			(sheetname "")
		)
		(fill
			(thermal_gap 0.5)
			(thermal_bridge_width 0.5)
			(island_removal_mode 0)
		)
		(polygon
			(pts
				(arc
					(start 155.946602 -76.64196)
					(mid 155.562808 -77.025373)
					(end 155.946348 -77.40904)
				)
				(arc
					(start 156.928312 -77.40904)
					(mid 157.311852 -77.0255)
					(end 156.928312 -76.64196)
				)
				(arc
					(start 156.775658 -76.64196)
					(mid 156.799141 -76.697774)
					(end 156.826204 -76.751942)
				)
				(arc
					(start 156.826204 -76.751942)
					(mid 157.103799 -77.259126)
					(end 156.693108 -76.852272)
				)
				(arc
					(start 156.693108 -76.852272)
					(mid 156.641488 -76.749536)
					(end 156.600906 -76.64196)
				)
				(arc
					(start 156.290264 -76.64196)
					(mid 156.242566 -76.751802)
					(end 156.1846 -76.85659)
				)
				(arc
					(start 156.1846 -76.85659)
					(mid 155.766034 -77.255242)
					(end 156.05379 -76.753974)
				)
				(arc
					(start 156.05379 -76.753974)
					(mid 156.084367 -76.698805)
					(end 156.111702 -76.64196)
				)
			)
		)
	)
	(zone
		(layer "F.Cu")
		(hatch none 0.5)
		(connect_pads
			(clearance 0)
		)
		(min_thickness 0.25)
		(keepout
			(tracks allowed)
			(vias allowed)
			(pads allowed)
			(copperpour allowed)
			(footprints allowed)
		)
		(placement
			(enabled no)
			(sheetname "")
		)
		(fill
			(thermal_gap 0.5)
			(thermal_bridge_width 0.5)
			(island_removal_mode 0)
		)
		(polygon
			(pts
				(xy 210.82 -103.505) (xy 210.82 -102.108) (xy 213.106 -102.108) (xy 213.106 -103.505)
			)
		)
	)
	(zone
		(layer "F.Cu")
		(hatch none 0.5)
		(connect_pads
			(clearance 0)
		)
		(min_thickness 0.25)
		(keepout
			(tracks allowed)
			(vias allowed)
			(pads allowed)
			(copperpour allowed)
			(footprints allowed)
		)
		(placement
			(enabled no)
			(sheetname "")
		)
		(fill
			(thermal_gap 0.5)
			(thermal_bridge_width 0.5)
			(island_removal_mode 0)
		)
		(polygon
			(pts
				(xy 198.12 -118.364) (xy 198.12 -115.951) (xy 200.914 -115.951) (xy 200.914 -118.364)
			)
		)
	)
	(zone
		(net "P12V")
		(layer "F.Cu")
		(hatch none 0.5)
		(connect_pads
			(clearance 0.5)
		)
		(min_thickness 0.25)
		(fill yes
			(thermal_gap 0.5)
			(thermal_bridge_width 0.5)
			(island_removal_mode 0)
		)
		(polygon
			(pts
				(xy 61.722 -223.012) (xy 61.341 -223.393) (xy 61.341 -227.711) (xy 61.595 -227.965) (xy 64.77 -227.965)
				(xy 65.024 -227.711) (xy 65.024 -226.06) (xy 65.278 -225.806) (xy 68.58 -225.806) (xy 68.834 -225.552)
				(xy 68.834 -223.52) (xy 68.326 -223.012)
			)
		)
		(polygon
			(pts
				(xy 68.2498 -224.8154) (xy 67.9958 -224.8154) (xy 67.9958 -225.0694) (xy 68.2498 -225.0694)
			)
		)
		(polygon
			(pts
				(xy 68.2498 -224.2566) (xy 67.9958 -224.2566) (xy 67.9958 -224.5106) (xy 68.2498 -224.5106)
			)
		)
	)
	(zone
		(layer "F.Cu")
		(hatch none 0.5)
		(connect_pads
			(clearance 0)
		)
		(min_thickness 0.25)
		(keepout
			(tracks allowed)
			(vias allowed)
			(pads allowed)
			(copperpour allowed)
			(footprints allowed)
		)
		(placement
			(enabled no)
			(sheetname "")
		)
		(fill
			(thermal_gap 0.5)
			(thermal_bridge_width 0.5)
			(island_removal_mode 0)
		)
		(polygon
			(pts
				(xy 263.906 -43.688) (xy 263.906 -41.656) (xy 265.938 -41.656) (xy 265.938 -43.688)
			)
		)
	)
	(zone
		(layer "F.Cu")
		(hatch none 0.5)
		(connect_pads
			(clearance 0)
		)
		(min_thickness 0.25)
		(keepout
			(tracks allowed)
			(vias allowed)
			(pads allowed)
			(copperpour allowed)
			(footprints allowed)
		)
		(placement
			(enabled no)
			(sheetname "")
		)
		(fill
			(thermal_gap 0.5)
			(thermal_bridge_width 0.5)
			(island_removal_mode 0)
		)
		(polygon
			(pts
				(xy 286.639 -211.074) (xy 286.639 -209.55) (xy 289.687 -209.55) (xy 289.687 -211.074)
			)
		)
	)
	(zone
		(layer "F.Cu")
		(hatch none 0.5)
		(connect_pads
			(clearance 0)
		)
		(min_thickness 0.25)
		(keepout
			(tracks allowed)
			(vias allowed)
			(pads allowed)
			(copperpour allowed)
			(footprints not_allowed)
		)
		(placement
			(enabled no)
			(sheetname "")
		)
		(fill
			(thermal_gap 0.5)
			(thermal_bridge_width 0.5)
			(island_removal_mode 0)
		)
		(polygon
			(pts
				(arc
					(start 314.366402 -42.999914)
					(mid 307.299996 -39.500125)
					(end 314.366402 -35.999928)
				)
				(xy 326.300084 -35.999928) (xy 326.300084 -42.999914)
			)
		)
	)
	(zone
		(net "GND")
		(layer "F.Cu")
		(hatch none 0.5)
		(connect_pads
			(clearance 0.5)
		)
		(min_thickness 0.25)
		(fill yes
			(thermal_gap 0.5)
			(thermal_bridge_width 0.5)
			(island_removal_mode 0)
		)
		(polygon
			(pts
				(xy 287.401 -191.008) (xy 287.401 -191.262) (xy 287.655 -191.516) (xy 287.909 -191.77) (xy 295.91 -191.77)
				(xy 296.037 -191.643) (xy 296.037 -191.389) (xy 296.037 -190.881) (xy 296.037 -190.754) (xy 295.91 -190.627)
				(xy 294.005 -190.627) (xy 293.37 -189.992) (xy 287.782 -189.992) (xy 287.401 -190.373)
			)
		)
	)
	(zone
		(layer "F.Cu")
		(hatch none 0.5)
		(connect_pads
			(clearance 0)
		)
		(min_thickness 0.25)
		(keepout
			(tracks allowed)
			(vias allowed)
			(pads allowed)
			(copperpour allowed)
			(footprints allowed)
		)
		(placement
			(enabled no)
			(sheetname "")
		)
		(fill
			(thermal_gap 0.5)
			(thermal_bridge_width 0.5)
			(island_removal_mode 0)
		)
		(polygon
			(pts
				(xy 21.59 -216.916) (xy 21.59 -215.011) (xy 22.606 -215.011) (xy 22.606 -216.916)
			)
		)
	)
	(zone
		(layer "F.Cu")
		(hatch none 0.5)
		(connect_pads
			(clearance 0)
		)
		(min_thickness 0.25)
		(keepout
			(tracks allowed)
			(vias allowed)
			(pads allowed)
			(copperpour allowed)
			(footprints allowed)
		)
		(placement
			(enabled no)
			(sheetname "")
		)
		(fill
			(thermal_gap 0.5)
			(thermal_bridge_width 0.5)
			(island_removal_mode 0)
		)
		(polygon
			(pts
				(xy 176.911 -33.02) (xy 176.911 -28.829) (xy 180.086 -28.829) (xy 180.086 -33.02)
			)
		)
	)
	(zone
		(layer "F.Cu")
		(hatch none 0.5)
		(connect_pads
			(clearance 0)
		)
		(min_thickness 0.25)
		(keepout
			(tracks allowed)
			(vias allowed)
			(pads allowed)
			(copperpour allowed)
			(footprints not_allowed)
		)
		(placement
			(enabled no)
			(sheetname "")
		)
		(fill
			(thermal_gap 0.5)
			(thermal_bridge_width 0.5)
			(island_removal_mode 0)
		)
		(polygon
			(pts
				(xy 249.899932 -82.350102) (xy 249.899932 -48.90008) (xy 259.899912 -48.90008) (xy 259.899912 -12.500102)
				(xy 130.50012 -12.500102) (xy 130.50012 -70.300088) (xy 119.000016 -70.300088) (xy 119.000016 -82.350102)
				(xy 224.700084 -82.350102) (xy 224.700084 -57.999884) (xy 236.199934 -57.999884) (xy 236.199934 -82.350102)
			)
		)
	)
	(zone
		(net "P3V3_STBY")
		(layer "F.Cu")
		(hatch none 0.5)
		(connect_pads
			(clearance 0.5)
		)
		(min_thickness 0.25)
		(fill yes
			(thermal_gap 0.5)
			(thermal_bridge_width 0.5)
			(island_removal_mode 0)
		)
		(polygon
			(pts
				(xy 181.864 -46.482) (xy 181.483 -46.863) (xy 181.483 -49.022) (xy 181.991 -49.53) (xy 182.88 -49.53)
				(xy 183.134 -49.276) (xy 183.134 -48.895) (xy 183.388 -48.641) (xy 184.023 -48.641) (xy 184.371996 -48.989996)
				(xy 185.514996 -48.989996) (xy 186.117992 -48.387) (xy 186.117992 -46.736) (xy 185.863992 -46.482)
			)
		)
		(polygon
			(pts
				(xy 182.5498 -48.7426) (xy 182.2958 -48.7426) (xy 182.2958 -48.9966) (xy 182.5498 -48.9966)
			)
		)
		(polygon
			(pts
				(xy 185.660792 -47.7266) (xy 185.406792 -47.7266) (xy 185.406792 -47.9806) (xy 185.660792 -47.9806)
			)
		)
		(polygon
			(pts
				(xy 185.787792 -46.99) (xy 185.533792 -46.99) (xy 185.533792 -47.244) (xy 185.787792 -47.244)
			)
		)
		(polygon
			(pts
				(xy 185.178192 -46.99) (xy 184.924192 -46.99) (xy 184.924192 -47.244) (xy 185.178192 -47.244)
			)
		)
		(polygon
			(pts
				(xy 184.746392 -46.9392) (xy 184.492392 -46.9392) (xy 184.492392 -47.1932) (xy 184.746392 -47.1932)
			)
		)
		(polygon
			(pts
				(xy 184.187592 -46.9392) (xy 183.933592 -46.9392) (xy 183.933592 -47.1932) (xy 184.187592 -47.1932)
			)
		)
	)
	(zone
		(net "P12V")
		(layer "F.Cu")
		(hatch none 0.5)
		(connect_pads
			(clearance 0.5)
		)
		(min_thickness 0.25)
		(fill yes
			(thermal_gap 0.5)
			(thermal_bridge_width 0.5)
			(island_removal_mode 0)
		)
		(polygon
			(pts
				(xy 305.562 -47.498) (xy 305.308 -47.752) (xy 305.308 -50.631852) (xy 305.435 -50.758852) (xy 307.000148 -50.758852)
				(xy 307.594 -50.165) (xy 309.626 -50.165) (xy 309.753 -50.038) (xy 309.753 -47.752) (xy 309.539894 -47.538894)
				(xy 308.060852 -47.538894) (xy 308.019958 -47.498)
			)
		)
	)
	(zone
		(layer "F.Cu")
		(hatch none 0.5)
		(connect_pads
			(clearance 0)
		)
		(min_thickness 0.25)
		(keepout
			(tracks not_allowed)
			(vias allowed)
			(pads allowed)
			(copperpour not_allowed)
			(footprints allowed)
		)
		(placement
			(enabled no)
			(sheetname "")
		)
		(fill
			(thermal_gap 0.5)
			(thermal_bridge_width 0.5)
			(island_removal_mode 0)
		)
		(polygon
			(pts
				(arc
					(start 350.87941 -147.26539)
					(mid 350.52127 -147.62353)
					(end 350.87941 -147.98167)
				)
				(xy 351.09785 -147.98167) (xy 351.09785 -147.95881)
				(arc
					(start 351.000314 -147.861274)
					(mid 350.69081 -147.43493)
					(end 351.117154 -147.744434)
				)
				(xy 351.21469 -147.84197) (xy 351.26295 -147.89023) (xy 351.26295 -147.95881) (xy 351.26295 -147.98167)
				(xy 351.44075 -147.98167) (xy 351.44075 -147.95881) (xy 351.44075 -147.89023) (xy 351.48901 -147.84197)
				(arc
					(start 351.586546 -147.744434)
					(mid 352.01289 -147.43493)
					(end 351.703386 -147.861274)
				)
				(xy 351.674176 -147.89023) (xy 351.60585 -147.95881) (xy 351.60585 -147.98167)
				(arc
					(start 351.824036 -147.98167)
					(mid 352.18243 -147.623657)
					(end 351.82429 -147.26539)
				)
			)
		)
	)
	(zone
		(net "PHY_AVDD")
		(layer "F.Cu")
		(hatch none 0.5)
		(connect_pads
			(clearance 0.5)
		)
		(min_thickness 0.25)
		(fill yes
			(thermal_gap 0.5)
			(thermal_bridge_width 0.5)
			(island_removal_mode 0)
		)
		(polygon
			(pts
				(xy 147.193 -15.494) (xy 147.066 -15.621) (xy 147.066 -18.415) (xy 150.749 -22.098) (xy 152.654 -22.098)
				(xy 152.908 -21.844) (xy 152.908 -15.748) (xy 152.654 -15.494)
			)
		)
		(polygon
			(pts
				(xy 147.828 -16.9418) (xy 147.574 -16.9418) (xy 147.574 -17.1958) (xy 147.828 -17.1958)
			)
		)
		(polygon
			(pts
				(xy 147.828 -16.3322) (xy 147.574 -16.3322) (xy 147.574 -16.5862) (xy 147.828 -16.5862)
			)
		)
		(polygon
			(pts
				(xy 147.828 -15.9258) (xy 147.574 -15.9258) (xy 147.574 -16.1798) (xy 147.828 -16.1798)
			)
		)
	)
	(zone
		(layer "F.Cu")
		(hatch none 0.5)
		(connect_pads
			(clearance 0)
		)
		(min_thickness 0.25)
		(keepout
			(tracks not_allowed)
			(vias allowed)
			(pads allowed)
			(copperpour not_allowed)
			(footprints allowed)
		)
		(placement
			(enabled no)
			(sheetname "")
		)
		(fill
			(thermal_gap 0.5)
			(thermal_bridge_width 0.5)
			(island_removal_mode 0)
		)
		(polygon
			(pts
				(arc
					(start 16.73606 -98.770694)
					(mid 16.97617 -98.242522)
					(end 16.86306 -98.811588)
				)
				(xy 16.86306 -98.906076) (xy 16.876268 -98.90633)
				(arc
					(start 16.876268 -98.90379)
					(mid 17.269968 -98.530918)
					(end 16.897096 -98.137218)
				)
				(xy 16.897096 -98.134678) (xy 15.95755 -98.109278) (xy 15.957296 -98.109532)
				(arc
					(start 15.957296 -98.111818)
					(mid 15.563603 -98.484436)
					(end 15.93596 -98.87839)
				)
				(arc
					(start 15.93596 -98.78695)
					(mid 15.892964 -98.208074)
					(end 16.06296 -98.763074)
				)
				(xy 16.06296 -98.884232) (xy 16.73606 -98.90252)
			)
		)
	)
	(zone
		(layer "F.Cu")
		(hatch none 0.5)
		(connect_pads
			(clearance 0)
		)
		(min_thickness 0.25)
		(keepout
			(tracks allowed)
			(vias allowed)
			(pads allowed)
			(copperpour allowed)
			(footprints allowed)
		)
		(placement
			(enabled no)
			(sheetname "")
		)
		(fill
			(thermal_gap 0.5)
			(thermal_bridge_width 0.5)
			(island_removal_mode 0)
		)
		(polygon
			(pts
				(xy 84.455 -20.701) (xy 84.455 -18.542) (xy 85.852 -18.542) (xy 86.36 -18.542) (xy 86.36 -20.701)
				(xy 85.852 -20.701)
			)
		)
	)
	(zone
		(layer "F.Cu")
		(hatch none 0.5)
		(connect_pads
			(clearance 0)
		)
		(min_thickness 0.25)
		(keepout
			(tracks allowed)
			(vias allowed)
			(pads allowed)
			(copperpour allowed)
			(footprints allowed)
		)
		(placement
			(enabled no)
			(sheetname "")
		)
		(fill
			(thermal_gap 0.5)
			(thermal_bridge_width 0.5)
			(island_removal_mode 0)
		)
		(polygon
			(pts
				(xy 24.257 -176.53) (xy 24.257 -175.26) (xy 25.4 -175.26) (xy 25.4 -176.53)
			)
		)
	)
	(zone
		(net "P3V3")
		(layer "F.Cu")
		(hatch none 0.5)
		(connect_pads
			(clearance 0.5)
		)
		(min_thickness 0.25)
		(fill yes
			(thermal_gap 0.5)
			(thermal_bridge_width 0.5)
			(island_removal_mode 0)
		)
		(polygon
			(pts
				(xy 312.42 -55.372) (xy 312.039 -55.753) (xy 312.039 -57.912) (xy 312.42 -58.293) (xy 316.103 -58.293)
				(xy 316.484 -57.912) (xy 316.484 -55.626) (xy 316.23 -55.372)
			)
		)
	)
	(zone
		(net "GND")
		(layer "F.Cu")
		(hatch none 0.5)
		(connect_pads
			(clearance 0.5)
		)
		(min_thickness 0.25)
		(fill yes
			(thermal_gap 0.5)
			(thermal_bridge_width 0.5)
			(island_removal_mode 0)
		)
		(polygon
			(pts
				(xy 270.637 -37.084) (xy 269.875 -37.846) (xy 263.652 -37.846) (xy 263.398 -38.1) (xy 263.398 -40.767)
				(xy 263.779 -41.148) (xy 269.24 -41.148) (xy 269.494 -40.894) (xy 276.733 -40.894) (xy 276.987 -40.64)
				(xy 276.987 -37.338) (xy 276.733 -37.084)
			)
		)
		(polygon
			(pts
				(xy 271.1958 -39.751) (xy 270.9418 -39.751) (xy 270.9418 -40.005) (xy 271.1958 -40.005)
			)
		)
		(polygon
			(pts
				(xy 270.3322 -39.751) (xy 270.0782 -39.751) (xy 270.0782 -40.005) (xy 270.3322 -40.005)
			)
		)
	)
	(zone
		(layer "F.Cu")
		(hatch none 0.5)
		(connect_pads
			(clearance 0)
		)
		(min_thickness 0.25)
		(keepout
			(tracks not_allowed)
			(vias allowed)
			(pads allowed)
			(copperpour not_allowed)
			(footprints allowed)
		)
		(placement
			(enabled no)
			(sheetname "")
		)
		(fill
			(thermal_gap 0.5)
			(thermal_bridge_width 0.5)
			(island_removal_mode 0)
		)
		(polygon
			(pts
				(arc
					(start 38.430454 -89.712546)
					(mid 38.046914 -90.096086)
					(end 38.430454 -90.479626)
				)
				(arc
					(start 39.407084 -90.479626)
					(mid 39.790878 -90.096213)
					(end 39.407338 -89.712546)
				)
				(xy 39.109396 -89.712546)
				(arc
					(start 39.109396 -89.899744)
					(mid 39.114934 -89.927766)
					(end 39.130732 -89.95156)
				)
				(arc
					(start 39.145718 -89.966292)
					(mid 39.69298 -90.156917)
					(end 39.115492 -90.108024)
				)
				(xy 39.091108 -90.089736) (xy 39.08933 -90.089736) (xy 39.04107 -90.041476) (xy 39.04107 -90.041222)
				(xy 39.022528 -90.022934)
				(arc
					(start 39.022528 -90.019886)
					(mid 38.997677 -89.976317)
					(end 38.984428 -89.927938)
				)
				(xy 38.982396 -89.92616) (xy 38.982396 -89.712546)
				(arc
					(start 38.75786 -89.712546)
					(mid 38.725574 -89.825776)
					(end 38.670738 -89.92997)
				)
				(arc
					(start 38.670738 -89.92997)
					(mid 38.232801 -90.311177)
					(end 38.575742 -89.842594)
				)
				(arc
					(start 38.575742 -89.842594)
					(mid 38.607196 -89.779659)
					(end 38.62832 -89.712546)
				)
			)
		)
	)
	(zone
		(layer "F.Cu")
		(hatch none 0.5)
		(connect_pads
			(clearance 0)
		)
		(min_thickness 0.25)
		(keepout
			(tracks not_allowed)
			(vias allowed)
			(pads allowed)
			(copperpour not_allowed)
			(footprints allowed)
		)
		(placement
			(enabled no)
			(sheetname "")
		)
		(fill
			(thermal_gap 0.5)
			(thermal_bridge_width 0.5)
			(island_removal_mode 0)
		)
		(polygon
			(pts
				(arc
					(start 39.975536 -79.746348)
					(mid 39.592123 -79.362554)
					(end 39.208456 -79.746094)
				)
				(xy 39.208456 -80.037686) (xy 39.210488 -80.037686)
				(arc
					(start 39.345362 -79.902812)
					(mid 39.798622 -79.539468)
					(end 39.435278 -79.992728)
				)
				(xy 39.300404 -80.127602) (xy 39.26332 -80.164686) (xy 39.210488 -80.164686) (xy 39.208456 -80.164686)
				(xy 39.208456 -80.380586) (xy 39.237412 -80.380586)
				(arc
					(start 39.238428 -80.381856)
					(mid 39.329696 -80.404158)
					(end 39.410132 -80.452722)
				)
				(xy 39.41191 -80.452722)
				(arc
					(start 39.435532 -80.476344)
					(mid 39.798326 -80.929708)
					(end 39.345616 -80.566006)
				)
				(arc
					(start 39.340536 -80.56118)
					(mid 39.28122 -80.521516)
					(end 39.21125 -80.507586)
				)
				(xy 39.208456 -80.507586)
				(arc
					(start 39.208456 -80.722978)
					(mid 39.591996 -81.106518)
					(end 39.975536 -80.722978)
				)
			)
		)
	)
	(zone
		(net "GND")
		(layer "F.Cu")
		(hatch none 0.5)
		(connect_pads
			(clearance 0.5)
		)
		(min_thickness 0.25)
		(fill yes
			(thermal_gap 0.5)
			(thermal_bridge_width 0.5)
			(island_removal_mode 0)
		)
		(polygon
			(pts
				(xy 207.01 -91.186) (xy 205.867 -92.329) (xy 205.867 -101.854) (xy 206.121 -102.108) (xy 207.772 -102.108)
				(xy 208.026 -101.854) (xy 208.026 -94.361) (xy 208.407 -93.98) (xy 208.407 -93.218) (xy 208.534 -93.091)
				(xy 211.836 -93.091) (xy 212.471 -93.726) (xy 212.471 -96.393) (xy 212.979 -96.901) (xy 215.646 -96.901)
				(xy 215.9 -96.647) (xy 215.9 -92.075) (xy 215.011 -91.186)
			)
		)
		(polygon
			(pts
				(xy 207.899 -93.7768) (xy 207.645 -93.7768) (xy 207.645 -94.0308) (xy 207.899 -94.0308)
			)
		)
		(polygon
			(pts
				(xy 207.899 -93.1672) (xy 207.645 -93.1672) (xy 207.645 -93.4212) (xy 207.899 -93.4212)
			)
		)
	)
	(zone
		(layer "F.Cu")
		(hatch none 0.5)
		(connect_pads
			(clearance 0)
		)
		(min_thickness 0.25)
		(keepout
			(tracks allowed)
			(vias allowed)
			(pads allowed)
			(copperpour allowed)
			(footprints allowed)
		)
		(placement
			(enabled no)
			(sheetname "")
		)
		(fill
			(thermal_gap 0.5)
			(thermal_bridge_width 0.5)
			(island_removal_mode 0)
		)
		(polygon
			(pts
				(xy 91.948 -131.953) (xy 91.948 -130.81) (xy 92.837 -130.81) (xy 92.837 -131.953)
			)
		)
	)
	(zone
		(net "PCE_AVDD")
		(layer "F.Cu")
		(hatch none 0.5)
		(connect_pads
			(clearance 0.5)
		)
		(min_thickness 0.25)
		(fill yes
			(thermal_gap 0.5)
			(thermal_bridge_width 0.5)
			(island_removal_mode 0)
		)
		(polygon
			(pts
				(xy 97.282 -10.922) (xy 97.155 -11.049) (xy 97.155 -12.319) (xy 96.901 -12.573) (xy 94.996 -12.573)
				(xy 94.869 -12.7) (xy 94.869 -15.875) (xy 94.615 -16.129) (xy 94.615 -17.272) (xy 94.869 -17.526)
				(xy 96.139 -17.526) (xy 100.076 -13.589) (xy 100.076 -11.43) (xy 99.568 -10.922)
			)
		)
		(polygon
			(pts
				(xy 99.2632 -11.811) (xy 99.0092 -11.811) (xy 99.0092 -12.065) (xy 99.2632 -12.065)
			)
		)
	)
	(zone
		(layer "F.Cu")
		(hatch none 0.5)
		(connect_pads
			(clearance 0)
		)
		(min_thickness 0.25)
		(keepout
			(tracks not_allowed)
			(vias allowed)
			(pads allowed)
			(copperpour not_allowed)
			(footprints allowed)
		)
		(placement
			(enabled no)
			(sheetname "")
		)
		(fill
			(thermal_gap 0.5)
			(thermal_bridge_width 0.5)
			(island_removal_mode 0)
		)
		(polygon
			(pts
				(arc
					(start 167.946832 -76.64196)
					(mid 167.563038 -77.025373)
					(end 167.946578 -77.40904)
				)
				(arc
					(start 168.928542 -77.40904)
					(mid 169.312082 -77.0255)
					(end 168.928542 -76.64196)
				)
				(arc
					(start 168.775888 -76.64196)
					(mid 168.799371 -76.697774)
					(end 168.826434 -76.751942)
				)
				(arc
					(start 168.826434 -76.751942)
					(mid 169.104029 -77.259126)
					(end 168.693338 -76.852272)
				)
				(arc
					(start 168.693338 -76.852272)
					(mid 168.641718 -76.749536)
					(end 168.601136 -76.64196)
				)
				(arc
					(start 168.290494 -76.64196)
					(mid 168.242796 -76.751802)
					(end 168.18483 -76.85659)
				)
				(arc
					(start 168.18483 -76.85659)
					(mid 167.766264 -77.255242)
					(end 168.05402 -76.753974)
				)
				(arc
					(start 168.05402 -76.753974)
					(mid 168.084597 -76.698805)
					(end 168.111932 -76.64196)
				)
			)
		)
	)
	(zone
		(layer "F.Cu")
		(hatch none 0.5)
		(connect_pads
			(clearance 0)
		)
		(min_thickness 0.25)
		(keepout
			(tracks not_allowed)
			(vias allowed)
			(pads allowed)
			(copperpour not_allowed)
			(footprints allowed)
		)
		(placement
			(enabled no)
			(sheetname "")
		)
		(fill
			(thermal_gap 0.5)
			(thermal_bridge_width 0.5)
			(island_removal_mode 0)
		)
		(polygon
			(pts
				(arc
					(start 131.02844 -79.37246)
					(mid 130.6449 -79.756)
					(end 131.02844 -80.13954)
				)
				(xy 131.281932 -80.13954) (xy 131.281932 -80.036416)
				(arc
					(start 131.221226 -79.975456)
					(mid 130.792136 -79.584279)
					(end 131.296664 -79.87157)
				)
				(xy 131.371848 -79.9465) (xy 131.408932 -79.983584) (xy 131.408932 -80.036416) (xy 131.408932 -80.13954)
				(xy 131.624832 -80.13954) (xy 131.624832 -79.983584)
				(arc
					(start 131.626102 -79.982568)
					(mid 131.653706 -79.877705)
					(end 131.715002 -79.788258)
				)
				(arc
					(start 131.715002 -79.788258)
					(mid 132.27744 -79.649791)
					(end 131.769866 -79.928974)
				)
				(arc
					(start 131.769866 -79.928974)
					(mid 131.756357 -79.96849)
					(end 131.751832 -80.01)
				)
				(xy 131.751832 -80.13954)
				(arc
					(start 132.00507 -80.13954)
					(mid 132.388864 -79.756127)
					(end 132.005324 -79.37246)
				)
			)
		)
	)
	(zone
		(net "GND")
		(layer "F.Cu")
		(hatch none 0.5)
		(connect_pads
			(clearance 0.5)
		)
		(min_thickness 0.25)
		(fill yes
			(thermal_gap 0.5)
			(thermal_bridge_width 0.5)
			(island_removal_mode 0)
		)
		(polygon
			(pts
				(xy 82.785966 -75.946) (xy 82.658966 -76.073) (xy 82.658966 -79.883) (xy 82.785966 -80.01) (xy 88.119966 -80.01)
				(xy 88.246966 -79.883) (xy 88.246966 -79.248) (xy 86.722966 -77.724) (xy 86.722966 -76.073) (xy 86.595966 -75.946)
			)
		)
		(polygon
			(pts
				(xy 87.942166 -79.5274) (xy 87.688166 -79.5274) (xy 87.688166 -79.7814) (xy 87.942166 -79.7814)
			)
		)
		(polygon
			(pts
				(xy 87.281766 -79.5274) (xy 86.672166 -79.5274) (xy 86.672166 -79.7814) (xy 87.281766 -79.7814)
			)
		)
	)
	(zone
		(layer "F.Cu")
		(hatch none 0.5)
		(connect_pads
			(clearance 0)
		)
		(min_thickness 0.25)
		(keepout
			(tracks not_allowed)
			(vias allowed)
			(pads allowed)
			(copperpour not_allowed)
			(footprints allowed)
		)
		(placement
			(enabled no)
			(sheetname "")
		)
		(fill
			(thermal_gap 0.5)
			(thermal_bridge_width 0.5)
			(island_removal_mode 0)
		)
		(polygon
			(pts
				(arc
					(start 85.37194 -32.885126)
					(mid 84.988527 -32.501332)
					(end 84.60486 -32.884872)
				)
				(arc
					(start 84.60486 -33.789874)
					(mid 84.9884 -34.173414)
					(end 85.37194 -33.789874)
				)
				(xy 85.37194 -33.572196)
				(arc
					(start 85.311742 -33.572196)
					(mid 85.297162 -33.575096)
					(end 85.284818 -33.583372)
				)
				(arc
					(start 85.235034 -33.633156)
					(mid 84.781774 -33.9965)
					(end 85.145118 -33.54324)
				)
				(xy 85.213444 -33.474914)
				(arc
					(start 85.217254 -33.474914)
					(mid 85.248554 -33.4578)
					(end 85.282786 -33.447736)
				)
				(xy 85.285326 -33.445196) (xy 85.37194 -33.445196) (xy 85.37194 -33.229296) (xy 85.285072 -33.229296)
				(arc
					(start 85.282532 -33.226756)
					(mid 85.248275 -33.216752)
					(end 85.217 -33.199578)
				)
				(xy 85.21319 -33.199578)
				(arc
					(start 85.145118 -33.131506)
					(mid 84.781774 -32.678246)
					(end 85.235034 -33.04159)
				)
				(arc
					(start 85.284564 -33.09112)
					(mid 85.296917 -33.099374)
					(end 85.311488 -33.102296)
				)
				(xy 85.37194 -33.102296)
			)
		)
	)
	(zone
		(net "HM40ADC_VDDA")
		(layer "F.Cu")
		(hatch none 0.5)
		(connect_pads
			(clearance 0.5)
		)
		(min_thickness 0.25)
		(fill yes
			(thermal_gap 0.5)
			(thermal_bridge_width 0.5)
			(island_removal_mode 0)
		)
		(polygon
			(pts
				(xy 101.835966 -60.6806) (xy 101.708966 -60.8076) (xy 101.708966 -62.8396) (xy 101.835966 -62.9666)
				(xy 101.835966 -69.450966) (xy 102.108 -69.723) (xy 103.505 -69.723) (xy 103.632 -69.596) (xy 103.632 -68.58)
				(xy 103.994966 -68.217034) (xy 103.994966 -63.6016) (xy 102.978966 -62.5856) (xy 102.978966 -61.0616)
				(xy 102.597966 -60.6806)
			)
		)
		(polygon
			(pts
				(xy 102.5652 -67.564) (xy 102.3112 -67.564) (xy 102.3112 -67.818) (xy 102.5652 -67.818)
			)
		)
		(polygon
			(pts
				(xy 102.5652 -67.0052) (xy 102.3112 -67.0052) (xy 102.3112 -67.2592) (xy 102.5652 -67.2592)
			)
		)
		(polygon
			(pts
				(xy 102.750366 -62.0268) (xy 102.496366 -62.0268) (xy 102.496366 -62.6364) (xy 102.750366 -62.6364)
			)
		)
		(polygon
			(pts
				(xy 102.750366 -61.1378) (xy 102.496366 -61.1378) (xy 102.496366 -61.7474) (xy 102.750366 -61.7474)
			)
		)
	)
	(zone
		(net "P1V8_STBY")
		(layer "F.Cu")
		(hatch none 0.5)
		(connect_pads
			(clearance 0.5)
		)
		(min_thickness 0.25)
		(fill yes
			(thermal_gap 0.5)
			(thermal_bridge_width 0.5)
			(island_removal_mode 0)
		)
		(polygon
			(pts
				(xy 265.938 -18.923) (xy 265.43 -19.431) (xy 265.43 -25.654) (xy 264.668 -26.416) (xy 264.668 -29.337)
				(xy 265.938 -30.607) (xy 272.288 -30.607) (xy 272.796 -30.099) (xy 272.796 -19.939) (xy 271.78 -18.923)
			)
		)
		(polygon
			(pts
				(xy 265.811 -28.4988) (xy 265.557 -28.4988) (xy 265.557 -28.7528) (xy 265.811 -28.7528)
			)
		)
		(polygon
			(pts
				(xy 265.811 -27.6352) (xy 265.557 -27.6352) (xy 265.557 -27.8892) (xy 265.811 -27.8892)
			)
		)
		(polygon
			(pts
				(xy 265.811 -27.1018) (xy 265.557 -27.1018) (xy 265.557 -27.3558) (xy 265.811 -27.3558)
			)
		)
		(polygon
			(pts
				(xy 265.811 -26.2382) (xy 265.557 -26.2382) (xy 265.557 -26.4922) (xy 265.811 -26.4922)
			)
		)
	)
	(zone
		(layer "F.Cu")
		(hatch none 0.5)
		(connect_pads
			(clearance 0)
		)
		(min_thickness 0.25)
		(keepout
			(tracks allowed)
			(vias allowed)
			(pads allowed)
			(copperpour allowed)
			(footprints not_allowed)
		)
		(placement
			(enabled no)
			(sheetname "")
		)
		(fill
			(thermal_gap 0.5)
			(thermal_bridge_width 0.5)
			(island_removal_mode 0)
		)
		(polygon
			(pts
				(arc
					(start 234.1499 -197.000114)
					(mid 234.442793 -196.293009)
					(end 235.149898 -196.000116)
				)
				(xy 236.199934 -196.000116) (xy 236.199934 -57.999884) (xy 224.700084 -57.999884) (xy 224.700084 -251.000006)
				(arc
					(start 229.14991 -251.000006)
					(mid 232.685437 -249.535543)
					(end 234.1499 -246.000016)
				)
			)
		)
	)
	(zone
		(layer "F.Cu")
		(hatch none 0.5)
		(connect_pads
			(clearance 0)
		)
		(min_thickness 0.25)
		(keepout
			(tracks allowed)
			(vias allowed)
			(pads allowed)
			(copperpour allowed)
			(footprints allowed)
		)
		(placement
			(enabled no)
			(sheetname "")
		)
		(fill
			(thermal_gap 0.5)
			(thermal_bridge_width 0.5)
			(island_removal_mode 0)
		)
		(polygon
			(pts
				(xy 336.55 -151.384) (xy 336.55 -149.098) (xy 338.709 -149.098) (xy 338.709 -151.384)
			)
		)
	)
	(zone
		(net "P12V_PCIE")
		(layer "F.Cu")
		(hatch none 0.5)
		(connect_pads
			(clearance 0.5)
		)
		(min_thickness 0.25)
		(fill yes
			(thermal_gap 0.5)
			(thermal_bridge_width 0.5)
			(island_removal_mode 0)
		)
		(polygon
			(pts
				(xy 240.03 -165.735) (xy 239.268 -166.497) (xy 239.268 -172.72) (xy 218.313 -193.675) (xy 218.313 -233.68)
				(xy 215.011 -236.982) (xy 192.024 -236.982) (xy 191.389 -237.617) (xy 191.389 -246.507) (xy 191.77 -246.888)
				(xy 223.774 -246.888) (xy 228.854 -241.808) (xy 228.854 -197.231) (xy 250.19 -175.895) (xy 250.19 -166.624)
				(xy 249.301 -165.735)
			)
		)
	)
	(zone
		(layer "F.Cu")
		(hatch none 0.5)
		(connect_pads
			(clearance 0)
		)
		(min_thickness 0.25)
		(keepout
			(tracks allowed)
			(vias allowed)
			(pads allowed)
			(copperpour allowed)
			(footprints not_allowed)
		)
		(placement
			(enabled no)
			(sheetname "")
		)
		(fill
			(thermal_gap 0.5)
			(thermal_bridge_width 0.5)
			(island_removal_mode 0)
		)
		(polygon
			(pts
				(xy 130.50012 -14.800072) (xy 119.000016 -14.800072) (xy 119.000016 0)
				(arc
					(start 281.485086 0)
					(mid 282.192191 -0.292893)
					(end 282.485084 -0.999998)
				)
				(xy 282.485084 -12.500102) (xy 130.50012 -12.500102)
			)
		)
	)
	(zone
		(layer "F.Cu")
		(hatch none 0.5)
		(connect_pads
			(clearance 0)
		)
		(min_thickness 0.25)
		(keepout
			(tracks allowed)
			(vias allowed)
			(pads allowed)
			(copperpour allowed)
			(footprints allowed)
		)
		(placement
			(enabled no)
			(sheetname "")
		)
		(fill
			(thermal_gap 0.5)
			(thermal_bridge_width 0.5)
			(island_removal_mode 0)
		)
		(polygon
			(pts
				(xy 217.043 -162.687) (xy 217.043 -161.29) (xy 221.742 -161.29) (xy 221.742 -162.687)
			)
		)
	)
	(zone
		(layer "F.Cu")
		(hatch none 0.5)
		(connect_pads
			(clearance 0)
		)
		(min_thickness 0.25)
		(keepout
			(tracks allowed)
			(vias allowed)
			(pads allowed)
			(copperpour allowed)
			(footprints allowed)
		)
		(placement
			(enabled no)
			(sheetname "")
		)
		(fill
			(thermal_gap 0.5)
			(thermal_bridge_width 0.5)
			(island_removal_mode 0)
		)
		(polygon
			(pts
				(xy 42.8498 -74.2442) (xy 55.2704 -74.2442) (xy 55.2704 -83.058) (xy 55.2704 -86.233) (xy 42.8498 -86.233)
				(xy 40.005 -86.233) (xy 40.005 -74.2442)
			)
		)
	)
	(zone
		(layer "F.Cu")
		(hatch none 0.5)
		(connect_pads
			(clearance 0)
		)
		(min_thickness 0.25)
		(keepout
			(tracks allowed)
			(vias allowed)
			(pads allowed)
			(copperpour allowed)
			(footprints allowed)
		)
		(placement
			(enabled no)
			(sheetname "")
		)
		(fill
			(thermal_gap 0.5)
			(thermal_bridge_width 0.5)
			(island_removal_mode 0)
		)
		(polygon
			(pts
				(xy 275.6916 -23.5458) (xy 275.6916 -21.463) (xy 277.8252 -21.463) (xy 277.8252 -23.5458)
			)
		)
	)
	(zone
		(layer "F.Cu")
		(hatch none 0.5)
		(connect_pads
			(clearance 0)
		)
		(min_thickness 0.25)
		(keepout
			(tracks allowed)
			(vias allowed)
			(pads allowed)
			(copperpour allowed)
			(footprints allowed)
		)
		(placement
			(enabled no)
			(sheetname "")
		)
		(fill
			(thermal_gap 0.5)
			(thermal_bridge_width 0.5)
			(island_removal_mode 0)
		)
		(polygon
			(pts
				(xy 289.814 -158.369) (xy 289.814 -156.972) (xy 291.592 -156.972) (xy 291.592 -158.369)
			)
		)
	)
	(zone
		(net "GND")
		(layer "F.Cu")
		(hatch none 0.5)
		(connect_pads
			(clearance 0.5)
		)
		(min_thickness 0.25)
		(fill yes
			(thermal_gap 0.5)
			(thermal_bridge_width 0.5)
			(island_removal_mode 0)
		)
		(polygon
			(pts
				(xy 161.163 -101.727) (xy 158.75 -104.14) (xy 158.75 -112.014) (xy 159.131 -112.395) (xy 161.163 -112.395)
				(xy 162.687 -110.871) (xy 162.687 -108.458) (xy 168.021 -103.124) (xy 168.021 -101.981) (xy 167.767 -101.727)
			)
		)
	)
	(zone
		(net "TPS74801_P1V5_C_IN")
		(layer "F.Cu")
		(hatch none 0.5)
		(connect_pads
			(clearance 0.5)
		)
		(min_thickness 0.25)
		(fill yes
			(thermal_gap 0.5)
			(thermal_bridge_width 0.5)
			(island_removal_mode 0)
		)
		(polygon
			(pts
				(xy 216.662 -92.456) (xy 216.281 -92.837) (xy 216.281 -98.044) (xy 216.535 -98.298) (xy 218.059 -98.298)
				(xy 218.567 -98.806) (xy 218.567 -101.981) (xy 218.694 -102.108) (xy 221.361 -102.108) (xy 221.742 -101.727)
				(xy 221.742 -92.837) (xy 221.361 -92.456)
			)
		)
		(polygon
			(pts
				(xy 217.043 -97.3582) (xy 216.789 -97.3582) (xy 216.789 -97.6122) (xy 217.043 -97.6122)
			)
		)
	)
	(zone
		(net "P12V_MSB")
		(layer "F.Cu")
		(hatch none 0.5)
		(connect_pads
			(clearance 0.5)
		)
		(min_thickness 0.25)
		(fill yes
			(thermal_gap 0.5)
			(thermal_bridge_width 0.5)
			(island_removal_mode 0)
		)
		(polygon
			(pts
				(xy 149.352 -63.881) (xy 149.098 -64.135) (xy 149.098 -65.532) (xy 148.463 -66.167) (xy 148.463 -69.342)
				(xy 148.082 -69.723) (xy 137.414 -69.723) (xy 136.949942 -70.187058) (xy 136.949942 -75.057) (xy 137.584942 -75.692)
				(xy 137.584942 -76.2) (xy 138.600942 -77.216) (xy 150.665942 -77.216) (xy 150.919942 -76.962) (xy 150.919942 -75.311)
				(xy 151.808942 -74.422) (xy 151.808942 -64.178942) (xy 151.511 -63.881)
			)
		)
	)
	(zone
		(layer "F.Cu")
		(hatch none 0.5)
		(connect_pads
			(clearance 0)
		)
		(min_thickness 0.25)
		(keepout
			(tracks allowed)
			(vias allowed)
			(pads allowed)
			(copperpour allowed)
			(footprints allowed)
		)
		(placement
			(enabled no)
			(sheetname "")
		)
		(fill
			(thermal_gap 0.5)
			(thermal_bridge_width 0.5)
			(island_removal_mode 0)
		)
		(polygon
			(pts
				(xy 336.423 -165.227) (xy 336.423 -163.068) (xy 338.709 -163.068) (xy 338.709 -165.227)
			)
		)
	)
	(zone
		(layer "F.Cu")
		(hatch none 0.5)
		(connect_pads
			(clearance 0)
		)
		(min_thickness 0.25)
		(keepout
			(tracks allowed)
			(vias allowed)
			(pads allowed)
			(copperpour allowed)
			(footprints not_allowed)
		)
		(placement
			(enabled no)
			(sheetname "")
		)
		(fill
			(thermal_gap 0.5)
			(thermal_bridge_width 0.5)
			(island_removal_mode 0)
		)
		(polygon
			(pts
				(xy 58.950098 -109.000036) (xy 0 -109.000036)
				(arc
					(start 0 -81.009998)
					(mid 0.878678 -78.888682)
					(end 2.999994 -78.010004)
				)
				(arc
					(start 25.500076 -78.010004)
					(mid 26.914287 -77.424219)
					(end 27.500072 -76.010008)
				)
				(arc
					(start 27.500072 -60.01004)
					(mid 28.085857 -58.595829)
					(end 29.500068 -58.010044)
				)
				(xy 58.950098 -58.010044)
			)
		)
	)
	(zone
		(layer "F.Cu")
		(hatch none 0.5)
		(connect_pads
			(clearance 0)
		)
		(min_thickness 0.25)
		(keepout
			(tracks allowed)
			(vias allowed)
			(pads allowed)
			(copperpour allowed)
			(footprints allowed)
		)
		(placement
			(enabled no)
			(sheetname "")
		)
		(fill
			(thermal_gap 0.5)
			(thermal_bridge_width 0.5)
			(island_removal_mode 0)
		)
		(polygon
			(pts
				(xy 184.404 -27.813) (xy 184.404 -26.289) (xy 186.055 -26.289) (xy 186.055 -27.813)
			)
		)
	)
	(zone
		(net "P3V3_STBY_VIN")
		(layer "F.Cu")
		(hatch none 0.5)
		(connect_pads
			(clearance 0.5)
		)
		(min_thickness 0.25)
		(fill yes
			(thermal_gap 0.5)
			(thermal_bridge_width 0.5)
			(island_removal_mode 0)
		)
		(polygon
			(pts
				(xy 326.136 -114.427) (xy 325.628 -114.935) (xy 325.628 -116.205) (xy 325.501 -116.332) (xy 322.326 -116.332)
				(xy 322.199 -116.459) (xy 322.199 -117.221) (xy 323.342 -118.364) (xy 331.597 -118.364) (xy 331.851 -118.11)
				(xy 331.851 -114.808) (xy 331.47 -114.427)
			)
		)
		(polygon
			(pts
				(xy 331.5335 -117.9703) (xy 331.2795 -117.9703) (xy 331.2795 -118.2243) (xy 331.5335 -118.2243)
			)
		)
		(polygon
			(pts
				(xy 330.1365 -117.9703) (xy 329.8825 -117.9703) (xy 329.8825 -118.2243) (xy 330.1365 -118.2243)
			)
		)
		(polygon
			(pts
				(xy 331.5335 -116.8273) (xy 331.2795 -116.8273) (xy 331.2795 -117.0813) (xy 331.5335 -117.0813)
			)
		)
		(polygon
			(pts
				(xy 330.1365 -116.8273) (xy 329.8825 -116.8273) (xy 329.8825 -117.0813) (xy 330.1365 -117.0813)
			)
		)
		(polygon
			(pts
				(xy 327.4568 -115.316) (xy 327.2028 -115.316) (xy 327.2028 -115.57) (xy 327.4568 -115.57)
			)
		)
		(polygon
			(pts
				(xy 326.5932 -115.316) (xy 326.3392 -115.316) (xy 326.3392 -115.57) (xy 326.5932 -115.57)
			)
		)
	)
	(zone
		(net "GND")
		(layer "F.Cu")
		(hatch none 0.5)
		(connect_pads
			(clearance 0.5)
		)
		(min_thickness 0.25)
		(fill yes
			(thermal_gap 0.5)
			(thermal_bridge_width 0.5)
			(island_removal_mode 0)
		)
		(polygon
			(pts
				(xy 167.64 -114.3) (xy 167.513 -114.427) (xy 167.513 -116.459) (xy 167.259 -116.713) (xy 166.751 -116.713)
				(xy 166.624 -116.84) (xy 166.624 -118.11) (xy 166.751 -118.237) (xy 167.64 -118.237) (xy 168.275 -117.602)
				(xy 174.117 -117.602) (xy 174.244 -117.729) (xy 174.244 -132.588) (xy 174.498 -132.842) (xy 176.403 -132.842)
				(xy 176.657 -132.588) (xy 176.657 -117.856) (xy 175.895 -117.094) (xy 175.895 -115.443) (xy 175.768 -115.316)
				(xy 175.006 -115.316) (xy 173.99 -114.3)
			)
		)
		(polygon
			(pts
				(xy 175.387 -120.4468) (xy 175.133 -120.4468) (xy 175.133 -120.7008) (xy 175.387 -120.7008)
			)
		)
		(polygon
			(pts
				(xy 175.387 -119.5832) (xy 175.133 -119.5832) (xy 175.133 -119.8372) (xy 175.387 -119.8372)
			)
		)
		(polygon
			(pts
				(xy 175.377348 -115.865656) (xy 175.123348 -115.865656) (xy 175.123348 -116.119656) (xy 175.377348 -116.119656)
			)
		)
	)
	(zone
		(layer "F.Cu")
		(hatch none 0.5)
		(connect_pads
			(clearance 0)
		)
		(min_thickness 0.25)
		(keepout
			(tracks not_allowed)
			(vias allowed)
			(pads allowed)
			(copperpour not_allowed)
			(footprints allowed)
		)
		(placement
			(enabled no)
			(sheetname "")
		)
		(fill
			(thermal_gap 0.5)
			(thermal_bridge_width 0.5)
			(island_removal_mode 0)
		)
		(polygon
			(pts
				(arc
					(start 320.595498 -75.209908)
					(mid 320.186558 -74.800968)
					(end 319.777618 -75.209908)
				)
				(arc
					(start 319.777618 -75.400408)
					(mid 319.854773 -75.378776)
					(end 319.925954 -75.341988)
				)
				(arc
					(start 319.925954 -75.341988)
					(mid 320.398579 -75.008894)
					(end 320.040762 -75.463146)
				)
				(arc
					(start 320.040762 -75.463146)
					(mid 319.915873 -75.532099)
					(end 319.777618 -75.567286)
				)
				(arc
					(start 319.777618 -75.7555)
					(mid 319.863799 -75.783395)
					(end 319.940432 -75.8317)
				)
				(xy 319.942718 -75.8317) (xy 319.966594 -75.855322) (xy 319.967102 -75.85583)
				(arc
					(start 320.046604 -75.935332)
					(mid 320.393702 -76.397863)
					(end 319.930018 -76.052172)
				)
				(arc
					(start 319.850008 -75.972162)
					(mid 319.816312 -75.945245)
					(end 319.777618 -75.926188)
				)
				(arc
					(start 319.777618 -76.191618)
					(mid 320.186431 -76.600812)
					(end 320.595498 -76.191872)
				)
			)
		)
	)
	(zone
		(layer "F.Cu")
		(hatch none 0.5)
		(connect_pads
			(clearance 0)
		)
		(min_thickness 0.25)
		(keepout
			(tracks not_allowed)
			(vias allowed)
			(pads allowed)
			(copperpour not_allowed)
			(footprints allowed)
		)
		(placement
			(enabled no)
			(sheetname "")
		)
		(fill
			(thermal_gap 0.5)
			(thermal_bridge_width 0.5)
			(island_removal_mode 0)
		)
		(polygon
			(pts
				(arc
					(start 41.351708 -89.712546)
					(mid 40.967914 -90.095959)
					(end 41.351454 -90.479626)
				)
				(arc
					(start 42.328338 -90.479626)
					(mid 42.711878 -90.096086)
					(end 42.328338 -89.712546)
				)
				(xy 42.074846 -89.712546)
				(arc
					(start 42.074846 -89.83599)
					(mid 42.079784 -89.879775)
					(end 42.094404 -89.921334)
				)
				(arc
					(start 42.094404 -89.921334)
					(mid 42.599308 -90.204893)
					(end 42.038524 -90.060526)
				)
				(arc
					(start 42.038524 -90.060526)
					(mid 41.976832 -89.969677)
					(end 41.949116 -89.863422)
				)
				(xy 41.947846 -89.862406) (xy 41.947846 -89.712546)
				(arc
					(start 41.729406 -89.712546)
					(mid 41.704622 -89.801534)
					(end 41.655746 -89.879932)
				)
				(xy 41.655746 -89.88171) (xy 41.637204 -89.899998) (xy 41.637204 -89.900252)
				(arc
					(start 41.598088 -89.939368)
					(mid 41.144828 -90.302712)
					(end 41.508172 -89.849452)
				)
				(arc
					(start 41.547542 -89.810336)
					(mid 41.581163 -89.76528)
					(end 41.600628 -89.712546)
				)
			)
		)
	)
	(zone
		(net "P12V_PCIE")
		(layer "F.Cu")
		(hatch none 0.5)
		(connect_pads
			(clearance 0.5)
		)
		(min_thickness 0.25)
		(fill yes
			(thermal_gap 0.5)
			(thermal_bridge_width 0.5)
			(island_removal_mode 0)
		)
		(polygon
			(pts
				(xy 55.626 -230.632) (xy 55.118 -231.14) (xy 39.751 -231.14) (xy 38.862 -232.029) (xy 38.862 -239.522)
				(xy 40.0685 -240.7285) (xy 55.1815 -240.7285) (xy 57.658 -238.252) (xy 57.658 -230.886) (xy 57.404 -230.632)
			)
		)
		(polygon
			(pts
				(xy 48.8188 -231.902) (xy 48.5648 -231.902) (xy 48.5648 -232.156) (xy 48.8188 -232.156)
			)
		)
		(polygon
			(pts
				(xy 47.9552 -231.902) (xy 47.7012 -231.902) (xy 47.7012 -232.156) (xy 47.9552 -232.156)
			)
		)
		(polygon
			(pts
				(xy 47.5488 -231.902) (xy 47.2948 -231.902) (xy 47.2948 -232.156) (xy 47.5488 -232.156)
			)
		)
		(polygon
			(pts
				(xy 46.6852 -231.902) (xy 46.4312 -231.902) (xy 46.4312 -232.156) (xy 46.6852 -232.156)
			)
		)
		(polygon
			(pts
				(xy 46.2788 -231.902) (xy 46.0248 -231.902) (xy 46.0248 -232.156) (xy 46.2788 -232.156)
			)
		)
		(polygon
			(pts
				(xy 45.4152 -231.902) (xy 45.1612 -231.902) (xy 45.1612 -232.156) (xy 45.4152 -232.156)
			)
		)
		(polygon
			(pts
				(xy 45.0088 -231.394) (xy 44.7548 -231.394) (xy 44.7548 -231.648) (xy 45.0088 -231.648)
			)
		)
		(polygon
			(pts
				(xy 44.3992 -231.394) (xy 44.1452 -231.394) (xy 44.1452 -231.648) (xy 44.3992 -231.648)
			)
		)
		(polygon
			(pts
				(xy 43.9928 -231.394) (xy 43.7388 -231.394) (xy 43.7388 -231.648) (xy 43.9928 -231.648)
			)
		)
		(polygon
			(pts
				(xy 43.3832 -231.394) (xy 43.1292 -231.394) (xy 43.1292 -231.648) (xy 43.3832 -231.648)
			)
		)
	)
	(zone
		(net "P12V")
		(layer "F.Cu")
		(hatch none 0.5)
		(connect_pads
			(clearance 0.5)
		)
		(min_thickness 0.25)
		(fill yes
			(thermal_gap 0.5)
			(thermal_bridge_width 0.5)
			(island_removal_mode 0)
		)
		(polygon
			(pts
				(xy 212.852 -112.395) (xy 212.217 -113.03) (xy 212.217 -121.666) (xy 207.518 -126.365) (xy 183.896 -126.365)
				(xy 176.657 -133.604) (xy 156.845 -133.604) (xy 148.717 -141.732) (xy 148.717 -167.132) (xy 148.844 -167.259)
				(xy 148.844 -167.64) (xy 149.479 -168.275) (xy 154.178 -168.275) (xy 154.813 -167.64) (xy 154.813 -144.653)
				(xy 159.131 -140.335) (xy 180.467 -140.335) (xy 187.071 -133.731) (xy 214.376 -133.731) (xy 217.424 -130.683)
				(xy 217.424 -114.173) (xy 215.646 -112.395)
			)
		)
	)
	(zone
		(layer "F.Cu")
		(hatch none 0.5)
		(connect_pads
			(clearance 0)
		)
		(min_thickness 0.25)
		(keepout
			(tracks allowed)
			(vias allowed)
			(pads allowed)
			(copperpour allowed)
			(footprints allowed)
		)
		(placement
			(enabled no)
			(sheetname "")
		)
		(fill
			(thermal_gap 0.5)
			(thermal_bridge_width 0.5)
			(island_removal_mode 0)
		)
		(polygon
			(pts
				(xy 88.138 -132.207) (xy 88.138 -130.937) (xy 89.027 -130.937) (xy 89.027 -132.207)
			)
		)
	)
	(zone
		(layer "F.Cu")
		(hatch none 0.5)
		(connect_pads
			(clearance 0)
		)
		(min_thickness 0.25)
		(keepout
			(tracks allowed)
			(vias allowed)
			(pads allowed)
			(copperpour allowed)
			(footprints not_allowed)
		)
		(placement
			(enabled no)
			(sheetname "")
		)
		(fill
			(thermal_gap 0.5)
			(thermal_bridge_width 0.5)
			(island_removal_mode 0)
		)
		(polygon
			(pts
				(xy 337.799934 -27.737308) (xy 326.300084 -27.737308) (xy 326.300084 -16.73733) (xy 337.799934 -16.73733)
			)
		)
	)
	(zone
		(layer "F.Cu")
		(hatch none 0.5)
		(connect_pads
			(clearance 0)
		)
		(min_thickness 0.25)
		(keepout
			(tracks allowed)
			(vias allowed)
			(pads allowed)
			(copperpour allowed)
			(footprints allowed)
		)
		(placement
			(enabled no)
			(sheetname "")
		)
		(fill
			(thermal_gap 0.5)
			(thermal_bridge_width 0.5)
			(island_removal_mode 0)
		)
		(polygon
			(pts
				(xy 344.043 -152.781) (xy 344.043 -148.844) (xy 347.091 -148.844) (xy 351.155 -148.844) (xy 351.155 -152.781)
				(xy 347.091 -152.781)
			)
		)
	)
	(zone
		(net "GND")
		(layer "F.Cu")
		(hatch none 0.5)
		(connect_pads
			(clearance 0.5)
		)
		(min_thickness 0.25)
		(fill yes
			(thermal_gap 0.5)
			(thermal_bridge_width 0.5)
			(island_removal_mode 0)
		)
		(polygon
			(pts
				(xy 77.324966 -54.737) (xy 77.089 -54.972966) (xy 77.089 -60.452) (xy 77.343 -60.706) (xy 78.467966 -60.706)
				(xy 78.594966 -60.579) (xy 78.594966 -54.864) (xy 78.467966 -54.737)
			)
		)
		(polygon
			(pts
				(xy 78.38059 -55.923688) (xy 78.12659 -55.923688) (xy 78.12659 -56.533288) (xy 78.38059 -56.533288)
			)
		)
		(polygon
			(pts
				(xy 78.38059 -55.034688) (xy 78.12659 -55.034688) (xy 78.12659 -55.644288) (xy 78.38059 -55.644288)
			)
		)
	)
	(zone
		(net "P1V8_C")
		(layer "F.Cu")
		(hatch none 0.5)
		(connect_pads
			(clearance 0.5)
		)
		(min_thickness 0.25)
		(fill yes
			(thermal_gap 0.5)
			(thermal_bridge_width 0.5)
			(island_removal_mode 0)
		)
		(polygon
			(pts
				(xy 77.47 -62.992) (xy 77.343 -63.119) (xy 77.343 -66.421) (xy 78.359 -67.437) (xy 82.042 -67.437)
				(xy 82.423 -67.056) (xy 82.423 -66.294) (xy 83.439 -65.278) (xy 83.439 -63.246) (xy 83.185 -62.992)
			)
		)
		(polygon
			(pts
				(xy 81.820766 -66.675) (xy 81.566766 -66.675) (xy 81.566766 -66.929) (xy 81.820766 -66.929)
			)
		)
		(polygon
			(pts
				(xy 81.211166 -66.675) (xy 80.957166 -66.675) (xy 80.957166 -66.929) (xy 81.211166 -66.929)
			)
		)
		(polygon
			(pts
				(xy 80.550766 -66.675) (xy 80.296766 -66.675) (xy 80.296766 -66.929) (xy 80.550766 -66.929)
			)
		)
		(polygon
			(pts
				(xy 79.941166 -66.675) (xy 79.687166 -66.675) (xy 79.687166 -66.929) (xy 79.941166 -66.929)
			)
		)
		(polygon
			(pts
				(xy 79.280766 -66.675) (xy 79.026766 -66.675) (xy 79.026766 -66.929) (xy 79.280766 -66.929)
			)
		)
		(polygon
			(pts
				(xy 78.671166 -66.675) (xy 78.417166 -66.675) (xy 78.417166 -66.929) (xy 78.671166 -66.929)
			)
		)
		(polygon
			(pts
				(xy 81.17459 -63.289688) (xy 80.92059 -63.289688) (xy 80.92059 -63.543688) (xy 81.17459 -63.543688)
			)
		)
		(polygon
			(pts
				(xy 80.61579 -63.289688) (xy 80.36179 -63.289688) (xy 80.36179 -63.543688) (xy 80.61579 -63.543688)
			)
		)
		(polygon
			(pts
				(xy 80.03159 -63.289688) (xy 79.77759 -63.289688) (xy 79.77759 -63.543688) (xy 80.03159 -63.543688)
			)
		)
		(polygon
			(pts
				(xy 79.47279 -63.289688) (xy 79.21879 -63.289688) (xy 79.21879 -63.543688) (xy 79.47279 -63.543688)
			)
		)
	)
	(zone
		(layer "F.Cu")
		(hatch none 0.5)
		(connect_pads
			(clearance 0)
		)
		(min_thickness 0.25)
		(keepout
			(tracks allowed)
			(vias allowed)
			(pads allowed)
			(copperpour allowed)
			(footprints allowed)
		)
		(placement
			(enabled no)
			(sheetname "")
		)
		(fill
			(thermal_gap 0.5)
			(thermal_bridge_width 0.5)
			(island_removal_mode 0)
		)
		(polygon
			(pts
				(xy 339.471 -148.336) (xy 339.471 -145.669) (xy 343.154 -145.669) (xy 343.154 -148.336)
			)
		)
	)
	(zone
		(layer "F.Cu")
		(hatch none 0.5)
		(connect_pads
			(clearance 0)
		)
		(min_thickness 0.25)
		(keepout
			(tracks allowed)
			(vias allowed)
			(pads allowed)
			(copperpour allowed)
			(footprints not_allowed)
		)
		(placement
			(enabled no)
			(sheetname "")
		)
		(fill
			(thermal_gap 0.5)
			(thermal_bridge_width 0.5)
			(island_removal_mode 0)
		)
		(polygon
			(pts
				(xy 355.6 -31.999936) (xy 355.6 -64.600074) (xy 352.160078 -64.600074) (xy 352.160078 -60.600082)
				(xy 340.226396 -60.600082) (xy 340.226396 -31.999936)
			)
		)
	)
	(zone
		(layer "F.Cu")
		(hatch none 0.5)
		(connect_pads
			(clearance 0)
		)
		(min_thickness 0.25)
		(keepout
			(tracks allowed)
			(vias allowed)
			(pads allowed)
			(copperpour allowed)
			(footprints allowed)
		)
		(placement
			(enabled no)
			(sheetname "")
		)
		(fill
			(thermal_gap 0.5)
			(thermal_bridge_width 0.5)
			(island_removal_mode 0)
		)
		(polygon
			(pts
				(xy 220.853 -88.646) (xy 220.853 -87.376) (xy 223.647 -87.376) (xy 223.647 -88.646)
			)
		)
	)
	(zone
		(layer "F.Cu")
		(hatch none 0.5)
		(connect_pads
			(clearance 0)
		)
		(min_thickness 0.25)
		(keepout
			(tracks not_allowed)
			(vias allowed)
			(pads allowed)
			(copperpour not_allowed)
			(footprints allowed)
		)
		(placement
			(enabled no)
			(sheetname "")
		)
		(fill
			(thermal_gap 0.5)
			(thermal_bridge_width 0.5)
			(island_removal_mode 0)
		)
		(polygon
			(pts
				(arc
					(start 350.369124 -154.275028)
					(mid 350.010984 -153.916888)
					(end 349.652844 -154.275028)
				)
				(xy 349.652844 -154.46121) (xy 349.707962 -154.46121)
				(arc
					(start 349.77324 -154.395932)
					(mid 350.199584 -154.086428)
					(end 349.89008 -154.512772)
				)
				(xy 349.824802 -154.57805) (xy 349.776542 -154.62631) (xy 349.707962 -154.62631) (xy 349.652844 -154.62631)
				(xy 349.652844 -154.80411) (xy 349.708216 -154.80411) (xy 349.776796 -154.80411) (xy 349.825056 -154.85237)
				(arc
					(start 349.89008 -154.917394)
					(mid 350.199584 -155.343738)
					(end 349.77324 -155.034234)
				)
				(xy 349.708216 -154.96921) (xy 349.652844 -154.96921)
				(arc
					(start 349.652844 -155.154884)
					(mid 350.010857 -155.513278)
					(end 350.369124 -155.155138)
				)
			)
		)
	)
	(zone
		(net "GND")
		(layer "F.Cu")
		(hatch none 0.5)
		(connect_pads
			(clearance 0.5)
		)
		(min_thickness 0.25)
		(fill yes
			(thermal_gap 0.5)
			(thermal_bridge_width 0.5)
			(island_removal_mode 0)
		)
		(polygon
			(pts
				(xy 268.605 -69.215) (xy 268.351 -69.469) (xy 268.351 -72.263) (xy 267.843 -72.771) (xy 267.843 -77.216)
				(xy 268.351 -77.724) (xy 269.621 -77.724) (xy 269.748 -77.597) (xy 269.748 -69.469) (xy 269.494 -69.215)
			)
		)
		(polygon
			(pts
				(xy 268.6558 -76.2762) (xy 268.4018 -76.2762) (xy 268.4018 -76.5302) (xy 268.6558 -76.5302)
			)
		)
		(polygon
			(pts
				(xy 268.661896 -75.401424) (xy 268.407896 -75.401424) (xy 268.407896 -75.655424) (xy 268.4018 -75.6666)
				(xy 268.4018 -75.9206) (xy 268.6558 -75.9206) (xy 268.6558 -75.6666) (xy 268.661896 -75.655424)
			)
		)
		(polygon
			(pts
				(xy 268.661896 -74.791824) (xy 268.407896 -74.791824) (xy 268.407896 -75.045824) (xy 268.661896 -75.045824)
			)
		)
		(polygon
			(pts
				(xy 268.661896 -74.283824) (xy 268.407896 -74.283824) (xy 268.407896 -74.537824) (xy 268.661896 -74.537824)
			)
		)
		(polygon
			(pts
				(xy 268.661896 -73.674224) (xy 268.407896 -73.674224) (xy 268.407896 -73.928224) (xy 268.661896 -73.928224)
			)
		)
		(polygon
			(pts
				(xy 268.732 -73.2028) (xy 268.478 -73.2028) (xy 268.478 -73.4568) (xy 268.732 -73.4568)
			)
		)
		(polygon
			(pts
				(xy 268.732 -72.5932) (xy 268.478 -72.5932) (xy 268.478 -72.8472) (xy 268.732 -72.8472)
			)
		)
		(polygon
			(pts
				(xy 268.859 -72.1868) (xy 268.605 -72.1868) (xy 268.605 -72.4408) (xy 268.859 -72.4408)
			)
		)
		(polygon
			(pts
				(xy 268.859 -71.3232) (xy 268.605 -71.3232) (xy 268.605 -71.5772) (xy 268.859 -71.5772)
			)
		)
		(polygon
			(pts
				(xy 268.913864 -70.908672) (xy 268.659864 -70.908672) (xy 268.659864 -71.162672) (xy 268.913864 -71.162672)
			)
		)
		(polygon
			(pts
				(xy 268.913864 -70.045072) (xy 268.659864 -70.045072) (xy 268.659864 -70.299072) (xy 268.913864 -70.299072)
			)
		)
	)
	(zone
		(net "VSENSE_HSC_MSB")
		(layer "F.Cu")
		(hatch none 0.5)
		(connect_pads
			(clearance 0.5)
		)
		(min_thickness 0.25)
		(fill yes
			(thermal_gap 0.5)
			(thermal_bridge_width 0.5)
			(island_removal_mode 0)
		)
		(polygon
			(pts
				(xy 265.811 -59.436) (xy 265.684 -59.563) (xy 265.684 -64.516) (xy 265.938 -64.77) (xy 270.383 -64.77)
				(xy 272.161 -62.992) (xy 275.209 -62.992) (xy 275.463 -62.738) (xy 275.463 -59.563) (xy 275.336 -59.436)
			)
		)
	)
	(zone
		(layer "F.Cu")
		(hatch none 0.5)
		(connect_pads
			(clearance 0)
		)
		(min_thickness 0.25)
		(keepout
			(tracks allowed)
			(vias allowed)
			(pads allowed)
			(copperpour allowed)
			(footprints allowed)
		)
		(placement
			(enabled no)
			(sheetname "")
		)
		(fill
			(thermal_gap 0.5)
			(thermal_bridge_width 0.5)
			(island_removal_mode 0)
		)
		(polygon
			(pts
				(xy 186.436 -32.004) (xy 186.436 -29.464) (xy 189.357 -29.464) (xy 189.357 -32.004)
			)
		)
	)
	(zone
		(net "TPS74801_1V53_STBY_OUT")
		(layer "F.Cu")
		(hatch none 0.5)
		(connect_pads
			(clearance 0.5)
		)
		(min_thickness 0.25)
		(fill yes
			(thermal_gap 0.5)
			(thermal_bridge_width 0.5)
			(island_removal_mode 0)
		)
		(polygon
			(pts
				(xy 292.735 -211.963) (xy 291.211 -213.487) (xy 291.211 -218.44) (xy 290.957 -218.694) (xy 289.306 -218.694)
				(xy 287.147 -220.853) (xy 285.75 -220.853) (xy 285.496 -221.107) (xy 285.496 -222.504) (xy 285.115 -222.885)
				(xy 284.734 -222.885) (xy 284.607 -223.012) (xy 284.607 -224.028) (xy 284.734 -224.155) (xy 287.401 -224.155)
				(xy 288.036 -223.52) (xy 296.545 -223.52) (xy 297.053 -223.012) (xy 297.053 -219.837) (xy 295.275 -218.059)
				(xy 295.275 -217.424) (xy 296.418 -216.281) (xy 300.101 -216.281) (xy 300.99 -215.392) (xy 300.99 -212.217)
				(xy 300.736 -211.963)
			)
		)
		(polygon
			(pts
				(xy 288.840672 -222.830136) (xy 288.586672 -222.830136) (xy 288.586672 -223.084136) (xy 288.840672 -223.084136)
			)
		)
		(polygon
			(pts
				(xy 288.231072 -222.830136) (xy 287.977072 -222.830136) (xy 287.977072 -223.084136) (xy 288.231072 -223.084136)
			)
		)
		(polygon
			(pts
				(xy 290.83 -219.1258) (xy 290.576 -219.1258) (xy 290.576 -219.3798) (xy 290.83 -219.3798)
			)
		)
	)
	(zone
		(net "TPS74801_1V26_STBY_OUT")
		(layer "F.Cu")
		(hatch none 0.5)
		(connect_pads
			(clearance 0.5)
		)
		(min_thickness 0.25)
		(fill yes
			(thermal_gap 0.5)
			(thermal_bridge_width 0.5)
			(island_removal_mode 0)
		)
		(polygon
			(pts
				(xy 260.35 -212.852) (xy 259.969 -213.233) (xy 259.969 -218.44) (xy 260.096 -218.567) (xy 262.001 -218.567)
				(xy 262.763 -219.329) (xy 262.763 -222.631) (xy 262.89 -222.758) (xy 264.414 -222.758) (xy 264.795 -223.139)
				(xy 264.795 -223.393) (xy 264.922 -223.52) (xy 267.716 -223.52) (xy 267.97 -223.266) (xy 267.97 -212.979)
				(xy 267.843 -212.852)
			)
		)
		(polygon
			(pts
				(xy 261.700264 -217.720672) (xy 261.446264 -217.720672) (xy 261.446264 -217.974672) (xy 261.700264 -217.974672)
			)
		)
		(polygon
			(pts
				(xy 261.141464 -217.720672) (xy 260.887464 -217.720672) (xy 260.887464 -217.974672) (xy 261.141464 -217.974672)
			)
		)
		(polygon
			(pts
				(xy 260.709664 -217.669872) (xy 260.455664 -217.669872) (xy 260.455664 -217.923872) (xy 260.709664 -217.923872)
			)
		)
		(polygon
			(pts
				(xy 267.589 -214.6808) (xy 267.335 -214.6808) (xy 267.335 -214.9348) (xy 267.589 -214.9348)
			)
		)
		(polygon
			(pts
				(xy 267.589 -214.0712) (xy 267.335 -214.0712) (xy 267.335 -214.3252) (xy 267.589 -214.3252)
			)
		)
	)
	(zone
		(net "GND")
		(layer "F.Cu")
		(hatch none 0.5)
		(connect_pads
			(clearance 0.5)
		)
		(min_thickness 0.25)
		(fill yes
			(thermal_gap 0.5)
			(thermal_bridge_width 0.5)
			(island_removal_mode 0)
		)
		(polygon
			(pts
				(xy 318.262 -41.91) (xy 318.008 -42.164) (xy 318.008 -53.721) (xy 318.262 -53.975) (xy 321.437 -53.975)
				(xy 321.691 -53.721) (xy 321.691 -42.418) (xy 321.183 -41.91)
			)
		)
		(polygon
			(pts
				(xy 319.0748 -53.5686) (xy 318.8208 -53.5686) (xy 318.8208 -53.8226) (xy 319.0748 -53.8226)
			)
		)
		(polygon
			(pts
				(xy 318.77 -52.3748) (xy 318.516 -52.3748) (xy 318.516 -52.6288) (xy 318.8208 -52.959) (xy 319.0748 -52.959)
				(xy 319.0748 -52.705)
			)
		)
		(polygon
			(pts
				(xy 318.77 -51.7652) (xy 318.516 -51.7652) (xy 318.516 -52.0192) (xy 318.77 -52.0192)
			)
		)
		(polygon
			(pts
				(xy 318.77 -51.3588) (xy 318.516 -51.3588) (xy 318.516 -51.6128) (xy 318.77 -51.6128)
			)
		)
		(polygon
			(pts
				(xy 318.77 -50.7492) (xy 318.516 -50.7492) (xy 318.516 -51.0032) (xy 318.77 -51.0032)
			)
		)
		(polygon
			(pts
				(xy 318.77 -50.3428) (xy 318.516 -50.3428) (xy 318.516 -50.5968) (xy 318.77 -50.5968)
			)
		)
		(polygon
			(pts
				(xy 318.77 -49.7332) (xy 318.516 -49.7332) (xy 318.516 -49.9872) (xy 318.77 -49.9872)
			)
		)
	)
	(zone
		(layer "F.Cu")
		(hatch none 0.5)
		(connect_pads
			(clearance 0)
		)
		(min_thickness 0.25)
		(keepout
			(tracks allowed)
			(vias allowed)
			(pads allowed)
			(copperpour allowed)
			(footprints allowed)
		)
		(placement
			(enabled no)
			(sheetname "")
		)
		(fill
			(thermal_gap 0.5)
			(thermal_bridge_width 0.5)
			(island_removal_mode 0)
		)
		(polygon
			(pts
				(xy 340.995 -109.855) (xy 340.995 -108.712) (xy 342.011 -108.712) (xy 342.011 -109.855)
			)
		)
	)
	(zone
		(net "P5V_STBY")
		(layer "F.Cu")
		(hatch none 0.5)
		(connect_pads
			(clearance 0.5)
		)
		(min_thickness 0.25)
		(fill yes
			(thermal_gap 0.5)
			(thermal_bridge_width 0.5)
			(island_removal_mode 0)
		)
		(polygon
			(pts
				(xy 314.071 -41.275) (xy 313.055 -42.291) (xy 313.055 -48.641) (xy 312.801 -48.895) (xy 312.293 -48.895)
				(xy 312.039 -49.149) (xy 312.039 -50.927) (xy 312.166 -51.054) (xy 313.69 -51.054) (xy 315.468 -52.832)
				(xy 315.468 -53.594) (xy 315.722 -53.848) (xy 317.627 -53.848) (xy 317.754 -53.721) (xy 317.754 -41.529)
				(xy 317.5 -41.275)
			)
		)
		(polygon
			(pts
				(xy 316.7888 -52.705) (xy 316.5348 -52.705) (xy 316.5348 -52.959) (xy 316.7888 -52.959)
			)
		)
		(polygon
			(pts
				(xy 317.246 -52.3748) (xy 316.992 -52.3748) (xy 316.992 -52.6288) (xy 317.246 -52.6288)
			)
		)
		(polygon
			(pts
				(xy 317.246 -51.7652) (xy 316.992 -51.7652) (xy 316.992 -52.0192) (xy 317.246 -52.0192)
			)
		)
		(polygon
			(pts
				(xy 317.246 -51.3588) (xy 316.992 -51.3588) (xy 316.992 -51.6128) (xy 317.246 -51.6128)
			)
		)
		(polygon
			(pts
				(xy 317.246 -50.7492) (xy 316.992 -50.7492) (xy 316.992 -51.0032) (xy 317.246 -51.0032)
			)
		)
		(polygon
			(pts
				(xy 317.246 -50.3428) (xy 316.992 -50.3428) (xy 316.992 -50.5968) (xy 317.246 -50.5968)
			)
		)
		(polygon
			(pts
				(xy 317.246 -49.7332) (xy 316.992 -49.7332) (xy 316.992 -49.9872) (xy 317.246 -49.9872)
			)
		)
	)
	(zone
		(layer "F.Cu")
		(hatch none 0.5)
		(connect_pads
			(clearance 0)
		)
		(min_thickness 0.25)
		(keepout
			(tracks allowed)
			(vias allowed)
			(pads allowed)
			(copperpour allowed)
			(footprints allowed)
		)
		(placement
			(enabled no)
			(sheetname "")
		)
		(fill
			(thermal_gap 0.5)
			(thermal_bridge_width 0.5)
			(island_removal_mode 0)
		)
		(polygon
			(pts
				(xy 325.501 -165.227) (xy 325.501 -162.687) (xy 328.041 -162.687) (xy 328.041 -165.227)
			)
		)
	)
	(zone
		(layer "F.Cu")
		(hatch none 0.5)
		(connect_pads
			(clearance 0)
		)
		(min_thickness 0.25)
		(keepout
			(tracks allowed)
			(vias allowed)
			(pads allowed)
			(copperpour allowed)
			(footprints not_allowed)
		)
		(placement
			(enabled no)
			(sheetname "")
		)
		(fill
			(thermal_gap 0.5)
			(thermal_bridge_width 0.5)
			(island_removal_mode 0)
		)
		(polygon
			(pts
				(xy 355.6 -109.000036) (xy 317.90005 -109.000036) (xy 317.90005 -108.000038) (xy 326.69988 -108.000038)
				(xy 326.69988 -101.000052) (xy 317.90005 -101.000052) (xy 317.90005 -42.999914) (xy 326.300084 -42.999914)
				(xy 326.300084 -72.237346) (xy 337.799934 -72.237346) (xy 337.799934 -16.73733) (xy 326.300084 -16.73733)
				(xy 326.300084 -35.999928) (xy 317.90005 -35.999928) (xy 317.90005 0)
				(arc
					(start 354.600002 0)
					(mid 355.307107 -0.292893)
					(end 355.6 -0.999998)
				)
				(xy 355.6 -31.999936) (xy 340.226396 -31.999936) (xy 340.226396 -60.600082) (xy 352.160078 -60.600082)
				(xy 352.160078 -64.600074) (xy 355.6 -64.600074)
			)
		)
	)
	(zone
		(layer "F.Cu")
		(hatch none 0.5)
		(connect_pads
			(clearance 0)
		)
		(min_thickness 0.25)
		(keepout
			(tracks allowed)
			(vias allowed)
			(pads allowed)
			(copperpour allowed)
			(footprints allowed)
		)
		(placement
			(enabled no)
			(sheetname "")
		)
		(fill
			(thermal_gap 0.5)
			(thermal_bridge_width 0.5)
			(island_removal_mode 0)
		)
		(polygon
			(pts
				(xy 164.973 -147.574) (xy 164.973 -146.431) (xy 166.497 -146.431) (xy 166.497 -147.574)
			)
		)
	)
	(zone
		(layer "F.Cu")
		(hatch none 0.5)
		(connect_pads
			(clearance 0)
		)
		(min_thickness 0.25)
		(keepout
			(tracks not_allowed)
			(vias allowed)
			(pads allowed)
			(copperpour not_allowed)
			(footprints allowed)
		)
		(placement
			(enabled no)
			(sheetname "")
		)
		(fill
			(thermal_gap 0.5)
			(thermal_bridge_width 0.5)
			(island_removal_mode 0)
		)
		(polygon
			(pts
				(arc
					(start 163.946332 -76.64196)
					(mid 163.562538 -77.025373)
					(end 163.946078 -77.40904)
				)
				(arc
					(start 164.928042 -77.40904)
					(mid 165.311582 -77.0255)
					(end 164.928042 -76.64196)
				)
				(arc
					(start 164.775388 -76.64196)
					(mid 164.798871 -76.697774)
					(end 164.825934 -76.751942)
				)
				(arc
					(start 164.825934 -76.751942)
					(mid 165.103529 -77.259126)
					(end 164.692838 -76.852272)
				)
				(arc
					(start 164.692838 -76.852272)
					(mid 164.641218 -76.749536)
					(end 164.600636 -76.64196)
				)
				(arc
					(start 164.289994 -76.64196)
					(mid 164.242296 -76.751802)
					(end 164.18433 -76.85659)
				)
				(arc
					(start 164.18433 -76.85659)
					(mid 163.765764 -77.255242)
					(end 164.05352 -76.753974)
				)
				(arc
					(start 164.05352 -76.753974)
					(mid 164.084097 -76.698805)
					(end 164.111432 -76.64196)
				)
			)
		)
	)
	(zone
		(net "GND")
		(layer "F.Cu")
		(hatch none 0.5)
		(connect_pads
			(clearance 0.5)
		)
		(min_thickness 0.25)
		(fill yes
			(thermal_gap 0.5)
			(thermal_bridge_width 0.5)
			(island_removal_mode 0)
		)
		(polygon
			(pts
				(xy 100.311966 -34.798) (xy 100.184966 -34.925) (xy 100.184966 -35.179) (xy 101.200966 -36.195)
				(xy 101.200966 -36.703) (xy 101.073966 -36.83) (xy 100.438966 -36.83) (xy 99.422966 -35.814) (xy 98.787966 -35.814)
				(xy 98.660966 -35.941) (xy 98.660966 -36.449) (xy 99.041966 -36.83) (xy 98.025966 -36.83) (xy 97.009966 -35.814)
				(xy 96.628966 -35.814) (xy 96.501966 -35.941) (xy 96.501966 -36.449) (xy 96.393 -36.557966) (xy 96.393 -37.211)
				(xy 96.266 -37.338) (xy 95.758 -37.338) (xy 95.631 -37.211) (xy 94.469966 -37.211) (xy 94.088966 -37.592)
				(xy 94.088966 -38.354) (xy 93.834966 -38.608) (xy 93.834966 -40.132) (xy 94.088966 -40.386) (xy 94.088966 -40.894)
				(xy 93.707966 -41.275) (xy 93.707966 -41.529) (xy 94.088966 -41.91) (xy 94.088966 -43.307) (xy 93.707966 -43.688)
				(xy 93.707966 -44.831) (xy 94.088966 -45.212) (xy 94.088966 -46.99) (xy 91.675966 -49.403) (xy 91.675966 -51.054)
				(xy 88.9 -53.829966) (xy 88.9 -57.404) (xy 89.154 -57.658) (xy 92.437966 -57.658) (xy 93.453966 -56.642)
				(xy 93.453966 -55.626) (xy 93.834966 -55.245) (xy 94.088966 -55.245) (xy 94.342966 -54.991) (xy 94.342966 -54.737)
				(xy 94.596966 -54.483) (xy 96.120966 -54.483) (xy 97.009966 -53.594) (xy 98.025966 -53.594) (xy 98.406966 -53.975)
				(xy 98.406966 -57.023) (xy 98.660966 -57.277) (xy 99.295966 -57.277) (xy 99.422966 -57.15) (xy 99.422966 -56.896)
				(xy 99.295966 -56.769) (xy 99.295966 -54.864) (xy 99.549966 -54.61) (xy 100.565966 -54.61) (xy 100.819966 -54.864)
				(xy 100.819966 -56.007) (xy 101.708966 -56.896) (xy 102.089966 -56.896) (xy 102.216966 -56.769)
				(xy 102.216966 -54.864) (xy 102.724966 -54.356) (xy 109.855 -54.356) (xy 110.109 -54.61) (xy 112.141 -54.61)
				(xy 112.268 -54.483) (xy 112.268 -52.451) (xy 112.122966 -52.305966) (xy 112.122966 -49.149) (xy 113.265966 -48.006)
				(xy 114.027966 -48.006) (xy 114.281966 -47.752) (xy 114.281966 -47.498) (xy 114.154966 -47.371)
				(xy 112.376966 -47.371) (xy 112.122966 -47.117) (xy 112.122966 -37.846) (xy 111.741966 -37.465)
				(xy 111.741966 -36.195) (xy 110.725966 -35.179) (xy 105.518966 -35.179) (xy 103.867966 -36.83) (xy 102.216966 -36.83)
				(xy 102.216966 -36.703) (xy 102.089966 -36.576) (xy 102.089966 -35.687) (xy 101.200966 -34.798)
			)
		)
	)
	(zone
		(layer "F.Cu")
		(hatch none 0.5)
		(connect_pads
			(clearance 0)
		)
		(min_thickness 0.25)
		(keepout
			(tracks allowed)
			(vias allowed)
			(pads allowed)
			(copperpour allowed)
			(footprints allowed)
		)
		(placement
			(enabled no)
			(sheetname "")
		)
		(fill
			(thermal_gap 0.5)
			(thermal_bridge_width 0.5)
			(island_removal_mode 0)
		)
		(polygon
			(pts
				(xy 27.559 -170.307) (xy 27.559 -168.529) (xy 28.702 -168.529) (xy 28.702 -170.307)
			)
		)
	)
	(zone
		(net "GND")
		(layer "F.Cu")
		(hatch none 0.5)
		(connect_pads
			(clearance 0.5)
		)
		(min_thickness 0.25)
		(fill yes
			(thermal_gap 0.5)
			(thermal_bridge_width 0.5)
			(island_removal_mode 0)
		)
		(polygon
			(pts
				(xy 102.489 -180.34) (xy 84.201 -198.628) (xy 84.201 -220.091) (xy 85.344 -221.234) (xy 95.631 -221.234)
				(xy 96.266 -221.869) (xy 101.473 -221.869) (xy 102.489 -220.853) (xy 102.489 -203.581) (xy 111.633 -194.437)
				(xy 111.633 -181.483) (xy 110.49 -180.34)
			)
		)
		(polygon
			(pts
				(xy 101.4984 -220.6498) (xy 101.2444 -220.6498) (xy 101.2444 -220.9038) (xy 101.4984 -220.9038)
			)
		)
		(polygon
			(pts
				(xy 100.9396 -220.6498) (xy 100.6856 -220.6498) (xy 100.6856 -220.9038) (xy 100.9396 -220.9038)
			)
		)
		(polygon
			(pts
				(xy 98.0694 -220.6498) (xy 97.8154 -220.6498) (xy 97.8154 -220.9038) (xy 98.0694 -220.9038)
			)
		)
		(polygon
			(pts
				(xy 97.5106 -220.6498) (xy 97.2566 -220.6498) (xy 97.2566 -220.9038) (xy 97.5106 -220.9038)
			)
		)
		(polygon
			(pts
				(xy 93.1672 -220.472) (xy 92.9132 -220.472) (xy 92.9132 -220.726) (xy 93.1672 -220.726)
			)
		)
	)
	(zone
		(net "GND")
		(layer "F.Cu")
		(hatch none 0.5)
		(connect_pads
			(clearance 0.5)
		)
		(min_thickness 0.25)
		(fill yes
			(thermal_gap 0.5)
			(thermal_bridge_width 0.5)
			(island_removal_mode 0)
		)
		(polygon
			(pts
				(xy 331.089 -109.474) (xy 330.708 -109.855) (xy 330.708 -111.125) (xy 330.327 -111.506) (xy 328.422 -111.506)
				(xy 328.168 -111.252) (xy 319.659 -111.252) (xy 319.405 -111.506) (xy 319.405 -114.173) (xy 319.786 -114.554)
				(xy 325.247 -114.554) (xy 325.755 -114.046) (xy 332.74 -114.046) (xy 333.375 -113.411) (xy 333.375 -109.855)
				(xy 332.994 -109.474)
			)
		)
		(polygon
			(pts
				(xy 327.4568 -113.03) (xy 327.2028 -113.03) (xy 327.2028 -113.284) (xy 327.4568 -113.284)
			)
		)
		(polygon
			(pts
				(xy 326.5932 -113.03) (xy 326.3392 -113.03) (xy 326.3392 -113.284) (xy 326.5932 -113.284)
			)
		)
	)
	(zone
		(net "XTAL_VDDA09")
		(layer "F.Cu")
		(hatch none 0.5)
		(connect_pads
			(clearance 0.5)
		)
		(min_thickness 0.25)
		(fill yes
			(thermal_gap 0.5)
			(thermal_bridge_width 0.5)
			(island_removal_mode 0)
		)
		(polygon
			(pts
				(xy 81.007966 -78.994) (xy 80.880966 -79.121) (xy 80.880966 -81.915) (xy 81.007966 -82.042) (xy 88.627966 -82.042)
				(xy 88.881966 -81.788) (xy 88.881966 -80.518) (xy 88.754966 -80.391) (xy 82.277966 -80.391) (xy 82.150966 -80.264)
				(xy 82.150966 -79.121) (xy 82.023966 -78.994)
			)
		)
		(polygon
			(pts
				(xy 81.48447 -79.693008) (xy 81.23047 -79.693008) (xy 81.23047 -79.947008) (xy 81.48447 -79.947008)
			)
		)
		(polygon
			(pts
				(xy 81.48447 -79.134208) (xy 81.23047 -79.134208) (xy 81.23047 -79.388208) (xy 81.48447 -79.388208)
			)
		)
	)
	(zone
		(net "GND")
		(layer "F.Cu")
		(hatch none 0.5)
		(connect_pads
			(clearance 0.5)
		)
		(min_thickness 0.25)
		(fill yes
			(thermal_gap 0.5)
			(thermal_bridge_width 0.5)
			(island_removal_mode 0)
		)
		(polygon
			(pts
				(xy 119.253 -174.117) (xy 117.729 -175.641) (xy 117.729 -193.548) (xy 121.666 -197.485) (xy 121.666 -203.2)
				(xy 122.301 -203.835) (xy 129.413 -203.835) (xy 130.429 -202.819) (xy 130.429 -177.165) (xy 127.381 -174.117)
			)
		)
	)
	(zone
		(layer "F.Cu")
		(hatch none 0.5)
		(connect_pads
			(clearance 0)
		)
		(min_thickness 0.25)
		(keepout
			(tracks allowed)
			(vias allowed)
			(pads allowed)
			(copperpour allowed)
			(footprints not_allowed)
		)
		(placement
			(enabled no)
			(sheetname "")
		)
		(fill
			(thermal_gap 0.5)
			(thermal_bridge_width 0.5)
			(island_removal_mode 0)
		)
		(polygon
			(pts
				(arc
					(start 351.600008 -250.898914)
					(mid 351.102555 -250.974641)
					(end 350.60001 -251.000006)
				)
				(arc
					(start 256.15011 -251.000006)
					(mid 252.614583 -249.535543)
					(end 251.15012 -246.000016)
				)
				(arc
					(start 251.15012 -197.000114)
					(mid 250.857227 -196.293009)
					(end 250.150122 -196.000116)
				)
				(xy 236.199934 -196.000116) (xy 236.199934 -109.000036) (xy 351.600008 -109.000036)
			)
		)
	)
	(zone
		(layer "F.Cu")
		(hatch none 0.5)
		(connect_pads
			(clearance 0)
		)
		(min_thickness 0.25)
		(keepout
			(tracks allowed)
			(vias allowed)
			(pads allowed)
			(copperpour allowed)
			(footprints allowed)
		)
		(placement
			(enabled no)
			(sheetname "")
		)
		(fill
			(thermal_gap 0.5)
			(thermal_bridge_width 0.5)
			(island_removal_mode 0)
		)
		(polygon
			(pts
				(xy 319.786 -117.602) (xy 319.786 -115.189) (xy 322.199 -115.189) (xy 322.199 -117.602)
			)
		)
	)
	(zone
		(layer "F.Cu")
		(hatch none 0.5)
		(connect_pads
			(clearance 0)
		)
		(min_thickness 0.25)
		(keepout
			(tracks allowed)
			(vias allowed)
			(pads allowed)
			(copperpour allowed)
			(footprints not_allowed)
		)
		(placement
			(enabled no)
			(sheetname "")
		)
		(fill
			(thermal_gap 0.5)
			(thermal_bridge_width 0.5)
			(island_removal_mode 0)
		)
		(polygon
			(pts
				(xy 195.699888 -82.350102) (xy 224.700084 -82.350102) (xy 224.700084 -109.000036) (xy 195.699888 -109.000036)
			)
		)
	)
	(zone
		(net "P5V_STBY_VIN")
		(layer "F.Cu")
		(hatch none 0.5)
		(connect_pads
			(clearance 0.5)
		)
		(min_thickness 0.25)
		(fill yes
			(thermal_gap 0.5)
			(thermal_bridge_width 0.5)
			(island_removal_mode 0)
		)
		(polygon
			(pts
				(xy 343.408 -108.458) (xy 341.884 -109.982) (xy 341.884 -110.744) (xy 342.011 -110.871) (xy 344.043 -110.871)
				(xy 344.932 -111.76) (xy 346.583 -111.76) (xy 346.964 -112.141) (xy 350.139 -112.141) (xy 350.393 -111.887)
				(xy 350.393 -108.712) (xy 350.139 -108.458)
			)
		)
		(polygon
			(pts
				(xy 346.6338 -110.744) (xy 346.3798 -110.744) (xy 346.3798 -110.998) (xy 346.6338 -110.998)
			)
		)
		(polygon
			(pts
				(xy 345.7702 -110.744) (xy 345.5162 -110.744) (xy 345.5162 -110.998) (xy 345.7702 -110.998)
			)
		)
		(polygon
			(pts
				(xy 345.9988 -109.347) (xy 345.7448 -109.347) (xy 345.7448 -109.601) (xy 345.9988 -109.601)
			)
		)
		(polygon
			(pts
				(xy 345.1352 -109.347) (xy 344.8812 -109.347) (xy 344.8812 -109.601) (xy 345.1352 -109.601)
			)
		)
	)
	(zone
		(layer "F.Cu")
		(hatch none 0.5)
		(connect_pads
			(clearance 0)
		)
		(min_thickness 0.25)
		(keepout
			(tracks allowed)
			(vias allowed)
			(pads allowed)
			(copperpour allowed)
			(footprints allowed)
		)
		(placement
			(enabled no)
			(sheetname "")
		)
		(fill
			(thermal_gap 0.5)
			(thermal_bridge_width 0.5)
			(island_removal_mode 0)
		)
		(polygon
			(pts
				(xy 286.004 -69.469) (xy 286.004 -67.183) (xy 288.417 -67.183) (xy 288.417 -69.469)
			)
		)
	)
	(zone
		(net "GND")
		(layer "F.Cu")
		(hatch none 0.5)
		(connect_pads
			(clearance 0.5)
		)
		(min_thickness 0.25)
		(fill yes
			(thermal_gap 0.5)
			(thermal_bridge_width 0.5)
			(island_removal_mode 0)
		)
		(polygon
			(pts
				(xy 83.801966 -52.578) (xy 83.293966 -53.086) (xy 83.293966 -60.452) (xy 83.420966 -60.579) (xy 84.690966 -60.579)
				(xy 84.817966 -60.452) (xy 84.817966 -59.944) (xy 86.595966 -58.166) (xy 86.595966 -52.705) (xy 86.468966 -52.578)
			)
		)
		(polygon
			(pts
				(xy 83.79079 -56.050688) (xy 83.53679 -56.050688) (xy 83.53679 -56.660288) (xy 83.79079 -56.660288)
			)
		)
		(polygon
			(pts
				(xy 83.79079 -55.161688) (xy 83.53679 -55.161688) (xy 83.53679 -55.771288) (xy 83.79079 -55.771288)
			)
		)
	)
	(zone
		(layer "F.Cu")
		(hatch none 0.5)
		(connect_pads
			(clearance 0)
		)
		(min_thickness 0.25)
		(keepout
			(tracks allowed)
			(vias allowed)
			(pads allowed)
			(copperpour allowed)
			(footprints not_allowed)
		)
		(placement
			(enabled no)
			(sheetname "")
		)
		(fill
			(thermal_gap 0.5)
			(thermal_bridge_width 0.5)
			(island_removal_mode 0)
		)
		(polygon
			(pts
				(arc
					(start 355.6 -246.000016)
					(mid 354.47299 -249.162282)
					(end 351.600008 -250.898914)
				)
				(xy 351.600008 -109.000036) (xy 355.6 -109.000036)
			)
		)
	)
	(zone
		(layer "F.Cu")
		(hatch none 0.5)
		(connect_pads
			(clearance 0)
		)
		(min_thickness 0.25)
		(keepout
			(tracks allowed)
			(vias allowed)
			(pads allowed)
			(copperpour allowed)
			(footprints allowed)
		)
		(placement
			(enabled no)
			(sheetname "")
		)
		(fill
			(thermal_gap 0.5)
			(thermal_bridge_width 0.5)
			(island_removal_mode 0)
		)
		(polygon
			(pts
				(xy 279.908 -69.469) (xy 279.908 -67.056) (xy 282.956 -67.056) (xy 282.956 -69.469)
			)
		)
	)
	(zone
		(layer "F.Cu")
		(hatch none 0.5)
		(connect_pads
			(clearance 0)
		)
		(min_thickness 0.25)
		(keepout
			(tracks not_allowed)
			(vias allowed)
			(pads allowed)
			(copperpour not_allowed)
			(footprints allowed)
		)
		(placement
			(enabled no)
			(sheetname "")
		)
		(fill
			(thermal_gap 0.5)
			(thermal_bridge_width 0.5)
			(island_removal_mode 0)
		)
		(polygon
			(pts
				(arc
					(start 134.11454 -89.654126)
					(mid 133.731 -89.270586)
					(end 133.34746 -89.654126)
				)
				(xy 133.34746 -89.87155)
				(arc
					(start 133.407912 -89.87155)
					(mid 133.422492 -89.86865)
					(end 133.434836 -89.860374)
				)
				(arc
					(start 133.484366 -89.810844)
					(mid 133.937626 -89.4475)
					(end 133.574282 -89.90076)
				)
				(xy 133.524752 -89.95029) (xy 133.50621 -89.968832)
				(arc
					(start 133.5024 -89.968832)
					(mid 133.4711 -89.985946)
					(end 133.436868 -89.99601)
				)
				(xy 133.434328 -89.99855) (xy 133.34746 -89.99855) (xy 133.34746 -90.21445) (xy 133.434074 -90.21445)
				(arc
					(start 133.436614 -90.21699)
					(mid 133.470871 -90.226994)
					(end 133.502146 -90.244168)
				)
				(xy 133.505956 -90.244168) (xy 133.524498 -90.26271)
				(arc
					(start 133.574282 -90.312494)
					(mid 133.937626 -90.765754)
					(end 133.484366 -90.40241)
				)
				(arc
					(start 133.434582 -90.352626)
					(mid 133.422229 -90.344372)
					(end 133.407658 -90.34145)
				)
				(xy 133.34746 -90.34145)
				(arc
					(start 133.34746 -90.558874)
					(mid 133.730873 -90.942668)
					(end 134.11454 -90.559128)
				)
			)
		)
	)
	(zone
		(net "P3V3_STBY")
		(layer "F.Cu")
		(hatch none 0.5)
		(connect_pads
			(clearance 0.5)
		)
		(min_thickness 0.25)
		(fill yes
			(thermal_gap 0.5)
			(thermal_bridge_width 0.5)
			(island_removal_mode 0)
		)
		(polygon
			(pts
				(xy 290.449 -148.209) (xy 290.195 -148.463) (xy 290.195 -152.273) (xy 290.83 -152.908) (xy 291.592 -152.908)
				(xy 292.1 -153.416) (xy 292.1 -153.924) (xy 292.227 -154.051) (xy 295.529 -154.051) (xy 295.656 -153.924)
				(xy 295.656 -148.463) (xy 295.402 -148.209)
			)
		)
		(polygon
			(pts
				(xy 293.3446 -153.035) (xy 293.0906 -153.035) (xy 293.0906 -153.289) (xy 293.3446 -153.289)
			)
		)
		(polygon
			(pts
				(xy 291.0078 -151.7904) (xy 290.7538 -151.7904) (xy 290.7538 -152.0444) (xy 291.0078 -152.0444)
			)
		)
		(polygon
			(pts
				(xy 291.0078 -151.2316) (xy 290.7538 -151.2316) (xy 290.7538 -151.4856) (xy 291.0078 -151.4856)
			)
		)
		(polygon
			(pts
				(xy 292.489636 -148.709888) (xy 292.235636 -148.709888) (xy 292.235636 -148.963888) (xy 292.489636 -148.963888)
			)
		)
		(polygon
			(pts
				(xy 291.930836 -148.709888) (xy 291.676836 -148.709888) (xy 291.676836 -148.963888) (xy 291.930836 -148.963888)
			)
		)
	)
	(zone
		(net "P1V53_STBY")
		(layer "F.Cu")
		(hatch none 0.5)
		(connect_pads
			(clearance 0.5)
		)
		(min_thickness 0.25)
		(fill yes
			(thermal_gap 0.5)
			(thermal_bridge_width 0.5)
			(island_removal_mode 0)
		)
		(polygon
			(pts
				(xy 298.958 -206.756) (xy 298.069 -207.645) (xy 298.069 -209.931) (xy 298.577 -210.439) (xy 300.736 -210.439)
				(xy 300.863 -210.312) (xy 300.863 -207.264) (xy 300.355 -206.756)
			)
		)
	)
	(zone
		(layer "F.Cu")
		(hatch none 0.5)
		(connect_pads
			(clearance 0)
		)
		(min_thickness 0.25)
		(keepout
			(tracks allowed)
			(vias allowed)
			(pads allowed)
			(copperpour allowed)
			(footprints allowed)
		)
		(placement
			(enabled no)
			(sheetname "")
		)
		(fill
			(thermal_gap 0.5)
			(thermal_bridge_width 0.5)
			(island_removal_mode 0)
		)
		(polygon
			(pts
				(xy 137.414 -62.738) (xy 137.414 -61.595) (xy 138.176 -61.595) (xy 138.176 -62.738)
			)
		)
	)
	(zone
		(net "P1V8_C")
		(layer "F.Cu")
		(hatch none 0.5)
		(connect_pads
			(clearance 0.5)
		)
		(min_thickness 0.25)
		(fill yes
			(thermal_gap 0.5)
			(thermal_bridge_width 0.5)
			(island_removal_mode 0)
		)
		(polygon
			(pts
				(xy 89.389966 -63.246) (xy 89.008966 -63.627) (xy 89.008966 -68.834) (xy 89.262966 -69.088) (xy 96.882966 -69.088)
				(xy 97.263966 -68.707) (xy 97.263966 -63.5) (xy 97.009966 -63.246)
			)
		)
		(polygon
			(pts
				(xy 96.679766 -68.453) (xy 96.425766 -68.453) (xy 96.425766 -68.707) (xy 96.679766 -68.707)
			)
		)
		(polygon
			(pts
				(xy 96.070166 -68.453) (xy 95.816166 -68.453) (xy 95.816166 -68.707) (xy 96.070166 -68.707)
			)
		)
		(polygon
			(pts
				(xy 95.6818 -68.453) (xy 95.4278 -68.453) (xy 95.4278 -68.707) (xy 95.6818 -68.707)
			)
		)
		(polygon
			(pts
				(xy 95.0722 -68.453) (xy 94.8182 -68.453) (xy 94.8182 -68.707) (xy 95.0722 -68.707)
			)
		)
		(polygon
			(pts
				(xy 94.647766 -68.453) (xy 94.393766 -68.453) (xy 94.393766 -68.707) (xy 94.647766 -68.707)
			)
		)
		(polygon
			(pts
				(xy 94.038166 -68.453) (xy 93.784166 -68.453) (xy 93.784166 -68.707) (xy 94.038166 -68.707)
			)
		)
		(polygon
			(pts
				(xy 92.361766 -68.453) (xy 92.107766 -68.453) (xy 92.107766 -68.707) (xy 92.361766 -68.707)
			)
		)
		(polygon
			(pts
				(xy 91.752166 -68.453) (xy 91.498166 -68.453) (xy 91.498166 -68.707) (xy 91.752166 -68.707)
			)
		)
		(polygon
			(pts
				(xy 90.075766 -68.453) (xy 89.821766 -68.453) (xy 89.821766 -68.707) (xy 90.075766 -68.707)
			)
		)
		(polygon
			(pts
				(xy 89.466166 -68.453) (xy 89.212166 -68.453) (xy 89.212166 -68.707) (xy 89.466166 -68.707)
			)
		)
		(polygon
			(pts
				(xy 96.908366 -63.7032) (xy 96.654366 -63.7032) (xy 96.654366 -63.9572) (xy 96.908366 -63.9572)
			)
		)
		(polygon
			(pts
				(xy 96.349566 -63.7032) (xy 96.095566 -63.7032) (xy 96.095566 -63.9572) (xy 96.349566 -63.9572)
			)
		)
		(polygon
			(pts
				(xy 95.765366 -63.7032) (xy 95.511366 -63.7032) (xy 95.511366 -63.9572) (xy 95.765366 -63.9572)
			)
		)
		(polygon
			(pts
				(xy 95.206566 -63.7032) (xy 94.952566 -63.7032) (xy 94.952566 -63.9572) (xy 95.206566 -63.9572)
			)
		)
		(polygon
			(pts
				(xy 94.622366 -63.7032) (xy 94.368366 -63.7032) (xy 94.368366 -63.9572) (xy 94.622366 -63.9572)
			)
		)
		(polygon
			(pts
				(xy 94.063566 -63.7032) (xy 93.809566 -63.7032) (xy 93.809566 -63.9572) (xy 94.063566 -63.9572)
			)
		)
		(polygon
			(pts
				(xy 93.479366 -63.7032) (xy 93.225366 -63.7032) (xy 93.225366 -63.9572) (xy 93.479366 -63.9572)
			)
		)
		(polygon
			(pts
				(xy 92.920566 -63.7032) (xy 92.666566 -63.7032) (xy 92.666566 -63.9572) (xy 92.920566 -63.9572)
			)
		)
		(polygon
			(pts
				(xy 92.336366 -63.7032) (xy 92.082366 -63.7032) (xy 92.082366 -63.9572) (xy 92.336366 -63.9572)
			)
		)
		(polygon
			(pts
				(xy 91.777566 -63.7032) (xy 91.523566 -63.7032) (xy 91.523566 -63.9572) (xy 91.777566 -63.9572)
			)
		)
		(polygon
			(pts
				(xy 91.193366 -63.7032) (xy 90.939366 -63.7032) (xy 90.939366 -63.9572) (xy 91.193366 -63.9572)
			)
		)
		(polygon
			(pts
				(xy 90.634566 -63.7032) (xy 90.380566 -63.7032) (xy 90.380566 -63.9572) (xy 90.634566 -63.9572)
			)
		)
		(polygon
			(pts
				(xy 90.050366 -63.7032) (xy 89.796366 -63.7032) (xy 89.796366 -63.9572) (xy 90.050366 -63.9572)
			)
		)
		(polygon
			(pts
				(xy 89.491566 -63.7032) (xy 89.237566 -63.7032) (xy 89.237566 -63.9572) (xy 89.491566 -63.9572)
			)
		)
	)
	(zone
		(layer "F.Cu")
		(hatch none 0.5)
		(connect_pads
			(clearance 0)
		)
		(min_thickness 0.25)
		(keepout
			(tracks not_allowed)
			(vias allowed)
			(pads allowed)
			(copperpour not_allowed)
			(footprints allowed)
		)
		(placement
			(enabled no)
			(sheetname "")
		)
		(fill
			(thermal_gap 0.5)
			(thermal_bridge_width 0.5)
			(island_removal_mode 0)
		)
		(polygon
			(pts
				(arc
					(start 132.59054 -91.170252)
					(mid 132.207127 -90.786458)
					(end 131.82346 -91.169998)
				)
				(xy 131.82346 -91.2495)
				(arc
					(start 131.861814 -91.2495)
					(mid 131.893267 -91.248371)
					(end 131.924552 -91.244928)
				)
				(arc
					(start 131.924552 -91.244928)
					(mid 132.464424 -91.031918)
					(end 131.987036 -91.362022)
				)
				(arc
					(start 131.987036 -91.362022)
					(mid 131.938195 -91.371087)
					(end 131.888738 -91.375738)
				)
				(xy 131.88823 -91.3765) (xy 131.82346 -91.3765) (xy 131.82346 -91.8845) (xy 131.926838 -91.8845)
				(arc
					(start 131.927346 -91.885262)
					(mid 131.953836 -91.887356)
					(end 131.980178 -91.89085)
				)
				(arc
					(start 131.980178 -91.89085)
					(mid 132.470123 -92.201987)
					(end 131.921758 -92.012008)
				)
				(xy 131.900422 -92.0115) (xy 131.82346 -92.0115)
				(arc
					(start 131.82346 -92.075)
					(mid 132.207 -92.45854)
					(end 132.59054 -92.075)
				)
			)
		)
	)
	(zone
		(net "GND")
		(layer "F.Cu")
		(hatch none 0.5)
		(connect_pads
			(clearance 0.5)
		)
		(min_thickness 0.25)
		(fill yes
			(thermal_gap 0.5)
			(thermal_bridge_width 0.5)
			(island_removal_mode 0)
		)
		(polygon
			(pts
				(xy 195.199 -113.03) (xy 195.072 -113.157) (xy 195.072 -114.554) (xy 195.199 -114.681) (xy 196.977 -114.681)
				(xy 197.104 -114.554) (xy 198.755 -114.554) (xy 198.882 -114.681) (xy 198.882 -115.316) (xy 199.009 -115.443)
				(xy 200.66 -115.443) (xy 200.787 -115.316) (xy 200.787 -113.792) (xy 200.66 -113.665) (xy 198.882 -113.665)
				(xy 198.247 -113.03)
			)
		)
	)
	(zone
		(layer "F.Cu")
		(hatch none 0.5)
		(connect_pads
			(clearance 0)
		)
		(min_thickness 0.25)
		(keepout
			(tracks not_allowed)
			(vias allowed)
			(pads allowed)
			(copperpour not_allowed)
			(footprints allowed)
		)
		(placement
			(enabled no)
			(sheetname "")
		)
		(fill
			(thermal_gap 0.5)
			(thermal_bridge_width 0.5)
			(island_removal_mode 0)
		)
		(polygon
			(pts
				(arc
					(start 318.243204 -79.19466)
					(mid 318.590302 -79.657191)
					(end 318.126618 -79.3115)
				)
				(xy 317.97879 -79.163926) (xy 317.971932 -79.440786) (xy 317.972186 -79.44104)
				(arc
					(start 317.974218 -79.44104)
					(mid 318.372998 -79.86014)
					(end 318.792098 -79.46136)
				)
				(xy 318.794384 -79.46136) (xy 318.819784 -78.44536)
				(arc
					(start 318.817498 -78.44536)
					(mid 318.418718 -78.02626)
					(end 317.999618 -78.42504)
				)
				(xy 317.997332 -78.42504)
				(arc
					(start 317.993522 -78.579472)
					(mid 318.06477 -78.560352)
					(end 318.133476 -78.533498)
				)
				(arc
					(start 318.133476 -78.533498)
					(mid 318.643796 -78.262008)
					(end 318.233044 -78.668626)
				)
				(arc
					(start 318.233044 -78.668626)
					(mid 318.114198 -78.71781)
					(end 317.989204 -78.748128)
				)
				(arc
					(start 317.98387 -78.964282)
					(mid 318.018272 -78.982416)
					(end 318.050164 -79.004668)
				)
				(xy 318.053212 -79.004668) (xy 318.076834 -79.02829) (xy 318.077342 -79.028798)
			)
		)
	)
	(zone
		(layer "F.Cu")
		(hatch none 0.5)
		(connect_pads
			(clearance 0)
		)
		(min_thickness 0.25)
		(keepout
			(tracks allowed)
			(vias allowed)
			(pads allowed)
			(copperpour allowed)
			(footprints allowed)
		)
		(placement
			(enabled no)
			(sheetname "")
		)
		(fill
			(thermal_gap 0.5)
			(thermal_bridge_width 0.5)
			(island_removal_mode 0)
		)
		(polygon
			(pts
				(xy 340.233 -155.956) (xy 340.233 -153.416) (xy 344.043 -153.416) (xy 344.043 -155.956)
			)
		)
	)
	(zone
		(net "GND")
		(layer "F.Cu")
		(hatch none 0.5)
		(connect_pads
			(clearance 0.5)
		)
		(min_thickness 0.25)
		(fill yes
			(thermal_gap 0.5)
			(thermal_bridge_width 0.5)
			(island_removal_mode 0)
		)
		(polygon
			(pts
				(xy 169.544746 -0.762254) (xy 169.037 -1.27) (xy 169.037 -5.08) (xy 173.355 -9.398) (xy 173.355 -11.938)
				(xy 174.371 -12.954) (xy 183.261 -12.954) (xy 183.515 -13.208) (xy 183.515 -13.843) (xy 183.769 -14.097)
				(xy 185.3438 -14.097) (xy 185.674 -13.7668) (xy 188.0616 -13.7668) (xy 188.722 -14.4272) (xy 190.6778 -14.4272)
				(xy 192.913 -12.192) (xy 194.945 -12.192) (xy 199.39 -16.637) (xy 199.39 -24.511) (xy 207.01 -32.131)
				(xy 210.693 -32.131) (xy 217.043 -25.781) (xy 217.043 -17.399) (xy 222.25 -12.192) (xy 235.966 -12.192)
				(xy 236.093 -12.319) (xy 236.093 -13.335) (xy 236.347 -13.589) (xy 238.125 -13.589) (xy 239.268 -12.446)
				(xy 242.189 -12.446) (xy 242.57 -12.827) (xy 242.57 -43.688) (xy 248.793 -49.911) (xy 258.953 -49.911)
				(xy 259.334 -49.53) (xy 259.334 -46.609) (xy 256.921 -44.196) (xy 256.921 -25.654) (xy 251.587 -20.32)
				(xy 251.587 -15.113) (xy 261.366 -5.334) (xy 280.162 -5.334) (xy 280.67 -5.842) (xy 280.67 -12.7)
				(xy 278.384 -14.986) (xy 278.384 -17.78) (xy 277.495 -18.669) (xy 277.495 -54.229) (xy 277.876 -54.61)
				(xy 281.051 -54.61) (xy 281.686 -53.975) (xy 281.686 -1.27) (xy 281.178254 -0.762254)
			)
		)
		(polygon
			(pts
				(xy 251.55144 -49.150778) (xy 251.29744 -49.150778) (xy 251.29744 -49.404778) (xy 251.55144 -49.404778)
			)
		)
		(polygon
			(pts
				(xy 250.94184 -49.150778) (xy 250.68784 -49.150778) (xy 250.68784 -49.404778) (xy 250.94184 -49.404778)
			)
		)
		(polygon
			(pts
				(xy 250.43384 -49.150778) (xy 250.17984 -49.150778) (xy 250.17984 -49.404778) (xy 250.43384 -49.404778)
			)
		)
		(polygon
			(pts
				(xy 249.82424 -49.150778) (xy 249.57024 -49.150778) (xy 249.57024 -49.404778) (xy 249.82424 -49.404778)
			)
		)
		(polygon
			(pts
				(xy 279.273 -17.1958) (xy 279.019 -17.1958) (xy 279.019 -17.4498) (xy 279.273 -17.4498)
			)
		)
		(polygon
			(pts
				(xy 279.273 -16.3322) (xy 279.019 -16.3322) (xy 279.019 -16.5862) (xy 279.273 -16.5862)
			)
		)
		(polygon
			(pts
				(xy 279.273 -15.7988) (xy 279.019 -15.7988) (xy 279.019 -16.0528) (xy 279.273 -16.0528)
			)
		)
		(polygon
			(pts
				(xy 279.273 -14.9352) (xy 279.019 -14.9352) (xy 279.019 -15.1892) (xy 279.273 -15.1892)
			)
		)
		(polygon
			(pts
				(xy 184.437528 -13.313664) (xy 184.183528 -13.313664) (xy 184.183528 -13.567664) (xy 184.437528 -13.567664)
			)
		)
		(polygon
			(pts
				(xy 236.855 -12.6492) (xy 236.601 -12.6492) (xy 236.601 -12.9032) (xy 236.855 -12.9032)
			)
		)
	)
	(zone
		(net "TPS74801_P1V26_STBY_IN")
		(layer "F.Cu")
		(hatch none 0.5)
		(connect_pads
			(clearance 0.5)
		)
		(min_thickness 0.25)
		(fill yes
			(thermal_gap 0.5)
			(thermal_bridge_width 0.5)
			(island_removal_mode 0)
		)
		(polygon
			(pts
				(xy 265.049 -225.806) (xy 264.287 -226.568) (xy 262.763 -226.568) (xy 262.763 -235.204) (xy 263.017 -235.458)
				(xy 266.065 -235.458) (xy 266.319 -235.204) (xy 266.319 -229.489) (xy 266.7 -229.108) (xy 266.7 -226.314)
				(xy 266.192 -225.806)
			)
		)
		(polygon
			(pts
				(xy 266.119864 -229.023672) (xy 265.865864 -229.023672) (xy 265.865864 -229.277672) (xy 266.119864 -229.277672)
			)
		)
		(polygon
			(pts
				(xy 266.119864 -228.414072) (xy 265.865864 -228.414072) (xy 265.865864 -228.668072) (xy 266.119864 -228.668072)
			)
		)
	)
	(zone
		(layer "F.Cu")
		(hatch none 0.5)
		(connect_pads
			(clearance 0)
		)
		(min_thickness 0.25)
		(keepout
			(tracks allowed)
			(vias allowed)
			(pads allowed)
			(copperpour allowed)
			(footprints allowed)
		)
		(placement
			(enabled no)
			(sheetname "")
		)
		(fill
			(thermal_gap 0.5)
			(thermal_bridge_width 0.5)
			(island_removal_mode 0)
		)
		(polygon
			(pts
				(xy 167.894 -120.015) (xy 167.894 -118.237) (xy 170.434 -118.237) (xy 170.434 -120.015)
			)
		)
	)
	(zone
		(layer "F.Cu")
		(hatch none 0.5)
		(connect_pads
			(clearance 0)
		)
		(min_thickness 0.25)
		(keepout
			(tracks not_allowed)
			(vias allowed)
			(pads allowed)
			(copperpour not_allowed)
			(footprints allowed)
		)
		(placement
			(enabled no)
			(sheetname "")
		)
		(fill
			(thermal_gap 0.5)
			(thermal_bridge_width 0.5)
			(island_removal_mode 0)
		)
		(polygon
			(pts
				(arc
					(start 48.803052 -84.16163)
					(mid 48.706927 -84.211906)
					(end 48.606456 -84.252816)
				)
				(arc
					(start 48.606456 -84.598256)
					(mid 48.706934 -84.63915)
					(end 48.803052 -84.689442)
				)
				(arc
					(start 48.803052 -84.689442)
					(mid 49.222055 -85.091521)
					(end 48.725074 -84.791042)
				)
				(arc
					(start 48.725074 -84.791042)
					(mid 48.666696 -84.760535)
					(end 48.606456 -84.733892)
				)
				(arc
					(start 48.606456 -84.913724)
					(mid 48.989869 -85.297518)
					(end 49.373536 -84.913978)
				)
				(arc
					(start 49.373536 -83.937094)
					(mid 48.989996 -83.553554)
					(end 48.606456 -83.937094)
				)
				(arc
					(start 48.606456 -84.11718)
					(mid 48.666697 -84.09054)
					(end 48.725074 -84.06003)
				)
				(arc
					(start 48.725074 -84.06003)
					(mid 49.222088 -83.759526)
					(end 48.803052 -84.16163)
				)
			)
		)
	)
	(zone
		(net "P3V3_STBY")
		(layer "F.Cu")
		(hatch none 0.5)
		(connect_pads
			(clearance 0.5)
		)
		(min_thickness 0.25)
		(fill yes
			(thermal_gap 0.5)
			(thermal_bridge_width 0.5)
			(island_removal_mode 0)
		)
		(polygon
			(pts
				(xy 98.044 -238.76) (xy 97.79 -239.014) (xy 97.79 -240.919) (xy 97.917 -241.046) (xy 99.441 -241.046)
				(xy 100.076 -240.411) (xy 100.076 -238.887) (xy 99.949 -238.76)
			)
		)
		(polygon
			(pts
				(xy 98.552 -239.8268) (xy 98.298 -239.8268) (xy 98.298 -240.3602) (xy 98.552 -240.3602)
			)
		)
		(polygon
			(pts
				(xy 98.552 -238.9632) (xy 98.298 -238.9632) (xy 98.298 -239.2172) (xy 98.552 -239.2172)
			)
		)
	)
	(zone
		(layer "F.Cu")
		(hatch none 0.5)
		(connect_pads
			(clearance 0)
		)
		(min_thickness 0.25)
		(keepout
			(tracks not_allowed)
			(vias allowed)
			(pads allowed)
			(copperpour not_allowed)
			(footprints allowed)
		)
		(placement
			(enabled no)
			(sheetname "")
		)
		(fill
			(thermal_gap 0.5)
			(thermal_bridge_width 0.5)
			(island_removal_mode 0)
		)
		(polygon
			(pts
				(arc
					(start 135.880094 -81.15046)
					(mid 135.4963 -81.533873)
					(end 135.87984 -81.91754)
				)
				(arc
					(start 136.091676 -81.91754)
					(mid 136.065932 -81.848723)
					(end 136.029446 -81.784952)
				)
				(arc
					(start 136.029446 -81.784952)
					(mid 135.678331 -81.322585)
					(end 136.12241 -81.69656)
				)
				(arc
					(start 136.12241 -81.69656)
					(mid 136.184082 -81.801783)
					(end 136.222486 -81.91754)
				)
				(arc
					(start 136.46531 -81.91754)
					(mid 136.503751 -81.8018)
					(end 136.565386 -81.69656)
				)
				(arc
					(start 136.565386 -81.69656)
					(mid 137.009464 -81.322586)
					(end 136.65835 -81.784952)
				)
				(arc
					(start 136.65835 -81.784952)
					(mid 136.6219 -81.84874)
					(end 136.59612 -81.91754)
				)
				(arc
					(start 136.807956 -81.91754)
					(mid 137.191496 -81.534)
					(end 136.807956 -81.15046)
				)
			)
		)
	)
	(zone
		(layer "F.Cu")
		(hatch none 0.5)
		(connect_pads
			(clearance 0)
		)
		(min_thickness 0.25)
		(keepout
			(tracks allowed)
			(vias allowed)
			(pads allowed)
			(copperpour allowed)
			(footprints allowed)
		)
		(placement
			(enabled no)
			(sheetname "")
		)
		(fill
			(thermal_gap 0.5)
			(thermal_bridge_width 0.5)
			(island_removal_mode 0)
		)
		(polygon
			(pts
				(xy 25.146 -203.581) (xy 25.146 -202.311) (xy 27.305 -202.311) (xy 27.305 -203.581)
			)
		)
	)
	(zone
		(net "GND")
		(layer "F.Cu")
		(hatch none 0.5)
		(connect_pads
			(clearance 0.5)
		)
		(min_thickness 0.25)
		(fill yes
			(thermal_gap 0.5)
			(thermal_bridge_width 0.5)
			(island_removal_mode 0)
		)
		(polygon
			(pts
				(xy 106.299 -0.889) (xy 105.918 -1.27) (xy 105.918 -3.556) (xy 106.299 -3.937) (xy 112.522 -3.937)
				(xy 113.665 -2.794) (xy 137.414 -2.794) (xy 143.891 -9.271) (xy 143.891 -15.494) (xy 145.669 -17.272)
				(xy 146.685 -17.272) (xy 146.812 -17.145) (xy 146.812 -15.24) (xy 147.193 -14.859) (xy 161.163 -14.859)
				(xy 165.1 -18.796) (xy 167.767 -18.796) (xy 168.402 -18.161) (xy 168.402 -10.668) (xy 167.513 -9.779)
				(xy 150.876 -9.779) (xy 148.082 -6.985) (xy 148.082 -2.54) (xy 146.431 -0.889)
			)
		)
		(polygon
			(pts
				(xy 146.304 -16.3322) (xy 146.05 -16.3322) (xy 146.05 -16.5862) (xy 146.304 -16.5862)
			)
		)
		(polygon
			(pts
				(xy 146.304 -15.9258) (xy 146.05 -15.9258) (xy 146.05 -16.1798) (xy 146.304 -16.1798)
			)
		)
		(polygon
			(pts
				(xy 146.304 -15.3162) (xy 146.05 -15.3162) (xy 146.05 -15.5702) (xy 146.304 -15.5702)
			)
		)
	)
	(zone
		(net "P5V_USB_BP1_F")
		(layer "F.Cu")
		(hatch none 0.5)
		(connect_pads
			(clearance 0.5)
		)
		(min_thickness 0.25)
		(fill yes
			(thermal_gap 0.5)
			(thermal_bridge_width 0.5)
			(island_removal_mode 0)
		)
		(polygon
			(pts
				(xy 255.397 -16.764) (xy 255.016 -17.145) (xy 255.016 -18.542) (xy 255.27 -18.796) (xy 256.54 -18.796)
				(xy 258.318 -20.574) (xy 259.461 -20.574) (xy 259.715 -20.32) (xy 259.715 -17.018) (xy 259.461 -16.764)
			)
		)
		(polygon
			(pts
				(xy 256.6797 -18.2245) (xy 256.4257 -18.2245) (xy 256.4257 -18.4785) (xy 256.6797 -18.4785)
			)
		)
		(polygon
			(pts
				(xy 255.5367 -18.2245) (xy 255.2827 -18.2245) (xy 255.2827 -18.4785) (xy 255.5367 -18.4785)
			)
		)
	)
	(zone
		(layer "F.Cu")
		(hatch none 0.5)
		(connect_pads
			(clearance 0)
		)
		(min_thickness 0.25)
		(keepout
			(tracks not_allowed)
			(vias allowed)
			(pads allowed)
			(copperpour not_allowed)
			(footprints allowed)
		)
		(placement
			(enabled no)
			(sheetname "")
		)
		(fill
			(thermal_gap 0.5)
			(thermal_bridge_width 0.5)
			(island_removal_mode 0)
		)
		(polygon
			(pts
				(xy 119.000016 -14.800072) (xy 119.000016 -25.80005) (xy 130.50012 -25.80005) (xy 130.50012 -14.800072)
			)
		)
	)
	(zone
		(layer "F.Cu")
		(hatch none 0.5)
		(connect_pads
			(clearance 0)
		)
		(min_thickness 0.25)
		(keepout
			(tracks not_allowed)
			(vias allowed)
			(pads allowed)
			(copperpour not_allowed)
			(footprints allowed)
		)
		(placement
			(enabled no)
			(sheetname "")
		)
		(fill
			(thermal_gap 0.5)
			(thermal_bridge_width 0.5)
			(island_removal_mode 0)
		)
		(polygon
			(pts
				(arc
					(start 318.080898 -72.009)
					(mid 317.671958 -71.60006)
					(end 317.263018 -72.009)
				)
				(arc
					(start 317.263018 -72.238362)
					(mid 317.344324 -72.202206)
					(end 317.415418 -72.1487)
				)
				(arc
					(start 317.415418 -72.1487)
					(mid 317.878512 -71.802446)
					(end 317.532258 -72.26554)
				)
				(xy 317.515748 -72.282304)
				(arc
					(start 317.51397 -72.282304)
					(mid 317.396585 -72.361691)
					(end 317.263018 -72.40905)
				)
				(arc
					(start 317.263018 -72.613012)
					(mid 317.384814 -72.657391)
					(end 317.492126 -72.730106)
				)
				(xy 317.493904 -72.730106)
				(arc
					(start 317.532258 -72.76846)
					(mid 317.878512 -73.231554)
					(end 317.415418 -72.8853)
				)
				(arc
					(start 317.401194 -72.871076)
					(mid 317.337031 -72.819912)
					(end 317.263018 -72.784462)
				)
				(arc
					(start 317.263018 -73.024746)
					(mid 317.671831 -73.43394)
					(end 318.080898 -73.025)
				)
			)
		)
	)
	(zone
		(net "P3V3")
		(layer "F.Cu")
		(hatch none 0.5)
		(connect_pads
			(clearance 0.5)
		)
		(min_thickness 0.25)
		(fill yes
			(thermal_gap 0.5)
			(thermal_bridge_width 0.5)
			(island_removal_mode 0)
		)
		(polygon
			(pts
				(xy 307.34 -54.61) (xy 304.7746 -57.1754) (xy 302.0314 -57.1754) (xy 301.879 -57.3278) (xy 301.879 -58.293)
				(xy 302.006 -58.42) (xy 302.895 -58.42) (xy 303.276 -58.801) (xy 305.689 -58.801) (xy 307.086 -57.404)
				(xy 309.626 -57.404) (xy 309.88 -57.15) (xy 309.88 -54.737) (xy 309.753 -54.61)
			)
		)
		(polygon
			(pts
				(xy 305.149758 -58.039) (xy 304.895758 -58.039) (xy 304.895758 -58.293) (xy 305.149758 -58.293)
			)
		)
		(polygon
			(pts
				(xy 304.540158 -58.039) (xy 304.286158 -58.039) (xy 304.286158 -58.293) (xy 304.540158 -58.293)
			)
		)
		(polygon
			(pts
				(xy 304.133758 -58.039) (xy 303.879758 -58.039) (xy 303.879758 -58.293) (xy 304.133758 -58.293)
			)
		)
		(polygon
			(pts
				(xy 303.524158 -58.039) (xy 303.270158 -58.039) (xy 303.270158 -58.293) (xy 303.524158 -58.293)
			)
		)
	)
	(zone
		(layer "F.Cu")
		(hatch none 0.5)
		(connect_pads
			(clearance 0)
		)
		(min_thickness 0.25)
		(keepout
			(tracks allowed)
			(vias allowed)
			(pads allowed)
			(copperpour allowed)
			(footprints allowed)
		)
		(placement
			(enabled no)
			(sheetname "")
		)
		(fill
			(thermal_gap 0.5)
			(thermal_bridge_width 0.5)
			(island_removal_mode 0)
		)
		(polygon
			(pts
				(xy 253.873 -131.191) (xy 253.873 -129.921) (xy 254.889 -129.921) (xy 254.889 -131.191)
			)
		)
	)
	(zone
		(layer "F.Cu")
		(hatch none 0.5)
		(connect_pads
			(clearance 0)
		)
		(min_thickness 0.25)
		(keepout
			(tracks not_allowed)
			(vias allowed)
			(pads allowed)
			(copperpour not_allowed)
			(footprints allowed)
		)
		(placement
			(enabled no)
			(sheetname "")
		)
		(fill
			(thermal_gap 0.5)
			(thermal_bridge_width 0.5)
			(island_removal_mode 0)
		)
		(polygon
			(pts
				(arc
					(start 318.715898 -81.407)
					(mid 318.306958 -80.99806)
					(end 317.898018 -81.407)
				)
				(arc
					(start 317.898018 -81.597246)
					(mid 317.973243 -81.570692)
					(end 318.043814 -81.533492)
				)
				(arc
					(start 318.043814 -81.533492)
					(mid 318.522865 -81.210457)
					(end 318.156336 -81.65719)
				)
				(arc
					(start 318.156336 -81.65719)
					(mid 318.032626 -81.724874)
					(end 317.898018 -81.766918)
				)
				(arc
					(start 317.898018 -81.980786)
					(mid 317.994256 -82.021338)
					(end 318.079882 -82.081116)
				)
				(xy 318.081406 -82.081116) (xy 318.105028 -82.104738) (xy 318.10579 -82.105246)
				(arc
					(start 318.167004 -82.16646)
					(mid 318.514102 -82.628991)
					(end 318.050418 -82.2833)
				)
				(arc
					(start 317.988442 -82.221578)
					(mid 317.94591 -82.18579)
					(end 317.898018 -82.15757)
				)
				(arc
					(start 317.898018 -82.422746)
					(mid 318.306831 -82.83194)
					(end 318.715898 -82.423)
				)
			)
		)
	)
	(zone
		(net "P1V5_E")
		(layer "F.Cu")
		(hatch none 0.5)
		(connect_pads
			(clearance 0.5)
		)
		(min_thickness 0.25)
		(fill yes
			(thermal_gap 0.5)
			(thermal_bridge_width 0.5)
			(island_removal_mode 0)
		)
		(polygon
			(pts
				(xy 203.2 -86.741) (xy 203.073 -86.868) (xy 203.073 -89.535) (xy 202.692 -89.916) (xy 199.39 -89.916)
				(xy 199.136 -90.17) (xy 199.136 -90.805) (xy 198.882 -91.059) (xy 198.882 -98.552) (xy 197.866 -99.568)
				(xy 197.866 -102.362) (xy 198.374 -102.87) (xy 203.835 -102.87) (xy 204.343 -102.362) (xy 204.343 -91.059)
				(xy 206.248 -89.154) (xy 206.248 -86.995) (xy 205.994 -86.741)
			)
		)
		(polygon
			(pts
				(xy 199.898 -90.4748) (xy 199.644 -90.4748) (xy 199.644 -90.7288) (xy 199.898 -90.7288)
			)
		)
		(polygon
			(pts
				(xy 206.0448 -87.63) (xy 205.7908 -87.63) (xy 205.7908 -87.884) (xy 206.0448 -87.884)
			)
		)
		(polygon
			(pts
				(xy 205.1812 -87.63) (xy 204.9272 -87.63) (xy 204.9272 -87.884) (xy 205.1812 -87.884)
			)
		)
	)
	(zone
		(layer "F.Cu")
		(hatch none 0.5)
		(connect_pads
			(clearance 0)
		)
		(min_thickness 0.25)
		(keepout
			(tracks allowed)
			(vias allowed)
			(pads allowed)
			(copperpour allowed)
			(footprints allowed)
		)
		(placement
			(enabled no)
			(sheetname "")
		)
		(fill
			(thermal_gap 0.5)
			(thermal_bridge_width 0.5)
			(island_removal_mode 0)
		)
		(polygon
			(pts
				(xy 261.366 -222.377) (xy 261.366 -220.345) (xy 262.509 -220.345) (xy 262.509 -222.377)
			)
		)
	)
	(zone
		(net "SYS_PLL_VDD")
		(layer "F.Cu")
		(hatch none 0.5)
		(connect_pads
			(clearance 0.5)
		)
		(min_thickness 0.25)
		(fill yes
			(thermal_gap 0.5)
			(thermal_bridge_width 0.5)
			(island_removal_mode 0)
		)
		(polygon
			(pts
				(xy 81.388966 -53.721) (xy 81.261966 -53.848) (xy 81.261966 -60.96) (xy 80.518 -61.703966) (xy 80.518 -62.484)
				(xy 80.645 -62.611) (xy 83.058 -62.611) (xy 83.185 -62.484) (xy 83.185 -61.105034) (xy 82.912966 -60.833)
				(xy 82.912966 -53.848) (xy 82.785966 -53.721)
			)
		)
		(polygon
			(pts
				(xy 81.17459 -61.867288) (xy 80.92059 -61.867288) (xy 80.92059 -62.121288) (xy 81.17459 -62.121288)
			)
		)
	)
	(zone
		(layer "F.Cu")
		(hatch none 0.5)
		(connect_pads
			(clearance 0)
		)
		(min_thickness 0.25)
		(keepout
			(tracks not_allowed)
			(vias allowed)
			(pads allowed)
			(copperpour not_allowed)
			(footprints allowed)
		)
		(placement
			(enabled no)
			(sheetname "")
		)
		(fill
			(thermal_gap 0.5)
			(thermal_bridge_width 0.5)
			(island_removal_mode 0)
		)
		(polygon
			(pts
				(arc
					(start 203.947522 -76.64196)
					(mid 203.563728 -77.025373)
					(end 203.947268 -77.40904)
				)
				(arc
					(start 204.929232 -77.40904)
					(mid 205.312772 -77.0255)
					(end 204.929232 -76.64196)
				)
				(arc
					(start 204.776578 -76.64196)
					(mid 204.800061 -76.697774)
					(end 204.827124 -76.751942)
				)
				(arc
					(start 204.827124 -76.751942)
					(mid 205.104719 -77.259126)
					(end 204.694028 -76.852272)
				)
				(arc
					(start 204.694028 -76.852272)
					(mid 204.642408 -76.749536)
					(end 204.601826 -76.64196)
				)
				(arc
					(start 204.291184 -76.64196)
					(mid 204.243486 -76.751802)
					(end 204.18552 -76.85659)
				)
				(arc
					(start 204.18552 -76.85659)
					(mid 203.766954 -77.255242)
					(end 204.05471 -76.753974)
				)
				(arc
					(start 204.05471 -76.753974)
					(mid 204.085287 -76.698805)
					(end 204.112622 -76.64196)
				)
			)
		)
	)
	(zone
		(layer "F.Cu")
		(hatch none 0.5)
		(connect_pads
			(clearance 0)
		)
		(min_thickness 0.25)
		(keepout
			(tracks allowed)
			(vias allowed)
			(pads allowed)
			(copperpour allowed)
			(footprints not_allowed)
		)
		(placement
			(enabled no)
			(sheetname "")
		)
		(fill
			(thermal_gap 0.5)
			(thermal_bridge_width 0.5)
			(island_removal_mode 0)
		)
		(polygon
			(pts
				(xy 130.50012 -14.800072) (xy 130.50012 -25.80005) (xy 119.000016 -25.80005) (xy 119.000016 -14.800072)
			)
		)
	)
	(zone
		(layer "F.Cu")
		(hatch none 0.5)
		(connect_pads
			(clearance 0)
		)
		(min_thickness 0.25)
		(keepout
			(tracks allowed)
			(vias allowed)
			(pads allowed)
			(copperpour allowed)
			(footprints allowed)
		)
		(placement
			(enabled no)
			(sheetname "")
		)
		(fill
			(thermal_gap 0.5)
			(thermal_bridge_width 0.5)
			(island_removal_mode 0)
		)
		(polygon
			(pts
				(xy 75.184 -133.985) (xy 75.184 -133.223) (xy 76.2 -133.223) (xy 76.2 -133.985)
			)
		)
	)
	(zone
		(layer "F.Cu")
		(hatch none 0.5)
		(connect_pads
			(clearance 0)
		)
		(min_thickness 0.25)
		(keepout
			(tracks allowed)
			(vias allowed)
			(pads allowed)
			(copperpour allowed)
			(footprints allowed)
		)
		(placement
			(enabled no)
			(sheetname "")
		)
		(fill
			(thermal_gap 0.5)
			(thermal_bridge_width 0.5)
			(island_removal_mode 0)
		)
		(polygon
			(pts
				(xy 79.375 -118.11) (xy 79.375 -116.205) (xy 80.899 -116.205) (xy 80.899 -118.11)
			)
		)
	)
	(zone
		(layer "F.Cu")
		(hatch none 0.5)
		(connect_pads
			(clearance 0)
		)
		(min_thickness 0.25)
		(keepout
			(tracks allowed)
			(vias allowed)
			(pads allowed)
			(copperpour allowed)
			(footprints allowed)
		)
		(placement
			(enabled no)
			(sheetname "")
		)
		(fill
			(thermal_gap 0.5)
			(thermal_bridge_width 0.5)
			(island_removal_mode 0)
		)
		(polygon
			(pts
				(xy 217.17 -88.646) (xy 217.17 -87.376) (xy 219.329 -87.376) (xy 219.329 -88.646)
			)
		)
	)
	(zone
		(layer "F.Cu")
		(hatch none 0.5)
		(connect_pads
			(clearance 0)
		)
		(min_thickness 0.25)
		(keepout
			(tracks allowed)
			(vias allowed)
			(pads allowed)
			(copperpour allowed)
			(footprints allowed)
		)
		(placement
			(enabled no)
			(sheetname "")
		)
		(fill
			(thermal_gap 0.5)
			(thermal_bridge_width 0.5)
			(island_removal_mode 0)
		)
		(polygon
			(pts
				(xy 85.725 -26.289) (xy 85.725 -25.4) (xy 86.995 -25.4) (xy 86.995 -26.289)
			)
		)
	)
	(zone
		(layer "F.Cu")
		(hatch none 0.5)
		(connect_pads
			(clearance 0)
		)
		(min_thickness 0.25)
		(keepout
			(tracks not_allowed)
			(vias allowed)
			(pads allowed)
			(copperpour not_allowed)
			(footprints allowed)
		)
		(placement
			(enabled no)
			(sheetname "")
		)
		(fill
			(thermal_gap 0.5)
			(thermal_bridge_width 0.5)
			(island_removal_mode 0)
		)
		(polygon
			(pts
				(xy 355.6 -64.600074) (xy 352.160078 -64.600074) (xy 352.160078 -60.600082) (xy 340.226396 -60.600082)
				(xy 340.226396 -31.999936) (xy 355.6 -31.999936)
			)
		)
	)
	(zone
		(layer "F.Cu")
		(hatch none 0.5)
		(connect_pads
			(clearance 0)
		)
		(min_thickness 0.25)
		(keepout
			(tracks allowed)
			(vias allowed)
			(pads allowed)
			(copperpour allowed)
			(footprints allowed)
		)
		(placement
			(enabled no)
			(sheetname "")
		)
		(fill
			(thermal_gap 0.5)
			(thermal_bridge_width 0.5)
			(island_removal_mode 0)
		)
		(polygon
			(pts
				(xy 331.724 -226.822) (xy 331.724 -225.679) (xy 333.121 -225.679) (xy 333.121 -226.822)
			)
		)
	)
	(zone
		(net "P12V_PCIE")
		(layer "F.Cu")
		(hatch none 0.5)
		(connect_pads
			(clearance 0.5)
		)
		(min_thickness 0.25)
		(fill yes
			(thermal_gap 0.5)
			(thermal_bridge_width 0.5)
			(island_removal_mode 0)
		)
		(polygon
			(pts
				(xy 270.764 -65.024) (xy 270.256 -65.532) (xy 270.256 -83.947) (xy 271.907 -85.598) (xy 271.907 -89.408)
				(xy 281.94 -99.441) (xy 281.94 -129.794) (xy 282.575 -130.429) (xy 294.259 -130.429) (xy 296.164 -128.524)
				(xy 296.164 -98.05416) (xy 289.36315 -91.25331) (xy 289.36315 -79.68615) (xy 275.717 -66.04) (xy 275.717 -65.786)
				(xy 274.955 -65.024)
			)
		)
	)
	(zone
		(net "P1V26_STBY")
		(layer "F.Cu")
		(hatch none 0.5)
		(connect_pads
			(clearance 0.5)
		)
		(min_thickness 0.25)
		(fill yes
			(thermal_gap 0.5)
			(thermal_bridge_width 0.5)
			(island_removal_mode 0)
		)
		(polygon
			(pts
				(xy 262.128 -208.534) (xy 261.874 -208.788) (xy 261.874 -211.709) (xy 262.128 -211.963) (xy 268.097 -211.963)
				(xy 268.224 -211.836) (xy 268.224 -208.661) (xy 268.097 -208.534)
			)
		)
	)
	(zone
		(layer "F.Cu")
		(hatch none 0.5)
		(connect_pads
			(clearance 0)
		)
		(min_thickness 0.25)
		(keepout
			(tracks allowed)
			(vias allowed)
			(pads allowed)
			(copperpour allowed)
			(footprints allowed)
		)
		(placement
			(enabled no)
			(sheetname "")
		)
		(fill
			(thermal_gap 0.5)
			(thermal_bridge_width 0.5)
			(island_removal_mode 0)
		)
		(polygon
			(pts
				(xy 141.859 -62.611) (xy 141.859 -61.595) (xy 142.621 -61.595) (xy 142.621 -62.611)
			)
		)
	)
	(zone
		(net "GND")
		(layer "F.Cu")
		(hatch none 0.5)
		(connect_pads
			(clearance 0.5)
		)
		(min_thickness 0.25)
		(fill yes
			(thermal_gap 0.5)
			(thermal_bridge_width 0.5)
			(island_removal_mode 0)
		)
		(polygon
			(pts
				(xy 138.303 -94.234) (xy 137.922 -94.615) (xy 137.922 -118.999) (xy 138.43 -119.507) (xy 144.272 -119.507)
				(xy 144.653 -119.126) (xy 144.653 -112.776) (xy 144.145 -112.268) (xy 144.145 -95.25) (xy 144.018 -95.123)
				(xy 141.224 -95.123) (xy 140.335 -94.234)
			)
		)
	)
	(zone
		(layer "F.Cu")
		(hatch none 0.5)
		(connect_pads
			(clearance 0)
		)
		(min_thickness 0.25)
		(keepout
			(tracks not_allowed)
			(vias allowed)
			(pads allowed)
			(copperpour not_allowed)
			(footprints allowed)
		)
		(placement
			(enabled no)
			(sheetname "")
		)
		(fill
			(thermal_gap 0.5)
			(thermal_bridge_width 0.5)
			(island_removal_mode 0)
		)
		(polygon
			(pts
				(arc
					(start 41.693592 -83.106006)
					(mid 41.309798 -83.489419)
					(end 41.693338 -83.873086)
				)
				(arc
					(start 42.670222 -83.873086)
					(mid 43.053762 -83.489546)
					(end 42.670222 -83.106006)
				)
				(arc
					(start 42.45229 -83.106006)
					(mid 42.479386 -83.175905)
					(end 42.518076 -83.240118)
				)
				(arc
					(start 42.518076 -83.240118)
					(mid 42.873274 -83.699624)
					(end 42.426128 -83.329018)
				)
				(arc
					(start 42.426128 -83.329018)
					(mid 42.361298 -83.223334)
					(end 42.321226 -83.106006)
				)
				(arc
					(start 42.076116 -83.106006)
					(mid 42.035242 -83.20933)
					(end 41.971468 -83.300316)
				)
				(xy 41.971468 -83.301586)
				(arc
					(start 41.939972 -83.333082)
					(mid 41.486608 -83.695876)
					(end 41.85031 -83.243166)
				)
				(arc
					(start 41.86301 -83.230212)
					(mid 41.90954 -83.172382)
					(end 41.942766 -83.106006)
				)
			)
		)
	)
	(zone
		(net "P3V3_STBY")
		(layer "F.Cu")
		(hatch none 0.5)
		(connect_pads
			(clearance 0.5)
		)
		(min_thickness 0.25)
		(fill yes
			(thermal_gap 0.5)
			(thermal_bridge_width 0.5)
			(island_removal_mode 0)
		)
		(polygon
			(pts
				(xy 217.424 -165.608) (xy 216.916 -166.116) (xy 216.916 -167.64) (xy 217.17 -167.894) (xy 218.567 -167.894)
				(xy 218.821 -167.64) (xy 218.821 -167.005) (xy 219.329 -166.497) (xy 219.329 -165.862) (xy 219.075 -165.608)
			)
		)
		(polygon
			(pts
				(xy 218.2368 -165.989) (xy 217.9828 -165.989) (xy 217.9828 -166.243) (xy 218.2368 -166.243)
			)
		)
		(polygon
			(pts
				(xy 217.6272 -165.989) (xy 217.3732 -165.989) (xy 217.3732 -166.243) (xy 217.6272 -166.243)
			)
		)
	)
	(zone
		(layer "F.Cu")
		(hatch none 0.5)
		(connect_pads
			(clearance 0)
		)
		(min_thickness 0.25)
		(keepout
			(tracks not_allowed)
			(vias allowed)
			(pads allowed)
			(copperpour not_allowed)
			(footprints allowed)
		)
		(placement
			(enabled no)
			(sheetname "")
		)
		(fill
			(thermal_gap 0.5)
			(thermal_bridge_width 0.5)
			(island_removal_mode 0)
		)
		(polygon
			(pts
				(arc
					(start 39.975536 -82.070194)
					(mid 39.591996 -81.686654)
					(end 39.208456 -82.070194)
				)
				(xy 39.208456 -82.323686) (xy 39.248588 -82.323686)
				(arc
					(start 39.345362 -82.226912)
					(mid 39.798622 -81.863568)
					(end 39.435278 -82.316828)
				)
				(xy 39.338504 -82.413602) (xy 39.30142 -82.450686) (xy 39.248588 -82.450686) (xy 39.208456 -82.450686)
				(xy 39.208456 -82.666586) (xy 39.248588 -82.666586) (xy 39.30142 -82.666586) (xy 39.338504 -82.70367)
				(arc
					(start 39.435278 -82.800444)
					(mid 39.798622 -83.253704)
					(end 39.345362 -82.89036)
				)
				(xy 39.248588 -82.793586) (xy 39.208456 -82.793586)
				(arc
					(start 39.208456 -83.046824)
					(mid 39.591869 -83.430618)
					(end 39.975536 -83.047078)
				)
			)
		)
	)
	(zone
		(net "P5V_STBY")
		(layer "F.Cu")
		(hatch none 0.5)
		(connect_pads
			(clearance 0.5)
		)
		(min_thickness 0.25)
		(fill yes
			(thermal_gap 0.5)
			(thermal_bridge_width 0.5)
			(island_removal_mode 0)
		)
		(polygon
			(pts
				(xy 227.203 -16.383) (xy 226.949 -16.637) (xy 226.949 -24.511) (xy 227.203 -24.765) (xy 228.6 -24.765)
				(xy 228.854 -24.511) (xy 228.854 -16.637) (xy 228.6 -16.383)
			)
		)
	)
	(zone
		(net "P1V8_C")
		(layer "F.Cu")
		(hatch none 0.5)
		(connect_pads
			(clearance 0.5)
		)
		(min_thickness 0.25)
		(fill yes
			(thermal_gap 0.5)
			(thermal_bridge_width 0.5)
			(island_removal_mode 0)
		)
		(polygon
			(pts
				(xy 153.543 -52.578) (xy 153.289 -52.832) (xy 153.289 -60.96) (xy 152.654 -61.595) (xy 150.368 -61.595)
				(xy 150.241 -61.722) (xy 150.241 -62.611) (xy 150.368 -62.738) (xy 153.797 -62.738) (xy 154.813 -61.722)
				(xy 154.813 -52.832) (xy 154.559 -52.578)
			)
		)
		(polygon
			(pts
				(xy 151.4348 -62.103) (xy 151.1808 -62.103) (xy 151.1808 -62.357) (xy 151.4348 -62.357)
			)
		)
		(polygon
			(pts
				(xy 150.8252 -62.103) (xy 150.5712 -62.103) (xy 150.5712 -62.357) (xy 150.8252 -62.357)
			)
		)
	)
	(zone
		(net "P3V3_STBY")
		(layer "F.Cu")
		(hatch none 0.5)
		(connect_pads
			(clearance 0.5)
		)
		(min_thickness 0.25)
		(fill yes
			(thermal_gap 0.5)
			(thermal_bridge_width 0.5)
			(island_removal_mode 0)
		)
		(polygon
			(pts
				(xy 188.722 -170.688) (xy 187.452 -171.958) (xy 187.452 -192.405) (xy 186.69 -193.167) (xy 186.69 -194.31)
				(xy 186.817 -194.437) (xy 197.993 -194.437) (xy 198.755 -195.199) (xy 198.755 -196.977) (xy 198.882 -197.104)
				(xy 201.422 -197.104) (xy 201.549 -196.977) (xy 201.549 -195.961) (xy 201.041 -195.453) (xy 201.041 -193.167)
				(xy 200.787 -192.913) (xy 200.152 -192.913) (xy 192.405 -185.166) (xy 192.405 -176.149) (xy 192.913 -175.641)
				(xy 196.215 -175.641) (xy 196.342 -175.514) (xy 196.342 -171.323) (xy 195.707 -170.688)
			)
		)
		(polygon
			(pts
				(xy 200.8632 -196.342) (xy 200.6092 -196.342) (xy 200.6092 -196.596) (xy 200.8632 -196.596)
			)
		)
		(polygon
			(pts
				(xy 200.4568 -196.342) (xy 200.2028 -196.342) (xy 200.2028 -196.596) (xy 200.4568 -196.596)
			)
		)
		(polygon
			(pts
				(xy 199.8472 -196.342) (xy 199.5932 -196.342) (xy 199.5932 -196.596) (xy 199.8472 -196.596)
			)
		)
		(polygon
			(pts
				(xy 187.393072 -193.645536) (xy 187.139072 -193.645536) (xy 187.139072 -193.899536) (xy 187.393072 -193.899536)
			)
		)
		(polygon
			(pts
				(xy 190.627 -178.689) (xy 190.373 -178.689) (xy 190.373 -178.943) (xy 190.627 -178.943)
			)
		)
		(polygon
			(pts
				(xy 189.484 -178.689) (xy 189.23 -178.689) (xy 189.23 -178.943) (xy 189.484 -178.943)
			)
		)
		(polygon
			(pts
				(xy 190.627 -175.895) (xy 190.373 -175.895) (xy 190.373 -176.149) (xy 190.627 -176.149)
			)
		)
		(polygon
			(pts
				(xy 189.484 -175.895) (xy 189.23 -175.895) (xy 189.23 -176.149) (xy 189.484 -176.149)
			)
		)
	)
	(zone
		(layer "F.Cu")
		(hatch none 0.5)
		(connect_pads
			(clearance 0)
		)
		(min_thickness 0.25)
		(keepout
			(tracks allowed)
			(vias allowed)
			(pads allowed)
			(copperpour allowed)
			(footprints allowed)
		)
		(placement
			(enabled no)
			(sheetname "")
		)
		(fill
			(thermal_gap 0.5)
			(thermal_bridge_width 0.5)
			(island_removal_mode 0)
		)
		(polygon
			(pts
				(xy 75.184 -138.176) (xy 75.184 -137.414) (xy 76.581 -137.414) (xy 76.581 -138.176)
			)
		)
	)
	(zone
		(net "GND")
		(layer "F.Cu")
		(hatch none 0.5)
		(connect_pads
			(clearance 0.5)
		)
		(min_thickness 0.25)
		(fill yes
			(thermal_gap 0.5)
			(thermal_bridge_width 0.5)
			(island_removal_mode 0)
		)
		(polygon
			(pts
				(xy 74.93 -18.669) (xy 74.803 -18.796) (xy 74.803 -21.59) (xy 74.93 -21.717) (xy 76.962 -21.717)
				(xy 77.089 -21.59) (xy 77.089 -19.939) (xy 77.216 -19.812) (xy 77.851 -19.812) (xy 78.232 -19.431)
				(xy 78.232 -18.796) (xy 78.105 -18.669)
			)
		)
		(polygon
			(pts
				(xy 77.5208 -19.4056) (xy 77.2668 -19.4056) (xy 77.2668 -19.6596) (xy 77.5208 -19.6596)
			)
		)
		(polygon
			(pts
				(xy 77.1144 -19.4056) (xy 76.8604 -19.4056) (xy 76.8604 -19.6596) (xy 77.1144 -19.6596)
			)
		)
		(polygon
			(pts
				(xy 76.2508 -19.4056) (xy 75.9968 -19.4056) (xy 75.9968 -19.6596) (xy 76.2508 -19.6596)
			)
		)
	)
	(zone
		(layer "F.Cu")
		(hatch none 0.5)
		(connect_pads
			(clearance 0)
		)
		(min_thickness 0.25)
		(keepout
			(tracks not_allowed)
			(vias allowed)
			(pads allowed)
			(copperpour not_allowed)
			(footprints allowed)
		)
		(placement
			(enabled no)
			(sheetname "")
		)
		(fill
			(thermal_gap 0.5)
			(thermal_bridge_width 0.5)
			(island_removal_mode 0)
		)
		(polygon
			(pts
				(arc
					(start 84.413852 -37.734494)
					(mid 84.04606 -37.386514)
					(end 83.69808 -37.754306)
				)
				(xy 83.69554 -37.754306) (xy 83.723734 -38.770306) (xy 83.723988 -38.77056)
				(arc
					(start 83.726274 -38.77056)
					(mid 84.094066 -39.11854)
					(end 84.442046 -38.750748)
				)
				(xy 84.444586 -38.750748)
				(arc
					(start 84.438744 -38.541706)
					(mid 84.373813 -38.572287)
					(end 84.317586 -38.61689)
				)
				(arc
					(start 84.312252 -38.622224)
					(mid 83.896133 -38.949836)
					(end 84.222336 -38.532562)
				)
				(xy 84.246212 -38.508432)
				(arc
					(start 84.247482 -38.508432)
					(mid 84.335352 -38.448045)
					(end 84.435188 -38.410642)
				)
				(arc
					(start 84.427314 -38.13048)
					(mid 84.318159 -38.073668)
					(end 84.220812 -37.9984)
				)
				(xy 84.22005 -37.9984) (xy 84.201762 -37.979858) (xy 84.201508 -37.979858)
				(arc
					(start 84.194142 -37.972492)
					(mid 83.867394 -37.555828)
					(end 84.284058 -37.882576)
				)
				(arc
					(start 84.291424 -37.890196)
					(mid 84.353872 -37.944059)
					(end 84.423504 -37.98824)
				)
				(xy 84.416392 -37.734494)
			)
		)
	)
	(zone
		(net "P1V8_STBY")
		(layer "F.Cu")
		(hatch none 0.5)
		(connect_pads
			(clearance 0.5)
		)
		(min_thickness 0.25)
		(fill yes
			(thermal_gap 0.5)
			(thermal_bridge_width 0.5)
			(island_removal_mode 0)
		)
		(polygon
			(pts
				(xy 273.685 -107.696) (xy 273.431 -107.95) (xy 273.431 -110.49) (xy 273.685 -110.744) (xy 276.86 -110.744)
				(xy 277.114 -110.49) (xy 277.114 -107.95) (xy 276.86 -107.696)
			)
		)
	)
	(zone
		(layer "F.Cu")
		(hatch none 0.5)
		(connect_pads
			(clearance 0)
		)
		(min_thickness 0.25)
		(keepout
			(tracks allowed)
			(vias allowed)
			(pads allowed)
			(copperpour allowed)
			(footprints allowed)
		)
		(placement
			(enabled no)
			(sheetname "")
		)
		(fill
			(thermal_gap 0.5)
			(thermal_bridge_width 0.5)
			(island_removal_mode 0)
		)
		(polygon
			(pts
				(xy 24.638 -110.998) (xy 24.638 -115.697) (xy 24.638 -116.205) (xy 22.606 -116.205) (xy 22.606 -115.697)
				(xy 22.606 -110.998) (xy 22.606 -110.236) (xy 24.638 -110.236)
			)
		)
	)
	(zone
		(layer "F.Cu")
		(hatch none 0.5)
		(connect_pads
			(clearance 0)
		)
		(min_thickness 0.25)
		(keepout
			(tracks allowed)
			(vias allowed)
			(pads allowed)
			(copperpour allowed)
			(footprints not_allowed)
		)
		(placement
			(enabled no)
			(sheetname "")
		)
		(fill
			(thermal_gap 0.5)
			(thermal_bridge_width 0.5)
			(island_removal_mode 0)
		)
		(polygon
			(pts
				(arc
					(start 314.366402 -108.000038)
					(mid 307.299996 -104.500249)
					(end 314.366402 -101.000052)
				)
				(xy 326.69988 -101.000052) (xy 326.69988 -108.000038)
			)
		)
	)
	(zone
		(layer "F.Cu")
		(hatch none 0.5)
		(connect_pads
			(clearance 0)
		)
		(min_thickness 0.25)
		(keepout
			(tracks allowed)
			(vias allowed)
			(pads allowed)
			(copperpour allowed)
			(footprints allowed)
		)
		(placement
			(enabled no)
			(sheetname "")
		)
		(fill
			(thermal_gap 0.5)
			(thermal_bridge_width 0.5)
			(island_removal_mode 0)
		)
		(polygon
			(pts
				(xy 331.089 -172.339) (xy 331.089 -171.069) (xy 332.994 -171.069) (xy 332.994 -172.339)
			)
		)
	)
	(zone
		(net "P3V3_STBY")
		(layer "F.Cu")
		(hatch none 0.5)
		(connect_pads
			(clearance 0.5)
		)
		(min_thickness 0.25)
		(fill yes
			(thermal_gap 0.5)
			(thermal_bridge_width 0.5)
			(island_removal_mode 0)
		)
		(polygon
			(pts
				(xy 336.804 -84.074) (xy 336.55 -84.328) (xy 336.55 -85.471) (xy 336.042 -85.979) (xy 328.803 -85.979)
				(xy 328.041 -86.741) (xy 328.041 -102.235) (xy 328.168 -102.362) (xy 328.803 -102.362) (xy 329.565 -101.6)
				(xy 332.105 -101.6) (xy 332.359 -101.346) (xy 332.359 -97.917) (xy 331.597 -97.155) (xy 331.597 -89.789)
				(xy 332.105 -89.281) (xy 341.884 -89.281) (xy 342.9 -88.265) (xy 342.9 -84.963) (xy 342.011 -84.074)
			)
		)
		(polygon
			(pts
				(xy 330.962 -92.5068) (xy 330.708 -92.5068) (xy 330.708 -92.7608) (xy 330.962 -92.7608)
			)
		)
		(polygon
			(pts
				(xy 329.057 -92.5068) (xy 328.803 -92.5068) (xy 328.803 -92.7608) (xy 329.057 -92.7608)
			)
		)
		(polygon
			(pts
				(xy 330.962 -91.6432) (xy 330.708 -91.6432) (xy 330.708 -91.8972) (xy 330.962 -91.8972)
			)
		)
		(polygon
			(pts
				(xy 329.057 -91.6432) (xy 328.803 -91.6432) (xy 328.803 -91.8972) (xy 329.057 -91.8972)
			)
		)
		(polygon
			(pts
				(xy 337.4644 -84.5312) (xy 337.2104 -84.5312) (xy 337.2104 -84.7852) (xy 337.4644 -84.7852)
			)
		)
	)
	(zone
		(net "GND")
		(layer "F.Cu")
		(hatch none 0.5)
		(connect_pads
			(clearance 0.5)
		)
		(min_thickness 0.25)
		(fill yes
			(thermal_gap 0.5)
			(thermal_bridge_width 0.5)
			(island_removal_mode 0)
		)
		(polygon
			(pts
				(xy 79.502 -5.969) (xy 79.248 -6.223) (xy 79.248 -11.811) (xy 79.756 -12.319) (xy 79.756 -16.256)
				(xy 80.137 -16.637) (xy 80.137 -17.907) (xy 80.264 -18.034) (xy 82.55 -18.034) (xy 82.677 -17.907)
				(xy 82.677 -16.891) (xy 81.915 -16.129) (xy 81.915 -7.112) (xy 80.772 -5.969)
			)
		)
		(polygon
			(pts
				(xy 80.7466 -15.9766) (xy 80.4926 -15.9766) (xy 80.4926 -16.2306) (xy 80.7466 -16.2306)
			)
		)
		(polygon
			(pts
				(xy 80.7466 -15.113) (xy 80.4926 -15.113) (xy 80.4926 -15.367) (xy 80.7466 -15.367)
			)
		)
		(polygon
			(pts
				(xy 80.7466 -14.7066) (xy 80.4926 -14.7066) (xy 80.4926 -14.9606) (xy 80.7466 -14.9606)
			)
		)
		(polygon
			(pts
				(xy 80.7466 -13.843) (xy 80.4926 -13.843) (xy 80.4926 -14.097) (xy 80.7466 -14.097)
			)
		)
		(polygon
			(pts
				(xy 80.7466 -13.4366) (xy 80.4926 -13.4366) (xy 80.4926 -13.6906) (xy 80.7466 -13.6906)
			)
		)
		(polygon
			(pts
				(xy 80.7466 -12.573) (xy 80.4926 -12.573) (xy 80.4926 -12.827) (xy 80.7466 -12.827)
			)
		)
	)
	(zone
		(net "P1V8_STBY")
		(layer "F.Cu")
		(hatch none 0.5)
		(connect_pads
			(clearance 0.5)
		)
		(min_thickness 0.25)
		(fill yes
			(thermal_gap 0.5)
			(thermal_bridge_width 0.5)
			(island_removal_mode 0)
		)
		(polygon
			(pts
				(xy 222.631 -93.599) (xy 222.123 -94.107) (xy 222.123 -101.6) (xy 222.25 -101.727) (xy 224.663 -101.727)
				(xy 224.917 -101.473) (xy 224.917 -94.107) (xy 224.409 -93.599)
			)
		)
	)
	(zone
		(net "P0V9_E")
		(layer "F.Cu")
		(hatch none 0.5)
		(connect_pads
			(clearance 0.5)
		)
		(min_thickness 0.25)
		(fill yes
			(thermal_gap 0.5)
			(thermal_bridge_width 0.5)
			(island_removal_mode 0)
		)
		(polygon
			(pts
				(xy 161.036 -86.995) (xy 158.496 -89.535) (xy 158.496 -93.218) (xy 154.178 -93.218) (xy 152.4 -94.996)
				(xy 152.4 -115.189) (xy 151.7015 -115.8875) (xy 149.0345 -115.8875) (xy 144.145 -120.777) (xy 141.097 -120.777)
				(xy 130.81 -131.064) (xy 130.81 -139.954) (xy 131.318 -140.462) (xy 148.463 -140.462) (xy 160.02 -128.905)
				(xy 160.02 -113.792) (xy 158.242 -112.014) (xy 158.242 -104.013) (xy 158.62046 -103.63454) (xy 158.623 -103.63454)
				(xy 161.03854 -101.219) (xy 173.101 -101.219) (xy 173.863 -100.457) (xy 173.863 -96.139) (xy 172.974 -95.25)
				(xy 172.974 -87.63) (xy 172.339 -86.995)
			)
		)
		(polygon
			(pts
				(xy 153.517092 -114.888264) (xy 153.263092 -114.888264) (xy 153.263092 -115.142264) (xy 153.517092 -115.142264)
			)
		)
		(polygon
			(pts
				(xy 153.517092 -114.024664) (xy 153.263092 -114.024664) (xy 153.263092 -114.278664) (xy 153.517092 -114.278664)
			)
		)
		(polygon
			(pts
				(xy 153.517092 -113.618264) (xy 153.263092 -113.618264) (xy 153.263092 -113.872264) (xy 153.517092 -113.872264)
			)
		)
		(polygon
			(pts
				(xy 153.517092 -112.754664) (xy 153.263092 -112.754664) (xy 153.263092 -113.008664) (xy 153.517092 -113.008664)
			)
		)
		(polygon
			(pts
				(xy 153.517092 -112.348264) (xy 153.263092 -112.348264) (xy 153.263092 -112.602264) (xy 153.517092 -112.602264)
			)
		)
		(polygon
			(pts
				(xy 153.517092 -111.484664) (xy 153.263092 -111.484664) (xy 153.263092 -111.738664) (xy 153.517092 -111.738664)
			)
		)
		(polygon
			(pts
				(xy 153.517092 -111.078264) (xy 153.263092 -111.078264) (xy 153.263092 -111.332264) (xy 153.517092 -111.332264)
			)
		)
		(polygon
			(pts
				(xy 153.517092 -110.214664) (xy 153.263092 -110.214664) (xy 153.263092 -110.468664) (xy 153.517092 -110.468664)
			)
		)
		(polygon
			(pts
				(xy 153.517092 -109.808264) (xy 153.263092 -109.808264) (xy 153.263092 -110.062264) (xy 153.517092 -110.062264)
			)
		)
		(polygon
			(pts
				(xy 153.517092 -108.944664) (xy 153.263092 -108.944664) (xy 153.263092 -109.198664) (xy 153.517092 -109.198664)
			)
		)
		(polygon
			(pts
				(xy 153.517092 -108.538264) (xy 153.263092 -108.538264) (xy 153.263092 -108.792264) (xy 153.517092 -108.792264)
			)
		)
		(polygon
			(pts
				(xy 153.517092 -107.674664) (xy 153.263092 -107.674664) (xy 153.263092 -107.928664) (xy 153.517092 -107.928664)
			)
		)
	)
	(zone
		(layer "F.Cu")
		(hatch none 0.5)
		(connect_pads
			(clearance 0)
		)
		(min_thickness 0.25)
		(keepout
			(tracks allowed)
			(vias allowed)
			(pads allowed)
			(copperpour allowed)
			(footprints allowed)
		)
		(placement
			(enabled no)
			(sheetname "")
		)
		(fill
			(thermal_gap 0.5)
			(thermal_bridge_width 0.5)
			(island_removal_mode 0)
		)
		(polygon
			(pts
				(xy 279.654 -220.599) (xy 279.654 -219.456) (xy 281.305 -219.456) (xy 281.305 -220.599)
			)
		)
	)
	(zone
		(layer "F.Cu")
		(hatch none 0.5)
		(connect_pads
			(clearance 0)
		)
		(min_thickness 0.25)
		(keepout
			(tracks allowed)
			(vias allowed)
			(pads allowed)
			(copperpour allowed)
			(footprints allowed)
		)
		(placement
			(enabled no)
			(sheetname "")
		)
		(fill
			(thermal_gap 0.5)
			(thermal_bridge_width 0.5)
			(island_removal_mode 0)
		)
		(polygon
			(pts
				(xy 80.645 -23.114) (xy 80.645 -21.082) (xy 84.963 -21.082) (xy 84.963 -23.114)
			)
		)
	)
	(zone
		(net "PLLDDR_VDDA18")
		(layer "F.Cu")
		(hatch none 0.5)
		(connect_pads
			(clearance 0.5)
		)
		(min_thickness 0.25)
		(fill yes
			(thermal_gap 0.5)
			(thermal_bridge_width 0.5)
			(island_removal_mode 0)
		)
		(polygon
			(pts
				(xy 81.134966 -82.423) (xy 80.880966 -82.677) (xy 80.880966 -85.344) (xy 81.007966 -85.471) (xy 81.896966 -85.471)
				(xy 82.150966 -85.217) (xy 82.150966 -84.455) (xy 82.531966 -84.074) (xy 88.246966 -84.074) (xy 88.373966 -83.947)
				(xy 88.373966 -82.55) (xy 88.246966 -82.423)
			)
		)
		(polygon
			(pts
				(xy 81.465166 -84.5566) (xy 81.211166 -84.5566) (xy 81.211166 -84.8106) (xy 81.465166 -84.8106)
			)
		)
	)
	(zone
		(net "TPS74801_1V5_C_BIAS")
		(layer "F.Cu")
		(hatch none 0.5)
		(connect_pads
			(clearance 0.5)
		)
		(min_thickness 0.25)
		(fill yes
			(thermal_gap 0.5)
			(thermal_bridge_width 0.5)
			(island_removal_mode 0)
		)
		(polygon
			(pts
				(xy 217.17 -103.124) (xy 217.043 -103.251) (xy 217.043 -103.505) (xy 217.17 -103.632) (xy 218.186 -103.632)
				(xy 218.44 -103.886) (xy 218.44 -104.902) (xy 219.202 -105.664) (xy 220.98 -105.664) (xy 221.234 -105.41)
				(xy 221.234 -103.759) (xy 221.107 -103.632) (xy 220.472 -103.632) (xy 219.964 -103.124)
			)
		)
		(polygon
			(pts
				(xy 220.7768 -104.7496) (xy 220.5228 -104.7496) (xy 220.5228 -105.0036) (xy 220.7768 -105.0036)
			)
		)
		(polygon
			(pts
				(xy 220.726 -104.1908) (xy 220.472 -104.1908) (xy 220.472 -104.4448) (xy 220.726 -104.4448)
			)
		)
	)
	(zone
		(net "P1V8_C")
		(layer "F.Cu")
		(hatch none 0.5)
		(connect_pads
			(clearance 0.5)
		)
		(min_thickness 0.25)
		(fill yes
			(thermal_gap 0.5)
			(thermal_bridge_width 0.5)
			(island_removal_mode 0)
		)
		(polygon
			(pts
				(xy 69.0626 -50.8254) (xy 68.7324 -51.1556) (xy 67.7164 -51.1556) (xy 67.691 -51.1302) (xy 65.8368 -51.1302)
				(xy 65.151 -51.816) (xy 65.151 -53.594) (xy 65.405 -53.848) (xy 65.4558 -53.848) (xy 65.532 -53.9242)
				(xy 69.3928 -53.9242) (xy 69.85 -53.467) (xy 69.85 -50.927) (xy 69.7484 -50.8254)
			)
		)
		(polygon
			(pts
				(xy 69.1388 -53.213) (xy 68.8848 -53.213) (xy 68.8848 -53.467) (xy 69.1388 -53.467)
			)
		)
		(polygon
			(pts
				(xy 68.5292 -53.213) (xy 68.2752 -53.213) (xy 68.2752 -53.467) (xy 68.5292 -53.467)
			)
		)
		(polygon
			(pts
				(xy 68.1228 -53.213) (xy 67.8688 -53.213) (xy 67.8688 -53.467) (xy 68.1228 -53.467)
			)
		)
		(polygon
			(pts
				(xy 67.5132 -53.213) (xy 67.2592 -53.213) (xy 67.2592 -53.467) (xy 67.5132 -53.467)
			)
		)
		(polygon
			(pts
				(xy 69.3166 -51.2572) (xy 69.0626 -51.2572) (xy 69.0626 -51.5112) (xy 69.3166 -51.5112)
			)
		)
	)
	(zone
		(net "GND")
		(layer "F.Cu")
		(hatch none 0.5)
		(connect_pads
			(clearance 0.5)
		)
		(min_thickness 0.25)
		(fill yes
			(thermal_gap 0.5)
			(thermal_bridge_width 0.5)
			(island_removal_mode 0)
		)
		(polygon
			(pts
				(xy 282.829 -216.535) (xy 282.702 -216.662) (xy 282.702 -218.948) (xy 282.829 -219.075) (xy 284.353 -219.075)
				(xy 284.48 -218.948) (xy 284.48 -216.662) (xy 284.353 -216.535)
			)
		)
	)
	(zone
		(net "P3V3_STBY")
		(layer "F.Cu")
		(hatch none 0.5)
		(connect_pads
			(clearance 0.5)
		)
		(min_thickness 0.25)
		(fill yes
			(thermal_gap 0.5)
			(thermal_bridge_width 0.5)
			(island_removal_mode 0)
		)
		(polygon
			(pts
				(xy 84.201 -238.379) (xy 83.9978 -238.5822) (xy 83.9978 -239.7252) (xy 84.1248 -239.8522) (xy 84.1248 -240.4872)
				(xy 84.3026 -240.665) (xy 85.598 -240.665) (xy 86.106 -240.157) (xy 86.741 -240.157) (xy 86.868 -240.03)
				(xy 86.868 -238.633) (xy 86.614 -238.379)
			)
		)
		(polygon
			(pts
				(xy 85.1408 -239.9284) (xy 84.8868 -239.9284) (xy 84.8868 -240.1824) (xy 85.1408 -240.1824)
			)
		)
		(polygon
			(pts
				(xy 84.5312 -239.9284) (xy 84.2772 -239.9284) (xy 84.2772 -240.1824) (xy 84.5312 -240.1824)
			)
		)
		(polygon
			(pts
				(xy 85.0138 -239.4204) (xy 84.7598 -239.4204) (xy 84.7598 -239.6744) (xy 85.0138 -239.6744)
			)
		)
	)
	(zone
		(layer "F.Cu")
		(hatch none 0.5)
		(connect_pads
			(clearance 0)
		)
		(min_thickness 0.25)
		(keepout
			(tracks allowed)
			(vias allowed)
			(pads allowed)
			(copperpour allowed)
			(footprints allowed)
		)
		(placement
			(enabled no)
			(sheetname "")
		)
		(fill
			(thermal_gap 0.5)
			(thermal_bridge_width 0.5)
			(island_removal_mode 0)
		)
		(polygon
			(pts
				(xy 337.82 -112.141) (xy 337.82 -110.871) (xy 339.725 -110.871) (xy 339.725 -112.141)
			)
		)
	)
	(zone
		(net "P12V")
		(layer "F.Cu")
		(hatch none 0.5)
		(connect_pads
			(clearance 0.5)
		)
		(min_thickness 0.25)
		(fill yes
			(thermal_gap 0.5)
			(thermal_bridge_width 0.5)
			(island_removal_mode 0)
		)
		(polygon
			(pts
				(xy 274.066 -45.339) (xy 273.812 -45.593) (xy 273.812 -49.276) (xy 274.193 -49.657) (xy 276.479 -49.657)
				(xy 276.86 -49.276) (xy 276.86 -45.72) (xy 276.479 -45.339)
			)
		)
		(polygon
			(pts
				(xy 275.9075 -46.3677) (xy 275.6535 -46.3677) (xy 275.6535 -46.6217) (xy 275.9075 -46.6217)
			)
		)
		(polygon
			(pts
				(xy 274.5105 -46.3677) (xy 274.2565 -46.3677) (xy 274.2565 -46.6217) (xy 274.5105 -46.6217)
			)
		)
	)
	(zone
		(layer "F.Cu")
		(hatch none 0.5)
		(connect_pads
			(clearance 0)
		)
		(min_thickness 0.25)
		(keepout
			(tracks allowed)
			(vias allowed)
			(pads allowed)
			(copperpour allowed)
			(footprints allowed)
		)
		(placement
			(enabled no)
			(sheetname "")
		)
		(fill
			(thermal_gap 0.5)
			(thermal_bridge_width 0.5)
			(island_removal_mode 0)
		)
		(polygon
			(pts
				(xy 88.138 -138.811) (xy 88.138 -136.906) (xy 90.17 -136.906) (xy 92.837 -136.906) (xy 92.837 -139.192)
				(xy 90.17 -139.192) (xy 90.17 -138.811)
			)
		)
	)
	(zone
		(net "GND")
		(layer "F.Cu")
		(hatch none 0.5)
		(connect_pads
			(clearance 0.5)
		)
		(min_thickness 0.25)
		(fill yes
			(thermal_gap 0.5)
			(thermal_bridge_width 0.5)
			(island_removal_mode 0)
		)
		(polygon
			(pts
				(xy 261.62 -17.018) (xy 261.112 -17.526) (xy 261.112 -28.829) (xy 261.366 -29.083) (xy 264.033 -29.083)
				(xy 264.287 -28.829) (xy 264.287 -26.162) (xy 264.541 -25.908) (xy 264.541 -19.177) (xy 265.049 -18.669)
				(xy 271.145 -18.669) (xy 271.272 -18.542) (xy 271.272 -17.145) (xy 271.145 -17.018)
			)
		)
		(polygon
			(pts
				(xy 263.525 -28.4988) (xy 263.271 -28.4988) (xy 263.271 -28.7528) (xy 263.525 -28.7528)
			)
		)
		(polygon
			(pts
				(xy 263.525 -27.6352) (xy 263.271 -27.6352) (xy 263.271 -27.8892) (xy 263.525 -27.8892)
			)
		)
		(polygon
			(pts
				(xy 263.525 -27.1018) (xy 263.271 -27.1018) (xy 263.271 -27.3558) (xy 263.525 -27.3558)
			)
		)
		(polygon
			(pts
				(xy 263.525 -26.2382) (xy 263.271 -26.2382) (xy 263.271 -26.4922) (xy 263.525 -26.4922)
			)
		)
		(polygon
			(pts
				(xy 271.0688 -17.399) (xy 270.8148 -17.399) (xy 270.8148 -17.653) (xy 271.0688 -17.653)
			)
		)
		(polygon
			(pts
				(xy 270.4592 -17.399) (xy 270.2052 -17.399) (xy 270.2052 -17.653) (xy 270.4592 -17.653)
			)
		)
	)
	(zone
		(layer "F.Cu")
		(hatch none 0.5)
		(connect_pads
			(clearance 0)
		)
		(min_thickness 0.25)
		(keepout
			(tracks allowed)
			(vias allowed)
			(pads allowed)
			(copperpour allowed)
			(footprints allowed)
		)
		(placement
			(enabled no)
			(sheetname "")
		)
		(fill
			(thermal_gap 0.5)
			(thermal_bridge_width 0.5)
			(island_removal_mode 0)
		)
		(polygon
			(pts
				(xy 15.494 -170.18) (xy 15.494 -168.402) (xy 16.002 -168.402) (xy 16.002 -170.18)
			)
		)
	)
	(zone
		(net "P1V8_E")
		(layer "F.Cu")
		(hatch none 0.5)
		(connect_pads
			(clearance 0.5)
		)
		(min_thickness 0.25)
		(fill yes
			(thermal_gap 0.5)
			(thermal_bridge_width 0.5)
			(island_removal_mode 0)
		)
		(polygon
			(pts
				(xy 77.451966 -82.677) (xy 76.943966 -83.185) (xy 76.943966 -87.63) (xy 78.213966 -88.9) (xy 79.991966 -88.9)
				(xy 80.245966 -88.646) (xy 80.245966 -86.106) (xy 80.499966 -85.852) (xy 80.499966 -83.058) (xy 80.118966 -82.677)
			)
		)
		(polygon
			(pts
				(xy 79.788766 -88.1126) (xy 79.534766 -88.1126) (xy 79.534766 -88.3666) (xy 79.788766 -88.3666)
			)
		)
		(polygon
			(pts
				(xy 80.042766 -85.1154) (xy 79.788766 -85.1154) (xy 79.788766 -85.3694) (xy 80.042766 -85.3694)
			)
		)
		(polygon
			(pts
				(xy 77.426566 -85.0392) (xy 77.172566 -85.0392) (xy 77.172566 -85.6488) (xy 77.426566 -85.6488)
			)
		)
		(polygon
			(pts
				(xy 80.042766 -84.5566) (xy 79.788766 -84.5566) (xy 79.788766 -84.8106) (xy 80.042766 -84.8106)
			)
		)
		(polygon
			(pts
				(xy 77.426566 -84.0232) (xy 77.172566 -84.0232) (xy 77.172566 -84.6328) (xy 77.426566 -84.6328)
			)
		)
	)
	(zone
		(layer "F.Cu")
		(hatch none 0.5)
		(connect_pads
			(clearance 0)
		)
		(min_thickness 0.25)
		(keepout
			(tracks allowed)
			(vias allowed)
			(pads allowed)
			(copperpour allowed)
			(footprints not_allowed)
		)
		(placement
			(enabled no)
			(sheetname "")
		)
		(fill
			(thermal_gap 0.5)
			(thermal_bridge_width 0.5)
			(island_removal_mode 0)
		)
		(polygon
			(pts
				(arc
					(start 117.849904 -65.499996)
					(mid 114.350038 -68.999862)
					(end 110.849918 -65.499996)
				)
				(arc
					(start 110.849918 -64.499998)
					(mid 110.264133 -63.085787)
					(end 108.849922 -62.500002)
				)
				(xy 86.849966 -62.500002)
				(arc
					(start 86.849966 -24.500078)
					(mid 90.350086 -20.999958)
					(end 93.849952 -24.500078)
				)
				(arc
					(start 93.849952 -25.500076)
					(mid 94.435737 -26.914287)
					(end 95.849948 -27.500072)
				)
				(xy 117.849904 -27.500072)
			)
		)
	)
	(zone
		(layer "F.Cu")
		(hatch none 0.5)
		(connect_pads
			(clearance 0)
		)
		(min_thickness 0.25)
		(keepout
			(tracks allowed)
			(vias allowed)
			(pads allowed)
			(copperpour allowed)
			(footprints not_allowed)
		)
		(placement
			(enabled no)
			(sheetname "")
		)
		(fill
			(thermal_gap 0.5)
			(thermal_bridge_width 0.5)
			(island_removal_mode 0)
		)
		(polygon
			(pts
				(arc
					(start 84.350098 -107.350052)
					(mid 80.850232 -103.850186)
					(end 84.350098 -100.350066)
				)
				(arc
					(start 85.350096 -100.350066)
					(mid 86.764307 -99.764281)
					(end 87.350092 -98.35007)
				)
				(xy 87.350092 -82.350102)
				(arc
					(start 145.349976 -82.350102)
					(mid 148.850096 -85.850222)
					(end 145.349976 -89.350088)
				)
				(arc
					(start 144.349978 -89.350088)
					(mid 142.874416 -90.00001)
					(end 142.357856 -91.527376)
				)
				(xy 142.349982 -107.350052)
			)
		)
	)
	(zone
		(layer "F.Cu")
		(hatch none 0.5)
		(connect_pads
			(clearance 0)
		)
		(min_thickness 0.25)
		(keepout
			(tracks allowed)
			(vias allowed)
			(pads allowed)
			(copperpour allowed)
			(footprints not_allowed)
		)
		(placement
			(enabled no)
			(sheetname "")
		)
		(fill
			(thermal_gap 0.5)
			(thermal_bridge_width 0.5)
			(island_removal_mode 0)
		)
		(polygon
			(pts
				(arc
					(start 305.485038 -44.500038)
					(mid 306.192143 -44.207145)
					(end 306.485036 -43.50004)
				)
				(arc
					(start 306.485036 -0.999998)
					(mid 306.777929 -0.292893)
					(end 307.485034 0)
				)
				(xy 317.90005 0) (xy 317.90005 -35.999928)
				(arc
					(start 314.366402 -35.999928)
					(mid 307.299794 -39.500125)
					(end 314.366402 -42.999914)
				)
				(xy 317.90005 -42.999914) (xy 317.90005 -67.399916) (xy 249.899932 -67.399916) (xy 249.899932 -48.90008)
				(xy 259.899912 -48.90008) (xy 259.899912 -12.500102) (xy 282.485084 -12.500102)
				(arc
					(start 282.485084 -53.50002)
					(mid 282.777977 -54.207125)
					(end 283.485082 -54.500018)
				)
				(arc
					(start 303.485042 -54.500018)
					(mid 304.192147 -54.207125)
					(end 304.48504 -53.50002)
				)
				(arc
					(start 304.48504 -45.500036)
					(mid 304.777933 -44.792931)
					(end 305.485038 -44.500038)
				)
			)
		)
	)
	(zone
		(layer "F.Cu")
		(hatch none 0.5)
		(connect_pads
			(clearance 0)
		)
		(min_thickness 0.25)
		(keepout
			(tracks not_allowed)
			(vias allowed)
			(pads allowed)
			(copperpour not_allowed)
			(footprints allowed)
		)
		(placement
			(enabled no)
			(sheetname "")
		)
		(fill
			(thermal_gap 0.5)
			(thermal_bridge_width 0.5)
			(island_removal_mode 0)
		)
		(polygon
			(pts
				(arc
					(start 199.946768 -76.64196)
					(mid 199.563228 -77.0255)
					(end 199.946768 -77.40904)
				)
				(arc
					(start 200.928478 -77.40904)
					(mid 201.312272 -77.025627)
					(end 200.928732 -76.64196)
				)
				(arc
					(start 200.776078 -76.64196)
					(mid 200.799561 -76.697774)
					(end 200.826624 -76.751942)
				)
				(arc
					(start 200.826624 -76.751942)
					(mid 201.104219 -77.259126)
					(end 200.693528 -76.852272)
				)
				(arc
					(start 200.693528 -76.852272)
					(mid 200.641908 -76.749536)
					(end 200.601326 -76.64196)
				)
				(arc
					(start 200.290684 -76.64196)
					(mid 200.242986 -76.751802)
					(end 200.18502 -76.85659)
				)
				(arc
					(start 200.18502 -76.85659)
					(mid 199.766454 -77.255242)
					(end 200.05421 -76.753974)
				)
				(arc
					(start 200.05421 -76.753974)
					(mid 200.084787 -76.698805)
					(end 200.112122 -76.64196)
				)
			)
		)
	)
	(zone
		(net "P3V3")
		(layer "F.Cu")
		(hatch none 0.5)
		(connect_pads
			(clearance 0.5)
		)
		(min_thickness 0.25)
		(fill yes
			(thermal_gap 0.5)
			(thermal_bridge_width 0.5)
			(island_removal_mode 0)
		)
		(polygon
			(pts
				(xy 290.83 -60.833) (xy 290.576 -61.087) (xy 290.576 -64.77) (xy 290.703 -64.897) (xy 293.878 -64.897)
				(xy 294.894 -63.881) (xy 296.037 -63.881) (xy 296.418 -63.5) (xy 296.418 -60.96) (xy 296.291 -60.833)
			)
		)
		(polygon
			(pts
				(xy 291.583872 -64.511936) (xy 291.329872 -64.511936) (xy 291.329872 -64.765936) (xy 291.583872 -64.765936)
			)
		)
		(polygon
			(pts
				(xy 291.583872 -63.648336) (xy 291.329872 -63.648336) (xy 291.329872 -63.902336) (xy 291.583872 -63.902336)
			)
		)
		(polygon
			(pts
				(xy 295.673272 -63.114936) (xy 295.419272 -63.114936) (xy 295.419272 -63.368936) (xy 295.673272 -63.368936)
			)
		)
		(polygon
			(pts
				(xy 295.114472 -63.114936) (xy 294.860472 -63.114936) (xy 294.860472 -63.368936) (xy 295.114472 -63.368936)
			)
		)
	)
	(zone
		(net "P1V8_STBY_LL")
		(layer "F.Cu")
		(hatch none 0.5)
		(connect_pads
			(clearance 0.5)
		)
		(min_thickness 0.25)
		(fill yes
			(thermal_gap 0.5)
			(thermal_bridge_width 0.5)
			(island_removal_mode 0)
		)
		(polygon
			(pts
				(xy 267.081 -31.242) (xy 266.446 -31.877) (xy 266.446 -36.195) (xy 266.192 -36.449) (xy 266.192 -37.465)
				(xy 266.319 -37.592) (xy 269.621 -37.592) (xy 270.51 -36.703) (xy 271.399 -36.703) (xy 271.653 -36.449)
				(xy 271.653 -35.56) (xy 272.669 -34.544) (xy 272.669 -31.75) (xy 272.161 -31.242)
			)
		)
		(polygon
			(pts
				(xy 270.891 -36.1188) (xy 270.637 -36.1188) (xy 270.637 -36.3728) (xy 270.891 -36.3728)
			)
		)
		(polygon
			(pts
				(xy 270.891 -35.2552) (xy 270.637 -35.2552) (xy 270.637 -35.5092) (xy 270.891 -35.5092)
			)
		)
	)
	(zone
		(net "P12V_MSB")
		(layer "F.Cu")
		(hatch none 0.5)
		(connect_pads
			(clearance 0.5)
		)
		(min_thickness 0.25)
		(fill yes
			(thermal_gap 0.5)
			(thermal_bridge_width 0.5)
			(island_removal_mode 0)
		)
		(polygon
			(pts
				(xy 266.065 -65.151) (xy 265.43 -65.786) (xy 260.985 -65.786) (xy 258.826 -67.945) (xy 258.826 -73.152)
				(xy 262.636 -76.962) (xy 267.335 -76.962) (xy 267.716 -76.581) (xy 267.716 -72.517) (xy 267.97 -72.263)
				(xy 267.97 -68.834) (xy 269.748 -67.056) (xy 269.748 -65.405) (xy 269.494 -65.151)
			)
		)
		(polygon
			(pts
				(xy 267.1318 -76.2762) (xy 266.8778 -76.2762) (xy 266.8778 -76.5302) (xy 267.1318 -76.5302)
			)
		)
		(polygon
			(pts
				(xy 267.137896 -75.401424) (xy 266.883896 -75.401424) (xy 266.883896 -75.655424) (xy 266.8778 -75.6666)
				(xy 266.8778 -75.9206) (xy 267.1318 -75.9206) (xy 267.1318 -75.6666) (xy 267.137896 -75.655424)
			)
		)
		(polygon
			(pts
				(xy 267.137896 -74.791824) (xy 266.883896 -74.791824) (xy 266.883896 -75.045824) (xy 267.137896 -75.045824)
			)
		)
		(polygon
			(pts
				(xy 267.137896 -74.283824) (xy 266.883896 -74.283824) (xy 266.883896 -74.537824) (xy 267.137896 -74.537824)
			)
		)
		(polygon
			(pts
				(xy 267.137896 -73.674224) (xy 266.883896 -73.674224) (xy 266.883896 -73.928224) (xy 267.137896 -73.928224)
			)
		)
		(polygon
			(pts
				(xy 267.208 -73.2028) (xy 266.954 -73.2028) (xy 266.954 -73.4568) (xy 267.208 -73.4568)
			)
		)
		(polygon
			(pts
				(xy 267.208 -72.5932) (xy 266.954 -72.5932) (xy 266.954 -72.8472) (xy 267.208 -72.8472)
			)
		)
		(polygon
			(pts
				(xy 266.573 -72.1868) (xy 266.319 -72.1868) (xy 266.319 -72.4408) (xy 266.573 -72.4408)
			)
		)
		(polygon
			(pts
				(xy 259.588 -71.6788) (xy 259.334 -71.6788) (xy 259.334 -71.9328) (xy 259.588 -71.9328)
			)
		)
		(polygon
			(pts
				(xy 266.573 -71.3232) (xy 266.319 -71.3232) (xy 266.319 -71.5772) (xy 266.573 -71.5772)
			)
		)
		(polygon
			(pts
				(xy 259.588 -71.0692) (xy 259.334 -71.0692) (xy 259.334 -71.3232) (xy 259.588 -71.3232)
			)
		)
		(polygon
			(pts
				(xy 266.627864 -70.908672) (xy 266.373864 -70.908672) (xy 266.373864 -71.162672) (xy 266.627864 -71.162672)
			)
		)
		(polygon
			(pts
				(xy 259.588 -70.6628) (xy 259.334 -70.6628) (xy 259.334 -70.9168) (xy 259.588 -70.9168)
			)
		)
		(polygon
			(pts
				(xy 259.588 -70.0532) (xy 259.334 -70.0532) (xy 259.334 -70.3072) (xy 259.588 -70.3072)
			)
		)
		(polygon
			(pts
				(xy 266.627864 -70.045072) (xy 266.373864 -70.045072) (xy 266.373864 -70.299072) (xy 266.627864 -70.299072)
			)
		)
	)
	(zone
		(layer "F.Cu")
		(hatch none 0.5)
		(connect_pads
			(clearance 0)
		)
		(min_thickness 0.25)
		(keepout
			(tracks not_allowed)
			(vias allowed)
			(pads allowed)
			(copperpour not_allowed)
			(footprints allowed)
		)
		(placement
			(enabled no)
			(sheetname "")
		)
		(fill
			(thermal_gap 0.5)
			(thermal_bridge_width 0.5)
			(island_removal_mode 0)
		)
		(polygon
			(pts
				(arc
					(start 134.581646 -82.29346)
					(mid 134.197852 -82.676873)
					(end 134.581392 -83.06054)
				)
				(xy 134.8105 -83.06054)
				(arc
					(start 134.8105 -83.011772)
					(mid 134.8076 -82.997192)
					(end 134.799324 -82.984848)
				)
				(arc
					(start 134.73811 -82.923634)
					(mid 134.374766 -82.470374)
					(end 134.828026 -82.833718)
				)
				(xy 134.907782 -82.913474)
				(arc
					(start 134.907782 -82.917284)
					(mid 134.924896 -82.948584)
					(end 134.93496 -82.982816)
				)
				(xy 134.9375 -82.985356) (xy 134.9375 -83.06054) (xy 135.1534 -83.06054) (xy 135.1534 -82.985356)
				(arc
					(start 135.15594 -82.982816)
					(mid 135.165944 -82.948559)
					(end 135.183118 -82.917284)
				)
				(xy 135.183118 -82.913474)
				(arc
					(start 135.262874 -82.833718)
					(mid 135.716134 -82.470374)
					(end 135.35279 -82.923634)
				)
				(arc
					(start 135.291576 -82.984848)
					(mid 135.283322 -82.997201)
					(end 135.2804 -83.011772)
				)
				(xy 135.2804 -83.06054)
				(arc
					(start 135.509508 -83.06054)
					(mid 135.893048 -82.677)
					(end 135.509508 -82.29346)
				)
			)
		)
	)
	(zone
		(layer "F.Cu")
		(hatch none 0.5)
		(connect_pads
			(clearance 0)
		)
		(min_thickness 0.25)
		(keepout
			(tracks allowed)
			(vias allowed)
			(pads allowed)
			(copperpour allowed)
			(footprints allowed)
		)
		(placement
			(enabled no)
			(sheetname "")
		)
		(fill
			(thermal_gap 0.5)
			(thermal_bridge_width 0.5)
			(island_removal_mode 0)
		)
		(polygon
			(pts
				(xy 79.756 -19.685) (xy 79.756 -18.669) (xy 82.296 -18.669) (xy 82.296 -19.685)
			)
		)
	)
	(zone
		(layer "F.Cu")
		(hatch none 0.5)
		(connect_pads
			(clearance 0)
		)
		(min_thickness 0.25)
		(keepout
			(tracks allowed)
			(vias allowed)
			(pads allowed)
			(copperpour allowed)
			(footprints allowed)
		)
		(placement
			(enabled no)
			(sheetname "")
		)
		(fill
			(thermal_gap 0.5)
			(thermal_bridge_width 0.5)
			(island_removal_mode 0)
		)
		(polygon
			(pts
				(xy 81.788 -139.192) (xy 81.788 -136.652) (xy 85.217 -136.652) (xy 85.217 -139.192)
			)
		)
	)
	(zone
		(layer "F.Cu")
		(hatch none 0.5)
		(connect_pads
			(clearance 0)
		)
		(min_thickness 0.25)
		(keepout
			(tracks allowed)
			(vias allowed)
			(pads allowed)
			(copperpour allowed)
			(footprints allowed)
		)
		(placement
			(enabled no)
			(sheetname "")
		)
		(fill
			(thermal_gap 0.5)
			(thermal_bridge_width 0.5)
			(island_removal_mode 0)
		)
		(polygon
			(pts
				(xy 261.239 -228.854) (xy 261.239 -226.695) (xy 262.763 -226.695) (xy 262.763 -228.854)
			)
		)
	)
	(zone
		(net "GND")
		(layer "F.Cu")
		(hatch none 0.5)
		(connect_pads
			(clearance 0.5)
		)
		(min_thickness 0.25)
		(fill yes
			(thermal_gap 0.5)
			(thermal_bridge_width 0.5)
			(island_removal_mode 0)
		)
		(polygon
			(pts
				(xy 147.828 -83.185) (xy 142.113 -88.9) (xy 142.113 -91.313) (xy 142.621 -91.821) (xy 155.067 -91.821)
				(xy 160.528 -86.36) (xy 172.974 -86.36) (xy 173.863 -87.249) (xy 173.863 -94.742) (xy 174.498 -95.377)
				(xy 174.498 -98.171) (xy 175.133 -98.806) (xy 180.848 -98.806) (xy 181.229 -98.425) (xy 181.229 -83.82)
				(xy 180.594 -83.185)
			)
		)
	)
	(zone
		(layer "F.Cu")
		(hatch none 0.5)
		(connect_pads
			(clearance 0)
		)
		(min_thickness 0.25)
		(keepout
			(tracks allowed)
			(vias allowed)
			(pads allowed)
			(copperpour allowed)
			(footprints allowed)
		)
		(placement
			(enabled no)
			(sheetname "")
		)
		(fill
			(thermal_gap 0.5)
			(thermal_bridge_width 0.5)
			(island_removal_mode 0)
		)
		(polygon
			(pts
				(xy 30.988 -203.454) (xy 30.988 -202.311) (xy 33.274 -202.311) (xy 33.274 -203.454)
			)
		)
	)
	(zone
		(net "GND")
		(layer "F.Cu")
		(hatch none 0.5)
		(connect_pads
			(clearance 0.5)
		)
		(min_thickness 0.25)
		(fill yes
			(thermal_gap 0.5)
			(thermal_bridge_width 0.5)
			(island_removal_mode 0)
		)
		(polygon
			(pts
				(xy 168.783 -56.515) (xy 168.529 -56.769) (xy 168.529 -66.675) (xy 168.91 -67.056) (xy 182.88 -67.056)
				(xy 183.134 -66.802) (xy 183.134 -65.151) (xy 174.498 -56.515)
			)
		)
		(polygon
			(pts
				(xy 182.81777 -66.294) (xy 182.56377 -66.294) (xy 182.56377 -66.548) (xy 182.81777 -66.548)
			)
		)
		(polygon
			(pts
				(xy 182.20817 -66.294) (xy 181.95417 -66.294) (xy 181.95417 -66.548) (xy 182.20817 -66.548)
			)
		)
		(polygon
			(pts
				(xy 181.80177 -66.294) (xy 181.54777 -66.294) (xy 181.54777 -66.548) (xy 181.80177 -66.548)
			)
		)
		(polygon
			(pts
				(xy 181.19217 -66.294) (xy 180.93817 -66.294) (xy 180.93817 -66.548) (xy 181.19217 -66.548)
			)
		)
		(polygon
			(pts
				(xy 180.78577 -66.294) (xy 180.53177 -66.294) (xy 180.53177 -66.548) (xy 180.78577 -66.548)
			)
		)
		(polygon
			(pts
				(xy 180.17617 -66.294) (xy 179.92217 -66.294) (xy 179.92217 -66.548) (xy 180.17617 -66.548)
			)
		)
		(polygon
			(pts
				(xy 179.76977 -66.294) (xy 179.51577 -66.294) (xy 179.51577 -66.548) (xy 179.76977 -66.548)
			)
		)
		(polygon
			(pts
				(xy 179.16017 -66.294) (xy 178.90617 -66.294) (xy 178.90617 -66.548) (xy 179.16017 -66.548)
			)
		)
		(polygon
			(pts
				(xy 174.94377 -66.294) (xy 174.68977 -66.294) (xy 174.68977 -66.548) (xy 174.94377 -66.548)
			)
		)
		(polygon
			(pts
				(xy 174.33417 -66.294) (xy 174.08017 -66.294) (xy 174.08017 -66.548) (xy 174.33417 -66.548)
			)
		)
		(polygon
			(pts
				(xy 173.92777 -66.294) (xy 173.67377 -66.294) (xy 173.67377 -66.548) (xy 173.92777 -66.548)
			)
		)
		(polygon
			(pts
				(xy 173.31817 -66.294) (xy 173.06417 -66.294) (xy 173.06417 -66.548) (xy 173.31817 -66.548)
			)
		)
		(polygon
			(pts
				(xy 172.91177 -66.294) (xy 172.65777 -66.294) (xy 172.65777 -66.548) (xy 172.91177 -66.548)
			)
		)
		(polygon
			(pts
				(xy 172.30217 -66.294) (xy 172.04817 -66.294) (xy 172.04817 -66.548) (xy 172.30217 -66.548)
			)
		)
		(polygon
			(pts
				(xy 171.89577 -66.294) (xy 171.64177 -66.294) (xy 171.64177 -66.548) (xy 171.89577 -66.548)
			)
		)
		(polygon
			(pts
				(xy 171.28617 -66.294) (xy 171.03217 -66.294) (xy 171.03217 -66.548) (xy 171.28617 -66.548)
			)
		)
	)
	(zone
		(layer "F.Cu")
		(hatch none 0.5)
		(connect_pads
			(clearance 0)
		)
		(min_thickness 0.25)
		(keepout
			(tracks allowed)
			(vias allowed)
			(pads allowed)
			(copperpour allowed)
			(footprints allowed)
		)
		(placement
			(enabled no)
			(sheetname "")
		)
		(fill
			(thermal_gap 0.5)
			(thermal_bridge_width 0.5)
			(island_removal_mode 0)
		)
		(polygon
			(pts
				(xy 200.914 -114.808) (xy 200.914 -113.919) (xy 202.692 -113.919) (xy 202.692 -114.808)
			)
		)
	)
	(zone
		(layer "F.Cu")
		(hatch none 0.5)
		(connect_pads
			(clearance 0)
		)
		(min_thickness 0.25)
		(keepout
			(tracks not_allowed)
			(vias allowed)
			(pads allowed)
			(copperpour not_allowed)
			(footprints allowed)
		)
		(placement
			(enabled no)
			(sheetname "")
		)
		(fill
			(thermal_gap 0.5)
			(thermal_bridge_width 0.5)
			(island_removal_mode 0)
		)
		(polygon
			(pts
				(arc
					(start 132.930392 -80.733646)
					(mid 132.546852 -81.117186)
					(end 132.930392 -81.500726)
				)
				(xy 133.1595 -81.500726)
				(arc
					(start 133.1595 -81.451958)
					(mid 133.1566 -81.437378)
					(end 133.148324 -81.425034)
				)
				(arc
					(start 133.08711 -81.36382)
					(mid 132.723766 -80.91056)
					(end 133.177026 -81.273904)
				)
				(xy 133.256782 -81.35366)
				(arc
					(start 133.256782 -81.35747)
					(mid 133.273896 -81.38877)
					(end 133.28396 -81.423002)
				)
				(xy 133.2865 -81.425542) (xy 133.2865 -81.500726) (xy 133.5024 -81.500726) (xy 133.5024 -81.425542)
				(arc
					(start 133.50494 -81.423002)
					(mid 133.514944 -81.388745)
					(end 133.532118 -81.35747)
				)
				(xy 133.532118 -81.35366)
				(arc
					(start 133.611874 -81.273904)
					(mid 134.065134 -80.91056)
					(end 133.70179 -81.36382)
				)
				(arc
					(start 133.640576 -81.425034)
					(mid 133.632322 -81.437387)
					(end 133.6294 -81.451958)
				)
				(xy 133.6294 -81.500726)
				(arc
					(start 133.858254 -81.500726)
					(mid 134.242048 -81.117313)
					(end 133.858508 -80.733646)
				)
			)
		)
	)
	(zone
		(layer "F.Cu")
		(hatch none 0.5)
		(connect_pads
			(clearance 0)
		)
		(min_thickness 0.25)
		(keepout
			(tracks allowed)
			(vias allowed)
			(pads allowed)
			(copperpour allowed)
			(footprints allowed)
		)
		(placement
			(enabled no)
			(sheetname "")
		)
		(fill
			(thermal_gap 0.5)
			(thermal_bridge_width 0.5)
			(island_removal_mode 0)
		)
		(polygon
			(pts
				(xy 325.755 -172.847) (xy 325.755 -171.323) (xy 327.66 -171.323) (xy 327.66 -172.847)
			)
		)
	)
	(zone
		(layer "F.Cu")
		(hatch none 0.5)
		(connect_pads
			(clearance 0)
		)
		(min_thickness 0.25)
		(keepout
			(tracks allowed)
			(vias allowed)
			(pads allowed)
			(copperpour allowed)
			(footprints allowed)
		)
		(placement
			(enabled no)
			(sheetname "")
		)
		(fill
			(thermal_gap 0.5)
			(thermal_bridge_width 0.5)
			(island_removal_mode 0)
		)
		(polygon
			(pts
				(xy 312.928 -54.991) (xy 312.928 -51.435) (xy 315.214 -51.435) (xy 315.214 -54.991)
			)
		)
	)
	(zone
		(net "GND")
		(layer "F.Cu")
		(hatch none 0.5)
		(connect_pads
			(clearance 0.5)
		)
		(min_thickness 0.25)
		(fill yes
			(thermal_gap 0.5)
			(thermal_bridge_width 0.5)
			(island_removal_mode 0)
		)
		(polygon
			(pts
				(xy 44.831 -247.65) (xy 44.577 -247.904) (xy 44.577 -249.809) (xy 44.958 -250.19) (xy 67.056 -250.19)
				(xy 68.199 -251.333) (xy 68.199 -252.222) (xy 68.58 -252.603) (xy 70.358 -252.603) (xy 70.739 -252.222)
				(xy 70.739 -248.158) (xy 70.231 -247.65)
			)
		)
	)
	(zone
		(layer "F.Cu")
		(hatch none 0.5)
		(connect_pads
			(clearance 0)
		)
		(min_thickness 0.25)
		(keepout
			(tracks allowed)
			(vias allowed)
			(pads allowed)
			(copperpour allowed)
			(footprints not_allowed)
		)
		(placement
			(enabled no)
			(sheetname "")
		)
		(fill
			(thermal_gap 0.5)
			(thermal_bridge_width 0.5)
			(island_removal_mode 0)
		)
		(polygon
			(pts
				(arc
					(start 108.849922 -62.500002)
					(mid 110.264133 -63.085787)
					(end 110.849918 -64.499998)
				)
				(arc
					(start 110.849918 -65.499996)
					(mid 114.350038 -69.000116)
					(end 117.849904 -65.499996)
				)
				(xy 117.849904 -27.500072)
				(arc
					(start 95.849948 -27.500072)
					(mid 94.435737 -26.914287)
					(end 93.849952 -25.500076)
				)
				(arc
					(start 93.849952 -24.500078)
					(mid 90.350086 -21.000212)
					(end 86.849966 -24.500078)
				)
				(xy 86.849966 -62.500002)
			)
		)
	)
	(zone
		(layer "F.Cu")
		(hatch none 0.5)
		(connect_pads
			(clearance 0)
		)
		(min_thickness 0.25)
		(keepout
			(tracks not_allowed)
			(vias allowed)
			(pads allowed)
			(copperpour not_allowed)
			(footprints allowed)
		)
		(placement
			(enabled no)
			(sheetname "")
		)
		(fill
			(thermal_gap 0.5)
			(thermal_bridge_width 0.5)
			(island_removal_mode 0)
		)
		(polygon
			(pts
				(arc
					(start 44.647104 -83.118706)
					(mid 44.263564 -83.502246)
					(end 44.647104 -83.885786)
				)
				(arc
					(start 45.623734 -83.885786)
					(mid 46.007528 -83.502373)
					(end 45.623988 -83.118706)
				)
				(arc
					(start 45.392594 -83.118706)
					(mid 45.424364 -83.190319)
					(end 45.468794 -83.25485)
				)
				(arc
					(start 45.468794 -83.25485)
					(mid 45.829445 -83.709797)
					(end 45.378116 -83.344512)
				)
				(arc
					(start 45.378116 -83.344512)
					(mid 45.305915 -83.238536)
					(end 45.26026 -83.118706)
				)
				(arc
					(start 45.010832 -83.118706)
					(mid 44.965168 -83.238532)
					(end 44.892976 -83.344512)
				)
				(arc
					(start 44.892976 -83.344512)
					(mid 44.441595 -83.709849)
					(end 44.802298 -83.25485)
				)
				(arc
					(start 44.802298 -83.25485)
					(mid 44.846759 -83.190336)
					(end 44.878498 -83.118706)
				)
			)
		)
	)
	(zone
		(layer "F.Cu")
		(hatch none 0.5)
		(connect_pads
			(clearance 0)
		)
		(min_thickness 0.25)
		(keepout
			(tracks allowed)
			(vias allowed)
			(pads allowed)
			(copperpour allowed)
			(footprints allowed)
		)
		(placement
			(enabled no)
			(sheetname "")
		)
		(fill
			(thermal_gap 0.5)
			(thermal_bridge_width 0.5)
			(island_removal_mode 0)
		)
		(polygon
			(pts
				(xy 320.167 -110.744) (xy 320.167 -108.204) (xy 322.326 -108.204) (xy 322.326 -110.744)
			)
		)
	)
	(zone
		(layer "F.Cu")
		(hatch none 0.5)
		(connect_pads
			(clearance 0)
		)
		(min_thickness 0.25)
		(keepout
			(tracks allowed)
			(vias allowed)
			(pads allowed)
			(copperpour allowed)
			(footprints allowed)
		)
		(placement
			(enabled no)
			(sheetname "")
		)
		(fill
			(thermal_gap 0.5)
			(thermal_bridge_width 0.5)
			(island_removal_mode 0)
		)
		(polygon
			(pts
				(xy 238.633 -115.062) (xy 238.633 -113.919) (xy 241.808 -113.919) (xy 241.808 -115.062)
			)
		)
	)
	(zone
		(layer "F.Cu")
		(hatch none 0.5)
		(connect_pads
			(clearance 0)
		)
		(min_thickness 0.25)
		(keepout
			(tracks allowed)
			(vias allowed)
			(pads allowed)
			(copperpour allowed)
			(footprints allowed)
		)
		(placement
			(enabled no)
			(sheetname "")
		)
		(fill
			(thermal_gap 0.5)
			(thermal_bridge_width 0.5)
			(island_removal_mode 0)
		)
		(polygon
			(pts
				(xy 98.298 -67.691) (xy 98.298 -64.897) (xy 101.727 -64.897) (xy 101.727 -67.691)
			)
		)
	)
	(zone
		(net "GND")
		(layer "F.Cu")
		(hatch none 0.5)
		(connect_pads
			(clearance 0.5)
		)
		(min_thickness 0.25)
		(fill yes
			(thermal_gap 0.5)
			(thermal_bridge_width 0.5)
			(island_removal_mode 0)
		)
		(polygon
			(pts
				(xy 89.389966 -69.469) (xy 89.008966 -69.85) (xy 89.008966 -70.866) (xy 89.262966 -71.12) (xy 96.374966 -71.12)
				(xy 96.882966 -70.612) (xy 96.882966 -69.723) (xy 96.628966 -69.469)
			)
		)
		(polygon
			(pts
				(xy 96.679766 -69.977) (xy 96.425766 -69.977) (xy 96.425766 -70.231) (xy 96.679766 -70.231)
			)
		)
		(polygon
			(pts
				(xy 96.070166 -69.977) (xy 95.816166 -69.977) (xy 95.816166 -70.231) (xy 96.070166 -70.231)
			)
		)
		(polygon
			(pts
				(xy 95.6818 -69.977) (xy 95.4278 -69.977) (xy 95.4278 -70.231) (xy 95.6818 -70.231)
			)
		)
		(polygon
			(pts
				(xy 95.0722 -69.977) (xy 94.8182 -69.977) (xy 94.8182 -70.231) (xy 95.0722 -70.231)
			)
		)
		(polygon
			(pts
				(xy 94.647766 -69.977) (xy 94.393766 -69.977) (xy 94.393766 -70.231) (xy 94.647766 -70.231)
			)
		)
		(polygon
			(pts
				(xy 94.038166 -69.977) (xy 93.784166 -69.977) (xy 93.784166 -70.231) (xy 94.038166 -70.231)
			)
		)
		(polygon
			(pts
				(xy 92.361766 -69.977) (xy 92.107766 -69.977) (xy 92.107766 -70.231) (xy 92.361766 -70.231)
			)
		)
		(polygon
			(pts
				(xy 91.752166 -69.977) (xy 91.498166 -69.977) (xy 91.498166 -70.231) (xy 91.752166 -70.231)
			)
		)
		(polygon
			(pts
				(xy 90.075766 -69.977) (xy 89.821766 -69.977) (xy 89.821766 -70.231) (xy 90.075766 -70.231)
			)
		)
		(polygon
			(pts
				(xy 89.466166 -69.977) (xy 89.212166 -69.977) (xy 89.212166 -70.231) (xy 89.466166 -70.231)
			)
		)
	)
	(zone
		(layer "F.Cu")
		(hatch none 0.5)
		(connect_pads
			(clearance 0)
		)
		(min_thickness 0.25)
		(keepout
			(tracks allowed)
			(vias allowed)
			(pads allowed)
			(copperpour allowed)
			(footprints not_allowed)
		)
		(placement
			(enabled no)
			(sheetname "")
		)
		(fill
			(thermal_gap 0.5)
			(thermal_bridge_width 0.5)
			(island_removal_mode 0)
		)
		(polygon
			(pts
				(arc
					(start 3.999992 -250.898914)
					(mid 1.127064 -249.162237)
					(end 0 -246.000016)
				)
				(xy 0 -109.000036) (xy 3.999992 -109.000036)
			)
		)
	)
	(zone
		(layer "F.Cu")
		(hatch none 0.5)
		(connect_pads
			(clearance 0)
		)
		(min_thickness 0.25)
		(keepout
			(tracks allowed)
			(vias allowed)
			(pads allowed)
			(copperpour allowed)
			(footprints not_allowed)
		)
		(placement
			(enabled no)
			(sheetname "")
		)
		(fill
			(thermal_gap 0.5)
			(thermal_bridge_width 0.5)
			(island_removal_mode 0)
		)
		(polygon
			(pts
				(xy 317.90005 -67.399916) (xy 317.90005 -101.000052)
				(arc
					(start 314.366402 -101.000052)
					(mid 307.299794 -104.500249)
					(end 314.366402 -108.000038)
				)
				(xy 317.90005 -108.000038) (xy 317.90005 -109.000036) (xy 249.899932 -109.000036) (xy 249.899932 -67.399916)
			)
		)
	)
	(zone
		(net "AGND_USB")
		(layer "F.Cu")
		(hatch none 0.5)
		(connect_pads
			(clearance 0.5)
		)
		(min_thickness 0.25)
		(fill yes
			(thermal_gap 0.5)
			(thermal_bridge_width 0.5)
			(island_removal_mode 0)
		)
		(polygon
			(pts
				(xy 264.16 -5.715) (xy 263.271 -6.604) (xy 263.271 -9.525) (xy 264.16 -10.414) (xy 266.573 -10.414)
				(xy 267.589 -9.398) (xy 274.701 -9.398) (xy 274.955 -9.652) (xy 274.955 -15.748) (xy 276.733 -17.526)
				(xy 277.495 -17.526) (xy 277.749 -17.272) (xy 277.749 -14.859) (xy 280.416 -12.192) (xy 280.416 -6.096)
				(xy 280.035 -5.715)
			)
		)
		(polygon
			(pts
				(xy 276.987 -16.3322) (xy 276.733 -16.3322) (xy 276.733 -16.5862) (xy 276.987 -16.5862)
			)
		)
		(polygon
			(pts
				(xy 276.987 -15.7988) (xy 276.733 -15.7988) (xy 276.733 -16.0528) (xy 276.987 -16.0528)
			)
		)
		(polygon
			(pts
				(xy 276.987 -14.9352) (xy 276.733 -14.9352) (xy 276.733 -15.1892) (xy 276.987 -15.1892)
			)
		)
	)
	(zone
		(layer "F.Cu")
		(hatch none 0.5)
		(connect_pads
			(clearance 0)
		)
		(min_thickness 0.25)
		(keepout
			(tracks allowed)
			(vias allowed)
			(pads allowed)
			(copperpour allowed)
			(footprints allowed)
		)
		(placement
			(enabled no)
			(sheetname "")
		)
		(fill
			(thermal_gap 0.5)
			(thermal_bridge_width 0.5)
			(island_removal_mode 0)
		)
		(polygon
			(pts
				(xy 331.597 -222.631) (xy 331.597 -220.726) (xy 332.994 -220.726) (xy 332.994 -222.631)
			)
		)
	)
	(zone
		(net "P3V3_STBY")
		(layer "F.Cu")
		(hatch none 0.5)
		(connect_pads
			(clearance 0.5)
		)
		(min_thickness 0.25)
		(fill yes
			(thermal_gap 0.5)
			(thermal_bridge_width 0.5)
			(island_removal_mode 0)
		)
		(polygon
			(pts
				(xy 14.301216 -198.68388) (xy 14.174216 -198.81088) (xy 14.174216 -201.85888) (xy 14.301216 -201.98588)
				(xy 17.476216 -201.98588) (xy 17.603216 -201.85888) (xy 17.603216 -198.93788) (xy 17.349216 -198.68388)
			)
		)
		(polygon
			(pts
				(xy 17.061688 -201.346816) (xy 16.807688 -201.346816) (xy 16.807688 -201.600816) (xy 17.061688 -201.600816)
			)
		)
		(polygon
			(pts
				(xy 16.477488 -201.346816) (xy 16.223488 -201.346816) (xy 16.223488 -201.600816) (xy 16.477488 -201.600816)
			)
		)
		(polygon
			(pts
				(xy 15.918688 -201.346816) (xy 15.664688 -201.346816) (xy 15.664688 -201.600816) (xy 15.918688 -201.600816)
			)
		)
		(polygon
			(pts
				(xy 15.334488 -201.346816) (xy 15.080488 -201.346816) (xy 15.080488 -201.600816) (xy 15.334488 -201.600816)
			)
		)
		(polygon
			(pts
				(xy 14.775688 -201.346816) (xy 14.521688 -201.346816) (xy 14.521688 -201.600816) (xy 14.775688 -201.600816)
			)
		)
	)
	(zone
		(layer "F.Cu")
		(hatch none 0.5)
		(connect_pads
			(clearance 0)
		)
		(min_thickness 0.25)
		(keepout
			(tracks not_allowed)
			(vias allowed)
			(pads allowed)
			(copperpour not_allowed)
			(footprints allowed)
		)
		(placement
			(enabled no)
			(sheetname "")
		)
		(fill
			(thermal_gap 0.5)
			(thermal_bridge_width 0.5)
			(island_removal_mode 0)
		)
		(polygon
			(pts
				(arc
					(start 303.80305 -87.141812)
					(mid 303.41951 -87.525352)
					(end 303.80305 -87.908892)
				)
				(arc
					(start 304.719736 -87.908892)
					(mid 305.10353 -87.525479)
					(end 304.71999 -87.141812)
				)
				(arc
					(start 304.519838 -87.141812)
					(mid 304.546459 -87.207052)
					(end 304.583846 -87.26678)
				)
				(arc
					(start 304.583846 -87.26678)
					(mid 304.923999 -87.734009)
					(end 304.464974 -87.382858)
				)
				(arc
					(start 304.464974 -87.382858)
					(mid 304.393009 -87.269137)
					(end 304.349404 -87.141812)
				)
				(arc
					(start 304.146966 -87.141812)
					(mid 304.111261 -87.262401)
					(end 304.052732 -87.373714)
				)
				(arc
					(start 304.052732 -87.373714)
					(mid 303.60802 -87.742746)
					(end 303.928018 -87.261446)
				)
				(arc
					(start 303.928018 -87.261446)
					(mid 303.957008 -87.203333)
					(end 303.977802 -87.141812)
				)
			)
		)
	)
	(zone
		(net "GND")
		(layer "F.Cu")
		(hatch none 0.5)
		(connect_pads
			(clearance 0.5)
		)
		(min_thickness 0.25)
		(fill yes
			(thermal_gap 0.5)
			(thermal_bridge_width 0.5)
			(island_removal_mode 0)
		)
		(polygon
			(pts
				(xy 323.596 -118.745) (xy 323.469 -118.872) (xy 323.469 -121.158) (xy 323.723 -121.412) (xy 327.025 -121.412)
				(xy 327.279 -121.158) (xy 327.279 -118.872) (xy 327.152 -118.745)
			)
		)
	)
	(zone
		(layer "F.Cu")
		(hatch none 0.5)
		(connect_pads
			(clearance 0)
		)
		(min_thickness 0.25)
		(keepout
			(tracks not_allowed)
			(vias allowed)
			(pads allowed)
			(copperpour not_allowed)
			(footprints allowed)
		)
		(placement
			(enabled no)
			(sheetname "")
		)
		(fill
			(thermal_gap 0.5)
			(thermal_bridge_width 0.5)
			(island_removal_mode 0)
		)
		(polygon
			(pts
				(arc
					(start 195.947792 -76.64196)
					(mid 195.563998 -77.025373)
					(end 195.947538 -77.40904)
				)
				(arc
					(start 196.929502 -77.40904)
					(mid 197.313042 -77.0255)
					(end 196.929502 -76.64196)
				)
				(arc
					(start 196.776848 -76.64196)
					(mid 196.800331 -76.697774)
					(end 196.827394 -76.751942)
				)
				(arc
					(start 196.827394 -76.751942)
					(mid 197.104989 -77.259126)
					(end 196.694298 -76.852272)
				)
				(arc
					(start 196.694298 -76.852272)
					(mid 196.642678 -76.749536)
					(end 196.602096 -76.64196)
				)
				(arc
					(start 196.291454 -76.64196)
					(mid 196.243756 -76.751802)
					(end 196.18579 -76.85659)
				)
				(arc
					(start 196.18579 -76.85659)
					(mid 195.767224 -77.255242)
					(end 196.05498 -76.753974)
				)
				(arc
					(start 196.05498 -76.753974)
					(mid 196.085557 -76.698805)
					(end 196.112892 -76.64196)
				)
			)
		)
	)
	(zone
		(layer "F.Cu")
		(hatch none 0.5)
		(connect_pads
			(clearance 0)
		)
		(min_thickness 0.25)
		(keepout
			(tracks not_allowed)
			(vias allowed)
			(pads allowed)
			(copperpour not_allowed)
			(footprints allowed)
		)
		(placement
			(enabled no)
			(sheetname "")
		)
		(fill
			(thermal_gap 0.5)
			(thermal_bridge_width 0.5)
			(island_removal_mode 0)
		)
		(polygon
			(pts
				(arc
					(start 48.803052 -86.99373)
					(mid 48.706927 -87.044006)
					(end 48.606456 -87.084916)
				)
				(arc
					(start 48.606456 -87.430356)
					(mid 48.706934 -87.47125)
					(end 48.803052 -87.521542)
				)
				(arc
					(start 48.803052 -87.521542)
					(mid 49.222055 -87.923621)
					(end 48.725074 -87.623142)
				)
				(arc
					(start 48.725074 -87.623142)
					(mid 48.666696 -87.592635)
					(end 48.606456 -87.565992)
				)
				(arc
					(start 48.606456 -87.746078)
					(mid 48.989996 -88.129618)
					(end 49.373536 -87.746078)
				)
				(arc
					(start 49.373536 -86.769448)
					(mid 48.990123 -86.385654)
					(end 48.606456 -86.769194)
				)
				(arc
					(start 48.606456 -86.94928)
					(mid 48.666697 -86.92264)
					(end 48.725074 -86.89213)
				)
				(arc
					(start 48.725074 -86.89213)
					(mid 49.222088 -86.591626)
					(end 48.803052 -86.99373)
				)
			)
		)
	)
	(zone
		(net "P1V8_C")
		(layer "F.Cu")
		(hatch none 0.5)
		(connect_pads
			(clearance 0.5)
		)
		(min_thickness 0.25)
		(fill yes
			(thermal_gap 0.5)
			(thermal_bridge_width 0.5)
			(island_removal_mode 0)
		)
		(polygon
			(pts
				(xy 243.84 -52.705) (xy 243.332 -53.213) (xy 243.332 -62.357) (xy 266.954 -85.979) (xy 266.954 -90.805)
				(xy 275.082 -98.933) (xy 275.082 -105.537) (xy 276.352 -106.807) (xy 279.146 -106.807) (xy 279.4 -106.553)
				(xy 279.4 -97.79) (xy 271.272 -89.662) (xy 271.272 -86.613746) (xy 247.015254 -62.357) (xy 247.015254 -54.229254)
				(xy 245.491 -52.705)
			)
		)
		(polygon
			(pts
				(xy 276.098 -104.9528) (xy 275.844 -104.9528) (xy 275.844 -105.2068) (xy 276.098 -105.2068)
			)
		)
		(polygon
			(pts
				(xy 277.1394 -104.8512) (xy 276.8854 -104.8512) (xy 276.8854 -105.1052) (xy 277.1394 -105.1052)
			)
		)
		(polygon
			(pts
				(xy 276.5806 -104.8512) (xy 276.3266 -104.8512) (xy 276.3266 -105.1052) (xy 276.5806 -105.1052)
			)
		)
	)
	(zone
		(layer "F.Cu")
		(hatch none 0.5)
		(connect_pads
			(clearance 0)
		)
		(min_thickness 0.25)
		(keepout
			(tracks not_allowed)
			(vias allowed)
			(pads allowed)
			(copperpour not_allowed)
			(footprints allowed)
		)
		(placement
			(enabled no)
			(sheetname "")
		)
		(fill
			(thermal_gap 0.5)
			(thermal_bridge_width 0.5)
			(island_removal_mode 0)
		)
		(polygon
			(pts
				(arc
					(start 132.59054 -88.376252)
					(mid 132.207127 -87.992458)
					(end 131.82346 -88.375998)
				)
				(xy 131.82346 -88.4555)
				(arc
					(start 131.861814 -88.4555)
					(mid 131.893267 -88.454371)
					(end 131.924552 -88.450928)
				)
				(arc
					(start 131.924552 -88.450928)
					(mid 132.464424 -88.237918)
					(end 131.987036 -88.568022)
				)
				(arc
					(start 131.987036 -88.568022)
					(mid 131.938195 -88.577087)
					(end 131.888738 -88.581738)
				)
				(xy 131.88823 -88.5825) (xy 131.82346 -88.5825) (xy 131.82346 -89.0905) (xy 131.926838 -89.0905)
				(arc
					(start 131.927346 -89.091262)
					(mid 131.953836 -89.093356)
					(end 131.980178 -89.09685)
				)
				(arc
					(start 131.980178 -89.09685)
					(mid 132.470123 -89.407987)
					(end 131.921758 -89.218008)
				)
				(xy 131.900422 -89.2175) (xy 131.82346 -89.2175)
				(arc
					(start 131.82346 -89.281)
					(mid 132.207 -89.66454)
					(end 132.59054 -89.281)
				)
			)
		)
	)
	(zone
		(net "P1V8_E")
		(layer "F.Cu")
		(hatch none 0.5)
		(connect_pads
			(clearance 0.5)
		)
		(min_thickness 0.25)
		(fill yes
			(thermal_gap 0.5)
			(thermal_bridge_width 0.5)
			(island_removal_mode 0)
		)
		(polygon
			(pts
				(xy 58.039 -144.272) (xy 57.531 -144.78) (xy 57.531 -163.703) (xy 52.197 -169.037) (xy 52.197 -179.705)
				(xy 52.451 -179.959) (xy 56.515 -179.959) (xy 56.769 -179.705) (xy 56.769 -172.847) (xy 61.468 -168.148)
				(xy 61.468 -144.653) (xy 61.087 -144.272)
			)
		)
		(polygon
			(pts
				(xy 56.5404 -179.2478) (xy 56.2864 -179.2478) (xy 56.2864 -179.5018) (xy 56.5404 -179.5018)
			)
		)
		(polygon
			(pts
				(xy 55.9816 -179.2478) (xy 55.7276 -179.2478) (xy 55.7276 -179.5018) (xy 55.9816 -179.5018)
			)
		)
		(polygon
			(pts
				(xy 55.3974 -179.2478) (xy 55.1434 -179.2478) (xy 55.1434 -179.5018) (xy 55.3974 -179.5018)
			)
		)
		(polygon
			(pts
				(xy 54.8386 -179.2478) (xy 54.5846 -179.2478) (xy 54.5846 -179.5018) (xy 54.8386 -179.5018)
			)
		)
		(polygon
			(pts
				(xy 54.2544 -179.2478) (xy 54.0004 -179.2478) (xy 54.0004 -179.5018) (xy 54.2544 -179.5018)
			)
		)
		(polygon
			(pts
				(xy 53.6956 -179.2478) (xy 53.4416 -179.2478) (xy 53.4416 -179.5018) (xy 53.6956 -179.5018)
			)
		)
		(polygon
			(pts
				(xy 53.1114 -179.2478) (xy 52.8574 -179.2478) (xy 52.8574 -179.5018) (xy 53.1114 -179.5018)
			)
		)
		(polygon
			(pts
				(xy 60.99937 -144.8054) (xy 60.74537 -144.8054) (xy 60.74537 -145.0594) (xy 60.99937 -145.0594)
			)
		)
		(polygon
			(pts
				(xy 60.38977 -144.8054) (xy 60.13577 -144.8054) (xy 60.13577 -145.0594) (xy 60.38977 -145.0594)
			)
		)
		(polygon
			(pts
				(xy 60.000642 -144.775682) (xy 59.746642 -144.775682) (xy 59.746642 -145.029682) (xy 60.000642 -145.029682)
			)
		)
		(polygon
			(pts
				(xy 59.441842 -144.775682) (xy 59.187842 -144.775682) (xy 59.187842 -145.029682) (xy 59.441842 -145.029682)
			)
		)
	)
	(zone
		(net "P5V_STBY_SW")
		(layer "F.Cu")
		(hatch none 0.5)
		(connect_pads
			(clearance 0.5)
		)
		(min_thickness 0.25)
		(fill yes
			(thermal_gap 0.5)
			(thermal_bridge_width 0.5)
			(island_removal_mode 0)
		)
		(polygon
			(pts
				(xy 337.058 -101.346) (xy 336.804 -101.6) (xy 336.804 -104.648) (xy 337.566 -105.41) (xy 337.566 -107.315)
				(xy 338.709 -108.458) (xy 341.503 -108.458) (xy 342.011 -107.95) (xy 342.011 -106.172) (xy 343.916 -104.267)
				(xy 343.916 -101.6) (xy 343.662 -101.346)
			)
		)
		(polygon
			(pts
				(xy 341.249 -106.9848) (xy 340.995 -106.9848) (xy 340.995 -107.2388) (xy 341.249 -107.2388)
			)
		)
		(polygon
			(pts
				(xy 338.582 -106.9848) (xy 338.328 -106.9848) (xy 338.328 -107.2388) (xy 338.582 -107.2388)
			)
		)
		(polygon
			(pts
				(xy 341.249 -106.1212) (xy 340.995 -106.1212) (xy 340.995 -106.3752) (xy 341.249 -106.3752)
			)
		)
		(polygon
			(pts
				(xy 338.582 -106.1212) (xy 338.328 -106.1212) (xy 338.328 -106.3752) (xy 338.582 -106.3752)
			)
		)
	)
	(zone
		(layer "F.Cu")
		(hatch none 0.5)
		(connect_pads
			(clearance 0)
		)
		(min_thickness 0.25)
		(keepout
			(tracks allowed)
			(vias allowed)
			(pads allowed)
			(copperpour allowed)
			(footprints allowed)
		)
		(placement
			(enabled no)
			(sheetname "")
		)
		(fill
			(thermal_gap 0.5)
			(thermal_bridge_width 0.5)
			(island_removal_mode 0)
		)
		(polygon
			(pts
				(xy 243.459 -114.935) (xy 243.459 -113.919) (xy 245.237 -113.919) (xy 245.237 -114.935)
			)
		)
	)
	(zone
		(net "GND")
		(layer "F.Cu")
		(hatch none 0.5)
		(connect_pads
			(clearance 0.5)
		)
		(min_thickness 0.25)
		(fill yes
			(thermal_gap 0.5)
			(thermal_bridge_width 0.5)
			(island_removal_mode 0)
		)
		(polygon
			(pts
				(xy 322.961 -86.233) (xy 322.326 -86.868) (xy 322.326 -97.155) (xy 322.961 -97.79) (xy 327.152 -97.79)
				(xy 327.533 -97.409) (xy 327.533 -86.995) (xy 326.771 -86.233)
			)
		)
		(polygon
			(pts
				(xy 326.771 -92.5068) (xy 326.517 -92.5068) (xy 326.517 -92.7608) (xy 326.771 -92.7608)
			)
		)
		(polygon
			(pts
				(xy 326.771 -91.6432) (xy 326.517 -91.6432) (xy 326.517 -91.8972) (xy 326.771 -91.8972)
			)
		)
	)
	(zone
		(layer "F.Cu")
		(hatch none 0.5)
		(connect_pads
			(clearance 0)
		)
		(min_thickness 0.25)
		(keepout
			(tracks allowed)
			(vias allowed)
			(pads allowed)
			(copperpour allowed)
			(footprints not_allowed)
		)
		(placement
			(enabled no)
			(sheetname "")
		)
		(fill
			(thermal_gap 0.5)
			(thermal_bridge_width 0.5)
			(island_removal_mode 0)
		)
		(polygon
			(pts
				(xy 236.199934 -82.350102) (xy 236.199934 -109.000036) (xy 249.899932 -109.000036) (xy 249.899932 -82.350102)
			)
		)
	)
	(zone
		(layer "F.Cu")
		(hatch none 0.5)
		(connect_pads
			(clearance 0)
		)
		(min_thickness 0.25)
		(keepout
			(tracks allowed)
			(vias allowed)
			(pads allowed)
			(copperpour allowed)
			(footprints not_allowed)
		)
		(placement
			(enabled no)
			(sheetname "")
		)
		(fill
			(thermal_gap 0.5)
			(thermal_bridge_width 0.5)
			(island_removal_mode 0)
		)
		(polygon
			(pts
				(xy 61.900054 -44.500038) (xy 72.749918 -44.500038) (xy 72.749918 -109.000036) (xy 58.950098 -109.000036)
				(xy 58.950098 -58.010044)
				(arc
					(start 60.950094 -58.010044)
					(mid 61.58304 -57.784032)
					(end 61.930026 -57.20842)
				)
			)
		)
	)
	(zone
		(layer "F.Cu")
		(hatch none 0.5)
		(connect_pads
			(clearance 0)
		)
		(min_thickness 0.25)
		(keepout
			(tracks allowed)
			(vias allowed)
			(pads allowed)
			(copperpour allowed)
			(footprints allowed)
		)
		(placement
			(enabled no)
			(sheetname "")
		)
		(fill
			(thermal_gap 0.5)
			(thermal_bridge_width 0.5)
			(island_removal_mode 0)
		)
		(polygon
			(pts
				(xy 146.431 -62.103) (xy 146.431 -59.944) (xy 147.574 -59.944) (xy 147.574 -62.103)
			)
		)
	)
	(zone
		(net "GND")
		(layer "F.Cu")
		(hatch none 0.5)
		(connect_pads
			(clearance 0.5)
		)
		(min_thickness 0.25)
		(fill yes
			(thermal_gap 0.5)
			(thermal_bridge_width 0.5)
			(island_removal_mode 0)
		)
		(polygon
			(pts
				(xy 196.215 -86.995) (xy 195.707 -87.503) (xy 195.707 -98.425) (xy 196.088 -98.806) (xy 198.12 -98.806)
				(xy 198.501 -98.425) (xy 198.501 -91.059) (xy 198.882 -90.678) (xy 198.882 -89.789) (xy 199.136 -89.535)
				(xy 202.565 -89.535) (xy 202.819 -89.281) (xy 202.819 -87.249) (xy 202.565 -86.995)
			)
		)
		(polygon
			(pts
				(xy 198.374 -90.4748) (xy 198.12 -90.4748) (xy 198.12 -90.7288) (xy 198.374 -90.7288)
			)
		)
		(polygon
			(pts
				(xy 198.374 -89.8652) (xy 198.12 -89.8652) (xy 198.12 -90.1192) (xy 198.374 -90.1192)
			)
		)
	)
	(zone
		(net "GND")
		(layer "F.Cu")
		(hatch none 0.5)
		(connect_pads
			(clearance 0.5)
		)
		(min_thickness 0.25)
		(fill yes
			(thermal_gap 0.5)
			(thermal_bridge_width 0.5)
			(island_removal_mode 0)
		)
		(polygon
			(pts
				(xy 293.43858 -171.96562) (xy 293.10076 -172.30344) (xy 289.7759 -172.30344) (xy 289.64636 -172.43298)
				(xy 289.64636 -173.14672) (xy 289.82924 -173.3296) (xy 289.82924 -179.03698) (xy 290.1442 -179.35194)
				(xy 297.14952 -179.35194) (xy 297.18508 -179.3875) (xy 297.33748 -179.2351) (xy 297.33748 -172.11802)
				(xy 297.18508 -171.96562)
			)
		)
	)
	(zone
		(net "P1V8_C")
		(layer "F.Cu")
		(hatch none 0.5)
		(connect_pads
			(clearance 0.5)
		)
		(min_thickness 0.25)
		(fill yes
			(thermal_gap 0.5)
			(thermal_bridge_width 0.5)
			(island_removal_mode 0)
		)
		(polygon
			(pts
				(xy 121.031 -33.528) (xy 120.523 -34.036) (xy 120.523 -37.592) (xy 120.904 -37.973) (xy 121.666 -37.973)
				(xy 123.571 -36.068) (xy 135.001 -36.068) (xy 137.668 -38.735) (xy 143.51 -38.735) (xy 143.637 -38.608)
				(xy 143.637 -36.068) (xy 141.097 -33.528)
			)
		)
		(polygon
			(pts
				(xy 143.1036 -38.0238) (xy 142.8496 -38.0238) (xy 142.8496 -38.2778) (xy 143.1036 -38.2778)
			)
		)
		(polygon
			(pts
				(xy 142.3924 -38.0238) (xy 142.1384 -38.0238) (xy 142.1384 -38.2778) (xy 142.3924 -38.2778)
			)
		)
		(polygon
			(pts
				(xy 141.8336 -38.0238) (xy 141.5796 -38.0238) (xy 141.5796 -38.2778) (xy 141.8336 -38.2778)
			)
		)
		(polygon
			(pts
				(xy 141.1224 -38.0238) (xy 140.8684 -38.0238) (xy 140.8684 -38.2778) (xy 141.1224 -38.2778)
			)
		)
		(polygon
			(pts
				(xy 140.5636 -38.0238) (xy 140.3096 -38.0238) (xy 140.3096 -38.2778) (xy 140.5636 -38.2778)
			)
		)
		(polygon
			(pts
				(xy 138.0236 -38.0238) (xy 137.7696 -38.0238) (xy 137.7696 -38.2778) (xy 138.0236 -38.2778)
			)
		)
	)
	(zone
		(net "GND")
		(layer "F.Cu")
		(hatch none 0.5)
		(connect_pads
			(clearance 0.5)
		)
		(min_thickness 0.25)
		(fill yes
			(thermal_gap 0.5)
			(thermal_bridge_width 0.5)
			(island_removal_mode 0)
		)
		(polygon
			(pts
				(xy 307.213 -53.086) (xy 306.832 -53.467) (xy 306.832 -54.229) (xy 306.959 -54.356) (xy 309.626 -54.356)
				(xy 309.753 -54.229) (xy 309.753 -53.213) (xy 309.626 -53.086)
			)
		)
	)
	(zone
		(layer "F.Cu")
		(hatch none 0.5)
		(connect_pads
			(clearance 0)
		)
		(min_thickness 0.25)
		(keepout
			(tracks allowed)
			(vias allowed)
			(pads allowed)
			(copperpour allowed)
			(footprints allowed)
		)
		(placement
			(enabled no)
			(sheetname "")
		)
		(fill
			(thermal_gap 0.5)
			(thermal_bridge_width 0.5)
			(island_removal_mode 0)
		)
		(polygon
			(pts
				(xy 255.905 -131.064) (xy 255.905 -128.651) (xy 258.318 -128.651) (xy 258.318 -131.064)
			)
		)
	)
	(zone
		(net "P3V3_STBY")
		(layer "F.Cu")
		(hatch none 0.5)
		(connect_pads
			(clearance 0.5)
		)
		(min_thickness 0.25)
		(fill yes
			(thermal_gap 0.5)
			(thermal_bridge_width 0.5)
			(island_removal_mode 0)
		)
		(polygon
			(pts
				(xy 320.04 -166.497) (xy 319.913 -166.624) (xy 319.913 -168.148) (xy 320.04 -168.275) (xy 321.564 -168.275)
				(xy 321.691 -168.148) (xy 321.691 -166.624) (xy 321.564 -166.497)
			)
		)
		(polygon
			(pts
				(xy 320.7512 -167.4876) (xy 320.4972 -167.4876) (xy 320.4972 -167.7416) (xy 320.7512 -167.7416)
			)
		)
		(polygon
			(pts
				(xy 320.7512 -167.0304) (xy 320.4972 -167.0304) (xy 320.4972 -167.2844) (xy 320.7512 -167.2844)
			)
		)
	)
	(zone
		(layer "F.Cu")
		(hatch none 0.5)
		(connect_pads
			(clearance 0)
		)
		(min_thickness 0.25)
		(keepout
			(tracks not_allowed)
			(vias allowed)
			(pads allowed)
			(copperpour not_allowed)
			(footprints allowed)
		)
		(placement
			(enabled no)
			(sheetname "")
		)
		(fill
			(thermal_gap 0.5)
			(thermal_bridge_width 0.5)
			(island_removal_mode 0)
		)
		(polygon
			(pts
				(arc
					(start 35.382454 -89.712546)
					(mid 34.998914 -90.096086)
					(end 35.382454 -90.479626)
				)
				(arc
					(start 36.359084 -90.479626)
					(mid 36.742878 -90.096213)
					(end 36.359338 -89.712546)
				)
				(arc
					(start 36.130738 -89.712546)
					(mid 36.163118 -89.783011)
					(end 36.205922 -89.847674)
				)
				(arc
					(start 36.205922 -89.847674)
					(mid 36.562912 -90.305499)
					(end 36.114482 -89.936828)
				)
				(arc
					(start 36.114482 -89.936828)
					(mid 36.04445 -89.830628)
					(end 35.997134 -89.712546)
				)
				(arc
					(start 35.732974 -89.712546)
					(mid 35.689351 -89.828094)
					(end 35.625024 -89.933526)
				)
				(arc
					(start 35.625024 -89.933526)
					(mid 35.181455 -90.3079)
					(end 35.53206 -89.845388)
				)
				(arc
					(start 35.53206 -89.845388)
					(mid 35.570759 -89.781355)
					(end 35.600132 -89.712546)
				)
			)
		)
	)
	(zone
		(net "SYSPLL_VDDA09")
		(layer "F.Cu")
		(hatch none 0.5)
		(connect_pads
			(clearance 0.5)
		)
		(min_thickness 0.25)
		(fill yes
			(thermal_gap 0.5)
			(thermal_bridge_width 0.5)
			(island_removal_mode 0)
		)
		(polygon
			(pts
				(xy 89.008966 -84.201) (xy 88.754966 -84.455) (xy 88.754966 -89.027) (xy 87.992966 -89.789) (xy 82.277966 -89.789)
				(xy 81.896966 -89.408) (xy 80.880966 -89.408) (xy 80.753966 -89.535) (xy 80.753966 -92.329) (xy 80.880966 -92.456)
				(xy 82.150966 -92.456) (xy 82.277966 -92.329) (xy 82.277966 -91.821) (xy 82.912966 -91.186) (xy 89.008966 -91.186)
				(xy 90.659966 -89.535) (xy 90.659966 -84.328) (xy 90.532966 -84.201)
			)
		)
		(polygon
			(pts
				(xy 81.211166 -90.0684) (xy 80.957166 -90.0684) (xy 80.957166 -90.3224) (xy 81.211166 -90.3224)
			)
		)
	)
	(zone
		(net "GND")
		(layer "F.Cu")
		(hatch none 0.5)
		(connect_pads
			(clearance 0.5)
		)
		(min_thickness 0.25)
		(fill yes
			(thermal_gap 0.5)
			(thermal_bridge_width 0.5)
			(island_removal_mode 0)
		)
		(polygon
			(pts
				(xy 1.143 -219.075) (xy 0.889 -219.329) (xy 0.889 -246.634) (xy 4.318 -250.063) (xy 26.162 -250.063)
				(xy 26.416 -249.809) (xy 26.416 -249.174) (xy 21.336 -244.094) (xy 11.684 -244.094) (xy 5.334 -237.744)
				(xy 5.334 -219.964) (xy 4.445 -219.075)
			)
		)
	)
	(zone
		(net "P1V8_STBY")
		(layer "F.Cu")
		(hatch none 0.5)
		(connect_pads
			(clearance 0.5)
		)
		(min_thickness 0.25)
		(fill yes
			(thermal_gap 0.5)
			(thermal_bridge_width 0.5)
			(island_removal_mode 0)
		)
		(polygon
			(pts
				(xy 72.14997 -108.712) (xy 68.396358 -112.465612) (xy 65.588388 -112.465612) (xy 57.531 -120.523)
				(xy 54.229 -120.523) (xy 46.99 -127.762) (xy 41.03497 -127.762) (xy 34.29 -134.50697) (xy 34.29 -141.351)
				(xy 37.592 -144.653) (xy 37.592 -146.812) (xy 38.862 -148.082) (xy 42.672 -148.082) (xy 43.307 -147.447)
				(xy 43.307 -144.018) (xy 41.529 -142.24) (xy 39.37 -142.24) (xy 37.345112 -140.215112) (xy 37.345112 -136.024112)
				(xy 43.314112 -130.055112) (xy 50.284888 -130.055112) (xy 55.753 -124.587) (xy 61.60897 -124.587)
				(xy 73.80097 -112.395) (xy 73.80097 -109.093) (xy 73.41997 -108.712)
			)
		)
	)
	(zone
		(layer "F.Cu")
		(hatch none 0.5)
		(connect_pads
			(clearance 0)
		)
		(min_thickness 0.25)
		(keepout
			(tracks allowed)
			(vias allowed)
			(pads allowed)
			(copperpour allowed)
			(footprints allowed)
		)
		(placement
			(enabled no)
			(sheetname "")
		)
		(fill
			(thermal_gap 0.5)
			(thermal_bridge_width 0.5)
			(island_removal_mode 0)
		)
		(polygon
			(pts
				(xy 54.483 -222.758) (xy 54.483 -220.472) (xy 58.674 -220.472) (xy 58.674 -222.758)
			)
		)
	)
	(zone
		(net "P0V9_E_VIN")
		(layer "F.Cu")
		(hatch none 0.5)
		(connect_pads
			(clearance 0.5)
		)
		(min_thickness 0.25)
		(fill yes
			(thermal_gap 0.5)
			(thermal_bridge_width 0.5)
			(island_removal_mode 0)
		)
		(polygon
			(pts
				(xy 170.815 -117.729) (xy 170.688 -117.856) (xy 170.688 -118.999) (xy 171.323 -119.634) (xy 171.323 -122.682)
				(xy 170.434 -123.571) (xy 170.434 -128.778) (xy 169.037 -130.175) (xy 169.037 -132.588) (xy 169.291 -132.842)
				(xy 173.736 -132.842) (xy 173.99 -132.588) (xy 173.99 -117.983) (xy 173.736 -117.729)
			)
		)
		(polygon
			(pts
				(xy 173.101 -120.4468) (xy 172.847 -120.4468) (xy 172.847 -120.7008) (xy 173.101 -120.7008)
			)
		)
		(polygon
			(pts
				(xy 173.101 -119.5832) (xy 172.847 -119.5832) (xy 172.847 -119.8372) (xy 173.101 -119.8372)
			)
		)
	)
	(zone
		(layer "F.Cu")
		(hatch none 0.5)
		(connect_pads
			(clearance 0)
		)
		(min_thickness 0.25)
		(keepout
			(tracks allowed)
			(vias allowed)
			(pads allowed)
			(copperpour allowed)
			(footprints allowed)
		)
		(placement
			(enabled no)
			(sheetname "")
		)
		(fill
			(thermal_gap 0.5)
			(thermal_bridge_width 0.5)
			(island_removal_mode 0)
		)
		(polygon
			(pts
				(xy 59.055 -227.203) (xy 59.055 -225.679) (xy 60.198 -225.679) (xy 60.198 -227.203)
			)
		)
	)
	(zone
		(net "GND")
		(layer "F.Cu")
		(hatch none 0.5)
		(connect_pads
			(clearance 0.5)
		)
		(min_thickness 0.25)
		(fill yes
			(thermal_gap 0.5)
			(thermal_bridge_width 0.5)
			(island_removal_mode 0)
		)
		(polygon
			(pts
				(xy 323.088 -179.832) (xy 322.961 -179.959) (xy 322.961 -182.118) (xy 323.088 -182.245) (xy 324.612 -182.245)
				(xy 324.739 -182.118) (xy 324.739 -179.959) (xy 324.612 -179.832)
			)
		)
		(polygon
			(pts
				(xy 324.2056 -181.5338) (xy 323.9516 -181.5338) (xy 323.9516 -181.7878) (xy 324.2056 -181.7878)
			)
		)
		(polygon
			(pts
				(xy 323.7738 -181.483) (xy 323.5198 -181.483) (xy 323.5198 -181.737) (xy 323.7738 -181.737)
			)
		)
		(polygon
			(pts
				(xy 323.7738 -180.34) (xy 323.5198 -180.34) (xy 323.5198 -180.594) (xy 323.7738 -180.594)
			)
		)
		(polygon
			(pts
				(xy 324.2056 -180.2892) (xy 323.9516 -180.2892) (xy 323.9516 -180.5432) (xy 324.2056 -180.5432)
			)
		)
	)
	(zone
		(net "P1V5_C")
		(layer "F.Cu")
		(hatch none 0.5)
		(connect_pads
			(clearance 0.5)
		)
		(min_thickness 0.25)
		(fill yes
			(thermal_gap 0.5)
			(thermal_bridge_width 0.5)
			(island_removal_mode 0)
		)
		(polygon
			(pts
				(xy 208.915 -93.345) (xy 208.661 -93.599) (xy 208.661 -93.98) (xy 208.534 -94.107) (xy 208.534 -102.87)
				(xy 208.661 -102.997) (xy 210.185 -102.997) (xy 211.328 -101.854) (xy 211.328 -93.599) (xy 211.074 -93.345)
			)
		)
		(polygon
			(pts
				(xy 209.3214 -102.2858) (xy 209.0674 -102.2858) (xy 209.0674 -102.5398) (xy 209.3214 -102.5398)
			)
		)
		(polygon
			(pts
				(xy 210.3628 -102.235) (xy 210.1088 -102.235) (xy 210.1088 -102.489) (xy 210.3628 -102.489)
			)
		)
		(polygon
			(pts
				(xy 209.7532 -102.235) (xy 209.4992 -102.235) (xy 209.4992 -102.489) (xy 209.7532 -102.489)
			)
		)
		(polygon
			(pts
				(xy 209.423 -93.7768) (xy 209.169 -93.7768) (xy 209.169 -94.0308) (xy 209.423 -94.0308)
			)
		)
	)
	(zone
		(layer "F.Cu")
		(hatch none 0.5)
		(connect_pads
			(clearance 0)
		)
		(min_thickness 0.25)
		(keepout
			(tracks not_allowed)
			(vias allowed)
			(pads allowed)
			(copperpour not_allowed)
			(footprints allowed)
		)
		(placement
			(enabled no)
			(sheetname "")
		)
		(fill
			(thermal_gap 0.5)
			(thermal_bridge_width 0.5)
			(island_removal_mode 0)
		)
		(polygon
			(pts
				(arc
					(start 270.999966 -10.199878)
					(mid 270.210026 -10.989818)
					(end 270.999966 -11.779758)
				)
				(xy 271.745964 -11.779758)
				(arc
					(start 271.745964 -11.34999)
					(mid 271.729118 -11.243792)
					(end 271.680178 -11.14806)
				)
				(arc
					(start 271.680178 -11.14806)
					(mid 270.303817 -10.934085)
					(end 271.696688 -10.941812)
				)
				(arc
					(start 271.696688 -10.941812)
					(mid 271.731219 -10.963826)
					(end 271.76222 -10.99058)
				)
				(arc
					(start 271.76222 -10.99058)
					(mid 271.865305 -11.13916)
					(end 271.909794 -11.31443)
				)
				(xy 271.911064 -11.3157) (xy 271.911064 -11.779758) (xy 272.088864 -11.779758) (xy 272.088864 -11.311128)
				(arc
					(start 272.090388 -11.309604)
					(mid 272.12599 -11.178212)
					(end 272.20418 -11.06678)
				)
				(arc
					(start 272.20418 -11.06678)
					(mid 272.250616 -11.025395)
					(end 272.301462 -10.989564)
				)
				(arc
					(start 272.301462 -10.989564)
					(mid 273.692061 -10.895722)
					(end 272.327116 -11.177524)
				)
				(arc
					(start 272.32102 -11.18362)
					(mid 272.271419 -11.257854)
					(end 272.253964 -11.345418)
				)
				(xy 272.253964 -11.779758)
				(arc
					(start 272.999962 -11.779758)
					(mid 273.789902 -10.989818)
					(end 272.999962 -10.199878)
				)
			)
		)
	)
	(zone
		(layer "F.Cu")
		(hatch none 0.5)
		(connect_pads
			(clearance 0)
		)
		(min_thickness 0.25)
		(keepout
			(tracks not_allowed)
			(vias allowed)
			(pads allowed)
			(copperpour not_allowed)
			(footprints allowed)
		)
		(placement
			(enabled no)
			(sheetname "")
		)
		(fill
			(thermal_gap 0.5)
			(thermal_bridge_width 0.5)
			(island_removal_mode 0)
		)
		(polygon
			(pts
				(arc
					(start 81.61274 -36.335462)
					(mid 81.229327 -35.951668)
					(end 80.84566 -36.335208)
				)
				(arc
					(start 80.84566 -37.312092)
					(mid 81.2292 -37.695632)
					(end 81.61274 -37.312092)
				)
				(xy 81.61274 -37.0586)
				(arc
					(start 81.588356 -37.0586)
					(mid 81.573776 -37.0615)
					(end 81.561432 -37.069776)
				)
				(arc
					(start 81.475834 -37.155374)
					(mid 81.022574 -37.518718)
					(end 81.385918 -37.065458)
				)
				(xy 81.490058 -36.961318)
				(arc
					(start 81.493868 -36.961318)
					(mid 81.525168 -36.944204)
					(end 81.5594 -36.93414)
				)
				(xy 81.56194 -36.9316) (xy 81.61274 -36.9316) (xy 81.61274 -36.7157) (xy 81.56194 -36.7157)
				(arc
					(start 81.5594 -36.71316)
					(mid 81.525143 -36.703156)
					(end 81.493868 -36.685982)
				)
				(xy 81.490058 -36.685982)
				(arc
					(start 81.385918 -36.581842)
					(mid 81.022574 -36.128582)
					(end 81.475834 -36.491926)
				)
				(arc
					(start 81.561432 -36.577524)
					(mid 81.573785 -36.585778)
					(end 81.588356 -36.5887)
				)
				(xy 81.61274 -36.5887)
			)
		)
	)
	(zone
		(layer "F.Cu")
		(hatch none 0.5)
		(connect_pads
			(clearance 0)
		)
		(min_thickness 0.25)
		(keepout
			(tracks allowed)
			(vias allowed)
			(pads allowed)
			(copperpour allowed)
			(footprints allowed)
		)
		(placement
			(enabled no)
			(sheetname "")
		)
		(fill
			(thermal_gap 0.5)
			(thermal_bridge_width 0.5)
			(island_removal_mode 0)
		)
		(polygon
			(pts
				(xy 18.796 -170.18) (xy 18.796 -168.402) (xy 19.685 -168.402) (xy 19.685 -170.18)
			)
		)
	)
	(zone
		(layer "F.Cu")
		(hatch none 0.5)
		(connect_pads
			(clearance 0)
		)
		(min_thickness 0.25)
		(keepout
			(tracks allowed)
			(vias allowed)
			(pads allowed)
			(copperpour allowed)
			(footprints allowed)
		)
		(placement
			(enabled no)
			(sheetname "")
		)
		(fill
			(thermal_gap 0.5)
			(thermal_bridge_width 0.5)
			(island_removal_mode 0)
		)
		(polygon
			(pts
				(xy 75.184 -129.032) (xy 75.184 -128.143) (xy 77.47 -128.143) (xy 77.47 -129.032)
			)
		)
	)
	(zone
		(layer "F.Cu")
		(hatch none 0.5)
		(connect_pads
			(clearance 0)
		)
		(min_thickness 0.25)
		(keepout
			(tracks allowed)
			(vias allowed)
			(pads allowed)
			(copperpour allowed)
			(footprints not_allowed)
		)
		(placement
			(enabled no)
			(sheetname "")
		)
		(fill
			(thermal_gap 0.5)
			(thermal_bridge_width 0.5)
			(island_removal_mode 0)
		)
		(polygon
			(pts
				(xy 119.000016 -59.30011) (xy 119.000016 -70.300088) (xy 130.50012 -70.300088) (xy 130.50012 -59.30011)
			)
		)
	)
	(zone
		(layer "F.Cu")
		(hatch none 0.5)
		(connect_pads
			(clearance 0)
		)
		(min_thickness 0.25)
		(keepout
			(tracks allowed)
			(vias allowed)
			(pads allowed)
			(copperpour allowed)
			(footprints allowed)
		)
		(placement
			(enabled no)
			(sheetname "")
		)
		(fill
			(thermal_gap 0.5)
			(thermal_bridge_width 0.5)
			(island_removal_mode 0)
		)
		(polygon
			(pts
				(xy 44.577 -120.396) (xy 44.577 -118.745) (xy 46.101 -118.745) (xy 46.482 -118.745) (xy 46.482 -120.396)
				(xy 46.101 -120.396)
			)
		)
	)
	(zone
		(net "TPS74801_1V5_C_EN")
		(layer "F.Cu")
		(hatch none 0.5)
		(connect_pads
			(clearance 0.5)
		)
		(min_thickness 0.25)
		(fill yes
			(thermal_gap 0.5)
			(thermal_bridge_width 0.5)
			(island_removal_mode 0)
		)
		(polygon
			(pts
				(xy 216.281 -103.886) (xy 216.154 -104.013) (xy 216.154 -105.664) (xy 215.646 -106.172) (xy 215.646 -107.569)
				(xy 217.297 -109.22) (xy 217.297 -109.855) (xy 217.678 -110.236) (xy 220.853 -110.236) (xy 220.98 -110.109)
				(xy 220.98 -108.204) (xy 218.059 -105.283) (xy 218.059 -104.267) (xy 217.678 -103.886)
			)
		)
		(polygon
			(pts
				(xy 220.6244 -109.5248) (xy 220.3704 -109.5248) (xy 220.3704 -109.7788) (xy 220.6244 -109.7788)
			)
		)
		(polygon
			(pts
				(xy 220.0656 -109.5248) (xy 219.8116 -109.5248) (xy 219.8116 -109.7788) (xy 220.0656 -109.7788)
			)
		)
		(polygon
			(pts
				(xy 219.4814 -109.5248) (xy 219.2274 -109.5248) (xy 219.2274 -109.7788) (xy 219.4814 -109.7788)
			)
		)
		(polygon
			(pts
				(xy 218.9226 -109.5248) (xy 218.6686 -109.5248) (xy 218.6686 -109.7788) (xy 218.9226 -109.7788)
			)
		)
		(polygon
			(pts
				(xy 218.4908 -109.474) (xy 218.2368 -109.474) (xy 218.2368 -109.728) (xy 218.4908 -109.728)
			)
		)
		(polygon
			(pts
				(xy 217.8812 -109.474) (xy 217.6272 -109.474) (xy 217.6272 -109.728) (xy 217.8812 -109.728)
			)
		)
	)
	(zone
		(net "GND")
		(layer "F.Cu")
		(hatch none 0.5)
		(connect_pads
			(clearance 0.5)
		)
		(min_thickness 0.25)
		(fill yes
			(thermal_gap 0.5)
			(thermal_bridge_width 0.5)
			(island_removal_mode 0)
		)
		(polygon
			(pts
				(xy 81.642966 -88.138) (xy 81.515966 -88.265) (xy 81.515966 -89.027) (xy 81.642966 -89.154) (xy 82.023966 -89.154)
				(xy 82.277966 -89.408) (xy 87.865966 -89.408) (xy 88.119966 -89.154) (xy 88.119966 -88.265) (xy 87.992966 -88.138)
			)
		)
		(polygon
			(pts
				(xy 87.815166 -88.3666) (xy 87.561166 -88.3666) (xy 87.561166 -88.6206) (xy 87.815166 -88.6206)
			)
		)
		(polygon
			(pts
				(xy 87.281766 -88.3666) (xy 86.672166 -88.3666) (xy 86.672166 -88.6206) (xy 87.281766 -88.6206)
			)
		)
	)
	(zone
		(net "GND")
		(layer "F.Cu")
		(hatch none 0.5)
		(connect_pads
			(clearance 0.5)
		)
		(min_thickness 0.25)
		(fill yes
			(thermal_gap 0.5)
			(thermal_bridge_width 0.5)
			(island_removal_mode 0)
		)
		(polygon
			(pts
				(xy 32.131 -214.884) (xy 32.004 -215.011) (xy 32.004 -218.313) (xy 33.274 -219.583) (xy 33.274 -227.1776)
				(xy 33.6296 -227.5332) (xy 33.8582 -227.5332) (xy 37.084 -230.759) (xy 54.483 -230.759) (xy 55.245 -229.997)
				(xy 55.245 -227.965) (xy 54.864 -227.584) (xy 52.451 -227.584) (xy 52.3875 -227.5205) (xy 48.7045 -227.5205)
				(xy 48.641 -227.457) (xy 45.593 -227.457) (xy 42.164 -224.028) (xy 42.164 -215.392) (xy 41.783 -215.011)
				(xy 33.909 -215.011) (xy 33.782 -214.884)
			)
		)
		(polygon
			(pts
				(xy 45.0088 -229.87) (xy 44.7548 -229.87) (xy 44.7548 -230.124) (xy 45.0088 -230.124)
			)
		)
		(polygon
			(pts
				(xy 44.3992 -229.87) (xy 44.1452 -229.87) (xy 44.1452 -230.124) (xy 44.3992 -230.124)
			)
		)
		(polygon
			(pts
				(xy 43.9928 -229.87) (xy 43.7388 -229.87) (xy 43.7388 -230.124) (xy 43.9928 -230.124)
			)
		)
		(polygon
			(pts
				(xy 43.3832 -229.87) (xy 43.1292 -229.87) (xy 43.1292 -230.124) (xy 43.3832 -230.124)
			)
		)
		(polygon
			(pts
				(xy 48.8188 -229.616) (xy 48.5648 -229.616) (xy 48.5648 -229.87) (xy 48.8188 -229.87)
			)
		)
		(polygon
			(pts
				(xy 47.9552 -229.616) (xy 47.7012 -229.616) (xy 47.7012 -229.87) (xy 47.9552 -229.87)
			)
		)
		(polygon
			(pts
				(xy 47.5488 -229.616) (xy 47.2948 -229.616) (xy 47.2948 -229.87) (xy 47.5488 -229.87)
			)
		)
		(polygon
			(pts
				(xy 46.6852 -229.616) (xy 46.4312 -229.616) (xy 46.4312 -229.87) (xy 46.6852 -229.87)
			)
		)
		(polygon
			(pts
				(xy 46.2788 -229.616) (xy 46.0248 -229.616) (xy 46.0248 -229.87) (xy 46.2788 -229.87)
			)
		)
		(polygon
			(pts
				(xy 45.4152 -229.616) (xy 45.1612 -229.616) (xy 45.1612 -229.87) (xy 45.4152 -229.87)
			)
		)
		(polygon
			(pts
				(xy 39.243 -215.5698) (xy 38.989 -215.5698) (xy 38.989 -215.8238) (xy 39.243 -215.8238)
			)
		)
	)
	(zone
		(net "GND")
		(layer "F.Cu")
		(hatch none 0.5)
		(connect_pads
			(clearance 0.5)
		)
		(min_thickness 0.25)
		(fill yes
			(thermal_gap 0.5)
			(thermal_bridge_width 0.5)
			(island_removal_mode 0)
		)
		(polygon
			(pts
				(xy 336.042 -107.696) (xy 335.788 -107.95) (xy 335.788 -110.236) (xy 335.915 -110.363) (xy 338.201 -110.363)
				(xy 338.709 -110.871) (xy 339.598 -110.871) (xy 339.725 -110.744) (xy 339.725 -109.728) (xy 337.693 -107.696)
			)
		)
		(polygon
			(pts
				(xy 336.5754 -109.6518) (xy 336.3214 -109.6518) (xy 336.3214 -109.9058) (xy 336.5754 -109.9058)
			)
		)
		(polygon
			(pts
				(xy 337.6168 -109.601) (xy 337.3628 -109.601) (xy 337.3628 -109.855) (xy 337.6168 -109.855)
			)
		)
		(polygon
			(pts
				(xy 337.0072 -109.601) (xy 336.7532 -109.601) (xy 336.7532 -109.855) (xy 337.0072 -109.855)
			)
		)
	)
	(zone
		(net "GND")
		(layer "F.Cu")
		(hatch none 0.5)
		(connect_pads
			(clearance 0.5)
		)
		(min_thickness 0.25)
		(fill yes
			(thermal_gap 0.5)
			(thermal_bridge_width 0.5)
			(island_removal_mode 0)
		)
		(polygon
			(pts
				(xy 83.166966 -91.567) (xy 82.785966 -91.948) (xy 82.785966 -92.837) (xy 82.404966 -93.218) (xy 73.641966 -93.218)
				(xy 73.641966 -101.981) (xy 74.403966 -102.743) (xy 89.154 -102.743) (xy 91.186 -100.711) (xy 91.694 -100.711)
				(xy 92.075 -100.33) (xy 92.075 -92.075) (xy 91.567 -91.567)
			)
		)
		(polygon
			(pts
				(xy 91.63177 -99.6696) (xy 91.37777 -99.6696) (xy 91.37777 -99.9236) (xy 91.63177 -99.9236)
			)
		)
		(polygon
			(pts
				(xy 91.63177 -99.0854) (xy 91.37777 -99.0854) (xy 91.37777 -99.3394) (xy 91.63177 -99.3394)
			)
		)
		(polygon
			(pts
				(xy 91.63177 -98.5266) (xy 91.37777 -98.5266) (xy 91.37777 -98.7806) (xy 91.63177 -98.7806)
			)
		)
		(polygon
			(pts
				(xy 91.63177 -97.9424) (xy 91.37777 -97.9424) (xy 91.37777 -98.1964) (xy 91.63177 -98.1964)
			)
		)
		(polygon
			(pts
				(xy 91.63177 -97.3836) (xy 91.37777 -97.3836) (xy 91.37777 -97.6376) (xy 91.63177 -97.6376)
			)
		)
		(polygon
			(pts
				(xy 91.63177 -96.7994) (xy 91.37777 -96.7994) (xy 91.37777 -97.0534) (xy 91.63177 -97.0534)
			)
		)
		(polygon
			(pts
				(xy 91.63177 -96.2406) (xy 91.37777 -96.2406) (xy 91.37777 -96.4946) (xy 91.63177 -96.4946)
			)
		)
		(polygon
			(pts
				(xy 91.63177 -95.6564) (xy 91.37777 -95.6564) (xy 91.37777 -95.9104) (xy 91.63177 -95.9104)
			)
		)
		(polygon
			(pts
				(xy 91.63177 -95.0976) (xy 91.37777 -95.0976) (xy 91.37777 -95.3516) (xy 91.63177 -95.3516)
			)
		)
		(polygon
			(pts
				(xy 91.63177 -94.3864) (xy 91.37777 -94.3864) (xy 91.37777 -94.6404) (xy 91.63177 -94.6404)
			)
		)
		(polygon
			(pts
				(xy 91.63177 -93.8276) (xy 91.37777 -93.8276) (xy 91.37777 -94.0816) (xy 91.63177 -94.0816)
			)
		)
		(polygon
			(pts
				(xy 88.170766 -91.7956) (xy 87.561166 -91.7956) (xy 87.561166 -92.0496) (xy 88.170766 -92.0496)
			)
		)
		(polygon
			(pts
				(xy 87.281766 -91.7956) (xy 86.672166 -91.7956) (xy 86.672166 -92.0496) (xy 87.281766 -92.0496)
			)
		)
	)
	(zone
		(layer "F.Cu")
		(hatch none 0.5)
		(connect_pads
			(clearance 0)
		)
		(min_thickness 0.25)
		(keepout
			(tracks allowed)
			(vias allowed)
			(pads allowed)
			(copperpour allowed)
			(footprints allowed)
		)
		(placement
			(enabled no)
			(sheetname "")
		)
		(fill
			(thermal_gap 0.5)
			(thermal_bridge_width 0.5)
			(island_removal_mode 0)
		)
		(polygon
			(pts
				(xy 14.732 -177.8) (xy 14.732 -175.387) (xy 16.764 -175.387) (xy 16.764 -177.8)
			)
		)
	)
	(zone
		(layer "F.Cu")
		(hatch none 0.5)
		(connect_pads
			(clearance 0)
		)
		(min_thickness 0.25)
		(keepout
			(tracks allowed)
			(vias allowed)
			(pads allowed)
			(copperpour allowed)
			(footprints not_allowed)
		)
		(placement
			(enabled no)
			(sheetname "")
		)
		(fill
			(thermal_gap 0.5)
			(thermal_bridge_width 0.5)
			(island_removal_mode 0)
		)
		(polygon
			(pts
				(arc
					(start 62.95009 -16.999966)
					(mid 62.242985 -17.292859)
					(end 61.950092 -17.999964)
				)
				(xy 61.950092 -44.500038) (xy 74.44994 -44.500038)
				(arc
					(start 74.44994 -15.999968)
					(mid 74.157047 -16.707073)
					(end 73.449942 -16.999966)
				)
			)
		)
	)
	(zone
		(net "GND")
		(layer "F.Cu")
		(hatch none 0.5)
		(connect_pads
			(clearance 0.5)
		)
		(min_thickness 0.25)
		(fill yes
			(thermal_gap 0.5)
			(thermal_bridge_width 0.5)
			(island_removal_mode 0)
		)
		(polygon
			(pts
				(xy 153.543 -22.606) (xy 153.162 -22.987) (xy 153.162 -24.892) (xy 172.212 -43.942) (xy 184.912 -43.942)
				(xy 185.166 -43.688) (xy 185.166 -38.608) (xy 184.912 -38.354) (xy 176.911 -38.354) (xy 175.768 -37.211)
				(xy 175.768 -34.925) (xy 175.641 -34.798) (xy 172.72 -34.798) (xy 171.577 -33.655) (xy 171.577 -32.893)
				(xy 171.45 -32.766) (xy 169.799 -32.766) (xy 168.275 -31.242) (xy 168.275 -26.416) (xy 168.656 -26.035)
				(xy 168.656 -24.892) (xy 168.148 -24.384) (xy 160.401 -24.384) (xy 158.623 -22.606)
			)
		)
		(polygon
			(pts
				(xy 184.560464 -38.756336) (xy 184.306464 -38.756336) (xy 184.306464 -39.010336) (xy 184.560464 -39.010336)
			)
		)
		(polygon
			(pts
				(xy 183.976264 -38.756336) (xy 183.722264 -38.756336) (xy 183.722264 -39.010336) (xy 183.976264 -39.010336)
			)
		)
		(polygon
			(pts
				(xy 183.417464 -38.756336) (xy 183.163464 -38.756336) (xy 183.163464 -39.010336) (xy 183.417464 -39.010336)
			)
		)
		(polygon
			(pts
				(xy 182.833264 -38.756336) (xy 182.579264 -38.756336) (xy 182.579264 -39.010336) (xy 182.833264 -39.010336)
			)
		)
		(polygon
			(pts
				(xy 182.274464 -38.756336) (xy 182.020464 -38.756336) (xy 182.020464 -39.010336) (xy 182.274464 -39.010336)
			)
		)
		(polygon
			(pts
				(xy 181.690264 -38.756336) (xy 181.436264 -38.756336) (xy 181.436264 -39.010336) (xy 181.690264 -39.010336)
			)
		)
		(polygon
			(pts
				(xy 181.131464 -38.756336) (xy 180.877464 -38.756336) (xy 180.877464 -39.010336) (xy 181.131464 -39.010336)
			)
		)
		(polygon
			(pts
				(xy 180.547264 -38.756336) (xy 180.293264 -38.756336) (xy 180.293264 -39.010336) (xy 180.547264 -39.010336)
			)
		)
		(polygon
			(pts
				(xy 179.988464 -38.756336) (xy 179.734464 -38.756336) (xy 179.734464 -39.010336) (xy 179.988464 -39.010336)
			)
		)
		(polygon
			(pts
				(xy 179.404264 -38.756336) (xy 179.150264 -38.756336) (xy 179.150264 -39.010336) (xy 179.404264 -39.010336)
			)
		)
		(polygon
			(pts
				(xy 178.845464 -38.756336) (xy 178.591464 -38.756336) (xy 178.591464 -39.010336) (xy 178.845464 -39.010336)
			)
		)
		(polygon
			(pts
				(xy 178.261264 -38.756336) (xy 178.007264 -38.756336) (xy 178.007264 -39.010336) (xy 178.261264 -39.010336)
			)
		)
		(polygon
			(pts
				(xy 177.702464 -38.756336) (xy 177.448464 -38.756336) (xy 177.448464 -39.010336) (xy 177.702464 -39.010336)
			)
		)
		(polygon
			(pts
				(xy 175.365664 -35.149536) (xy 175.111664 -35.149536) (xy 175.111664 -35.403536) (xy 175.365664 -35.403536)
			)
		)
		(polygon
			(pts
				(xy 171.049188 -33.256728) (xy 170.795188 -33.256728) (xy 170.795188 -33.510728) (xy 171.049188 -33.510728)
			)
		)
		(polygon
			(pts
				(xy 167.837104 -24.768556) (xy 167.583104 -24.768556) (xy 167.583104 -25.022556) (xy 167.837104 -25.022556)
			)
		)
		(polygon
			(pts
				(xy 167.252904 -24.768556) (xy 166.998904 -24.768556) (xy 166.998904 -25.022556) (xy 167.252904 -25.022556)
			)
		)
		(polygon
			(pts
				(xy 166.694104 -24.768556) (xy 166.440104 -24.768556) (xy 166.440104 -25.022556) (xy 166.694104 -25.022556)
			)
		)
		(polygon
			(pts
				(xy 166.109904 -24.768556) (xy 165.855904 -24.768556) (xy 165.855904 -25.022556) (xy 166.109904 -25.022556)
			)
		)
		(polygon
			(pts
				(xy 165.551104 -24.768556) (xy 165.297104 -24.768556) (xy 165.297104 -25.022556) (xy 165.551104 -25.022556)
			)
		)
		(polygon
			(pts
				(xy 164.966904 -24.768556) (xy 164.712904 -24.768556) (xy 164.712904 -25.022556) (xy 164.966904 -25.022556)
			)
		)
		(polygon
			(pts
				(xy 164.408104 -24.768556) (xy 164.154104 -24.768556) (xy 164.154104 -25.022556) (xy 164.408104 -25.022556)
			)
		)
		(polygon
			(pts
				(xy 163.823904 -24.768556) (xy 163.569904 -24.768556) (xy 163.569904 -25.022556) (xy 163.823904 -25.022556)
			)
		)
		(polygon
			(pts
				(xy 163.265104 -24.768556) (xy 163.011104 -24.768556) (xy 163.011104 -25.022556) (xy 163.265104 -25.022556)
			)
		)
		(polygon
			(pts
				(xy 162.680904 -24.768556) (xy 162.426904 -24.768556) (xy 162.426904 -25.022556) (xy 162.680904 -25.022556)
			)
		)
		(polygon
			(pts
				(xy 162.122104 -24.768556) (xy 161.868104 -24.768556) (xy 161.868104 -25.022556) (xy 162.122104 -25.022556)
			)
		)
	)
	(zone
		(layer "F.Cu")
		(hatch none 0.5)
		(connect_pads
			(clearance 0)
		)
		(min_thickness 0.25)
		(keepout
			(tracks allowed)
			(vias allowed)
			(pads allowed)
			(copperpour allowed)
			(footprints not_allowed)
		)
		(placement
			(enabled no)
			(sheetname "")
		)
		(fill
			(thermal_gap 0.5)
			(thermal_bridge_width 0.5)
			(island_removal_mode 0)
		)
		(polygon
			(pts
				(xy 326.300084 -61.237368) (xy 326.300084 -72.237346) (xy 337.799934 -72.237346) (xy 337.799934 -61.237368)
			)
		)
	)
	(zone
		(layer "F.Cu")
		(hatch none 0.5)
		(connect_pads
			(clearance 0)
		)
		(min_thickness 0.25)
		(keepout
			(tracks allowed)
			(vias allowed)
			(pads allowed)
			(copperpour allowed)
			(footprints allowed)
		)
		(placement
			(enabled no)
			(sheetname "")
		)
		(fill
			(thermal_gap 0.5)
			(thermal_bridge_width 0.5)
			(island_removal_mode 0)
		)
		(polygon
			(pts
				(xy 184.277 -36.449) (xy 184.277 -33.909) (xy 185.928 -33.909) (xy 185.928 -36.449)
			)
		)
	)
	(zone
		(net "P1V8_E")
		(layer "F.Cu")
		(hatch none 0.5)
		(connect_pads
			(clearance 0.5)
		)
		(min_thickness 0.25)
		(fill yes
			(thermal_gap 0.5)
			(thermal_bridge_width 0.5)
			(island_removal_mode 0)
		)
		(polygon
			(pts
				(xy 91.45397 -101.092) (xy 86.50097 -106.045) (xy 78.49997 -106.045) (xy 78.11897 -106.426) (xy 78.11897 -108.3056)
				(xy 77.67701 -108.74756) (xy 76.32065 -108.74756) (xy 75.65517 -109.41304) (xy 75.15225 -109.41304)
				(xy 75.14463 -109.40542) (xy 74.74331 -109.40542) (xy 74.30389 -109.84484) (xy 74.30389 -111.24692)
				(xy 74.39279 -111.33582) (xy 74.40803 -111.33582) (xy 74.94651 -111.8743) (xy 78.36027 -111.8743)
				(xy 78.37297 -111.887) (xy 93.472 -111.887) (xy 94.240858 -111.118142) (xy 94.240858 -110.116112)
				(xy 94.62897 -109.728) (xy 95.26397 -109.728) (xy 95.51797 -109.474) (xy 95.51797 -106.934) (xy 95.26397 -106.68)
				(xy 92.46997 -106.68) (xy 92.21597 -106.426) (xy 92.21597 -101.219) (xy 92.08897 -101.092)
			)
		)
		(polygon
			(pts
				(xy 93.1672 -111.4044) (xy 92.9132 -111.4044) (xy 92.9132 -111.6584) (xy 93.1672 -111.6584)
			)
		)
		(polygon
			(pts
				(xy 92.64777 -111.4044) (xy 92.03817 -111.4044) (xy 92.03817 -111.6584) (xy 92.64777 -111.6584)
			)
		)
		(polygon
			(pts
				(xy 91.63177 -111.4044) (xy 91.02217 -111.4044) (xy 91.02217 -111.6584) (xy 91.63177 -111.6584)
			)
		)
		(polygon
			(pts
				(xy 90.61577 -111.4044) (xy 90.00617 -111.4044) (xy 90.00617 -111.6584) (xy 90.61577 -111.6584)
			)
		)
		(polygon
			(pts
				(xy 89.59977 -111.4044) (xy 88.99017 -111.4044) (xy 88.99017 -111.6584) (xy 89.59977 -111.6584)
			)
		)
		(polygon
			(pts
				(xy 88.58377 -111.4044) (xy 87.97417 -111.4044) (xy 87.97417 -111.6584) (xy 88.58377 -111.6584)
			)
		)
		(polygon
			(pts
				(xy 87.56777 -111.4044) (xy 86.95817 -111.4044) (xy 86.95817 -111.6584) (xy 87.56777 -111.6584)
			)
		)
		(polygon
			(pts
				(xy 86.55177 -111.4044) (xy 85.94217 -111.4044) (xy 85.94217 -111.6584) (xy 86.55177 -111.6584)
			)
		)
		(polygon
			(pts
				(xy 85.53577 -111.4044) (xy 84.92617 -111.4044) (xy 84.92617 -111.6584) (xy 85.53577 -111.6584)
			)
		)
		(polygon
			(pts
				(xy 84.51977 -111.4044) (xy 83.91017 -111.4044) (xy 83.91017 -111.6584) (xy 84.51977 -111.6584)
			)
		)
		(polygon
			(pts
				(xy 79.79537 -111.1758) (xy 79.54137 -111.1758) (xy 79.54137 -111.4298) (xy 79.79537 -111.4298)
			)
		)
		(polygon
			(pts
				(xy 79.23657 -111.1758) (xy 78.98257 -111.1758) (xy 78.98257 -111.4298) (xy 79.23657 -111.4298)
			)
		)
		(polygon
			(pts
				(xy 77.307186 -109.646212) (xy 77.053186 -109.646212) (xy 77.053186 -109.900212) (xy 77.307186 -109.900212)
			)
		)
		(polygon
			(pts
				(xy 76.443586 -109.646212) (xy 76.189586 -109.646212) (xy 76.189586 -109.900212) (xy 76.443586 -109.900212)
			)
		)
		(polygon
			(pts
				(xy 95.12427 -109.0676) (xy 94.87027 -109.0676) (xy 94.87027 -109.3216) (xy 95.12427 -109.3216)
			)
		)
		(polygon
			(pts
				(xy 95.12427 -108.4834) (xy 94.87027 -108.4834) (xy 94.87027 -108.7374) (xy 95.12427 -108.7374)
			)
		)
		(polygon
			(pts
				(xy 95.12427 -107.9246) (xy 94.87027 -107.9246) (xy 94.87027 -108.1786) (xy 95.12427 -108.1786)
			)
		)
		(polygon
			(pts
				(xy 95.12427 -107.3404) (xy 94.87027 -107.3404) (xy 94.87027 -107.5944) (xy 95.12427 -107.5944)
			)
		)
		(polygon
			(pts
				(xy 91.69527 -106.5784) (xy 91.44127 -106.5784) (xy 91.44127 -106.8324) (xy 91.69527 -106.8324)
			)
		)
		(polygon
			(pts
				(xy 91.69527 -106.0196) (xy 91.44127 -106.0196) (xy 91.44127 -106.2736) (xy 91.69527 -106.2736)
			)
		)
		(polygon
			(pts
				(xy 91.69527 -105.4354) (xy 91.44127 -105.4354) (xy 91.44127 -105.6894) (xy 91.69527 -105.6894)
			)
		)
		(polygon
			(pts
				(xy 91.69527 -104.8766) (xy 91.44127 -104.8766) (xy 91.44127 -105.1306) (xy 91.69527 -105.1306)
			)
		)
		(polygon
			(pts
				(xy 91.69527 -104.2924) (xy 91.44127 -104.2924) (xy 91.44127 -104.5464) (xy 91.69527 -104.5464)
			)
		)
		(polygon
			(pts
				(xy 91.69527 -103.7336) (xy 91.44127 -103.7336) (xy 91.44127 -103.9876) (xy 91.69527 -103.9876)
			)
		)
		(polygon
			(pts
				(xy 91.69527 -103.09098) (xy 91.44127 -103.09098) (xy 91.44127 -103.34498) (xy 91.69527 -103.34498)
			)
		)
		(polygon
			(pts
				(xy 91.69527 -102.53218) (xy 91.44127 -102.53218) (xy 91.44127 -102.78618) (xy 91.69527 -102.78618)
			)
		)
		(polygon
			(pts
				(xy 91.69781 -101.8794) (xy 91.44381 -101.8794) (xy 91.44381 -102.1334) (xy 91.69781 -102.1334)
			)
		)
	)
	(zone
		(net "GND")
		(layer "F.Cu")
		(hatch none 0.5)
		(connect_pads
			(clearance 0.5)
		)
		(min_thickness 0.25)
		(fill yes
			(thermal_gap 0.5)
			(thermal_bridge_width 0.5)
			(island_removal_mode 0)
		)
		(polygon
			(pts
				(xy 259.842 -187.96) (xy 255.651 -192.151) (xy 255.651 -228.346) (xy 255.778 -228.473) (xy 257.175 -228.473)
				(xy 257.302 -228.346) (xy 257.302 -226.314) (xy 258.064 -225.552) (xy 260.858 -225.552) (xy 260.985 -225.425)
				(xy 260.985 -220.218) (xy 259.715 -218.948) (xy 259.715 -209.931) (xy 261.493 -208.153) (xy 268.224 -208.153)
				(xy 268.605 -208.534) (xy 268.605 -212.852) (xy 268.351 -213.106) (xy 268.351 -223.393) (xy 267.97 -223.774)
				(xy 265.0744 -223.774) (xy 264.8966 -223.9518) (xy 264.8966 -225.425) (xy 265.0236 -225.552) (xy 266.446 -225.552)
				(xy 266.954 -226.06) (xy 266.954 -228.346) (xy 266.827 -228.473) (xy 266.827 -233.045) (xy 266.954 -233.172)
				(xy 269.113 -233.172) (xy 269.24 -233.045) (xy 269.24 -225.933) (xy 275.59 -219.583) (xy 277.749 -219.583)
				(xy 277.876 -219.456) (xy 277.876 -214.757) (xy 277.495 -214.376) (xy 274.701 -214.376) (xy 273.431 -213.106)
				(xy 273.431 -209.55) (xy 271.907 -208.026) (xy 271.907 -195.58) (xy 271.018 -194.691) (xy 271.018 -191.135)
				(xy 267.843 -187.96)
			)
		)
		(polygon
			(pts
				(xy 267.643864 -229.023672) (xy 267.389864 -229.023672) (xy 267.389864 -229.277672) (xy 267.643864 -229.277672)
			)
		)
		(polygon
			(pts
				(xy 267.643864 -228.414072) (xy 267.389864 -228.414072) (xy 267.389864 -228.668072) (xy 267.643864 -228.668072)
			)
		)
		(polygon
			(pts
				(xy 256.848864 -227.779072) (xy 256.594864 -227.779072) (xy 256.594864 -228.033072) (xy 256.848864 -228.033072)
			)
		)
		(polygon
			(pts
				(xy 256.848864 -223.689672) (xy 256.594864 -223.689672) (xy 256.594864 -223.943672) (xy 256.848864 -223.943672)
			)
		)
		(polygon
			(pts
				(xy 256.848864 -223.080072) (xy 256.594864 -223.080072) (xy 256.594864 -223.334072) (xy 256.848864 -223.334072)
			)
		)
		(polygon
			(pts
				(xy 260.201664 -220.362272) (xy 259.947664 -220.362272) (xy 259.947664 -220.616272) (xy 260.201664 -220.616272)
			)
		)
		(polygon
			(pts
				(xy 260.201664 -219.803472) (xy 259.947664 -219.803472) (xy 259.947664 -220.057472) (xy 260.201664 -220.057472)
			)
		)
		(polygon
			(pts
				(xy 277.359872 -218.842336) (xy 277.105872 -218.842336) (xy 277.105872 -219.096336) (xy 277.359872 -219.096336)
			)
		)
		(polygon
			(pts
				(xy 269.113 -214.6808) (xy 268.859 -214.6808) (xy 268.859 -214.9348) (xy 269.113 -214.9348)
			)
		)
		(polygon
			(pts
				(xy 269.113 -214.0712) (xy 268.859 -214.0712) (xy 268.859 -214.3252) (xy 269.113 -214.3252)
			)
		)
		(polygon
			(pts
				(xy 270.570452 -193.508376) (xy 270.316452 -193.508376) (xy 270.316452 -193.762376) (xy 270.570452 -193.762376)
			)
		)
		(polygon
			(pts
				(xy 270.532352 -191.491616) (xy 270.278352 -191.491616) (xy 270.278352 -191.745616) (xy 270.532352 -191.745616)
			)
		)
	)
	(zone
		(layer "F.Cu")
		(hatch none 0.5)
		(connect_pads
			(clearance 0)
		)
		(min_thickness 0.25)
		(keepout
			(tracks not_allowed)
			(vias allowed)
			(pads allowed)
			(copperpour not_allowed)
			(footprints allowed)
		)
		(placement
			(enabled no)
			(sheetname "")
		)
		(fill
			(thermal_gap 0.5)
			(thermal_bridge_width 0.5)
			(island_removal_mode 0)
		)
		(polygon
			(pts
				(arc
					(start 301.975012 -73.22566)
					(mid 301.591218 -73.609073)
					(end 301.974758 -73.99274)
				)
				(arc
					(start 302.956722 -73.99274)
					(mid 303.340262 -73.6092)
					(end 302.956722 -73.22566)
				)
				(arc
					(start 302.734218 -73.22566)
					(mid 302.76004 -73.284458)
					(end 302.799496 -73.335134)
				)
				(arc
					(start 302.817022 -73.35266)
					(mid 303.163276 -73.815754)
					(end 302.700182 -73.4695)
				)
				(xy 302.682656 -73.451974) (xy 302.658526 -73.427844)
				(arc
					(start 302.658526 -73.425558)
					(mid 302.598416 -73.331819)
					(end 302.5648 -73.22566)
				)
				(arc
					(start 302.374046 -73.22566)
					(mid 302.34222 -73.324714)
					(end 302.286162 -73.41235)
				)
				(xy 302.286162 -73.414636) (xy 302.262032 -73.438766)
				(arc
					(start 302.231298 -73.4695)
					(mid 301.768204 -73.815754)
					(end 302.114458 -73.35266)
				)
				(arc
					(start 302.145192 -73.321926)
					(mid 302.180406 -73.277312)
					(end 302.20412 -73.22566)
				)
			)
		)
	)
	(zone
		(net "P0V9_E_LX")
		(layer "F.Cu")
		(hatch none 0.5)
		(connect_pads
			(clearance 0.5)
		)
		(min_thickness 0.25)
		(fill yes
			(thermal_gap 0.5)
			(thermal_bridge_width 0.5)
			(island_removal_mode 0)
		)
		(polygon
			(pts
				(xy 168.783 -104.648) (xy 168.656 -104.775) (xy 168.656 -110.236) (xy 170.815 -112.395) (xy 170.815 -113.792)
				(xy 170.942 -113.919) (xy 174.244 -113.919) (xy 174.879 -113.284) (xy 176.53 -113.284) (xy 176.784 -113.03)
				(xy 176.784 -111.252) (xy 173.736 -108.204) (xy 173.736 -105.156) (xy 173.228 -104.648)
			)
		)
	)
	(zone
		(layer "F.Cu")
		(hatch none 0.5)
		(connect_pads
			(clearance 0)
		)
		(min_thickness 0.25)
		(keepout
			(tracks allowed)
			(vias allowed)
			(pads allowed)
			(copperpour allowed)
			(footprints not_allowed)
		)
		(placement
			(enabled no)
			(sheetname "")
		)
		(fill
			(thermal_gap 0.5)
			(thermal_bridge_width 0.5)
			(island_removal_mode 0)
		)
		(polygon
			(pts
				(arc
					(start 109.450124 -5.999988)
					(mid 104.950006 -10.500106)
					(end 100.449888 -5.999988)
				)
				(arc
					(start 100.449888 -5.999988)
					(mid 104.950006 -1.49987)
					(end 109.450124 -5.999988)
				)
			)
		)
	)
	(zone
		(net "GND")
		(layer "F.Cu")
		(hatch none 0.5)
		(connect_pads
			(clearance 0.5)
		)
		(min_thickness 0.25)
		(fill yes
			(thermal_gap 0.5)
			(thermal_bridge_width 0.5)
			(island_removal_mode 0)
		)
		(polygon
			(pts
				(xy 82.26171 -112.05972) (xy 82.18043 -112.141) (xy 77.216 -112.141) (xy 76.581 -112.776) (xy 76.581 -113.792)
				(xy 77.597 -114.808) (xy 80.772 -114.808) (xy 81.026 -114.554) (xy 81.026 -114.173) (xy 81.28 -113.919)
				(xy 82.41919 -113.919) (xy 82.56143 -114.06124) (xy 84.69757 -114.06124) (xy 85.09381 -113.665)
				(xy 86.52637 -113.665) (xy 86.78037 -113.919) (xy 86.78037 -114.42192) (xy 86.95817 -114.59972)
				(xy 88.47201 -114.59972) (xy 89.67597 -113.39576) (xy 93.36024 -113.39576) (xy 93.599 -113.157)
				(xy 93.599 -112.268) (xy 93.45168 -112.12068) (xy 85.95995 -112.12068) (xy 85.89899 -112.05972)
			)
		)
		(polygon
			(pts
				(xy 80.389222 -113.962942) (xy 80.135222 -113.962942) (xy 80.135222 -114.216942) (xy 80.389222 -114.216942)
			)
		)
		(polygon
			(pts
				(xy 87.56777 -113.82756) (xy 87.31377 -113.82756) (xy 87.31377 -114.08156) (xy 87.56777 -114.08156)
			)
		)
		(polygon
			(pts
				(xy 79.79537 -112.5982) (xy 79.54137 -112.5982) (xy 79.54137 -112.8522) (xy 79.79537 -112.8522)
			)
		)
		(polygon
			(pts
				(xy 79.23657 -112.5982) (xy 78.98257 -112.5982) (xy 78.98257 -112.8522) (xy 79.23657 -112.8522)
			)
		)
		(polygon
			(pts
				(xy 93.1672 -112.3696) (xy 92.9132 -112.3696) (xy 92.9132 -112.6236) (xy 93.1672 -112.6236)
			)
		)
		(polygon
			(pts
				(xy 92.64777 -112.3696) (xy 92.03817 -112.3696) (xy 92.03817 -112.6236) (xy 92.64777 -112.6236)
			)
		)
		(polygon
			(pts
				(xy 91.63177 -112.3696) (xy 91.02217 -112.3696) (xy 91.02217 -112.6236) (xy 91.63177 -112.6236)
			)
		)
		(polygon
			(pts
				(xy 90.61577 -112.3696) (xy 90.00617 -112.3696) (xy 90.00617 -112.6236) (xy 90.61577 -112.6236)
			)
		)
		(polygon
			(pts
				(xy 89.59977 -112.3696) (xy 88.99017 -112.3696) (xy 88.99017 -112.6236) (xy 89.59977 -112.6236)
			)
		)
		(polygon
			(pts
				(xy 88.58377 -112.3696) (xy 87.97417 -112.3696) (xy 87.97417 -112.6236) (xy 88.58377 -112.6236)
			)
		)
		(polygon
			(pts
				(xy 87.56777 -112.3696) (xy 86.95817 -112.3696) (xy 86.95817 -112.6236) (xy 87.56777 -112.6236)
			)
		)
		(polygon
			(pts
				(xy 86.55177 -112.3696) (xy 85.94217 -112.3696) (xy 85.94217 -112.6236) (xy 86.55177 -112.6236)
			)
		)
		(polygon
			(pts
				(xy 85.53577 -112.3696) (xy 84.92617 -112.3696) (xy 84.92617 -112.6236) (xy 85.53577 -112.6236)
			)
		)
		(polygon
			(pts
				(xy 84.51977 -112.3696) (xy 83.91017 -112.3696) (xy 83.91017 -112.6236) (xy 84.51977 -112.6236)
			)
		)
	)
	(zone
		(net "P3V3_STBY")
		(layer "F.Cu")
		(hatch none 0.5)
		(connect_pads
			(clearance 0.5)
		)
		(min_thickness 0.25)
		(fill yes
			(thermal_gap 0.5)
			(thermal_bridge_width 0.5)
			(island_removal_mode 0)
		)
		(polygon
			(pts
				(xy 85.598 -242.57) (xy 85.471 -242.697) (xy 85.471 -243.84) (xy 85.852 -244.221) (xy 92.075 -244.221)
				(xy 92.329 -243.967) (xy 92.329 -242.824) (xy 92.075 -242.57)
			)
		)
		(polygon
			(pts
				(xy 91.9734 -243.0272) (xy 91.7194 -243.0272) (xy 91.7194 -243.2812) (xy 91.9734 -243.2812)
			)
		)
		(polygon
			(pts
				(xy 91.4146 -243.0272) (xy 91.1606 -243.0272) (xy 91.1606 -243.2812) (xy 91.4146 -243.2812)
			)
		)
		(polygon
			(pts
				(xy 90.8304 -243.0272) (xy 90.5764 -243.0272) (xy 90.5764 -243.2812) (xy 90.8304 -243.2812)
			)
		)
		(polygon
			(pts
				(xy 90.2716 -243.0272) (xy 90.0176 -243.0272) (xy 90.0176 -243.2812) (xy 90.2716 -243.2812)
			)
		)
		(polygon
			(pts
				(xy 89.6874 -243.0272) (xy 89.4334 -243.0272) (xy 89.4334 -243.2812) (xy 89.6874 -243.2812)
			)
		)
		(polygon
			(pts
				(xy 89.1286 -243.0272) (xy 88.8746 -243.0272) (xy 88.8746 -243.2812) (xy 89.1286 -243.2812)
			)
		)
		(polygon
			(pts
				(xy 88.5444 -243.0272) (xy 88.2904 -243.0272) (xy 88.2904 -243.2812) (xy 88.5444 -243.2812)
			)
		)
		(polygon
			(pts
				(xy 87.9856 -243.0272) (xy 87.7316 -243.0272) (xy 87.7316 -243.2812) (xy 87.9856 -243.2812)
			)
		)
		(polygon
			(pts
				(xy 87.4014 -243.0272) (xy 87.1474 -243.0272) (xy 87.1474 -243.2812) (xy 87.4014 -243.2812)
			)
		)
		(polygon
			(pts
				(xy 86.8426 -243.0272) (xy 86.5886 -243.0272) (xy 86.5886 -243.2812) (xy 86.8426 -243.2812)
			)
		)
		(polygon
			(pts
				(xy 86.2584 -243.0272) (xy 86.0044 -243.0272) (xy 86.0044 -243.2812) (xy 86.2584 -243.2812)
			)
		)
	)
	(zone
		(layer "F.Cu")
		(hatch none 0.5)
		(connect_pads
			(clearance 0)
		)
		(min_thickness 0.25)
		(keepout
			(tracks allowed)
			(vias allowed)
			(pads allowed)
			(copperpour allowed)
			(footprints allowed)
		)
		(placement
			(enabled no)
			(sheetname "")
		)
		(fill
			(thermal_gap 0.5)
			(thermal_bridge_width 0.5)
			(island_removal_mode 0)
		)
		(polygon
			(pts
				(xy 18.288 -177.673) (xy 18.288 -175.26) (xy 19.939 -175.26) (xy 19.939 -177.673)
			)
		)
	)
	(zone
		(net "MB0_P12V_MAIN_R")
		(layer "F.Cu")
		(hatch none 0.5)
		(connect_pads
			(clearance 0.5)
		)
		(min_thickness 0.25)
		(fill yes
			(thermal_gap 0.5)
			(thermal_bridge_width 0.5)
			(island_removal_mode 0)
		)
		(polygon
			(pts
				(xy 60.452 -228.219) (xy 59.563 -229.108) (xy 59.563 -230.124) (xy 59.055 -230.632) (xy 58.293 -230.632)
				(xy 57.912 -231.013) (xy 57.912 -233.68) (xy 58.547 -234.315) (xy 66.04 -234.315) (xy 66.548 -233.807)
				(xy 66.548 -228.6) (xy 66.167 -228.219)
			)
		)
	)
	(zone
		(layer "F.Cu")
		(hatch none 0.5)
		(connect_pads
			(clearance 0)
		)
		(min_thickness 0.25)
		(keepout
			(tracks not_allowed)
			(vias allowed)
			(pads allowed)
			(copperpour not_allowed)
			(footprints allowed)
		)
		(placement
			(enabled no)
			(sheetname "")
		)
		(fill
			(thermal_gap 0.5)
			(thermal_bridge_width 0.5)
			(island_removal_mode 0)
		)
		(polygon
			(pts
				(arc
					(start 276.867112 -31.74746)
					(mid 276.483572 -32.131)
					(end 276.867112 -32.51454)
				)
				(arc
					(start 277.848822 -32.51454)
					(mid 278.232616 -32.131127)
					(end 277.849076 -31.74746)
				)
				(arc
					(start 277.660354 -31.74746)
					(mid 277.688596 -31.809091)
					(end 277.722838 -31.867602)
				)
				(arc
					(start 277.722838 -31.867602)
					(mid 278.044855 -32.347946)
					(end 277.59914 -31.979616)
				)
				(arc
					(start 277.59914 -31.979616)
					(mid 277.533286 -31.867927)
					(end 277.485348 -31.74746)
				)
				(arc
					(start 277.23084 -31.74746)
					(mid 277.182868 -31.86791)
					(end 277.117048 -31.979616)
				)
				(arc
					(start 277.117048 -31.979616)
					(mid 276.671389 -32.347883)
					(end 276.99335 -31.867602)
				)
				(arc
					(start 276.99335 -31.867602)
					(mid 277.027596 -31.809093)
					(end 277.055834 -31.74746)
				)
			)
		)
	)
	(zone
		(layer "F.Cu")
		(hatch none 0.5)
		(connect_pads
			(clearance 0)
		)
		(min_thickness 0.25)
		(keepout
			(tracks allowed)
			(vias allowed)
			(pads allowed)
			(copperpour allowed)
			(footprints allowed)
		)
		(placement
			(enabled no)
			(sheetname "")
		)
		(fill
			(thermal_gap 0.5)
			(thermal_bridge_width 0.5)
			(island_removal_mode 0)
		)
		(polygon
			(pts
				(xy 186.69 -146.431) (xy 186.69 -145.288) (xy 188.722 -145.288) (xy 188.722 -146.431)
			)
		)
	)
	(zone
		(layer "F.Cu")
		(hatch none 0.5)
		(connect_pads
			(clearance 0)
		)
		(min_thickness 0.25)
		(keepout
			(tracks not_allowed)
			(vias allowed)
			(pads allowed)
			(copperpour not_allowed)
			(footprints allowed)
		)
		(placement
			(enabled no)
			(sheetname "")
		)
		(fill
			(thermal_gap 0.5)
			(thermal_bridge_width 0.5)
			(island_removal_mode 0)
		)
		(polygon
			(pts
				(arc
					(start 297.05681 -81.840324)
					(mid 296.67327 -82.223864)
					(end 297.05681 -82.607404)
				)
				(arc
					(start 297.973496 -82.607404)
					(mid 298.35729 -82.223991)
					(end 297.97375 -81.840324)
				)
				(arc
					(start 297.828208 -81.840324)
					(mid 297.846578 -81.896496)
					(end 297.869864 -81.950814)
				)
				(arc
					(start 297.869864 -81.950814)
					(mid 298.152193 -82.455489)
					(end 297.736768 -82.053176)
				)
				(arc
					(start 297.736768 -82.053176)
					(mid 297.690099 -81.94945)
					(end 297.658028 -81.840324)
				)
				(arc
					(start 297.436032 -81.840324)
					(mid 297.386204 -81.967133)
					(end 297.311572 -82.081116)
				)
				(arc
					(start 297.311572 -82.081116)
					(mid 296.853106 -82.433114)
					(end 297.1927 -81.965292)
				)
				(arc
					(start 297.1927 -81.965292)
					(mid 297.232109 -81.905315)
					(end 297.26255 -81.840324)
				)
			)
		)
	)
	(zone
		(net "P5V_STBY")
		(layer "F.Cu")
		(hatch none 0.5)
		(connect_pads
			(clearance 0.5)
		)
		(min_thickness 0.25)
		(fill yes
			(thermal_gap 0.5)
			(thermal_bridge_width 0.5)
			(island_removal_mode 0)
		)
		(polygon
			(pts
				(xy 252.984 -16.764) (xy 252.476 -17.272) (xy 252.476 -20.447) (xy 253.873 -21.844) (xy 257.683 -21.844)
				(xy 257.937 -21.59) (xy 257.937 -20.955) (xy 256.286 -19.304) (xy 255.27 -19.304) (xy 254.762 -18.796)
				(xy 254.762 -17.018) (xy 254.508 -16.764)
			)
		)
		(polygon
			(pts
				(xy 253.6063 -18.2245) (xy 253.3523 -18.2245) (xy 253.3523 -18.4785) (xy 253.6063 -18.4785)
			)
		)
	)
	(zone
		(layer "F.Cu")
		(hatch none 0.5)
		(connect_pads
			(clearance 0)
		)
		(min_thickness 0.25)
		(keepout
			(tracks not_allowed)
			(vias allowed)
			(pads allowed)
			(copperpour not_allowed)
			(footprints allowed)
		)
		(placement
			(enabled no)
			(sheetname "")
		)
		(fill
			(thermal_gap 0.5)
			(thermal_bridge_width 0.5)
			(island_removal_mode 0)
		)
		(polygon
			(pts
				(arc
					(start 18.258536 -98.162364)
					(mid 17.874742 -98.545777)
					(end 18.258282 -98.929444)
				)
				(xy 18.33626 -98.929444)
				(arc
					(start 18.33626 -98.887534)
					(mid 18.335273 -98.857998)
					(end 18.332196 -98.828606)
				)
				(arc
					(start 18.332196 -98.828606)
					(mid 18.122003 -98.287424)
					(end 18.449798 -98.76663)
				)
				(arc
					(start 18.449798 -98.76663)
					(mid 18.458186 -98.813344)
					(end 18.462498 -98.86061)
				)
				(xy 18.46326 -98.861118) (xy 18.46326 -98.929444) (xy 19.13636 -98.929444) (xy 19.13636 -98.821748)
				(arc
					(start 19.137122 -98.82124)
					(mid 19.138949 -98.797305)
					(end 19.141948 -98.773488)
				)
				(arc
					(start 19.141948 -98.773488)
					(mid 19.450134 -98.28173)
					(end 19.263868 -98.8314)
				)
				(xy 19.26336 -98.848164) (xy 19.26336 -98.929444)
				(arc
					(start 19.325082 -98.929444)
					(mid 19.708622 -98.545904)
					(end 19.325082 -98.162364)
				)
			)
		)
	)
	(zone
		(layer "F.Cu")
		(hatch none 0.5)
		(connect_pads
			(clearance 0)
		)
		(min_thickness 0.25)
		(keepout
			(tracks allowed)
			(vias allowed)
			(pads allowed)
			(copperpour allowed)
			(footprints allowed)
		)
		(placement
			(enabled no)
			(sheetname "")
		)
		(fill
			(thermal_gap 0.5)
			(thermal_bridge_width 0.5)
			(island_removal_mode 0)
		)
		(polygon
			(pts
				(xy 118.745 -78.105) (xy 118.745 -75.057) (xy 122.555 -75.057) (xy 122.555 -78.105)
			)
		)
	)
	(zone
		(net "P3V3_STBY")
		(layer "F.Cu")
		(hatch none 0.5)
		(connect_pads
			(clearance 0.5)
		)
		(min_thickness 0.25)
		(fill yes
			(thermal_gap 0.5)
			(thermal_bridge_width 0.5)
			(island_removal_mode 0)
		)
		(polygon
			(pts
				(xy 193.675 -214.122) (xy 192.405 -215.392) (xy 182.88 -215.392) (xy 182.499 -215.773) (xy 182.499 -219.964)
				(xy 182.626 -220.091) (xy 184.15 -220.091) (xy 184.277 -219.964) (xy 184.277 -218.948) (xy 184.912 -218.313)
				(xy 194.945 -218.313) (xy 195.199 -218.059) (xy 195.199 -214.503) (xy 194.818 -214.122)
			)
		)
		(polygon
			(pts
				(xy 183.261 -219.6338) (xy 183.007 -219.6338) (xy 183.007 -219.8878) (xy 183.261 -219.8878)
			)
		)
		(polygon
			(pts
				(xy 183.8198 -219.6084) (xy 183.5658 -219.6084) (xy 183.5658 -219.8624) (xy 183.8198 -219.8624)
			)
		)
		(polygon
			(pts
				(xy 183.8198 -219.0496) (xy 183.5658 -219.0496) (xy 183.5658 -219.3036) (xy 183.8198 -219.3036)
			)
		)
		(polygon
			(pts
				(xy 183.261 -219.0242) (xy 183.007 -219.0242) (xy 183.007 -219.2782) (xy 183.261 -219.2782)
			)
		)
		(polygon
			(pts
				(xy 194.6148 -217.5256) (xy 194.3608 -217.5256) (xy 194.3608 -217.7796) (xy 194.6148 -217.7796)
			)
		)
		(polygon
			(pts
				(xy 194.6148 -216.9414) (xy 194.3608 -216.9414) (xy 194.3608 -217.1954) (xy 194.6148 -217.1954)
			)
		)
		(polygon
			(pts
				(xy 194.6148 -216.3826) (xy 194.3608 -216.3826) (xy 194.3608 -216.6366) (xy 194.6148 -216.6366)
			)
		)
	)
	(zone
		(layer "F.Cu")
		(hatch none 0.5)
		(connect_pads
			(clearance 0)
		)
		(min_thickness 0.25)
		(keepout
			(tracks allowed)
			(vias allowed)
			(pads allowed)
			(copperpour allowed)
			(footprints allowed)
		)
		(placement
			(enabled no)
			(sheetname "")
		)
		(fill
			(thermal_gap 0.5)
			(thermal_bridge_width 0.5)
			(island_removal_mode 0)
		)
		(polygon
			(pts
				(xy 336.677 -169.545) (xy 336.677 -167.259) (xy 338.582 -167.259) (xy 338.582 -169.545)
			)
		)
	)
	(zone
		(net "GND")
		(layer "F.Cu")
		(hatch none 0.5)
		(connect_pads
			(clearance 0.5)
		)
		(min_thickness 0.25)
		(fill yes
			(thermal_gap 0.5)
			(thermal_bridge_width 0.5)
			(island_removal_mode 0)
		)
		(polygon
			(pts
				(xy 256.921 -69.723) (xy 256.667 -69.977) (xy 256.667 -71.501) (xy 257.175 -72.009) (xy 258.445 -72.009)
				(xy 258.572 -71.882) (xy 258.572 -69.977) (xy 258.318 -69.723)
			)
		)
		(polygon
			(pts
				(xy 258.064 -71.0692) (xy 257.81 -71.0692) (xy 257.81 -71.3232) (xy 258.064 -71.3232)
			)
		)
		(polygon
			(pts
				(xy 258.064 -70.6628) (xy 257.81 -70.6628) (xy 257.81 -70.9168) (xy 258.064 -70.9168)
			)
		)
		(polygon
			(pts
				(xy 258.064 -70.0532) (xy 257.81 -70.0532) (xy 257.81 -70.3072) (xy 258.064 -70.3072)
			)
		)
	)
	(zone
		(layer "F.Cu")
		(hatch none 0.5)
		(connect_pads
			(clearance 0)
		)
		(min_thickness 0.25)
		(keepout
			(tracks allowed)
			(vias allowed)
			(pads allowed)
			(copperpour allowed)
			(footprints allowed)
		)
		(placement
			(enabled no)
			(sheetname "")
		)
		(fill
			(thermal_gap 0.5)
			(thermal_bridge_width 0.5)
			(island_removal_mode 0)
		)
		(polygon
			(pts
				(xy 24.257 -170.18) (xy 24.257 -168.529) (xy 24.892 -168.529) (xy 24.892 -170.18)
			)
		)
	)
	(zone
		(net "P1V8_STBY")
		(layer "F.Cu")
		(hatch none 0.5)
		(connect_pads
			(clearance 0.5)
		)
		(min_thickness 0.25)
		(fill yes
			(thermal_gap 0.5)
			(thermal_bridge_width 0.5)
			(island_removal_mode 0)
		)
		(polygon
			(pts
				(xy 343.662 -168.91) (xy 338.074 -174.498) (xy 338.074 -232.156) (xy 334.645 -235.585) (xy 275.844 -235.585)
				(xy 274.574 -234.315) (xy 274.574 -226.441) (xy 274.066 -225.933) (xy 270.256 -225.933) (xy 269.875 -226.314)
				(xy 269.875 -233.299) (xy 269.494 -233.68) (xy 266.827 -233.68) (xy 266.7 -233.807) (xy 266.7 -237.871)
				(xy 266.827 -237.998) (xy 272.415 -237.998) (xy 273.558 -239.141) (xy 337.185 -239.141) (xy 341.757 -234.569)
				(xy 341.757 -175.641) (xy 344.805 -172.593) (xy 344.805 -169.291) (xy 344.424 -168.91)
			)
		)
		(polygon
			(pts
				(xy 267.335 -236.3978) (xy 267.081 -236.3978) (xy 267.081 -236.6518) (xy 267.335 -236.6518)
			)
		)
		(polygon
			(pts
				(xy 267.335 -235.7882) (xy 267.081 -235.7882) (xy 267.081 -236.0422) (xy 267.335 -236.0422)
			)
		)
	)
	(zone
		(net "GND")
		(layer "F.Cu")
		(hatch none 0.5)
		(connect_pads
			(clearance 0.5)
		)
		(min_thickness 0.25)
		(fill yes
			(thermal_gap 0.5)
			(thermal_bridge_width 0.5)
			(island_removal_mode 0)
		)
		(polygon
			(pts
				(xy 2.921254 -79.248) (xy 0.762254 -81.407) (xy 0.762254 -215.900254) (xy 1.016 -216.154) (xy 2.286 -216.154)
				(xy 3.302 -215.138) (xy 6.096 -215.138) (xy 6.223 -215.011) (xy 6.223 -214.376) (xy 6.096 -214.249)
				(xy 5.461 -214.249) (xy 5.207 -213.995) (xy 5.207 -211.582) (xy 5.969 -210.82) (xy 9.271 -210.82)
				(xy 9.652 -211.201) (xy 10.922 -211.201) (xy 11.557 -210.566) (xy 11.557 -165.735) (xy 27.432 -149.86)
				(xy 27.432 -120.0658) (xy 26.8224 -119.4562) (xy 7.6962 -119.4562) (xy 5.207 -116.967) (xy 5.207 -84.582)
				(xy 3.81 -83.185) (xy 3.81 -79.502) (xy 3.556 -79.248)
			)
		)
	)
	(zone
		(net "P3V3_STBY")
		(layer "F.Cu")
		(hatch none 0.5)
		(connect_pads
			(clearance 0.5)
		)
		(min_thickness 0.25)
		(fill yes
			(thermal_gap 0.5)
			(thermal_bridge_width 0.5)
			(island_removal_mode 0)
		)
		(polygon
			(pts
				(xy 233.172 -12.446) (xy 233.045 -12.573) (xy 233.045 -13.335) (xy 233.172 -13.462) (xy 233.934 -13.462)
				(xy 234.188 -13.716) (xy 234.188 -14.732) (xy 234.315 -14.859) (xy 235.712 -14.859) (xy 235.839 -14.732)
				(xy 235.839 -12.573) (xy 235.712 -12.446)
			)
		)
		(polygon
			(pts
				(xy 235.331 -13.2588) (xy 235.077 -13.2588) (xy 235.077 -13.5128) (xy 235.331 -13.5128)
			)
		)
		(polygon
			(pts
				(xy 233.8324 -12.7508) (xy 233.5784 -12.7508) (xy 233.5784 -13.0048) (xy 233.8324 -13.0048)
			)
		)
		(polygon
			(pts
				(xy 235.331 -12.6492) (xy 235.077 -12.6492) (xy 235.077 -12.9032) (xy 235.331 -12.9032)
			)
		)
	)
	(zone
		(net "P3V3_STBY")
		(layer "F.Cu")
		(hatch none 0.5)
		(connect_pads
			(clearance 0.5)
		)
		(min_thickness 0.25)
		(fill yes
			(thermal_gap 0.5)
			(thermal_bridge_width 0.5)
			(island_removal_mode 0)
		)
		(polygon
			(pts
				(xy 330.962 -195.199) (xy 330.708 -195.453) (xy 330.708 -197.104) (xy 330.835 -197.104) (xy 330.962 -197.231)
				(xy 334.01 -197.231) (xy 334.137 -197.104) (xy 334.137 -195.326) (xy 334.01 -195.199)
			)
		)
		(polygon
			(pts
				(xy 333.548736 -196.527928) (xy 333.294736 -196.527928) (xy 333.294736 -196.781928) (xy 333.548736 -196.781928)
			)
		)
		(polygon
			(pts
				(xy 332.837536 -196.527928) (xy 332.583536 -196.527928) (xy 332.583536 -196.781928) (xy 332.837536 -196.781928)
			)
		)
		(polygon
			(pts
				(xy 332.278736 -196.527928) (xy 332.024736 -196.527928) (xy 332.024736 -196.781928) (xy 332.278736 -196.781928)
			)
		)
		(polygon
			(pts
				(xy 331.567536 -196.527928) (xy 331.313536 -196.527928) (xy 331.313536 -196.781928) (xy 331.567536 -196.781928)
			)
		)
	)
	(zone
		(net "GND")
		(layer "F.Cu")
		(hatch none 0.5)
		(connect_pads
			(clearance 0.5)
		)
		(min_thickness 0.25)
		(fill yes
			(thermal_gap 0.5)
			(thermal_bridge_width 0.5)
			(island_removal_mode 0)
		)
		(polygon
			(pts
				(xy 332.486 -90.551) (xy 332.105 -90.932) (xy 332.105 -97.155) (xy 332.486 -97.536) (xy 336.169 -97.536)
				(xy 336.55 -97.155) (xy 336.55 -91.313) (xy 335.788 -90.551)
			)
		)
		(polygon
			(pts
				(xy 333.248 -92.5068) (xy 332.994 -92.5068) (xy 332.994 -92.7608) (xy 333.248 -92.7608)
			)
		)
		(polygon
			(pts
				(xy 333.248 -91.6432) (xy 332.994 -91.6432) (xy 332.994 -91.8972) (xy 333.248 -91.8972)
			)
		)
	)
	(zone
		(layer "F.Cu")
		(hatch none 0.5)
		(connect_pads
			(clearance 0)
		)
		(min_thickness 0.25)
		(keepout
			(tracks allowed)
			(vias allowed)
			(pads allowed)
			(copperpour allowed)
			(footprints allowed)
		)
		(placement
			(enabled no)
			(sheetname "")
		)
		(fill
			(thermal_gap 0.5)
			(thermal_bridge_width 0.5)
			(island_removal_mode 0)
		)
		(polygon
			(pts
				(xy 27.686 -176.53) (xy 27.686 -175.133) (xy 28.575 -175.133) (xy 28.575 -176.53)
			)
		)
	)
	(zone
		(net "P3V3_STBY")
		(layer "F.Cu")
		(hatch none 0.5)
		(connect_pads
			(clearance 0.5)
		)
		(min_thickness 0.25)
		(fill yes
			(thermal_gap 0.5)
			(thermal_bridge_width 0.5)
			(island_removal_mode 0)
		)
		(polygon
			(pts
				(xy 318.262 -160.909) (xy 318.135 -161.036) (xy 318.135 -164.592) (xy 318.389 -164.846) (xy 319.786 -164.846)
				(xy 319.913 -164.973) (xy 319.913 -165.481) (xy 320.04 -165.608) (xy 321.564 -165.608) (xy 321.818 -165.354)
				(xy 321.818 -161.036) (xy 321.691 -160.909)
			)
		)
		(polygon
			(pts
				(xy 320.7512 -164.9476) (xy 320.4972 -164.9476) (xy 320.4972 -165.2016) (xy 320.7512 -165.2016)
			)
		)
		(polygon
			(pts
				(xy 318.8462 -163.9316) (xy 318.5922 -163.9316) (xy 318.5922 -164.1856) (xy 318.8462 -164.1856)
			)
		)
		(polygon
			(pts
				(xy 318.8462 -163.4744) (xy 318.5922 -163.4744) (xy 318.5922 -163.7284) (xy 318.8462 -163.7284)
			)
		)
		(polygon
			(pts
				(xy 318.8462 -162.9156) (xy 318.5922 -162.9156) (xy 318.5922 -163.1696) (xy 318.8462 -163.1696)
			)
		)
		(polygon
			(pts
				(xy 318.8462 -162.4584) (xy 318.5922 -162.4584) (xy 318.5922 -162.7124) (xy 318.8462 -162.7124)
			)
		)
		(polygon
			(pts
				(xy 318.8462 -161.8996) (xy 318.5922 -161.8996) (xy 318.5922 -162.1536) (xy 318.8462 -162.1536)
			)
		)
		(polygon
			(pts
				(xy 318.8462 -161.4424) (xy 318.5922 -161.4424) (xy 318.5922 -161.6964) (xy 318.8462 -161.6964)
			)
		)
	)
	(zone
		(layer "F.Cu")
		(hatch none 0.5)
		(connect_pads
			(clearance 0)
		)
		(min_thickness 0.25)
		(keepout
			(tracks not_allowed)
			(vias allowed)
			(pads allowed)
			(copperpour not_allowed)
			(footprints allowed)
		)
		(placement
			(enabled no)
			(sheetname "")
		)
		(fill
			(thermal_gap 0.5)
			(thermal_bridge_width 0.5)
			(island_removal_mode 0)
		)
		(polygon
			(pts
				(arc
					(start 83.46694 -34.61893)
					(mid 83.083527 -34.235136)
					(end 82.69986 -34.618676)
				)
				(arc
					(start 82.69986 -35.523678)
					(mid 83.0834 -35.907218)
					(end 83.46694 -35.523678)
				)
				(xy 83.46694 -35.228784) (xy 83.4517 -35.233864)
				(arc
					(start 83.277964 -35.305746)
					(mid 82.95667 -35.786906)
					(end 83.132422 -35.235642)
				)
				(xy 83.1596 -35.218878) (xy 83.160362 -35.2171) (xy 83.184746 -35.20694) (xy 83.402678 -35.11677)
				(xy 83.403186 -35.116516) (xy 83.427062 -35.10661)
				(arc
					(start 83.429094 -35.107372)
					(mid 83.447871 -35.102628)
					(end 83.46694 -35.099244)
				)
				(arc
					(start 83.46694 -34.874454)
					(mid 83.375678 -34.856744)
					(end 83.287362 -34.827718)
				)
				(arc
					(start 83.287362 -34.827718)
					(mid 82.83798 -34.459758)
					(end 83.357974 -34.718498)
				)
				(arc
					(start 83.357974 -34.718498)
					(mid 83.411822 -34.734838)
					(end 83.46694 -34.746184)
				)
			)
		)
	)
	(zone
		(net "GND")
		(layer "F.Cu")
		(hatch none 0.5)
		(connect_pads
			(clearance 0.5)
		)
		(min_thickness 0.25)
		(fill yes
			(thermal_gap 0.5)
			(thermal_bridge_width 0.5)
			(island_removal_mode 0)
		)
		(polygon
			(pts
				(xy 260.858 -62.611) (xy 260.477 -62.992) (xy 260.477 -64.897) (xy 260.731 -65.151) (xy 264.033 -65.151)
				(xy 264.16 -65.024) (xy 264.16 -62.865) (xy 263.906 -62.611)
			)
		)
	)
	(zone
		(net "TPS74801_P1V53_STBY_IN")
		(layer "F.Cu")
		(hatch none 0.5)
		(connect_pads
			(clearance 0.5)
		)
		(min_thickness 0.25)
		(fill yes
			(thermal_gap 0.5)
			(thermal_bridge_width 0.5)
			(island_removal_mode 0)
		)
		(polygon
			(pts
				(xy 280.035 -220.853) (xy 278.765 -222.123) (xy 273.177 -222.123) (xy 272.415 -222.885) (xy 272.415 -224.663)
				(xy 272.796 -225.044) (xy 281.94 -225.044) (xy 282.448 -224.536) (xy 282.448 -223.139) (xy 282.321 -223.012)
				(xy 281.813 -223.012) (xy 281.686 -222.885) (xy 281.686 -220.98) (xy 281.559 -220.853)
			)
		)
		(polygon
			(pts
				(xy 279.696672 -224.227136) (xy 279.442672 -224.227136) (xy 279.442672 -224.481136) (xy 279.696672 -224.481136)
			)
		)
		(polygon
			(pts
				(xy 279.087072 -224.227136) (xy 278.833072 -224.227136) (xy 278.833072 -224.481136) (xy 279.087072 -224.481136)
			)
		)
	)
	(zone
		(net "SAS0_AVDD")
		(layer "F.Cu")
		(hatch none 0.5)
		(connect_pads
			(clearance 0.5)
		)
		(min_thickness 0.25)
		(fill yes
			(thermal_gap 0.5)
			(thermal_bridge_width 0.5)
			(island_removal_mode 0)
		)
		(polygon
			(pts
				(xy 79.502 -26.289) (xy 78.867 -26.924) (xy 78.867 -29.21) (xy 76.962 -31.115) (xy 76.073 -31.115)
				(xy 75.946 -31.242) (xy 75.946 -32.385) (xy 75.819 -32.512) (xy 74.676 -32.512) (xy 74.549 -32.639)
				(xy 74.549 -33.655) (xy 74.676 -33.782) (xy 81.534 -33.782) (xy 83.693 -31.623) (xy 85.217 -31.623)
				(xy 85.725 -31.115) (xy 85.725 -26.543) (xy 85.471 -26.289)
			)
		)
		(polygon
			(pts
				(xy 84.9122 -31.1404) (xy 84.0232 -31.1404) (xy 84.0232 -31.3944) (xy 84.9122 -31.3944)
			)
		)
	)
	(zone
		(layer "F.Cu")
		(hatch none 0.5)
		(connect_pads
			(clearance 0)
		)
		(min_thickness 0.25)
		(keepout
			(tracks allowed)
			(vias allowed)
			(pads allowed)
			(copperpour allowed)
			(footprints allowed)
		)
		(placement
			(enabled no)
			(sheetname "")
		)
		(fill
			(thermal_gap 0.5)
			(thermal_bridge_width 0.5)
			(island_removal_mode 0)
		)
		(polygon
			(pts
				(xy 285.75 -220.599) (xy 285.75 -219.456) (xy 287.782 -219.456) (xy 287.782 -220.599)
			)
		)
	)
	(zone
		(net "VT235_VDDH")
		(layer "F.Cu")
		(hatch none 0.5)
		(connect_pads
			(clearance 0.5)
		)
		(min_thickness 0.25)
		(fill yes
			(thermal_gap 0.5)
			(thermal_bridge_width 0.5)
			(island_removal_mode 0)
		)
		(polygon
			(pts
				(xy 75.438 -3.429) (xy 75.2348 -3.6322) (xy 75.2348 -17.7292) (xy 75.7428 -18.2372) (xy 77.851 -18.2372)
				(xy 78.6511 -19.0373) (xy 79.0067 -19.0373) (xy 79.0448 -19.0754) (xy 79.8576 -19.0754) (xy 79.883 -19.05)
				(xy 81.788 -19.05) (xy 82.296 -19.558) (xy 83.947 -19.558) (xy 84.074 -19.431) (xy 84.074 -18.796)
				(xy 83.947 -18.669) (xy 82.804 -18.669) (xy 82.55 -18.415) (xy 80.01 -18.415) (xy 79.883 -18.288)
				(xy 79.883 -17.9324) (xy 79.8957 -17.9197) (xy 79.8957 -16.8021) (xy 79.4512 -16.3576) (xy 79.4512 -12.4714)
				(xy 78.994 -12.0142) (xy 78.994 -3.683) (xy 78.74 -3.429)
			)
		)
		(polygon
			(pts
				(xy 78.3844 -17.1196) (xy 78.1304 -17.1196) (xy 78.1304 -17.3736) (xy 78.3844 -17.3736)
			)
		)
		(polygon
			(pts
				(xy 77.5208 -17.1196) (xy 77.2668 -17.1196) (xy 77.2668 -17.3736) (xy 77.5208 -17.3736)
			)
		)
		(polygon
			(pts
				(xy 77.1144 -17.1196) (xy 76.8604 -17.1196) (xy 76.8604 -17.3736) (xy 77.1144 -17.3736)
			)
		)
		(polygon
			(pts
				(xy 76.2508 -17.1196) (xy 75.9968 -17.1196) (xy 75.9968 -17.3736) (xy 76.2508 -17.3736)
			)
		)
		(polygon
			(pts
				(xy 78.4606 -15.9766) (xy 78.2066 -15.9766) (xy 78.2066 -16.2306) (xy 78.4606 -16.2306)
			)
		)
		(polygon
			(pts
				(xy 78.4606 -15.113) (xy 78.2066 -15.113) (xy 78.2066 -15.367) (xy 78.4606 -15.367)
			)
		)
		(polygon
			(pts
				(xy 78.4606 -14.7066) (xy 78.2066 -14.7066) (xy 78.2066 -14.9606) (xy 78.4606 -14.9606)
			)
		)
		(polygon
			(pts
				(xy 78.4606 -13.843) (xy 78.2066 -13.843) (xy 78.2066 -14.097) (xy 78.4606 -14.097)
			)
		)
		(polygon
			(pts
				(xy 78.4606 -13.4366) (xy 78.2066 -13.4366) (xy 78.2066 -13.6906) (xy 78.4606 -13.6906)
			)
		)
		(polygon
			(pts
				(xy 78.4606 -12.573) (xy 78.2066 -12.573) (xy 78.2066 -12.827) (xy 78.4606 -12.827)
			)
		)
	)
	(zone
		(net "VT235_VX")
		(layer "F.Cu")
		(hatch none 0.5)
		(connect_pads
			(clearance 0.5)
		)
		(min_thickness 0.25)
		(fill yes
			(thermal_gap 0.5)
			(thermal_bridge_width 0.5)
			(island_removal_mode 0)
		)
		(polygon
			(pts
				(xy 83.947 -12.954) (xy 83.566 -13.335) (xy 83.566 -16.129) (xy 82.931 -16.764) (xy 82.931 -18.415)
				(xy 83.058 -18.542) (xy 85.344 -18.542) (xy 86.233 -17.653) (xy 88.265 -17.653) (xy 88.773 -17.145)
				(xy 88.773 -13.335) (xy 88.392 -12.954)
			)
		)
		(polygon
			(pts
				(xy 87.6808 -16.637) (xy 87.4268 -16.637) (xy 87.4268 -16.891) (xy 87.6808 -16.891)
			)
		)
		(polygon
			(pts
				(xy 86.8172 -16.637) (xy 86.5632 -16.637) (xy 86.5632 -16.891) (xy 86.8172 -16.891)
			)
		)
	)
	(zone
		(net "GND")
		(layer "F.Cu")
		(hatch none 0.5)
		(connect_pads
			(clearance 0.5)
		)
		(min_thickness 0.25)
		(fill yes
			(thermal_gap 0.5)
			(thermal_bridge_width 0.5)
			(island_removal_mode 0)
		)
		(polygon
			(pts
				(xy 82.931 -33.655) (xy 82.423 -34.163) (xy 75.946 -34.163) (xy 75.565 -34.544) (xy 75.565 -37.973)
				(xy 75.946 -38.354) (xy 82.677 -38.354) (xy 84.3534 -36.6776) (xy 84.3534 -33.8836) (xy 84.1248 -33.655)
			)
		)
	)
	(zone
		(net "GB_VDDA")
		(layer "F.Cu")
		(hatch none 0.5)
		(connect_pads
			(clearance 0.5)
		)
		(min_thickness 0.25)
		(fill yes
			(thermal_gap 0.5)
			(thermal_bridge_width 0.5)
			(island_removal_mode 0)
		)
		(polygon
			(pts
				(xy 145.288 -92.837) (xy 145.034 -93.091) (xy 145.034 -115.062) (xy 145.415 -115.443) (xy 151.638 -115.443)
				(xy 152.146 -114.935) (xy 152.146 -93.091) (xy 151.892 -92.837)
			)
		)
		(polygon
			(pts
				(xy 151.231092 -114.888264) (xy 150.977092 -114.888264) (xy 150.977092 -115.142264) (xy 151.231092 -115.142264)
			)
		)
		(polygon
			(pts
				(xy 151.231092 -114.024664) (xy 150.977092 -114.024664) (xy 150.977092 -114.278664) (xy 151.231092 -114.278664)
			)
		)
		(polygon
			(pts
				(xy 151.231092 -113.618264) (xy 150.977092 -113.618264) (xy 150.977092 -113.872264) (xy 151.231092 -113.872264)
			)
		)
		(polygon
			(pts
				(xy 151.231092 -112.754664) (xy 150.977092 -112.754664) (xy 150.977092 -113.008664) (xy 151.231092 -113.008664)
			)
		)
		(polygon
			(pts
				(xy 151.231092 -112.348264) (xy 150.977092 -112.348264) (xy 150.977092 -112.602264) (xy 151.231092 -112.602264)
			)
		)
		(polygon
			(pts
				(xy 151.231092 -111.484664) (xy 150.977092 -111.484664) (xy 150.977092 -111.738664) (xy 151.231092 -111.738664)
			)
		)
		(polygon
			(pts
				(xy 151.231092 -111.078264) (xy 150.977092 -111.078264) (xy 150.977092 -111.332264) (xy 151.231092 -111.332264)
			)
		)
		(polygon
			(pts
				(xy 151.231092 -110.214664) (xy 150.977092 -110.214664) (xy 150.977092 -110.468664) (xy 151.231092 -110.468664)
			)
		)
		(polygon
			(pts
				(xy 151.231092 -109.808264) (xy 150.977092 -109.808264) (xy 150.977092 -110.062264) (xy 151.231092 -110.062264)
			)
		)
		(polygon
			(pts
				(xy 151.231092 -108.944664) (xy 150.977092 -108.944664) (xy 150.977092 -109.198664) (xy 151.231092 -109.198664)
			)
		)
		(polygon
			(pts
				(xy 151.231092 -108.538264) (xy 150.977092 -108.538264) (xy 150.977092 -108.792264) (xy 151.231092 -108.792264)
			)
		)
		(polygon
			(pts
				(xy 151.231092 -107.674664) (xy 150.977092 -107.674664) (xy 150.977092 -107.928664) (xy 151.231092 -107.928664)
			)
		)
	)
	(zone
		(layer "F.Cu")
		(hatch none 0.5)
		(connect_pads
			(clearance 0)
		)
		(min_thickness 0.25)
		(keepout
			(tracks allowed)
			(vias allowed)
			(pads allowed)
			(copperpour allowed)
			(footprints allowed)
		)
		(placement
			(enabled no)
			(sheetname "")
		)
		(fill
			(thermal_gap 0.5)
			(thermal_bridge_width 0.5)
			(island_removal_mode 0)
		)
		(polygon
			(pts
				(xy 83.312 -123.317) (xy 83.312 -122.301) (xy 84.836 -122.301) (xy 84.836 -123.317)
			)
		)
	)
	(zone
		(net "P3V3_STBY")
		(layer "F.Cu")
		(hatch none 0.5)
		(connect_pads
			(clearance 0.5)
		)
		(min_thickness 0.25)
		(fill yes
			(thermal_gap 0.5)
			(thermal_bridge_width 0.5)
			(island_removal_mode 0)
		)
		(polygon
			(pts
				(xy 305.562 -51.943) (xy 305.308 -52.197) (xy 305.308 -54.356) (xy 304.292 -55.372) (xy 286.004 -55.372)
				(xy 285.75 -55.626) (xy 285.75 -58.547) (xy 286.004 -58.801) (xy 294.259 -58.801) (xy 294.894 -58.166)
				(xy 300.863 -58.166) (xy 301.117 -57.912) (xy 301.117 -57.277) (xy 301.4853 -56.9087) (xy 302.5521 -56.9087)
				(xy 302.5648 -56.9214) (xy 304.6476 -56.9214) (xy 306.578 -54.991) (xy 306.578 -53.467) (xy 307.34 -52.705)
				(xy 309.626 -52.705) (xy 309.753 -52.578) (xy 309.753 -52.197) (xy 309.499 -51.943)
			)
		)
		(polygon
			(pts
				(xy 300.958758 -57.404) (xy 300.704758 -57.404) (xy 300.704758 -57.658) (xy 300.958758 -57.658)
			)
		)
		(polygon
			(pts
				(xy 300.349158 -57.404) (xy 299.815758 -57.404) (xy 299.815758 -57.658) (xy 300.349158 -57.658)
			)
		)
		(polygon
			(pts
				(xy 299.460158 -57.404) (xy 299.206158 -57.404) (xy 299.206158 -57.658) (xy 299.460158 -57.658)
			)
		)
		(polygon
			(pts
				(xy 299.053758 -56.896) (xy 298.799758 -56.896) (xy 298.799758 -57.15) (xy 299.053758 -57.15)
			)
		)
		(polygon
			(pts
				(xy 298.190158 -56.896) (xy 297.936158 -56.896) (xy 297.936158 -57.15) (xy 298.190158 -57.15)
			)
		)
	)
	(zone
		(layer "F.Cu")
		(hatch none 0.5)
		(connect_pads
			(clearance 0)
		)
		(min_thickness 0.25)
		(keepout
			(tracks not_allowed)
			(vias allowed)
			(pads allowed)
			(copperpour not_allowed)
			(footprints allowed)
		)
		(placement
			(enabled no)
			(sheetname "")
		)
		(fill
			(thermal_gap 0.5)
			(thermal_bridge_width 0.5)
			(island_removal_mode 0)
		)
		(polygon
			(pts
				(arc
					(start 13.53693 -98.760534)
					(mid 13.413998 -98.193183)
					(end 13.66393 -98.7171)
				)
				(xy 13.66393 -98.862388) (xy 14.33703 -98.89871)
				(arc
					(start 14.33703 -98.790506)
					(mid 14.49724 -98.232613)
					(end 14.46403 -98.812096)
				)
				(arc
					(start 14.46403 -98.90379)
					(mid 14.831883 -98.523047)
					(end 14.46911 -98.137472)
				)
				(arc
					(start 13.52931 -98.086672)
					(mid 13.12545 -98.448876)
					(end 13.487654 -98.852736)
				)
				(xy 13.53693 -98.855276)
			)
		)
	)
	(zone
		(net "P5V_USB")
		(layer "F.Cu")
		(hatch none 0.5)
		(connect_pads
			(clearance 0.5)
		)
		(min_thickness 0.25)
		(fill yes
			(thermal_gap 0.5)
			(thermal_bridge_width 0.5)
			(island_removal_mode 0)
		)
		(polygon
			(pts
				(xy 267.589 -9.906) (xy 266.192 -11.303) (xy 257.429 -11.303) (xy 256.921 -11.811) (xy 256.921 -16.129)
				(xy 257.302 -16.51) (xy 271.2085 -16.51) (xy 271.399 -16.7005) (xy 271.4625 -16.7005) (xy 273.177 -18.415)
				(xy 273.177 -19.05) (xy 273.558 -19.431) (xy 276.098 -19.431) (xy 276.606 -19.939) (xy 276.606 -20.828)
				(xy 276.733 -20.955) (xy 277.241 -20.955) (xy 277.368 -20.828) (xy 277.368 -18.923) (xy 276.733 -18.288)
				(xy 275.463 -18.288) (xy 269.748 -12.573) (xy 269.748 -10.287) (xy 269.367 -9.906)
			)
		)
		(polygon
			(pts
				(xy 274.047966 -18.912332) (xy 273.793966 -18.912332) (xy 273.793966 -19.166332) (xy 274.047966 -19.166332)
			)
		)
		(polygon
			(pts
				(xy 274.047966 -18.302732) (xy 273.793966 -18.302732) (xy 273.793966 -18.556732) (xy 274.047966 -18.556732)
			)
		)
		(polygon
			(pts
				(xy 271.0688 -15.875) (xy 270.8148 -15.875) (xy 270.8148 -16.129) (xy 271.0688 -16.129)
			)
		)
		(polygon
			(pts
				(xy 270.4592 -15.875) (xy 270.2052 -15.875) (xy 270.2052 -16.129) (xy 270.4592 -16.129)
			)
		)
	)
	(zone
		(layer "F.Cu")
		(hatch none 0.5)
		(connect_pads
			(clearance 0)
		)
		(min_thickness 0.25)
		(keepout
			(tracks not_allowed)
			(vias allowed)
			(pads allowed)
			(copperpour not_allowed)
			(footprints allowed)
		)
		(placement
			(enabled no)
			(sheetname "")
		)
		(fill
			(thermal_gap 0.5)
			(thermal_bridge_width 0.5)
			(island_removal_mode 0)
		)
		(polygon
			(pts
				(arc
					(start 11.13663 -98.785172)
					(mid 11.091569 -98.206532)
					(end 11.26363 -98.760788)
				)
				(xy 11.26363 -98.87712) (xy 11.93673 -98.87839)
				(arc
					(start 11.93673 -98.759518)
					(mid 12.123202 -98.209684)
					(end 12.06373 -98.787204)
				)
				(arc
					(start 12.06373 -98.878644)
					(mid 12.444232 -98.493961)
					(end 12.061444 -98.111564)
				)
				(arc
					(start 11.147044 -98.109786)
					(mid 10.762777 -98.48812)
					(end 11.13663 -98.876866)
				)
			)
		)
	)
	(zone
		(net "GND")
		(layer "F.Cu")
		(hatch none 0.5)
		(connect_pads
			(clearance 0.5)
		)
		(min_thickness 0.25)
		(fill yes
			(thermal_gap 0.5)
			(thermal_bridge_width 0.5)
			(island_removal_mode 0)
		)
		(polygon
			(pts
				(xy 78.594966 -67.818) (xy 78.340966 -68.072) (xy 78.340966 -69.469) (xy 78.467966 -69.596) (xy 81.769966 -69.596)
				(xy 81.896966 -69.469) (xy 81.896966 -67.945) (xy 81.769966 -67.818)
			)
		)
		(polygon
			(pts
				(xy 81.211166 -68.199) (xy 80.957166 -68.199) (xy 80.957166 -68.453) (xy 81.211166 -68.453)
			)
		)
		(polygon
			(pts
				(xy 80.550766 -68.199) (xy 80.296766 -68.199) (xy 80.296766 -68.453) (xy 80.550766 -68.453)
			)
		)
		(polygon
			(pts
				(xy 79.941166 -68.199) (xy 79.687166 -68.199) (xy 79.687166 -68.453) (xy 79.941166 -68.453)
			)
		)
		(polygon
			(pts
				(xy 79.280766 -68.199) (xy 79.026766 -68.199) (xy 79.026766 -68.453) (xy 79.280766 -68.453)
			)
		)
	)
	(zone
		(layer "F.Cu")
		(hatch none 0.5)
		(connect_pads
			(clearance 0)
		)
		(min_thickness 0.25)
		(keepout
			(tracks not_allowed)
			(vias allowed)
			(pads allowed)
			(copperpour not_allowed)
			(footprints allowed)
		)
		(placement
			(enabled no)
			(sheetname "")
		)
		(fill
			(thermal_gap 0.5)
			(thermal_bridge_width 0.5)
			(island_removal_mode 0)
		)
		(polygon
			(pts
				(xy 119.000016 -59.30011) (xy 119.000016 -70.300088) (xy 130.50012 -70.300088) (xy 130.50012 -59.30011)
			)
		)
	)
	(zone
		(layer "F.Cu")
		(hatch none 0.5)
		(connect_pads
			(clearance 0)
		)
		(min_thickness 0.25)
		(keepout
			(tracks allowed)
			(vias allowed)
			(pads allowed)
			(copperpour allowed)
			(footprints not_allowed)
		)
		(placement
			(enabled no)
			(sheetname "")
		)
		(fill
			(thermal_gap 0.5)
			(thermal_bridge_width 0.5)
			(island_removal_mode 0)
		)
		(polygon
			(pts
				(xy 119.000016 -25.80005) (xy 119.000016 -59.30011) (xy 130.50012 -59.30011) (xy 130.50012 -25.80005)
			)
		)
	)
	(zone
		(net "SAS0_VDDH")
		(layer "F.Cu")
		(hatch none 0.5)
		(connect_pads
			(clearance 0.5)
		)
		(min_thickness 0.25)
		(fill yes
			(thermal_gap 0.5)
			(thermal_bridge_width 0.5)
			(island_removal_mode 0)
		)
		(polygon
			(pts
				(xy 69.596 -44.6278) (xy 69.0372 -45.1866) (xy 69.0372 -48.641) (xy 68.6562 -49.022) (xy 67.5132 -49.022)
				(xy 67.2592 -49.276) (xy 67.2592 -50.3428) (xy 67.4624 -50.546) (xy 69.85 -50.546) (xy 73.152 -47.244)
				(xy 73.152 -44.8056) (xy 72.9742 -44.6278)
			)
		)
		(polygon
			(pts
				(xy 69.8754 -49.8348) (xy 69.6214 -49.8348) (xy 69.6214 -50.0888) (xy 69.8754 -50.0888)
			)
		)
		(polygon
			(pts
				(xy 69.3166 -49.8348) (xy 69.0626 -49.8348) (xy 69.0626 -50.0888) (xy 69.3166 -50.0888)
			)
		)
	)
	(zone
		(layer "F.Cu")
		(hatch none 0.5)
		(connect_pads
			(clearance 0)
		)
		(min_thickness 0.25)
		(keepout
			(tracks allowed)
			(vias allowed)
			(pads allowed)
			(copperpour allowed)
			(footprints allowed)
		)
		(placement
			(enabled no)
			(sheetname "")
		)
		(fill
			(thermal_gap 0.5)
			(thermal_bridge_width 0.5)
			(island_removal_mode 0)
		)
		(polygon
			(pts
				(xy 58.547 -219.583) (xy 58.547 -217.678) (xy 60.96 -217.678) (xy 60.96 -219.583)
			)
		)
	)
	(zone
		(net "P0V955_C")
		(layer "F.Cu")
		(hatch none 0.5)
		(connect_pads
			(clearance 0.5)
		)
		(min_thickness 0.25)
		(fill yes
			(thermal_gap 0.5)
			(thermal_bridge_width 0.5)
			(island_removal_mode 0)
		)
		(polygon
			(pts
				(xy 94.615 -4.318) (xy 94.488 -4.445) (xy 83.185 -4.445) (xy 83.058 -4.572) (xy 83.058 -10.541)
				(xy 83.439 -10.922) (xy 88.773 -10.922) (xy 89.408 -10.287) (xy 96.901 -10.287) (xy 97.155 -10.541)
				(xy 101.727 -10.541) (xy 102.108 -10.16) (xy 102.108 -4.572) (xy 101.854 -4.318)
			)
		)
		(polygon
			(pts
				(xy 100.1268 -9.525) (xy 99.8728 -9.525) (xy 99.8728 -9.779) (xy 100.1268 -9.779)
			)
		)
		(polygon
			(pts
				(xy 99.2632 -9.525) (xy 99.0092 -9.525) (xy 99.0092 -9.779) (xy 99.2632 -9.779)
			)
		)
		(polygon
			(pts
				(xy 97.0788 -4.826) (xy 96.8248 -4.826) (xy 96.8248 -5.08) (xy 97.0788 -5.08)
			)
		)
		(polygon
			(pts
				(xy 96.4692 -4.826) (xy 95.9358 -4.826) (xy 95.9358 -5.08) (xy 96.4692 -5.08)
			)
		)
		(polygon
			(pts
				(xy 95.5802 -4.826) (xy 95.0468 -4.826) (xy 95.0468 -5.08) (xy 95.5802 -5.08)
			)
		)
		(polygon
			(pts
				(xy 94.6912 -4.826) (xy 94.4372 -4.826) (xy 94.4372 -5.08) (xy 94.6912 -5.08)
			)
		)
	)
	(zone
		(net "GND")
		(layer "F.Cu")
		(hatch none 0.5)
		(connect_pads
			(clearance 0.5)
		)
		(min_thickness 0.25)
		(fill yes
			(thermal_gap 0.5)
			(thermal_bridge_width 0.5)
			(island_removal_mode 0)
		)
		(polygon
			(pts
				(xy 49.53 -142.621) (xy 48.895 -143.256) (xy 48.895 -146.177) (xy 47.625 -147.447) (xy 44.958 -147.447)
				(xy 44.45 -147.955) (xy 44.45 -165.989) (xy 44.958 -166.497) (xy 52.07 -166.497) (xy 55.626 -162.941)
				(xy 55.626 -145.796) (xy 53.594 -143.764) (xy 53.594 -142.875) (xy 53.34 -142.621)
			)
		)
	)
	(zone
		(net "SHELL_PLL_VDD")
		(layer "F.Cu")
		(hatch none 0.5)
		(connect_pads
			(clearance 0.5)
		)
		(min_thickness 0.25)
		(fill yes
			(thermal_gap 0.5)
			(thermal_bridge_width 0.5)
			(island_removal_mode 0)
		)
		(polygon
			(pts
				(xy 79.356966 -53.34) (xy 78.848966 -53.848) (xy 78.848966 -60.833) (xy 78.603856 -61.07811) (xy 77.47889 -61.07811)
				(xy 77.343 -61.214) (xy 77.343 -62.357) (xy 77.597 -62.611) (xy 79.756 -62.611) (xy 80.01 -62.357)
				(xy 80.01 -61.849) (xy 80.880966 -60.978034) (xy 80.880966 -53.594) (xy 80.626966 -53.34)
			)
		)
		(polygon
			(pts
				(xy 79.47279 -61.867288) (xy 79.21879 -61.867288) (xy 79.21879 -62.121288) (xy 79.47279 -62.121288)
			)
		)
		(polygon
			(pts
				(xy 79.34579 -55.923688) (xy 79.09179 -55.923688) (xy 79.09179 -56.533288) (xy 79.34579 -56.533288)
			)
		)
		(polygon
			(pts
				(xy 79.34579 -55.034688) (xy 79.09179 -55.034688) (xy 79.09179 -55.644288) (xy 79.34579 -55.644288)
			)
		)
	)
	(zone
		(layer "F.Cu")
		(hatch none 0.5)
		(connect_pads
			(clearance 0)
		)
		(min_thickness 0.25)
		(keepout
			(tracks allowed)
			(vias allowed)
			(pads allowed)
			(copperpour allowed)
			(footprints not_allowed)
		)
		(placement
			(enabled no)
			(sheetname "")
		)
		(fill
			(thermal_gap 0.5)
			(thermal_bridge_width 0.5)
			(island_removal_mode 0)
		)
		(polygon
			(pts
				(arc
					(start 4.99999 -251.000006)
					(mid 4.497443 -250.974661)
					(end 3.999992 -250.898914)
				)
				(xy 3.999992 -109.000036) (xy 224.700084 -109.000036) (xy 224.700084 -251.000006)
			)
		)
	)
	(zone
		(net "GND")
		(layer "F.Cu")
		(hatch none 0.5)
		(connect_pads
			(clearance 0.5)
		)
		(min_thickness 0.25)
		(fill yes
			(thermal_gap 0.5)
			(thermal_bridge_width 0.5)
			(island_removal_mode 0)
		)
		(polygon
			(pts
				(xy 353.187 -90.678) (xy 351.917 -91.948) (xy 351.917 -144.145) (xy 353.822 -146.05) (xy 353.822 -168.402)
				(xy 343.535 -178.689) (xy 343.535 -234.569) (xy 337.693 -240.411) (xy 264.922 -240.411) (xy 254.635 -230.124)
				(xy 254.635 -198.374) (xy 253.492 -197.231) (xy 253.492 -196.215) (xy 253.111 -195.834) (xy 253.111 -194.564)
				(xy 251.714 -193.167) (xy 250.698 -193.167) (xy 250.19 -192.659) (xy 250.19 -191.516) (xy 256.54 -185.166)
				(xy 256.54 -154.178) (xy 252.095 -149.733) (xy 239.395 -149.733) (xy 238.76 -150.368) (xy 238.76 -164.084)
				(xy 239.903 -165.227) (xy 249.428 -165.227) (xy 250.698 -166.497) (xy 250.698 -176.149) (xy 229.362 -197.485)
				(xy 229.362 -242.316) (xy 224.282 -247.396) (xy 191.77 -247.396) (xy 190.881 -246.507) (xy 190.881 -237.236)
				(xy 191.643 -236.474) (xy 214.63 -236.474) (xy 217.805 -233.299) (xy 217.805 -220.218) (xy 217.297 -219.71)
				(xy 215.773 -219.71) (xy 215.265 -220.218) (xy 215.265 -221.107) (xy 214.503 -221.869) (xy 203.581 -221.869)
				(xy 202.438 -223.012) (xy 202.438 -226.441) (xy 201.422 -227.457) (xy 200.152 -227.457) (xy 200.025 -227.584)
				(xy 200.025 -228.346) (xy 199.644 -228.727) (xy 176.53 -228.727) (xy 168.021 -220.218) (xy 168.021 -177.673)
				(xy 170.18 -175.514) (xy 183.642 -175.514) (xy 186.055 -173.101) (xy 186.055 -172.212) (xy 188.087 -170.18)
				(xy 192.786 -170.18) (xy 193.675 -169.291) (xy 193.675 -167.386) (xy 193.04 -166.751) (xy 193.04 -163.576)
				(xy 193.929 -162.687) (xy 208.915 -162.687) (xy 210.058 -161.544) (xy 210.058 -147.447) (xy 209.042 -146.431)
				(xy 203.962 -146.431) (xy 202.565 -147.828) (xy 201.93 -147.828) (xy 201.803 -147.955) (xy 201.803 -148.717)
				(xy 201.549 -148.971) (xy 197.739 -148.971) (xy 195.707 -151.003) (xy 181.864 -151.003) (xy 174.244 -158.623)
				(xy 157.353 -158.623) (xy 155.575 -160.401) (xy 155.575 -168.021) (xy 151.765 -171.831) (xy 151.765 -234.569)
				(xy 151.13 -235.204) (xy 151.13 -249.936) (xy 151.384 -250.19) (xy 181.991 -250.19) (xy 183.007 -251.206)
				(xy 183.007 -253.365) (xy 183.261 -253.619) (xy 188.087 -253.619) (xy 188.468 -253.238) (xy 188.468 -251.841)
				(xy 189.611 -250.698) (xy 191.008 -250.698) (xy 192.151 -251.841) (xy 192.151 -253.746) (xy 192.278 -253.873)
				(xy 201.422 -253.873) (xy 201.676 -253.619) (xy 201.676 -251.206) (xy 202.692 -250.19) (xy 229.362 -250.19)
				(xy 233.299 -246.253) (xy 233.299 -196.215) (xy 234.442 -195.072) (xy 250.825 -195.072) (xy 251.968 -196.215)
				(xy 251.968 -246.634) (xy 255.397 -250.063) (xy 351.282 -250.063) (xy 354.711 -246.634) (xy 354.711 -228.473)
				(xy 354.838 -228.346) (xy 354.838 -91.059) (xy 354.457 -90.678)
			)
		)
		(polygon
			(pts
				(xy 201.168 -228.1428) (xy 200.914 -228.1428) (xy 200.914 -228.3968) (xy 201.168 -228.3968)
			)
		)
		(polygon
			(pts
				(xy 216.154 -220.7768) (xy 215.9 -220.7768) (xy 215.9 -221.0308) (xy 216.154 -221.0308)
			)
		)
		(polygon
			(pts
				(xy 216.154 -220.1672) (xy 215.9 -220.1672) (xy 215.9 -220.4212) (xy 216.154 -220.4212)
			)
		)
		(polygon
			(pts
				(xy 202.588876 -148.378672) (xy 202.334876 -148.378672) (xy 202.334876 -148.632672) (xy 202.588876 -148.632672)
			)
		)
	)
	(zone
		(layer "F.Cu")
		(hatch none 0.5)
		(connect_pads
			(clearance 0)
		)
		(min_thickness 0.25)
		(keepout
			(tracks not_allowed)
			(vias allowed)
			(pads allowed)
			(copperpour not_allowed)
			(footprints allowed)
		)
		(placement
			(enabled no)
			(sheetname "")
		)
		(fill
			(thermal_gap 0.5)
			(thermal_bridge_width 0.5)
			(island_removal_mode 0)
		)
		(polygon
			(pts
				(arc
					(start 74.44994 -15.999968)
					(mid 74.157047 -16.707073)
					(end 73.449942 -16.999966)
				)
				(arc
					(start 62.95009 -16.999966)
					(mid 62.242985 -17.292859)
					(end 61.950092 -17.999964)
				)
				(xy 61.900054 -44.500038) (xy 74.44994 -44.500038)
			)
		)
	)
	(zone
		(layer "F.Cu")
		(hatch none 0.5)
		(connect_pads
			(clearance 0)
		)
		(min_thickness 0.25)
		(keepout
			(tracks not_allowed)
			(vias allowed)
			(pads allowed)
			(copperpour not_allowed)
			(footprints allowed)
		)
		(placement
			(enabled no)
			(sheetname "")
		)
		(fill
			(thermal_gap 0.5)
			(thermal_bridge_width 0.5)
			(island_removal_mode 0)
		)
		(polygon
			(pts
				(xy 326.300084 -16.73733) (xy 326.300084 -27.737308) (xy 337.799934 -27.737308) (xy 337.799934 -16.73733)
			)
		)
	)
	(zone
		(net "GND")
		(layer "F.Cu")
		(hatch none 0.5)
		(connect_pads
			(clearance 0.5)
		)
		(min_thickness 0.25)
		(fill yes
			(thermal_gap 0.5)
			(thermal_bridge_width 0.5)
			(island_removal_mode 0)
		)
		(polygon
			(pts
				(xy 216.027 -28.194) (xy 215.265 -28.956) (xy 215.265 -39.497) (xy 230.378 -54.61) (xy 238.506 -54.61)
				(xy 238.76 -54.356) (xy 238.76 -39.116) (xy 227.838 -28.194)
			)
		)
	)
	(zone
		(layer "F.Cu")
		(hatch none 0.5)
		(connect_pads
			(clearance 0)
		)
		(min_thickness 0.25)
		(keepout
			(tracks not_allowed)
			(vias allowed)
			(pads allowed)
			(copperpour not_allowed)
			(footprints allowed)
		)
		(placement
			(enabled no)
			(sheetname "")
		)
		(fill
			(thermal_gap 0.5)
			(thermal_bridge_width 0.5)
			(island_removal_mode 0)
		)
		(polygon
			(pts
				(arc
					(start 159.947102 -76.64196)
					(mid 159.563308 -77.025373)
					(end 159.946848 -77.40904)
				)
				(arc
					(start 160.928812 -77.40904)
					(mid 161.312352 -77.0255)
					(end 160.928812 -76.64196)
				)
				(arc
					(start 160.776158 -76.64196)
					(mid 160.799641 -76.697774)
					(end 160.826704 -76.751942)
				)
				(arc
					(start 160.826704 -76.751942)
					(mid 161.104299 -77.259126)
					(end 160.693608 -76.852272)
				)
				(arc
					(start 160.693608 -76.852272)
					(mid 160.641988 -76.749536)
					(end 160.601406 -76.64196)
				)
				(arc
					(start 160.290764 -76.64196)
					(mid 160.243066 -76.751802)
					(end 160.1851 -76.85659)
				)
				(arc
					(start 160.1851 -76.85659)
					(mid 159.766534 -77.255242)
					(end 160.05429 -76.753974)
				)
				(arc
					(start 160.05429 -76.753974)
					(mid 160.084867 -76.698805)
					(end 160.112202 -76.64196)
				)
			)
		)
	)
	(zone
		(layer "F.Cu")
		(hatch none 0.5)
		(connect_pads
			(clearance 0)
		)
		(min_thickness 0.25)
		(keepout
			(tracks allowed)
			(vias allowed)
			(pads allowed)
			(copperpour allowed)
			(footprints not_allowed)
		)
		(placement
			(enabled no)
			(sheetname "")
		)
		(fill
			(thermal_gap 0.5)
			(thermal_bridge_width 0.5)
			(island_removal_mode 0)
		)
		(polygon
			(pts
				(xy 87.350092 -82.350102) (xy 119.000016 -82.350102) (xy 119.000016 0)
				(arc
					(start 75.449938 0)
					(mid 74.742833 -0.292893)
					(end 74.44994 -0.999998)
				)
				(xy 74.44994 -44.500038) (xy 72.749918 -44.500038) (xy 72.749918 -109.000036) (xy 182.699914 -109.000036)
				(xy 182.699914 -82.350102)
				(arc
					(start 145.349976 -82.350102)
					(mid 148.850096 -85.850222)
					(end 145.349976 -89.350088)
				)
				(arc
					(start 144.349978 -89.350088)
					(mid 142.874416 -90.00001)
					(end 142.357856 -91.527376)
				)
				(xy 142.349982 -107.350052)
				(arc
					(start 84.350098 -107.350052)
					(mid 80.850232 -103.850186)
					(end 84.350098 -100.350066)
				)
				(arc
					(start 85.350096 -100.350066)
					(mid 86.764307 -99.764281)
					(end 87.350092 -98.35007)
				)
			)
		)
	)
	(zone
		(layer "F.Cu")
		(hatch none 0.5)
		(connect_pads
			(clearance 0)
		)
		(min_thickness 0.25)
		(keepout
			(tracks allowed)
			(vias allowed)
			(pads allowed)
			(copperpour allowed)
			(footprints allowed)
		)
		(placement
			(enabled no)
			(sheetname "")
		)
		(fill
			(thermal_gap 0.5)
			(thermal_bridge_width 0.5)
			(island_removal_mode 0)
		)
		(polygon
			(pts
				(xy 51.435 -220.472) (xy 51.435 -217.551) (xy 53.975 -217.551) (xy 53.975 -220.472)
			)
		)
	)
	(zone
		(layer "F.Cu")
		(hatch none 0.5)
		(connect_pads
			(clearance 0)
		)
		(min_thickness 0.25)
		(keepout
			(tracks allowed)
			(vias allowed)
			(pads allowed)
			(copperpour allowed)
			(footprints not_allowed)
		)
		(placement
			(enabled no)
			(sheetname "")
		)
		(fill
			(thermal_gap 0.5)
			(thermal_bridge_width 0.5)
			(island_removal_mode 0)
		)
		(polygon
			(pts
				(arc
					(start 100.449888 -5.999988)
					(mid 104.950006 -1.49987)
					(end 109.450124 -5.999988)
				)
				(arc
					(start 109.450124 -5.999988)
					(mid 104.950006 -10.500106)
					(end 100.449888 -5.999988)
				)
			)
		)
	)
	(zone
		(net "GND")
		(layer "F.Cu")
		(hatch none 0.5)
		(connect_pads
			(clearance 0.5)
		)
		(min_thickness 0.25)
		(fill yes
			(thermal_gap 0.5)
			(thermal_bridge_width 0.5)
			(island_removal_mode 0)
		)
		(polygon
			(pts
				(xy 226.441 -14.859) (xy 226.187 -15.113) (xy 226.187 -15.748) (xy 226.441 -16.002) (xy 228.854 -16.002)
				(xy 229.235 -16.383) (xy 229.235 -17.399) (xy 229.489 -17.653) (xy 230.251 -17.653) (xy 230.378 -17.78)
				(xy 230.378 -18.288) (xy 230.505 -18.415) (xy 231.013 -18.415) (xy 231.14 -18.288) (xy 231.14 -14.986)
				(xy 231.013 -14.859)
			)
		)
		(polygon
			(pts
				(xy 230.1748 -16.764) (xy 229.9208 -16.764) (xy 229.9208 -17.018) (xy 230.1748 -17.018)
			)
		)
	)
	(zone
		(layer "F.Cu")
		(hatch none 0.5)
		(connect_pads
			(clearance 0)
		)
		(min_thickness 0.25)
		(keepout
			(tracks allowed)
			(vias allowed)
			(pads allowed)
			(copperpour allowed)
			(footprints not_allowed)
		)
		(placement
			(enabled no)
			(sheetname "")
		)
		(fill
			(thermal_gap 0.5)
			(thermal_bridge_width 0.5)
			(island_removal_mode 0)
		)
		(polygon
			(pts
				(xy 195.699888 -109.000036) (xy 182.699914 -109.000036) (xy 182.699914 -82.350102) (xy 195.699888 -82.350102)
			)
		)
	)
	(zone
		(net "P1V8_STBY_VIN")
		(layer "F.Cu")
		(hatch none 0.5)
		(connect_pads
			(clearance 0.5)
		)
		(min_thickness 0.25)
		(fill yes
			(thermal_gap 0.5)
			(thermal_bridge_width 0.5)
			(island_removal_mode 0)
		)
		(polygon
			(pts
				(xy 266.319 -41.275) (xy 266.192 -41.402) (xy 266.192 -42.545) (xy 266.446 -42.799) (xy 266.827 -42.799)
				(xy 267.208 -43.18) (xy 269.621 -43.18) (xy 270.002 -43.561) (xy 270.002 -44.577) (xy 270.256 -44.831)
				(xy 276.733 -44.831) (xy 276.987 -44.577) (xy 276.987 -41.529) (xy 276.733 -41.275)
			)
		)
		(polygon
			(pts
				(xy 275.9075 -44.4373) (xy 275.6535 -44.4373) (xy 275.6535 -44.6913) (xy 275.9075 -44.6913)
			)
		)
		(polygon
			(pts
				(xy 274.5105 -44.4373) (xy 274.2565 -44.4373) (xy 274.2565 -44.6913) (xy 274.5105 -44.6913)
			)
		)
		(polygon
			(pts
				(xy 275.9075 -43.2943) (xy 275.6535 -43.2943) (xy 275.6535 -43.5483) (xy 275.9075 -43.5483)
			)
		)
		(polygon
			(pts
				(xy 274.5105 -43.2943) (xy 274.2565 -43.2943) (xy 274.2565 -43.5483) (xy 274.5105 -43.5483)
			)
		)
		(polygon
			(pts
				(xy 271.1958 -42.037) (xy 270.9418 -42.037) (xy 270.9418 -42.291) (xy 271.1958 -42.291)
			)
		)
		(polygon
			(pts
				(xy 270.3322 -42.037) (xy 270.0782 -42.037) (xy 270.0782 -42.291) (xy 270.3322 -42.291)
			)
		)
	)
	(zone
		(layer "F.Cu")
		(hatch none 0.5)
		(connect_pads
			(clearance 0)
		)
		(min_thickness 0.25)
		(keepout
			(tracks allowed)
			(vias allowed)
			(pads allowed)
			(copperpour allowed)
			(footprints allowed)
		)
		(placement
			(enabled no)
			(sheetname "")
		)
		(fill
			(thermal_gap 0.5)
			(thermal_bridge_width 0.5)
			(island_removal_mode 0)
		)
		(polygon
			(pts
				(xy 305.181 -96.139) (xy 305.181 -75.311) (xy 300.863 -75.311) (xy 300.863 -74.803) (xy 300.863 -65.913)
				(xy 305.181 -65.913) (xy 313.69 -65.913) (xy 319.278 -65.913) (xy 319.278 -74.803) (xy 319.278 -83.439)
				(xy 317.246 -83.439) (xy 313.69 -83.439) (xy 313.69 -96.139)
			)
		)
	)
	(zone
		(layer "F.Cu")
		(hatch none 0.5)
		(connect_pads
			(clearance 0)
		)
		(min_thickness 0.25)
		(keepout
			(tracks allowed)
			(vias allowed)
			(pads allowed)
			(copperpour allowed)
			(footprints allowed)
		)
		(placement
			(enabled no)
			(sheetname "")
		)
		(fill
			(thermal_gap 0.5)
			(thermal_bridge_width 0.5)
			(island_removal_mode 0)
		)
		(polygon
			(pts
				(xy 340.233 -113.919) (xy 340.233 -112.268) (xy 341.63 -112.268) (xy 341.63 -113.919)
			)
		)
	)
	(zone
		(layers "F.Cu" "B.Cu")
		(hatch none 0.5)
		(connect_pads
			(clearance 0)
		)
		(min_thickness 0.25)
		(keepout
			(tracks allowed)
			(vias allowed)
			(pads allowed)
			(copperpour allowed)
			(footprints not_allowed)
		)
		(placement
			(enabled no)
			(sheetname "")
		)
		(fill yes
			(thermal_gap 0.5)
			(thermal_bridge_width 0.5)
			(island_removal_mode 0)
		)
		(polygon
			(pts
				(arc
					(start 260.46176 -61.999876)
					(mid 256.061718 -66.399918)
					(end 251.661676 -61.999876)
				)
				(arc
					(start 251.661676 -61.999876)
					(mid 256.061718 -57.599834)
					(end 260.46176 -61.999876)
				)
			)
		)
	)
	(zone
		(layers "F.Cu" "B.Cu")
		(hatch none 0.5)
		(connect_pads
			(clearance 0)
		)
		(min_thickness 0.25)
		(keepout
			(tracks not_allowed)
			(vias allowed)
			(pads allowed)
			(copperpour not_allowed)
			(footprints allowed)
		)
		(placement
			(enabled no)
			(sheetname "")
		)
		(fill yes
			(thermal_gap 0.5)
			(thermal_bridge_width 0.5)
			(island_removal_mode 0)
		)
		(polygon
			(pts
				(arc
					(start 53.311298 -74.523346)
					(mid 52.927758 -74.906886)
					(end 53.311298 -75.290426)
				)
				(xy 53.56479 -75.290426)
				(arc
					(start 53.56479 -75.266042)
					(mid 53.56189 -75.251462)
					(end 53.553614 -75.239118)
				)
				(arc
					(start 53.468016 -75.15352)
					(mid 53.104672 -74.70026)
					(end 53.557932 -75.063604)
				)
				(xy 53.662072 -75.167744)
				(arc
					(start 53.662072 -75.171554)
					(mid 53.679186 -75.202854)
					(end 53.68925 -75.237086)
				)
				(xy 53.69179 -75.239626) (xy 53.69179 -75.290426) (xy 53.90769 -75.290426) (xy 53.90769 -75.239626)
				(arc
					(start 53.91023 -75.237086)
					(mid 53.920234 -75.202829)
					(end 53.937408 -75.171554)
				)
				(xy 53.937408 -75.167744)
				(arc
					(start 54.041548 -75.063604)
					(mid 54.494808 -74.70026)
					(end 54.131464 -75.15352)
				)
				(arc
					(start 54.045866 -75.239118)
					(mid 54.037612 -75.251471)
					(end 54.03469 -75.266042)
				)
				(xy 54.03469 -75.290426)
				(arc
					(start 54.287928 -75.290426)
					(mid 54.671722 -74.907013)
					(end 54.288182 -74.523346)
				)
			)
		)
	)
	(zone
		(layers "F.Cu" "B.Cu")
		(hatch none 0.5)
		(connect_pads
			(clearance 0)
		)
		(min_thickness 0.25)
		(keepout
			(tracks allowed)
			(vias allowed)
			(pads allowed)
			(copperpour allowed)
			(footprints not_allowed)
		)
		(placement
			(enabled no)
			(sheetname "")
		)
		(fill yes
			(thermal_gap 0.5)
			(thermal_bridge_width 0.5)
			(island_removal_mode 0)
		)
		(polygon
			(pts
				(arc
					(start 260.46176 -104.499918)
					(mid 256.061718 -108.89996)
					(end 251.661676 -104.499918)
				)
				(arc
					(start 251.661676 -104.499918)
					(mid 256.061718 -100.099876)
					(end 260.46176 -104.499918)
				)
			)
		)
	)
	(zone
		(layers "F.Cu" "B.Cu")
		(hatch none 0.5)
		(connect_pads
			(clearance 0)
		)
		(min_thickness 0.25)
		(keepout
			(tracks not_allowed)
			(vias allowed)
			(pads allowed)
			(copperpour not_allowed)
			(footprints allowed)
		)
		(placement
			(enabled no)
			(sheetname "")
		)
		(fill yes
			(thermal_gap 0.5)
			(thermal_bridge_width 0.5)
			(island_removal_mode 0)
		)
		(polygon
			(pts
				(arc
					(start 44.511468 -74.523346)
					(mid 44.127928 -74.906886)
					(end 44.511468 -75.290426)
				)
				(xy 44.76496 -75.290426)
				(arc
					(start 44.76496 -75.266042)
					(mid 44.76206 -75.251462)
					(end 44.753784 -75.239118)
				)
				(arc
					(start 44.668186 -75.15352)
					(mid 44.304842 -74.70026)
					(end 44.758102 -75.063604)
				)
				(xy 44.862242 -75.167744)
				(arc
					(start 44.862242 -75.171554)
					(mid 44.879356 -75.202854)
					(end 44.88942 -75.237086)
				)
				(xy 44.89196 -75.239626) (xy 44.89196 -75.290426) (xy 45.10786 -75.290426) (xy 45.10786 -75.239626)
				(arc
					(start 45.1104 -75.237086)
					(mid 45.120404 -75.202829)
					(end 45.137578 -75.171554)
				)
				(xy 45.137578 -75.167744)
				(arc
					(start 45.241718 -75.063604)
					(mid 45.694978 -74.70026)
					(end 45.331634 -75.15352)
				)
				(arc
					(start 45.246036 -75.239118)
					(mid 45.237782 -75.251471)
					(end 45.23486 -75.266042)
				)
				(xy 45.23486 -75.290426)
				(arc
					(start 45.488098 -75.290426)
					(mid 45.871892 -74.907013)
					(end 45.488352 -74.523346)
				)
			)
		)
	)
	(zone
		(layers "F.Cu" "B.Cu")
		(hatch none 0.5)
		(connect_pads
			(clearance 0)
		)
		(min_thickness 0.25)
		(keepout
			(tracks not_allowed)
			(vias allowed)
			(pads allowed)
			(copperpour not_allowed)
			(footprints allowed)
		)
		(placement
			(enabled no)
			(sheetname "")
		)
		(fill yes
			(thermal_gap 0.5)
			(thermal_bridge_width 0.5)
			(island_removal_mode 0)
		)
		(polygon
			(pts
				(arc
					(start 42.111676 -74.370946)
					(mid 41.727882 -74.754359)
					(end 42.111422 -75.138026)
				)
				(xy 42.364914 -75.138026)
				(arc
					(start 42.364914 -75.113642)
					(mid 42.362014 -75.099062)
					(end 42.353738 -75.086718)
				)
				(arc
					(start 42.26814 -75.00112)
					(mid 41.904796 -74.54786)
					(end 42.358056 -74.911204)
				)
				(xy 42.462196 -75.015344)
				(arc
					(start 42.462196 -75.019154)
					(mid 42.47931 -75.050454)
					(end 42.489374 -75.084686)
				)
				(xy 42.491914 -75.087226) (xy 42.491914 -75.138026) (xy 42.707814 -75.138026) (xy 42.707814 -75.087226)
				(arc
					(start 42.710354 -75.084686)
					(mid 42.720358 -75.050429)
					(end 42.737532 -75.019154)
				)
				(xy 42.737532 -75.015344)
				(arc
					(start 42.841672 -74.911204)
					(mid 43.294932 -74.54786)
					(end 42.931588 -75.00112)
				)
				(arc
					(start 42.84599 -75.086718)
					(mid 42.837736 -75.099071)
					(end 42.834814 -75.113642)
				)
				(xy 42.834814 -75.138026)
				(arc
					(start 43.088306 -75.138026)
					(mid 43.471846 -74.754486)
					(end 43.088306 -74.370946)
				)
			)
		)
	)
	(zone
		(layers "F.Cu" "B.Cu")
		(hatch none 0.5)
		(connect_pads
			(clearance 0)
		)
		(min_thickness 0.25)
		(keepout
			(tracks allowed)
			(vias allowed)
			(pads allowed)
			(copperpour allowed)
			(footprints not_allowed)
		)
		(placement
			(enabled no)
			(sheetname "")
		)
		(fill yes
			(thermal_gap 0.5)
			(thermal_bridge_width 0.5)
			(island_removal_mode 0)
		)
		(polygon
			(pts
				(arc
					(start 251.661676 -104.499918)
					(mid 256.061718 -100.099876)
					(end 260.46176 -104.499918)
				)
				(arc
					(start 260.46176 -104.499918)
					(mid 256.061718 -108.89996)
					(end 251.661676 -104.499918)
				)
			)
		)
	)
	(zone
		(layers "F.Cu" "B.Cu")
		(hatch none 0.5)
		(connect_pads
			(clearance 0)
		)
		(min_thickness 0.25)
		(keepout
			(tracks not_allowed)
			(vias allowed)
			(pads allowed)
			(copperpour not_allowed)
			(footprints allowed)
		)
		(placement
			(enabled no)
			(sheetname "")
		)
		(fill yes
			(thermal_gap 0.5)
			(thermal_bridge_width 0.5)
			(island_removal_mode 0)
		)
		(polygon
			(pts
				(arc
					(start 50.911506 -74.523346)
					(mid 50.527966 -74.906886)
					(end 50.911506 -75.290426)
				)
				(xy 51.164998 -75.290426)
				(arc
					(start 51.164998 -75.266042)
					(mid 51.162098 -75.251462)
					(end 51.153822 -75.239118)
				)
				(arc
					(start 51.068224 -75.15352)
					(mid 50.70488 -74.70026)
					(end 51.15814 -75.063604)
				)
				(xy 51.26228 -75.167744)
				(arc
					(start 51.26228 -75.171554)
					(mid 51.279394 -75.202854)
					(end 51.289458 -75.237086)
				)
				(xy 51.291998 -75.239626) (xy 51.291998 -75.290426) (xy 51.507898 -75.290426) (xy 51.507898 -75.239626)
				(arc
					(start 51.510438 -75.237086)
					(mid 51.520442 -75.202829)
					(end 51.537616 -75.171554)
				)
				(xy 51.537616 -75.167744)
				(arc
					(start 51.641756 -75.063604)
					(mid 52.095016 -74.70026)
					(end 51.731672 -75.15352)
				)
				(arc
					(start 51.646074 -75.239118)
					(mid 51.63782 -75.251471)
					(end 51.634898 -75.266042)
				)
				(xy 51.634898 -75.290426)
				(arc
					(start 51.888136 -75.290426)
					(mid 52.27193 -74.907013)
					(end 51.88839 -74.523346)
				)
			)
		)
	)
	(zone
		(layers "F.Cu" "B.Cu")
		(hatch none 0.5)
		(connect_pads
			(clearance 0)
		)
		(min_thickness 0.25)
		(keepout
			(tracks allowed)
			(vias allowed)
			(pads allowed)
			(copperpour allowed)
			(footprints not_allowed)
		)
		(placement
			(enabled no)
			(sheetname "")
		)
		(fill yes
			(thermal_gap 0.5)
			(thermal_bridge_width 0.5)
			(island_removal_mode 0)
		)
		(polygon
			(pts
				(arc
					(start 251.661676 -61.999876)
					(mid 256.061718 -57.599834)
					(end 260.46176 -61.999876)
				)
				(arc
					(start 260.46176 -61.999876)
					(mid 256.061718 -66.399918)
					(end 251.661676 -61.999876)
				)
			)
		)
	)
	(zone
		(layers "F.Cu" "B.Cu" "In1.Cu" "In2.Cu" "In3.Cu" "In4.Cu" "In5.Cu" "In6.Cu")
		(name "Package Keepin")
		(hatch none 0.5)
		(connect_pads
			(clearance 0)
		)
		(min_thickness 0.25)
		(keepout
			(tracks allowed)
			(vias allowed)
			(pads allowed)
			(copperpour allowed)
			(footprints allowed)
		)
		(placement
			(enabled no)
			(sheetname "")
		)
		(fill
			(thermal_gap 0.5)
			(thermal_bridge_width 0.5)
			(island_removal_mode 0)
		)
		(polygon
			(pts
				(xy 78.46314 -4.0132)
				(arc
					(start 78.46314 -15.999968)
					(mid 76.994808 -19.544834)
					(end 73.449942 -21.013166)
				)
				(xy 65.963292 -21.013166)
				(arc
					(start 65.963292 -57.010046)
					(mid 64.49496 -60.554912)
					(end 60.950094 -62.023244)
				)
				(xy 31.513272 -62.023244)
				(arc
					(start 31.513272 -76.010008)
					(mid 29.752048 -80.26198)
					(end 25.500076 -82.023204)
				)
				(xy 4.0132 -82.023204)
				(arc
					(start 4.0132 -246.000016)
					(mid 4.302224 -246.697782)
					(end 4.99999 -246.986806)
				)
				(arc
					(start 26.34996 -246.986806)
					(mid 29.236841 -247.901459)
					(end 31.070296 -250.311666)
				)
				(arc
					(start 31.070296 -250.311666)
					(mid 36.650515 -247.721977)
					(end 40.463216 -252.549914)
				)
				(xy 40.463216 -254.58674) (xy 43.636692 -254.58674)
				(arc
					(start 43.636692 -252.000004)
					(mid 45.105024 -248.455138)
					(end 48.64989 -246.986806)
				)
				(arc
					(start 66.350134 -246.986806)
					(mid 69.894746 -248.455138)
					(end 71.363078 -251.99975)
				)
				(xy 71.363078 -254.58674) (xy 134.536688 -254.58674)
				(arc
					(start 134.536688 -252.549914)
					(mid 139.500102 -247.5865)
					(end 144.463262 -252.549914)
				)
				(xy 144.463262 -254.58674) (xy 147.636738 -254.58674)
				(arc
					(start 147.636738 -252.000004)
					(mid 149.10507 -248.455138)
					(end 152.649936 -246.986806)
				)
				(arc
					(start 181.150006 -246.986806)
					(mid 184.036789 -247.90139)
					(end 185.870342 -250.311412)
				)
				(arc
					(start 185.870342 -250.311412)
					(mid 191.450698 -247.721892)
					(end 195.263262 -252.549914)
				)
				(xy 195.263262 -254.58674) (xy 198.436738 -254.58674)
				(arc
					(start 198.436738 -252.000004)
					(mid 199.90507 -248.455138)
					(end 203.449936 -246.986806)
				)
				(arc
					(start 229.14991 -246.986806)
					(mid 229.847676 -246.697782)
					(end 230.1367 -246.000016)
				)
				(arc
					(start 230.1367 -197.000114)
					(mid 231.605032 -193.455248)
					(end 235.149898 -191.986916)
				)
				(arc
					(start 250.150122 -191.986916)
					(mid 253.694988 -193.455248)
					(end 255.16332 -197.000114)
				)
				(arc
					(start 255.16332 -246.000016)
					(mid 255.452344 -246.697782)
					(end 256.15011 -246.986806)
				)
				(arc
					(start 350.60001 -246.986806)
					(mid 351.297776 -246.697782)
					(end 351.5868 -246.000016)
				)
				(xy 351.5868 -4.0132) (xy 310.498236 -4.0132)
				(arc
					(start 310.498236 -43.50004)
					(mid 309.970454 -45.739056)
					(end 308.49824 -47.506636)
				)
				(arc
					(start 308.49824 -53.50002)
					(mid 307.029908 -57.044886)
					(end 303.485042 -58.513218)
				)
				(arc
					(start 283.485082 -58.513218)
					(mid 279.940216 -57.044886)
					(end 278.471884 -53.50002)
				)
				(xy 278.471884 -4.0132)
			)
		)
	)
	(zone
		(layers "F.Cu" "B.Cu" "In1.Cu" "In2.Cu" "In3.Cu" "In4.Cu" "In5.Cu" "In6.Cu")
		(name "Route Keepin")
		(hatch none 0.5)
		(connect_pads
			(clearance 0)
		)
		(min_thickness 0.25)
		(keepout
			(tracks allowed)
			(vias allowed)
			(pads allowed)
			(copperpour allowed)
			(footprints allowed)
		)
		(placement
			(enabled no)
			(sheetname "")
		)
		(fill
			(thermal_gap 0.5)
			(thermal_bridge_width 0.5)
			(island_removal_mode 0)
		)
		(polygon
			(pts
				(arc
					(start 75.449938 -0.762)
					(mid 75.281648 -0.831708)
					(end 75.21194 -0.999998)
				)
				(arc
					(start 75.21194 -15.999968)
					(mid 74.695863 -17.245889)
					(end 73.449942 -17.761966)
				)
				(arc
					(start 62.95009 -17.761966)
					(mid 62.7818 -17.831674)
					(end 62.712092 -17.999964)
				)
				(arc
					(start 62.712092 -57.010046)
					(mid 62.196015 -58.255967)
					(end 60.950094 -58.772044)
				)
				(arc
					(start 29.500068 -58.772044)
					(mid 28.624673 -59.134645)
					(end 28.262072 -60.01004)
				)
				(arc
					(start 28.262072 -76.010008)
					(mid 27.453102 -77.963034)
					(end 25.500076 -78.772004)
				)
				(arc
					(start 2.999994 -78.772004)
					(mid 1.417493 -79.427497)
					(end 0.762 -81.009998)
				)
				(arc
					(start 0.762 -246.000016)
					(mid 2.003279 -248.996727)
					(end 4.99999 -250.238006)
				)
				(arc
					(start 26.34996 -250.238006)
					(mid 27.595881 -250.754083)
					(end 28.111958 -252.000004)
				)
				(xy 28.111958 -257.83794) (xy 33.788096 -257.83794)
				(arc
					(start 33.788096 -252.549914)
					(mid 35.500056 -250.837954)
					(end 37.212016 -252.549914)
				)
				(xy 37.212016 -257.83794) (xy 46.887892 -257.83794)
				(arc
					(start 46.887892 -252.000004)
					(mid 47.403969 -250.754083)
					(end 48.64989 -250.238006)
				)
				(arc
					(start 66.34988 -250.238006)
					(mid 67.595801 -250.754083)
					(end 68.111878 -252.000004)
				)
				(xy 68.111878 -257.83794) (xy 137.787888 -257.83794)
				(arc
					(start 137.787888 -252.549914)
					(mid 139.500102 -250.8377)
					(end 141.212062 -252.549914)
				)
				(xy 141.212062 -257.83794) (xy 150.887938 -257.83794)
				(arc
					(start 150.887938 -252.000004)
					(mid 151.404015 -250.754083)
					(end 152.649936 -250.238006)
				)
				(arc
					(start 181.150006 -250.238006)
					(mid 182.395927 -250.754083)
					(end 182.912004 -252.000004)
				)
				(xy 182.912004 -257.83794) (xy 188.587888 -257.83794)
				(arc
					(start 188.587888 -252.549914)
					(mid 190.300102 -250.8377)
					(end 192.012062 -252.549914)
				)
				(xy 192.012062 -257.83794) (xy 201.687938 -257.83794)
				(arc
					(start 201.687938 -252.000004)
					(mid 202.204015 -250.754083)
					(end 203.449936 -250.238006)
				)
				(arc
					(start 229.14991 -250.238006)
					(mid 232.146621 -248.996727)
					(end 233.3879 -246.000016)
				)
				(arc
					(start 233.3879 -197.000114)
					(mid 233.903977 -195.754193)
					(end 235.149898 -195.238116)
				)
				(arc
					(start 250.150122 -195.238116)
					(mid 251.396043 -195.754193)
					(end 251.91212 -197.000114)
				)
				(arc
					(start 251.91212 -246.000016)
					(mid 253.153399 -248.996727)
					(end 256.15011 -250.238006)
				)
				(arc
					(start 350.60001 -250.238006)
					(mid 353.596721 -248.996727)
					(end 354.838 -246.000016)
				)
				(arc
					(start 354.838 -0.999998)
					(mid 354.768292 -0.831708)
					(end 354.600002 -0.762)
				)
				(arc
					(start 307.485034 -0.762)
					(mid 307.316744 -0.831708)
					(end 307.247036 -0.999998)
				)
				(arc
					(start 307.247036 -43.50004)
					(mid 306.730959 -44.745961)
					(end 305.485038 -45.262038)
				)
				(arc
					(start 305.485038 -45.262038)
					(mid 305.316748 -45.331746)
					(end 305.24704 -45.500036)
				)
				(arc
					(start 305.24704 -53.50002)
					(mid 304.730963 -54.745941)
					(end 303.485042 -55.262018)
				)
				(arc
					(start 283.485082 -55.262018)
					(mid 282.239161 -54.745941)
					(end 281.723084 -53.50002)
				)
				(arc
					(start 281.723084 -0.999998)
					(mid 281.653376 -0.831708)
					(end 281.485086 -0.762)
				)
			)
		)
	)
	(zone
		(layers "F.Cu" "In2.Cu")
		(hatch none 0.5)
		(connect_pads
			(clearance 0)
		)
		(min_thickness 0.25)
		(keepout
			(tracks not_allowed)
			(vias allowed)
			(pads allowed)
			(copperpour not_allowed)
			(footprints allowed)
		)
		(placement
			(enabled no)
			(sheetname "")
		)
		(fill yes
			(thermal_gap 0.5)
			(thermal_bridge_width 0.5)
			(island_removal_mode 0)
		)
		(polygon
			(pts
				(arc
					(start 296.29354 -77.35951)
					(mid 295.91 -76.97597)
					(end 295.52646 -77.35951)
				)
				(arc
					(start 295.52646 -78.276196)
					(mid 295.908603 -78.659988)
					(end 296.29354 -78.27899)
				)
				(arc
					(start 296.2021 -78.27899)
					(mid 295.91 -78.568561)
					(end 295.6179 -78.27899)
				)
				(arc
					(start 295.6179 -78.27645)
					(mid 295.91 -77.98435)
					(end 296.2021 -78.27645)
				)
				(xy 296.29354 -78.27645) (xy 296.29354 -77.36205)
				(arc
					(start 296.2021 -77.36205)
					(mid 295.91 -77.651621)
					(end 295.6179 -77.36205)
				)
				(arc
					(start 295.6179 -77.35951)
					(mid 295.91 -77.06741)
					(end 296.2021 -77.35951)
				)
			)
		)
	)
	(zone
		(layers "F.Cu" "In5.Cu")
		(hatch none 0.5)
		(connect_pads
			(clearance 0)
		)
		(min_thickness 0.25)
		(keepout
			(tracks not_allowed)
			(vias allowed)
			(pads allowed)
			(copperpour not_allowed)
			(footprints allowed)
		)
		(placement
			(enabled no)
			(sheetname "")
		)
		(fill yes
			(thermal_gap 0.5)
			(thermal_bridge_width 0.5)
			(island_removal_mode 0)
		)
		(polygon
			(pts
				(arc
					(start 124.779532 -79.868268)
					(mid 124.395738 -80.251681)
					(end 124.779278 -80.635348)
				)
				(arc
					(start 125.756162 -80.635348)
					(mid 126.026466 -80.523908)
					(end 126.139702 -80.254348)
				)
				(arc
					(start 126.048262 -80.254348)
					(mid 125.756162 -80.543919)
					(end 125.464062 -80.254348)
				)
				(arc
					(start 125.071378 -80.254348)
					(mid 124.779278 -80.543919)
					(end 124.487178 -80.254348)
				)
				(arc
					(start 124.487178 -80.251808)
					(mid 124.779278 -79.959708)
					(end 125.071378 -80.251808)
				)
				(arc
					(start 125.464062 -80.251808)
					(mid 125.756162 -79.959708)
					(end 126.048262 -80.251808)
				)
				(arc
					(start 126.139702 -80.251808)
					(mid 126.027366 -79.980604)
					(end 125.756162 -79.868268)
				)
			)
		)
	)
	(zone
		(layers "F.Cu" "In5.Cu")
		(hatch none 0.5)
		(connect_pads
			(clearance 0)
		)
		(min_thickness 0.25)
		(keepout
			(tracks not_allowed)
			(vias allowed)
			(pads allowed)
			(copperpour not_allowed)
			(footprints allowed)
		)
		(placement
			(enabled no)
			(sheetname "")
		)
		(fill yes
			(thermal_gap 0.5)
			(thermal_bridge_width 0.5)
			(island_removal_mode 0)
		)
		(polygon
			(pts
				(arc
					(start 129.159 -80.89646)
					(mid 128.77546 -81.28)
					(end 129.159 -81.66354)
				)
				(arc
					(start 130.047746 -81.66354)
					(mid 130.318214 -81.55219)
					(end 130.43154 -81.28254)
				)
				(arc
					(start 130.3401 -81.28254)
					(mid 130.048 -81.572111)
					(end 129.7559 -81.28254)
				)
				(arc
					(start 129.4511 -81.28254)
					(mid 129.159 -81.572111)
					(end 128.8669 -81.28254)
				)
				(arc
					(start 128.8669 -81.28)
					(mid 129.159 -80.9879)
					(end 129.4511 -81.28)
				)
				(arc
					(start 129.7559 -81.28)
					(mid 130.048 -80.9879)
					(end 130.3401 -81.28)
				)
				(arc
					(start 130.43154 -81.28)
					(mid 130.319204 -81.008796)
					(end 130.048 -80.89646)
				)
			)
		)
	)
	(zone
		(layers "F.Cu" "In5.Cu")
		(hatch none 0.5)
		(connect_pads
			(clearance 0)
		)
		(min_thickness 0.25)
		(keepout
			(tracks not_allowed)
			(vias allowed)
			(pads allowed)
			(copperpour not_allowed)
			(footprints allowed)
		)
		(placement
			(enabled no)
			(sheetname "")
		)
		(fill yes
			(thermal_gap 0.5)
			(thermal_bridge_width 0.5)
			(island_removal_mode 0)
		)
		(polygon
			(pts
				(arc
					(start 77.686408 -41.22166)
					(mid 77.302868 -41.6052)
					(end 77.686408 -41.98874)
				)
				(arc
					(start 78.663038 -41.98874)
					(mid 78.933506 -41.87739)
					(end 79.046832 -41.60774)
				)
				(arc
					(start 78.955392 -41.60774)
					(mid 78.663292 -41.897311)
					(end 78.371192 -41.60774)
				)
				(arc
					(start 77.978508 -41.60774)
					(mid 77.686408 -41.897311)
					(end 77.394308 -41.60774)
				)
				(arc
					(start 77.394308 -41.6052)
					(mid 77.686408 -41.3131)
					(end 77.978508 -41.6052)
				)
				(arc
					(start 78.371192 -41.6052)
					(mid 78.663292 -41.3131)
					(end 78.955392 -41.6052)
				)
				(arc
					(start 79.046832 -41.6052)
					(mid 78.934496 -41.333996)
					(end 78.663292 -41.22166)
				)
			)
		)
	)
	(zone
		(layers "F.Cu" "In5.Cu")
		(hatch none 0.5)
		(connect_pads
			(clearance 0)
		)
		(min_thickness 0.25)
		(keepout
			(tracks not_allowed)
			(vias allowed)
			(pads allowed)
			(copperpour not_allowed)
			(footprints allowed)
		)
		(placement
			(enabled no)
			(sheetname "")
		)
		(fill yes
			(thermal_gap 0.5)
			(thermal_bridge_width 0.5)
			(island_removal_mode 0)
		)
		(polygon
			(pts
				(arc
					(start 79.604108 -39.24046)
					(mid 79.220568 -39.624)
					(end 79.604108 -40.00754)
				)
				(arc
					(start 80.580738 -40.00754)
					(mid 80.851206 -39.89619)
					(end 80.964532 -39.62654)
				)
				(arc
					(start 80.873092 -39.62654)
					(mid 80.580992 -39.916111)
					(end 80.288892 -39.62654)
				)
				(arc
					(start 79.896208 -39.62654)
					(mid 79.604108 -39.916111)
					(end 79.312008 -39.62654)
				)
				(arc
					(start 79.312008 -39.624)
					(mid 79.604108 -39.3319)
					(end 79.896208 -39.624)
				)
				(arc
					(start 80.288892 -39.624)
					(mid 80.580992 -39.3319)
					(end 80.873092 -39.624)
				)
				(arc
					(start 80.964532 -39.624)
					(mid 80.852196 -39.352796)
					(end 80.580992 -39.24046)
				)
			)
		)
	)
	(zone
		(layers "F.Cu" "In5.Cu")
		(hatch none 0.5)
		(connect_pads
			(clearance 0)
		)
		(min_thickness 0.25)
		(keepout
			(tracks not_allowed)
			(vias allowed)
			(pads allowed)
			(copperpour not_allowed)
			(footprints allowed)
		)
		(placement
			(enabled no)
			(sheetname "")
		)
		(fill yes
			(thermal_gap 0.5)
			(thermal_bridge_width 0.5)
			(island_removal_mode 0)
		)
		(polygon
			(pts
				(arc
					(start 83.294728 -37.831776)
					(mid 82.911188 -37.448236)
					(end 82.527648 -37.831776)
				)
				(arc
					(start 82.527648 -38.736524)
					(mid 82.909791 -39.120316)
					(end 83.294728 -38.739318)
				)
				(arc
					(start 83.203288 -38.739318)
					(mid 82.911188 -39.028889)
					(end 82.619088 -38.739318)
				)
				(arc
					(start 82.619088 -38.736778)
					(mid 82.911188 -38.444678)
					(end 83.203288 -38.736778)
				)
				(xy 83.294728 -38.736778) (xy 83.294728 -37.834316)
				(arc
					(start 83.203288 -37.834316)
					(mid 82.911188 -38.123887)
					(end 82.619088 -37.834316)
				)
				(arc
					(start 82.619088 -37.831776)
					(mid 82.911188 -37.539676)
					(end 83.203288 -37.831776)
				)
			)
		)
	)
	(zone
		(layers "F.Cu" "In5.Cu")
		(hatch none 0.5)
		(connect_pads
			(clearance 0)
		)
		(min_thickness 0.25)
		(keepout
			(tracks not_allowed)
			(vias allowed)
			(pads allowed)
			(copperpour not_allowed)
			(footprints allowed)
		)
		(placement
			(enabled no)
			(sheetname "")
		)
		(fill yes
			(thermal_gap 0.5)
			(thermal_bridge_width 0.5)
			(island_removal_mode 0)
		)
		(polygon
			(pts
				(arc
					(start 127.154178 -79.42326)
					(mid 126.770638 -79.8068)
					(end 127.154178 -80.19034)
				)
				(arc
					(start 128.130808 -80.19034)
					(mid 128.401276 -80.07899)
					(end 128.514602 -79.80934)
				)
				(arc
					(start 128.423162 -79.80934)
					(mid 128.131062 -80.098911)
					(end 127.838962 -79.80934)
				)
				(arc
					(start 127.446278 -79.80934)
					(mid 127.154178 -80.098911)
					(end 126.862078 -79.80934)
				)
				(arc
					(start 126.862078 -79.8068)
					(mid 127.154178 -79.5147)
					(end 127.446278 -79.8068)
				)
				(arc
					(start 127.838962 -79.8068)
					(mid 128.131062 -79.5147)
					(end 128.423162 -79.8068)
				)
				(arc
					(start 128.514602 -79.8068)
					(mid 128.402266 -79.535596)
					(end 128.131062 -79.42326)
				)
			)
		)
	)
	(zone
		(layers "F.Cu" "In5.Cu")
		(hatch none 0.5)
		(connect_pads
			(clearance 0)
		)
		(min_thickness 0.25)
		(keepout
			(tracks not_allowed)
			(vias allowed)
			(pads allowed)
			(copperpour not_allowed)
			(footprints allowed)
		)
		(placement
			(enabled no)
			(sheetname "")
		)
		(fill yes
			(thermal_gap 0.5)
			(thermal_bridge_width 0.5)
			(island_removal_mode 0)
		)
		(polygon
			(pts
				(arc
					(start 76.157328 -36.275772)
					(mid 75.773534 -36.659185)
					(end 76.157074 -37.042852)
				)
				(arc
					(start 77.133958 -37.042852)
					(mid 77.404262 -36.931412)
					(end 77.517498 -36.661852)
				)
				(arc
					(start 77.426058 -36.661852)
					(mid 77.133958 -36.951423)
					(end 76.841858 -36.661852)
				)
				(arc
					(start 76.449174 -36.661852)
					(mid 76.157074 -36.951423)
					(end 75.864974 -36.661852)
				)
				(arc
					(start 75.864974 -36.659312)
					(mid 76.157074 -36.367212)
					(end 76.449174 -36.659312)
				)
				(arc
					(start 76.841858 -36.659312)
					(mid 77.133958 -36.367212)
					(end 77.426058 -36.659312)
				)
				(arc
					(start 77.517498 -36.659312)
					(mid 77.405162 -36.388108)
					(end 77.133958 -36.275772)
				)
			)
		)
	)
	(zone
		(layers "F.Cu" "In5.Cu")
		(hatch none 0.5)
		(connect_pads
			(clearance 0)
		)
		(min_thickness 0.25)
		(keepout
			(tracks not_allowed)
			(vias allowed)
			(pads allowed)
			(copperpour not_allowed)
			(footprints allowed)
		)
		(placement
			(enabled no)
			(sheetname "")
		)
		(fill yes
			(thermal_gap 0.5)
			(thermal_bridge_width 0.5)
			(island_removal_mode 0)
		)
		(polygon
			(pts
				(arc
					(start 124.236988 -80.925924)
					(mid 124.124831 -80.6549)
					(end 123.853956 -80.542384)
				)
				(xy 123.833128 -80.542892)
				(arc
					(start 122.925332 -80.56626)
					(mid 122.566684 -80.923765)
					(end 122.924062 -81.28254)
				)
				(xy 123.831858 -81.308956)
				(arc
					(start 123.85294 -81.309464)
					(mid 124.123572 -81.198203)
					(end 124.236988 -80.928464)
				)
				(arc
					(start 124.145548 -80.928464)
					(mid 123.853448 -81.218035)
					(end 123.561348 -80.928464)
				)
				(xy 123.561348 -80.92694)
				(arc
					(start 123.19127 -80.92694)
					(mid 122.92457 -81.191112)
					(end 122.65787 -80.92694)
				)
				(arc
					(start 122.65787 -80.9244)
					(mid 122.92457 -80.6577)
					(end 123.19127 -80.9244)
				)
				(arc
					(start 123.561348 -80.9244)
					(mid 123.85421 -80.633821)
					(end 124.145548 -80.925924)
				)
			)
		)
	)
	(zone
		(layer "B.Cu")
		(hatch none 0.5)
		(connect_pads
			(clearance 0)
		)
		(min_thickness 0.25)
		(keepout
			(tracks allowed)
			(vias allowed)
			(pads allowed)
			(copperpour allowed)
			(footprints allowed)
		)
		(placement
			(enabled no)
			(sheetname "")
		)
		(fill
			(thermal_gap 0.5)
			(thermal_bridge_width 0.5)
			(island_removal_mode 0)
		)
		(polygon
			(pts
				(xy 11.8618 -97.7138) (xy 21.7424 -97.7138) (xy 21.7424 -102.7938) (xy 11.8618 -102.7938) (xy 8.509 -102.7938)
				(xy 8.509 -97.7138)
			)
		)
	)
	(zone
		(net "GB_VDDH2")
		(layer "B.Cu")
		(hatch none 0.5)
		(connect_pads
			(clearance 0.5)
		)
		(min_thickness 0.25)
		(fill yes
			(thermal_gap 0.5)
			(thermal_bridge_width 0.5)
			(island_removal_mode 0)
		)
		(polygon
			(pts
				(xy 193.548 -85.725) (xy 193.294 -85.979) (xy 193.294 -97.79) (xy 193.167 -97.917) (xy 193.167 -108.077)
				(xy 192.405 -108.839) (xy 189.738 -108.839) (xy 189.484 -109.093) (xy 189.484 -110.998) (xy 189.738 -111.252)
				(xy 196.85 -111.252) (xy 198.247 -109.855) (xy 198.247 -90.805) (xy 196.723 -89.281) (xy 196.723 -87.63)
				(xy 197.104 -87.249) (xy 199.009 -87.249) (xy 199.263 -86.995) (xy 199.263 -85.852) (xy 199.136 -85.725)
			)
		)
		(polygon
			(pts
				(xy 198.989696 -86.803992) (xy 198.786496 -86.803992) (xy 198.786496 -87.007192) (xy 198.989696 -87.007192)
			)
		)
		(polygon
			(pts
				(xy 198.634096 -86.803992) (xy 198.430896 -86.803992) (xy 198.430896 -87.007192) (xy 198.634096 -87.007192)
			)
		)
		(polygon
			(pts
				(xy 198.100696 -86.803992) (xy 197.897496 -86.803992) (xy 197.897496 -87.007192) (xy 198.100696 -87.007192)
			)
		)
		(polygon
			(pts
				(xy 197.745096 -86.803992) (xy 197.541896 -86.803992) (xy 197.541896 -87.007192) (xy 197.745096 -87.007192)
			)
		)
	)
	(zone
		(layer "B.Cu")
		(hatch none 0.5)
		(connect_pads
			(clearance 0)
		)
		(min_thickness 0.25)
		(keepout
			(tracks allowed)
			(vias allowed)
			(pads allowed)
			(copperpour allowed)
			(footprints allowed)
		)
		(placement
			(enabled no)
			(sheetname "")
		)
		(fill
			(thermal_gap 0.5)
			(thermal_bridge_width 0.5)
			(island_removal_mode 0)
		)
		(polygon
			(pts
				(xy 68.199 -258.826) (xy 68.199 -253.492) (xy 68.199 -252.603) (xy 96.393 -252.603) (xy 96.393 -251.46)
				(xy 99.441 -251.46) (xy 99.441 -252.603) (xy 147.447 -252.603) (xy 147.447 -250.063) (xy 150.241 -250.063)
				(xy 150.241 -253.492) (xy 150.241 -258.826)
			)
		)
	)
	(zone
		(layer "B.Cu")
		(hatch none 0.5)
		(connect_pads
			(clearance 0)
		)
		(min_thickness 0.25)
		(keepout
			(tracks allowed)
			(vias allowed)
			(pads allowed)
			(copperpour allowed)
			(footprints not_allowed)
		)
		(placement
			(enabled no)
			(sheetname "")
		)
		(fill
			(thermal_gap 0.5)
			(thermal_bridge_width 0.5)
			(island_removal_mode 0)
		)
		(polygon
			(pts
				(arc
					(start 86.849966 -24.500078)
					(mid 90.350086 -20.999958)
					(end 93.849952 -24.500078)
				)
				(arc
					(start 93.849952 -24.500078)
					(mid 90.350086 -27.999944)
					(end 86.849966 -24.500078)
				)
			)
		)
	)
	(zone
		(layer "B.Cu")
		(hatch none 0.5)
		(connect_pads
			(clearance 0)
		)
		(min_thickness 0.25)
		(keepout
			(tracks not_allowed)
			(vias allowed)
			(pads allowed)
			(copperpour not_allowed)
			(footprints allowed)
		)
		(placement
			(enabled no)
			(sheetname "")
		)
		(fill
			(thermal_gap 0.5)
			(thermal_bridge_width 0.5)
			(island_removal_mode 0)
		)
		(polygon
			(pts
				(arc
					(start 48.606456 -87.746078)
					(mid 48.989996 -88.129618)
					(end 49.373536 -87.746078)
				)
				(arc
					(start 49.373536 -87.556594)
					(mid 49.312531 -87.586443)
					(end 49.253394 -87.61984)
				)
				(arc
					(start 49.253394 -87.61984)
					(mid 48.761184 -87.927367)
					(end 49.174146 -87.51951)
				)
				(arc
					(start 49.174146 -87.51951)
					(mid 49.271628 -87.464715)
					(end 49.373536 -87.418672)
				)
				(arc
					(start 49.373536 -87.069422)
					(mid 49.27536 -87.034599)
					(end 49.181258 -86.98992)
				)
				(arc
					(start 49.181258 -86.98992)
					(mid 48.754886 -86.595919)
					(end 49.257458 -86.886542)
				)
				(arc
					(start 49.257458 -86.886542)
					(mid 49.314619 -86.913364)
					(end 49.373536 -86.936072)
				)
				(arc
					(start 49.373536 -86.769448)
					(mid 48.990123 -86.385654)
					(end 48.606456 -86.769194)
				)
			)
		)
	)
	(zone
		(net "P3V3_STBY")
		(layer "B.Cu")
		(hatch none 0.5)
		(connect_pads
			(clearance 0.5)
		)
		(min_thickness 0.25)
		(fill yes
			(thermal_gap 0.5)
			(thermal_bridge_width 0.5)
			(island_removal_mode 0)
		)
		(polygon
			(pts
				(xy 335.788 -92.837) (xy 335.407 -93.218) (xy 335.407 -96.901) (xy 332.486 -99.822) (xy 298.577 -99.822)
				(xy 297.688 -98.933) (xy 296.037 -98.933) (xy 295.656 -99.314) (xy 295.656 -100.076) (xy 296.164 -100.584)
				(xy 296.164 -103.759) (xy 297.942 -105.537) (xy 305.689 -105.537) (xy 309.0545 -102.1715) (xy 327.3425 -102.1715)
				(xy 327.533 -101.981) (xy 327.533 -101.727) (xy 327.787 -101.473) (xy 328.803 -101.473) (xy 329.057 -101.727)
				(xy 329.057 -102.108) (xy 329.1205 -102.1715) (xy 335.8515 -102.1715) (xy 337.185 -100.838) (xy 337.185 -96.012)
				(xy 338.201 -94.996) (xy 339.344 -94.996) (xy 339.725 -94.615) (xy 339.725 -93.472) (xy 339.09 -92.837)
			)
		)
	)
	(zone
		(net "P1V8_E")
		(layer "B.Cu")
		(hatch none 0.5)
		(connect_pads
			(clearance 0.5)
		)
		(min_thickness 0.25)
		(fill yes
			(thermal_gap 0.5)
			(thermal_bridge_width 0.5)
			(island_removal_mode 0)
		)
		(polygon
			(pts
				(xy 46.482 -129.921) (xy 45.593 -130.81) (xy 45.593 -141.224) (xy 47.498 -143.129) (xy 47.498 -147.32)
				(xy 48.006 -147.828) (xy 54.11597 -147.828) (xy 55.38597 -146.558) (xy 55.38597 -130.81) (xy 54.49697 -129.921)
			)
		)
	)
	(zone
		(net "P3V3_STBY")
		(layer "B.Cu")
		(hatch none 0.5)
		(connect_pads
			(clearance 0.5)
		)
		(min_thickness 0.25)
		(fill yes
			(thermal_gap 0.5)
			(thermal_bridge_width 0.5)
			(island_removal_mode 0)
		)
		(polygon
			(pts
				(xy 316.357 -190.627) (xy 315.722 -191.262) (xy 304.927 -191.262) (xy 304.546 -190.881) (xy 303.784 -190.881)
				(xy 302.26 -192.405) (xy 301.752 -192.405) (xy 301.498 -192.659) (xy 301.498 -193.675) (xy 301.244 -193.929)
				(xy 301.244 -201.549) (xy 302.895 -203.2) (xy 302.895 -220.726) (xy 299.72 -223.901) (xy 299.72 -237.109)
				(xy 302.895 -240.284) (xy 340.36 -240.284) (xy 340.868 -239.776) (xy 340.868 -196.088) (xy 335.407 -190.627)
			)
		)
	)
	(zone
		(layer "B.Cu")
		(hatch none 0.5)
		(connect_pads
			(clearance 0)
		)
		(min_thickness 0.25)
		(keepout
			(tracks allowed)
			(vias allowed)
			(pads allowed)
			(copperpour allowed)
			(footprints not_allowed)
		)
		(placement
			(enabled no)
			(sheetname "")
		)
		(fill
			(thermal_gap 0.5)
			(thermal_bridge_width 0.5)
			(island_removal_mode 0)
		)
		(polygon
			(pts
				(arc
					(start 345.74988 -37.399976)
					(mid 349.750126 -33.39973)
					(end 353.750118 -37.399976)
				)
				(arc
					(start 353.750118 -37.399976)
					(mid 349.750126 -41.399968)
					(end 345.74988 -37.399976)
				)
			)
		)
	)
	(zone
		(layer "B.Cu")
		(hatch none 0.5)
		(connect_pads
			(clearance 0)
		)
		(min_thickness 0.25)
		(keepout
			(tracks allowed)
			(vias allowed)
			(pads allowed)
			(copperpour allowed)
			(footprints allowed)
		)
		(placement
			(enabled no)
			(sheetname "")
		)
		(fill
			(thermal_gap 0.5)
			(thermal_bridge_width 0.5)
			(island_removal_mode 0)
		)
		(polygon
			(pts
				(xy 335.6864 -135.6868) (xy 335.6864 -133.1468) (xy 343.8144 -133.1468) (xy 343.8144 -135.6868)
			)
		)
	)
	(zone
		(net "GND")
		(layer "B.Cu")
		(hatch none 0.5)
		(connect_pads
			(clearance 0.5)
		)
		(min_thickness 0.25)
		(fill yes
			(thermal_gap 0.5)
			(thermal_bridge_width 0.5)
			(island_removal_mode 0)
		)
		(polygon
			(pts
				(xy 285.623 -209.677) (xy 281.813 -213.487) (xy 281.813 -231.267) (xy 290.576 -240.03) (xy 297.053 -240.03)
				(xy 298.196 -238.887) (xy 298.196 -210.947) (xy 296.926 -209.677)
			)
		)
	)
	(zone
		(layer "B.Cu")
		(hatch none 0.5)
		(connect_pads
			(clearance 0)
		)
		(min_thickness 0.25)
		(keepout
			(tracks allowed)
			(vias allowed)
			(pads allowed)
			(copperpour allowed)
			(footprints not_allowed)
		)
		(placement
			(enabled no)
			(sheetname "")
		)
		(fill
			(thermal_gap 0.5)
			(thermal_bridge_width 0.5)
			(island_removal_mode 0)
		)
		(polygon
			(pts
				(arc
					(start 128.800098 -20.299934)
					(mid 124.800106 -24.299926)
					(end 120.800114 -20.299934)
				)
				(arc
					(start 120.800114 -20.299934)
					(mid 124.800106 -16.299942)
					(end 128.800098 -20.299934)
				)
			)
		)
	)
	(zone
		(net "P0V9_E")
		(layer "B.Cu")
		(hatch none 0.5)
		(connect_pads
			(clearance 0.5)
		)
		(min_thickness 0.25)
		(fill yes
			(thermal_gap 0.5)
			(thermal_bridge_width 0.5)
			(island_removal_mode 0)
		)
		(polygon
			(pts
				(xy 158.496 -89.408) (xy 157.988 -89.916) (xy 157.988 -93.599) (xy 158.496 -94.107) (xy 171.323 -94.107)
				(xy 171.958 -93.472) (xy 171.958 -89.916) (xy 171.45 -89.408)
			)
		)
		(polygon
			(pts
				(xy 163.2458 -90.17) (xy 162.9918 -90.17) (xy 162.9918 -90.424) (xy 163.2458 -90.424)
			)
		)
		(polygon
			(pts
				(xy 162.3822 -90.17) (xy 162.1282 -90.17) (xy 162.1282 -90.424) (xy 162.3822 -90.424)
			)
		)
		(polygon
			(pts
				(xy 161.9758 -90.17) (xy 161.7218 -90.17) (xy 161.7218 -90.424) (xy 161.9758 -90.424)
			)
		)
		(polygon
			(pts
				(xy 161.1122 -90.17) (xy 160.8582 -90.17) (xy 160.8582 -90.424) (xy 161.1122 -90.424)
			)
		)
		(polygon
			(pts
				(xy 160.7058 -90.17) (xy 160.4518 -90.17) (xy 160.4518 -90.424) (xy 160.7058 -90.424)
			)
		)
		(polygon
			(pts
				(xy 159.8422 -90.17) (xy 159.5882 -90.17) (xy 159.5882 -90.424) (xy 159.8422 -90.424)
			)
		)
		(polygon
			(pts
				(xy 159.4358 -90.17) (xy 159.1818 -90.17) (xy 159.1818 -90.424) (xy 159.4358 -90.424)
			)
		)
		(polygon
			(pts
				(xy 158.5722 -90.17) (xy 158.3182 -90.17) (xy 158.3182 -90.424) (xy 158.5722 -90.424)
			)
		)
	)
	(zone
		(net "P5V_STBY")
		(layer "B.Cu")
		(hatch none 0.5)
		(connect_pads
			(clearance 0.5)
		)
		(min_thickness 0.25)
		(fill yes
			(thermal_gap 0.5)
			(thermal_bridge_width 0.5)
			(island_removal_mode 0)
		)
		(polygon
			(pts
				(xy 255.016 -19.558) (xy 254.762 -19.812) (xy 254.762 -21.59) (xy 255.016 -21.844) (xy 257.683 -21.844)
				(xy 257.937 -21.59) (xy 257.937 -19.812) (xy 257.683 -19.558)
			)
		)
		(polygon
			(pts
				(xy 256.0828 -20.066) (xy 255.8288 -20.066) (xy 255.8288 -20.32) (xy 256.0828 -20.32)
			)
		)
		(polygon
			(pts
				(xy 255.4732 -20.066) (xy 255.2192 -20.066) (xy 255.2192 -20.32) (xy 255.4732 -20.32)
			)
		)
		(polygon
			(pts
				(xy 257.0734 -20.0152) (xy 256.8194 -20.0152) (xy 256.8194 -20.2692) (xy 257.0734 -20.2692)
			)
		)
		(polygon
			(pts
				(xy 256.5146 -20.0152) (xy 256.2606 -20.0152) (xy 256.2606 -20.2692) (xy 256.5146 -20.2692)
			)
		)
	)
	(zone
		(layer "B.Cu")
		(hatch none 0.5)
		(connect_pads
			(clearance 0)
		)
		(min_thickness 0.25)
		(keepout
			(tracks not_allowed)
			(vias allowed)
			(pads allowed)
			(copperpour not_allowed)
			(footprints allowed)
		)
		(placement
			(enabled no)
			(sheetname "")
		)
		(fill
			(thermal_gap 0.5)
			(thermal_bridge_width 0.5)
			(island_removal_mode 0)
		)
		(polygon
			(pts
				(arc
					(start 83.294728 -37.831776)
					(mid 82.911188 -37.448236)
					(end 82.527648 -37.831776)
				)
				(arc
					(start 82.527648 -38.736524)
					(mid 82.911061 -39.120318)
					(end 83.294728 -38.736778)
				)
				(xy 83.294728 -38.5191)
				(arc
					(start 83.166966 -38.5191)
					(mid 83.140169 -38.520941)
					(end 83.11388 -38.526466)
				)
				(arc
					(start 83.11388 -38.526466)
					(mid 82.770652 -38.992834)
					(end 82.979768 -38.452806)
				)
				(arc
					(start 82.979768 -38.452806)
					(mid 83.055606 -38.41221)
					(end 83.139534 -38.39337)
				)
				(xy 83.14055 -38.3921) (xy 83.294728 -38.3921) (xy 83.294728 -38.1762) (xy 83.14944 -38.1762)
				(arc
					(start 83.148424 -38.17493)
					(mid 83.06227 -38.155858)
					(end 82.98434 -38.114478)
				)
				(arc
					(start 82.98434 -38.114478)
					(mid 82.767362 -37.577639)
					(end 83.115912 -38.040056)
				)
				(arc
					(start 83.115912 -38.040056)
					(mid 83.145538 -38.046897)
					(end 83.175856 -38.0492)
				)
				(xy 83.294728 -38.0492)
			)
		)
	)
	(zone
		(net "PHY_AVDD")
		(layer "B.Cu")
		(hatch none 0.5)
		(connect_pads
			(clearance 0.5)
		)
		(min_thickness 0.25)
		(fill yes
			(thermal_gap 0.5)
			(thermal_bridge_width 0.5)
			(island_removal_mode 0)
		)
		(polygon
			(pts
				(xy 149.922992 -13.716) (xy 149.287992 -14.351) (xy 149.287992 -20.636992) (xy 150.241 -21.59) (xy 152.019 -21.59)
				(xy 152.273 -21.336) (xy 152.273 -19.558) (xy 153.224992 -18.606008) (xy 153.224992 -15.558008)
				(xy 154.178 -14.605) (xy 164.084 -14.605) (xy 170.942 -21.463) (xy 174.433992 -21.463) (xy 177.608992 -24.638)
				(xy 177.608992 -31.242) (xy 176.592992 -32.258) (xy 176.592992 -32.639) (xy 176.846992 -32.893)
				(xy 177.227992 -32.893) (xy 177.735992 -32.385) (xy 179.767992 -32.385) (xy 179.894992 -32.258)
				(xy 179.894992 -30.353) (xy 180.275992 -29.972) (xy 180.275992 -24.638) (xy 173.798992 -18.161)
				(xy 173.736 -18.161) (xy 169.291 -13.716)
			)
		)
		(polygon
			(pts
				(xy 179.378864 -31.364936) (xy 179.124864 -31.364936) (xy 179.124864 -31.898336) (xy 179.378864 -31.898336)
			)
		)
		(polygon
			(pts
				(xy 179.378864 -30.755336) (xy 179.124864 -30.755336) (xy 179.124864 -31.009336) (xy 179.378864 -31.009336)
			)
		)
		(polygon
			(pts
				(xy 179.259992 -30.0228) (xy 179.005992 -30.0228) (xy 179.005992 -30.2768) (xy 179.259992 -30.2768)
			)
		)
		(polygon
			(pts
				(xy 179.259992 -29.1592) (xy 179.005992 -29.1592) (xy 179.005992 -29.4132) (xy 179.259992 -29.4132)
			)
		)
	)
	(zone
		(net "P3V3_STBY")
		(layer "B.Cu")
		(hatch none 0.5)
		(connect_pads
			(clearance 0.5)
		)
		(min_thickness 0.25)
		(fill yes
			(thermal_gap 0.5)
			(thermal_bridge_width 0.5)
			(island_removal_mode 0)
		)
		(polygon
			(pts
				(xy 177.735992 -32.639) (xy 176.53 -33.844992) (xy 176.53 -35.433) (xy 181.229 -40.132) (xy 181.229 -46.482)
				(xy 183.515 -48.768) (xy 184.531 -48.768) (xy 205.867 -70.104) (xy 218.44 -70.104) (xy 219.075 -69.469)
				(xy 219.075 -63.881) (xy 218.44 -63.246) (xy 207.772 -63.246) (xy 199.136 -54.61) (xy 199.136 -44.577)
				(xy 188.722 -34.163) (xy 184.847992 -34.163) (xy 183.958992 -35.052) (xy 180.402992 -35.052) (xy 179.767992 -34.417)
				(xy 179.767992 -33.401) (xy 179.894992 -33.274) (xy 179.894992 -32.893) (xy 179.640992 -32.639)
			)
		)
		(polygon
			(pts
				(xy 186.795664 -34.616136) (xy 186.541664 -34.616136) (xy 186.541664 -34.870136) (xy 186.795664 -34.870136)
			)
		)
		(polygon
			(pts
				(xy 186.186064 -34.616136) (xy 185.652664 -34.616136) (xy 185.652664 -34.870136) (xy 186.186064 -34.870136)
			)
		)
		(polygon
			(pts
				(xy 185.297064 -34.616136) (xy 185.043064 -34.616136) (xy 185.043064 -34.870136) (xy 185.297064 -34.870136)
			)
		)
	)
	(zone
		(net "P1V26_STBY")
		(layer "B.Cu")
		(hatch none 0.5)
		(connect_pads
			(clearance 0.5)
		)
		(min_thickness 0.25)
		(fill yes
			(thermal_gap 0.5)
			(thermal_bridge_width 0.5)
			(island_removal_mode 0)
		)
		(polygon
			(pts
				(xy 215.646 -189.484) (xy 214.757 -190.373) (xy 214.757 -199.263) (xy 215.519 -200.025) (xy 218.567 -200.025)
				(xy 218.821 -199.771) (xy 218.821 -195.326) (xy 220.726 -193.421) (xy 268.351 -193.421) (xy 271.145 -196.215)
				(xy 271.145 -197.739) (xy 261.747 -207.137) (xy 261.747 -211.582) (xy 262.255 -212.09) (xy 265.684 -212.09)
				(xy 280.797 -196.977) (xy 280.797 -193.802) (xy 279.908 -192.913) (xy 275.971 -192.913) (xy 272.542 -189.484)
			)
		)
	)
	(zone
		(layer "B.Cu")
		(hatch none 0.5)
		(connect_pads
			(clearance 0)
		)
		(min_thickness 0.25)
		(keepout
			(tracks allowed)
			(vias allowed)
			(pads allowed)
			(copperpour allowed)
			(footprints not_allowed)
		)
		(placement
			(enabled no)
			(sheetname "")
		)
		(fill
			(thermal_gap 0.5)
			(thermal_bridge_width 0.5)
			(island_removal_mode 0)
		)
		(polygon
			(pts
				(arc
					(start 192.950084 -89.799922)
					(mid 188.950092 -93.799914)
					(end 184.9501 -89.799922)
				)
				(arc
					(start 184.9501 -89.799922)
					(mid 188.950092 -85.79993)
					(end 192.950084 -89.799922)
				)
			)
		)
	)
	(zone
		(net "GB_VDDA")
		(layer "B.Cu")
		(hatch none 0.5)
		(connect_pads
			(clearance 0.5)
		)
		(min_thickness 0.25)
		(fill yes
			(thermal_gap 0.5)
			(thermal_bridge_width 0.5)
			(island_removal_mode 0)
		)
		(polygon
			(pts
				(xy 121.67997 -95.123) (xy 121.42597 -95.377) (xy 121.42597 -97.536) (xy 120.91797 -98.044) (xy 119.52097 -98.044)
				(xy 119.26697 -98.298) (xy 119.26697 -103.886) (xy 118.63197 -104.521) (xy 118.63197 -105.537) (xy 118.88597 -105.791)
				(xy 119.39397 -105.791) (xy 119.90197 -106.299) (xy 120.79097 -106.299) (xy 120.91797 -106.426)
				(xy 120.91797 -107.442) (xy 121.29897 -107.823) (xy 122.82297 -107.823) (xy 123.96597 -108.966)
				(xy 127.14097 -108.966) (xy 128.28397 -107.823) (xy 128.28397 -104.648) (xy 128.02997 -104.394)
				(xy 128.02997 -96.774) (xy 126.37897 -95.123)
			)
		)
		(polygon
			(pts
				(xy 120.81637 -105.8418) (xy 120.61317 -105.8418) (xy 120.61317 -106.045) (xy 120.81637 -106.045)
			)
		)
		(polygon
			(pts
				(xy 120.46077 -105.8418) (xy 120.25757 -105.8418) (xy 120.25757 -106.045) (xy 120.46077 -106.045)
			)
		)
		(polygon
			(pts
				(xy 119.41937 -105.3338) (xy 119.21617 -105.3338) (xy 119.21617 -105.537) (xy 119.41937 -105.537)
			)
		)
		(polygon
			(pts
				(xy 124.37237 -104.775) (xy 124.16917 -104.775) (xy 124.16917 -104.9782) (xy 124.37237 -104.9782)
			)
		)
		(polygon
			(pts
				(xy 124.01677 -104.775) (xy 123.81357 -104.775) (xy 123.81357 -104.9782) (xy 124.01677 -104.9782)
			)
		)
		(polygon
			(pts
				(xy 120.86717 -104.2162) (xy 120.66397 -104.2162) (xy 120.66397 -104.4194) (xy 120.86717 -104.4194)
			)
		)
		(polygon
			(pts
				(xy 120.86717 -103.8606) (xy 120.66397 -103.8606) (xy 120.66397 -104.0638) (xy 120.86717 -104.0638)
			)
		)
		(polygon
			(pts
				(xy 125.61697 -103.0732) (xy 125.41377 -103.0732) (xy 125.41377 -103.2764) (xy 125.61697 -103.2764)
			)
		)
		(polygon
			(pts
				(xy 122.46737 -102.7938) (xy 122.26417 -102.7938) (xy 122.26417 -102.997) (xy 122.46737 -102.997)
			)
		)
		(polygon
			(pts
				(xy 122.11177 -102.7938) (xy 121.90857 -102.7938) (xy 121.90857 -102.997) (xy 122.11177 -102.997)
			)
		)
		(polygon
			(pts
				(xy 125.61697 -102.7176) (xy 125.41377 -102.7176) (xy 125.41377 -102.9208) (xy 125.61697 -102.9208)
			)
		)
		(polygon
			(pts
				(xy 120.61317 -102.6922) (xy 120.40997 -102.6922) (xy 120.40997 -102.8954) (xy 120.61317 -102.8954)
			)
		)
		(polygon
			(pts
				(xy 120.61317 -102.3366) (xy 120.40997 -102.3366) (xy 120.40997 -102.5398) (xy 120.61317 -102.5398)
			)
		)
		(polygon
			(pts
				(xy 124.49937 -100.711) (xy 124.29617 -100.711) (xy 124.29617 -100.9142) (xy 124.49937 -100.9142)
			)
		)
		(polygon
			(pts
				(xy 124.14377 -100.711) (xy 123.94057 -100.711) (xy 123.94057 -100.9142) (xy 124.14377 -100.9142)
			)
		)
		(polygon
			(pts
				(xy 126.63297 -99.8982) (xy 126.42977 -99.8982) (xy 126.42977 -100.1014) (xy 126.63297 -100.1014)
			)
		)
		(polygon
			(pts
				(xy 122.97537 -99.7458) (xy 122.77217 -99.7458) (xy 122.77217 -99.949) (xy 122.97537 -99.949)
			)
		)
		(polygon
			(pts
				(xy 122.61977 -99.7458) (xy 122.41657 -99.7458) (xy 122.41657 -99.949) (xy 122.61977 -99.949)
			)
		)
		(polygon
			(pts
				(xy 126.63297 -99.5426) (xy 126.42977 -99.5426) (xy 126.42977 -99.7458) (xy 126.63297 -99.7458)
			)
		)
		(polygon
			(pts
				(xy 124.37237 -98.679) (xy 124.16917 -98.679) (xy 124.16917 -98.8822) (xy 124.37237 -98.8822)
			)
		)
		(polygon
			(pts
				(xy 124.01677 -98.679) (xy 123.81357 -98.679) (xy 123.81357 -98.8822) (xy 124.01677 -98.8822)
			)
		)
		(polygon
			(pts
				(xy 126.25197 -96.5962) (xy 126.04877 -96.5962) (xy 126.04877 -96.7994) (xy 126.25197 -96.7994)
			)
		)
		(polygon
			(pts
				(xy 126.25197 -96.2406) (xy 126.04877 -96.2406) (xy 126.04877 -96.4438) (xy 126.25197 -96.4438)
			)
		)
		(polygon
			(pts
				(xy 122.84837 -95.8088) (xy 122.64517 -95.8088) (xy 122.64517 -96.012) (xy 122.84837 -96.012)
			)
		)
		(polygon
			(pts
				(xy 122.49277 -95.8088) (xy 122.28957 -95.8088) (xy 122.28957 -96.012) (xy 122.49277 -96.012)
			)
		)
		(polygon
			(pts
				(xy 122.72137 -95.377) (xy 122.51817 -95.377) (xy 122.51817 -95.5802) (xy 122.72137 -95.5802)
			)
		)
		(polygon
			(pts
				(xy 122.36577 -95.377) (xy 122.16257 -95.377) (xy 122.16257 -95.5802) (xy 122.36577 -95.5802)
			)
		)
	)
	(zone
		(net "P1V8_E")
		(layer "B.Cu")
		(hatch none 0.5)
		(connect_pads
			(clearance 0.5)
		)
		(min_thickness 0.25)
		(fill yes
			(thermal_gap 0.5)
			(thermal_bridge_width 0.5)
			(island_removal_mode 0)
		)
		(polygon
			(pts
				(xy 99.70897 -110.109) (xy 99.32797 -110.49) (xy 99.32797 -112.649) (xy 99.45497 -112.776) (xy 100.72497 -112.776)
				(xy 101.23297 -112.268) (xy 102.37597 -112.268) (xy 102.88397 -111.76) (xy 102.88397 -110.236) (xy 102.75697 -110.109)
			)
		)
		(polygon
			(pts
				(xy 101.63937 -111.8108) (xy 101.43617 -111.8108) (xy 101.43617 -112.014) (xy 101.63937 -112.014)
			)
		)
		(polygon
			(pts
				(xy 101.28377 -111.8108) (xy 101.08057 -111.8108) (xy 101.08057 -112.014) (xy 101.28377 -112.014)
			)
		)
		(polygon
			(pts
				(xy 101.86797 -110.5916) (xy 101.66477 -110.5916) (xy 101.66477 -110.7948) (xy 101.86797 -110.7948)
			)
		)
		(polygon
			(pts
				(xy 101.30917 -110.5916) (xy 101.10597 -110.5916) (xy 101.10597 -110.7948) (xy 101.30917 -110.7948)
			)
		)
		(polygon
			(pts
				(xy 100.59797 -110.5916) (xy 100.39477 -110.5916) (xy 100.39477 -110.7948) (xy 100.59797 -110.7948)
			)
		)
		(polygon
			(pts
				(xy 100.03917 -110.5916) (xy 99.83597 -110.5916) (xy 99.83597 -110.7948) (xy 100.03917 -110.7948)
			)
		)
	)
	(zone
		(layer "B.Cu")
		(hatch none 0.5)
		(connect_pads
			(clearance 0)
		)
		(min_thickness 0.25)
		(keepout
			(tracks not_allowed)
			(vias allowed)
			(pads allowed)
			(copperpour not_allowed)
			(footprints allowed)
		)
		(placement
			(enabled no)
			(sheetname "")
		)
		(fill
			(thermal_gap 0.5)
			(thermal_bridge_width 0.5)
			(island_removal_mode 0)
		)
		(polygon
			(pts
				(arc
					(start 39.975536 -79.746348)
					(mid 39.592123 -79.362554)
					(end 39.208456 -79.746094)
				)
				(arc
					(start 39.208456 -80.722978)
					(mid 39.591996 -81.106518)
					(end 39.975536 -80.722978)
				)
				(xy 39.975536 -80.469486) (xy 39.935404 -80.469486)
				(arc
					(start 39.83863 -80.56626)
					(mid 39.38537 -80.929604)
					(end 39.748714 -80.476344)
				)
				(xy 39.845488 -80.37957) (xy 39.882572 -80.342486) (xy 39.935404 -80.342486) (xy 39.975536 -80.342486)
				(xy 39.975536 -80.126586) (xy 39.935404 -80.126586) (xy 39.882572 -80.126586) (xy 39.845488 -80.089502)
				(arc
					(start 39.748714 -79.992728)
					(mid 39.38537 -79.539468)
					(end 39.83863 -79.902812)
				)
				(xy 39.935404 -79.999586) (xy 39.975536 -79.999586)
			)
		)
	)
	(zone
		(layer "B.Cu")
		(hatch none 0.5)
		(connect_pads
			(clearance 0)
		)
		(min_thickness 0.25)
		(keepout
			(tracks allowed)
			(vias allowed)
			(pads allowed)
			(copperpour allowed)
			(footprints not_allowed)
		)
		(placement
			(enabled no)
			(sheetname "")
		)
		(fill
			(thermal_gap 0.5)
			(thermal_bridge_width 0.5)
			(island_removal_mode 0)
		)
		(polygon
			(pts
				(arc
					(start 110.849918 -65.499996)
					(mid 114.350038 -61.999876)
					(end 117.849904 -65.499996)
				)
				(arc
					(start 117.849904 -65.499996)
					(mid 114.350038 -68.999862)
					(end 110.849918 -65.499996)
				)
			)
		)
	)
	(zone
		(layer "B.Cu")
		(hatch none 0.5)
		(connect_pads
			(clearance 0)
		)
		(min_thickness 0.25)
		(keepout
			(tracks not_allowed)
			(vias allowed)
			(pads allowed)
			(copperpour not_allowed)
			(footprints allowed)
		)
		(placement
			(enabled no)
			(sheetname "")
		)
		(fill
			(thermal_gap 0.5)
			(thermal_bridge_width 0.5)
			(island_removal_mode 0)
		)
		(polygon
			(pts
				(arc
					(start 39.975536 -82.070194)
					(mid 39.591996 -81.686654)
					(end 39.208456 -82.070194)
				)
				(arc
					(start 39.208456 -83.046824)
					(mid 39.591869 -83.430618)
					(end 39.975536 -83.047078)
				)
				(xy 39.975536 -82.793586) (xy 39.935404 -82.793586)
				(arc
					(start 39.83863 -82.89036)
					(mid 39.38537 -83.253704)
					(end 39.748714 -82.800444)
				)
				(xy 39.845488 -82.70367) (xy 39.882572 -82.666586) (xy 39.935404 -82.666586) (xy 39.975536 -82.666586)
				(xy 39.975536 -82.450686) (xy 39.935404 -82.450686) (xy 39.882572 -82.450686) (xy 39.845488 -82.413602)
				(arc
					(start 39.748714 -82.316828)
					(mid 39.38537 -81.863568)
					(end 39.83863 -82.226912)
				)
				(xy 39.935404 -82.323686) (xy 39.975536 -82.323686)
			)
		)
	)
	(zone
		(net "P3V3")
		(layer "B.Cu")
		(hatch none 0.5)
		(connect_pads
			(clearance 0.5)
		)
		(min_thickness 0.25)
		(fill yes
			(thermal_gap 0.5)
			(thermal_bridge_width 0.5)
			(island_removal_mode 0)
		)
		(polygon
			(pts
				(xy 308.61 -54.991) (xy 308.356 -55.245) (xy 308.356 -55.88) (xy 307.467 -56.769) (xy 303.657 -56.769)
				(xy 303.149 -57.277) (xy 303.149 -60.198) (xy 303.403 -60.452) (xy 315.849 -60.452) (xy 316.484 -59.817)
				(xy 316.484 -55.245) (xy 316.23 -54.991)
			)
		)
	)
	(zone
		(net "P1V8_STBY")
		(layer "B.Cu")
		(hatch none 0.5)
		(connect_pads
			(clearance 0.5)
		)
		(min_thickness 0.25)
		(fill yes
			(thermal_gap 0.5)
			(thermal_bridge_width 0.5)
			(island_removal_mode 0)
		)
		(polygon
			(pts
				(xy 223.52 -112.268) (xy 223.139 -112.649) (xy 223.139 -119.507) (xy 223.901 -120.269) (xy 223.901 -157.226)
				(xy 224.536 -157.861) (xy 227.457 -157.861) (xy 228.473 -156.845) (xy 228.473 -112.903) (xy 227.838 -112.268)
			)
		)
	)
	(zone
		(layer "B.Cu")
		(hatch none 0.5)
		(connect_pads
			(clearance 0)
		)
		(min_thickness 0.25)
		(keepout
			(tracks not_allowed)
			(vias allowed)
			(pads allowed)
			(copperpour not_allowed)
			(footprints allowed)
		)
		(placement
			(enabled no)
			(sheetname "")
		)
		(fill
			(thermal_gap 0.5)
			(thermal_bridge_width 0.5)
			(island_removal_mode 0)
		)
		(polygon
			(pts
				(arc
					(start 18.258536 -98.162364)
					(mid 17.875014 -98.525813)
					(end 18.218404 -98.927412)
				)
				(arc
					(start 18.218404 -98.83521)
					(mid 18.234596 -98.254811)
					(end 18.345404 -98.824796)
				)
				(xy 18.345404 -98.929444) (xy 19.107404 -98.929444) (xy 19.107404 -98.891598)
				(arc
					(start 19.107912 -98.89109)
					(mid 19.114595 -98.825873)
					(end 19.128486 -98.761804)
				)
				(arc
					(start 19.128486 -98.761804)
					(mid 19.467832 -98.291178)
					(end 19.243548 -98.82632)
				)
				(arc
					(start 19.243548 -98.82632)
					(mid 19.236698 -98.871939)
					(end 19.234404 -98.918014)
				)
				(xy 19.234404 -98.929444)
				(arc
					(start 19.325082 -98.929444)
					(mid 19.708622 -98.545904)
					(end 19.325082 -98.162364)
				)
			)
		)
	)
	(zone
		(layer "B.Cu")
		(hatch none 0.5)
		(connect_pads
			(clearance 0)
		)
		(min_thickness 0.25)
		(keepout
			(tracks allowed)
			(vias allowed)
			(pads allowed)
			(copperpour allowed)
			(footprints not_allowed)
		)
		(placement
			(enabled no)
			(sheetname "")
		)
		(fill
			(thermal_gap 0.5)
			(thermal_bridge_width 0.5)
			(island_removal_mode 0)
		)
		(polygon
			(pts
				(arc
					(start 184.9501 -89.799922)
					(mid 188.950092 -85.79993)
					(end 192.950084 -89.799922)
				)
				(arc
					(start 192.950084 -89.799922)
					(mid 188.950092 -93.799914)
					(end 184.9501 -89.799922)
				)
			)
		)
	)
	(zone
		(net "P3V3_STBY")
		(layer "B.Cu")
		(hatch none 0.5)
		(connect_pads
			(clearance 0.5)
		)
		(min_thickness 0.25)
		(fill yes
			(thermal_gap 0.5)
			(thermal_bridge_width 0.5)
			(island_removal_mode 0)
		)
		(polygon
			(pts
				(xy 216.916 -157.353) (xy 206.121 -168.148) (xy 195.834 -168.148) (xy 194.945 -169.037) (xy 194.945 -183.261)
				(xy 198.12 -186.436) (xy 228.092 -186.436) (xy 229.616 -184.912) (xy 229.616 -171.323) (xy 235.712 -165.227)
				(xy 257.302 -165.227) (xy 257.556 -164.973) (xy 257.556 -158.496) (xy 257.048 -157.988) (xy 224.409 -157.988)
				(xy 223.774 -157.353)
			)
		)
	)
	(zone
		(layer "B.Cu")
		(hatch none 0.5)
		(connect_pads
			(clearance 0)
		)
		(min_thickness 0.25)
		(keepout
			(tracks allowed)
			(vias allowed)
			(pads allowed)
			(copperpour allowed)
			(footprints not_allowed)
		)
		(placement
			(enabled no)
			(sheetname "")
		)
		(fill
			(thermal_gap 0.5)
			(thermal_bridge_width 0.5)
			(island_removal_mode 0)
		)
		(polygon
			(pts
				(arc
					(start 353.750118 -54.99989)
					(mid 349.750126 -58.999882)
					(end 345.74988 -54.99989)
				)
				(arc
					(start 345.74988 -54.99989)
					(mid 349.750126 -50.999644)
					(end 353.750118 -54.99989)
				)
			)
		)
	)
	(zone
		(net "GND")
		(layer "B.Cu")
		(hatch none 0.5)
		(connect_pads
			(clearance 0.5)
		)
		(min_thickness 0.25)
		(fill yes
			(thermal_gap 0.5)
			(thermal_bridge_width 0.5)
			(island_removal_mode 0)
		)
		(polygon
			(pts
				(xy 106.369612 -208.788) (xy 105.734612 -209.423) (xy 105.734612 -219.71) (xy 105.988612 -219.964)
				(xy 107.512612 -219.964) (xy 107.766612 -219.71) (xy 107.766612 -209.042) (xy 107.512612 -208.788)
			)
		)
		(polygon
			(pts
				(xy 107.360212 -219.0242) (xy 107.106212 -219.0242) (xy 107.106212 -219.2782) (xy 107.360212 -219.2782)
			)
		)
		(polygon
			(pts
				(xy 107.436412 -218.5924) (xy 107.182412 -218.5924) (xy 107.182412 -218.8464) (xy 107.436412 -218.8464)
			)
		)
		(polygon
			(pts
				(xy 107.436412 -218.0336) (xy 107.182412 -218.0336) (xy 107.182412 -218.2876) (xy 107.436412 -218.2876)
			)
		)
		(polygon
			(pts
				(xy 107.436412 -217.4494) (xy 107.182412 -217.4494) (xy 107.182412 -217.7034) (xy 107.436412 -217.7034)
			)
		)
		(polygon
			(pts
				(xy 107.436412 -216.8906) (xy 107.182412 -216.8906) (xy 107.182412 -217.1446) (xy 107.436412 -217.1446)
			)
		)
		(polygon
			(pts
				(xy 107.436412 -216.3064) (xy 107.182412 -216.3064) (xy 107.182412 -216.5604) (xy 107.436412 -216.5604)
			)
		)
		(polygon
			(pts
				(xy 107.436412 -215.7476) (xy 107.182412 -215.7476) (xy 107.182412 -216.0016) (xy 107.436412 -216.0016)
			)
		)
		(polygon
			(pts
				(xy 107.436412 -215.1634) (xy 107.182412 -215.1634) (xy 107.182412 -215.4174) (xy 107.436412 -215.4174)
			)
		)
		(polygon
			(pts
				(xy 107.436412 -214.6046) (xy 107.182412 -214.6046) (xy 107.182412 -214.8586) (xy 107.436412 -214.8586)
			)
		)
		(polygon
			(pts
				(xy 107.436412 -214.0204) (xy 107.182412 -214.0204) (xy 107.182412 -214.2744) (xy 107.436412 -214.2744)
			)
		)
		(polygon
			(pts
				(xy 107.436412 -213.4616) (xy 107.182412 -213.4616) (xy 107.182412 -213.7156) (xy 107.436412 -213.7156)
			)
		)
		(polygon
			(pts
				(xy 107.436412 -212.8774) (xy 107.182412 -212.8774) (xy 107.182412 -213.1314) (xy 107.436412 -213.1314)
			)
		)
		(polygon
			(pts
				(xy 107.436412 -212.3186) (xy 107.182412 -212.3186) (xy 107.182412 -212.5726) (xy 107.436412 -212.5726)
			)
		)
		(polygon
			(pts
				(xy 107.436412 -211.7344) (xy 107.182412 -211.7344) (xy 107.182412 -211.9884) (xy 107.436412 -211.9884)
			)
		)
		(polygon
			(pts
				(xy 107.436412 -211.1756) (xy 107.182412 -211.1756) (xy 107.182412 -211.4296) (xy 107.436412 -211.4296)
			)
		)
		(polygon
			(pts
				(xy 107.436412 -210.5914) (xy 107.182412 -210.5914) (xy 107.182412 -210.8454) (xy 107.436412 -210.8454)
			)
		)
		(polygon
			(pts
				(xy 107.436412 -210.0326) (xy 107.182412 -210.0326) (xy 107.182412 -210.2866) (xy 107.436412 -210.2866)
			)
		)
		(polygon
			(pts
				(xy 107.385612 -209.6008) (xy 107.131612 -209.6008) (xy 107.131612 -209.8548) (xy 107.385612 -209.8548)
			)
		)
		(polygon
			(pts
				(xy 107.385612 -208.9912) (xy 107.131612 -208.9912) (xy 107.131612 -209.2452) (xy 107.385612 -209.2452)
			)
		)
	)
	(zone
		(net "P5V_USB_BP1_F")
		(layer "B.Cu")
		(hatch none 0.5)
		(connect_pads
			(clearance 0.5)
		)
		(min_thickness 0.25)
		(fill yes
			(thermal_gap 0.5)
			(thermal_bridge_width 0.5)
			(island_removal_mode 0)
		)
		(polygon
			(pts
				(xy 257.81 -14.224) (xy 257.556 -14.478) (xy 257.556 -19.177) (xy 258.064 -19.685) (xy 259.588 -19.685)
				(xy 259.715 -19.558) (xy 259.715 -14.478) (xy 259.461 -14.224)
			)
		)
	)
	(zone
		(layer "B.Cu")
		(hatch none 0.5)
		(connect_pads
			(clearance 0)
		)
		(min_thickness 0.25)
		(keepout
			(tracks not_allowed)
			(vias allowed)
			(pads allowed)
			(copperpour not_allowed)
			(footprints allowed)
		)
		(placement
			(enabled no)
			(sheetname "")
		)
		(fill
			(thermal_gap 0.5)
			(thermal_bridge_width 0.5)
			(island_removal_mode 0)
		)
		(polygon
			(pts
				(arc
					(start 77.686408 -41.22166)
					(mid 77.302868 -41.6052)
					(end 77.686408 -41.98874)
				)
				(arc
					(start 78.663038 -41.98874)
					(mid 79.046832 -41.605327)
					(end 78.663292 -41.22166)
				)
				(xy 78.4098 -41.22166)
				(arc
					(start 78.4098 -41.246044)
					(mid 78.4127 -41.260624)
					(end 78.420976 -41.272968)
				)
				(arc
					(start 78.506574 -41.358566)
					(mid 78.869918 -41.811826)
					(end 78.416658 -41.448482)
				)
				(xy 78.312518 -41.344342)
				(arc
					(start 78.312518 -41.340532)
					(mid 78.295404 -41.309232)
					(end 78.28534 -41.275)
				)
				(xy 78.2828 -41.27246) (xy 78.2828 -41.246044) (xy 78.2828 -41.22166) (xy 78.0669 -41.22166) (xy 78.0669 -41.27246)
				(arc
					(start 78.06436 -41.275)
					(mid 78.054356 -41.309257)
					(end 78.037182 -41.340532)
				)
				(xy 78.037182 -41.344342)
				(arc
					(start 77.933042 -41.448482)
					(mid 77.479782 -41.811826)
					(end 77.843126 -41.358566)
				)
				(arc
					(start 77.928724 -41.272968)
					(mid 77.936978 -41.260615)
					(end 77.9399 -41.246044)
				)
				(xy 77.9399 -41.22166)
			)
		)
	)
	(zone
		(net "GND")
		(layer "B.Cu")
		(hatch none 0.5)
		(connect_pads
			(clearance 0.5)
		)
		(min_thickness 0.25)
		(fill yes
			(thermal_gap 0.5)
			(thermal_bridge_width 0.5)
			(island_removal_mode 0)
		)
		(polygon
			(pts
				(xy 197.358 -87.503) (xy 197.104 -87.757) (xy 197.104 -89.281) (xy 197.358 -89.535) (xy 199.009 -89.535)
				(xy 199.263 -89.281) (xy 199.263 -87.757) (xy 199.009 -87.503)
			)
		)
		(polygon
			(pts
				(xy 198.989696 -87.769192) (xy 198.786496 -87.769192) (xy 198.786496 -87.972392) (xy 198.989696 -87.972392)
			)
		)
		(polygon
			(pts
				(xy 198.634096 -87.769192) (xy 198.430896 -87.769192) (xy 198.430896 -87.972392) (xy 198.634096 -87.972392)
			)
		)
		(polygon
			(pts
				(xy 198.100696 -87.769192) (xy 197.897496 -87.769192) (xy 197.897496 -87.972392) (xy 198.100696 -87.972392)
			)
		)
		(polygon
			(pts
				(xy 197.745096 -87.769192) (xy 197.541896 -87.769192) (xy 197.541896 -87.972392) (xy 197.745096 -87.972392)
			)
		)
	)
	(zone
		(layer "B.Cu")
		(hatch none 0.5)
		(connect_pads
			(clearance 0)
		)
		(min_thickness 0.25)
		(keepout
			(tracks allowed)
			(vias allowed)
			(pads allowed)
			(copperpour allowed)
			(footprints not_allowed)
		)
		(placement
			(enabled no)
			(sheetname "")
		)
		(fill
			(thermal_gap 0.5)
			(thermal_bridge_width 0.5)
			(island_removal_mode 0)
		)
		(polygon
			(pts
				(arc
					(start 117.849904 -65.499996)
					(mid 114.350038 -68.999862)
					(end 110.849918 -65.499996)
				)
				(arc
					(start 110.849918 -65.499996)
					(mid 114.350038 -61.999876)
					(end 117.849904 -65.499996)
				)
			)
		)
	)
	(zone
		(layer "B.Cu")
		(hatch none 0.5)
		(connect_pads
			(clearance 0)
		)
		(min_thickness 0.25)
		(keepout
			(tracks allowed)
			(vias allowed)
			(pads allowed)
			(copperpour allowed)
			(footprints not_allowed)
		)
		(placement
			(enabled no)
			(sheetname "")
		)
		(fill
			(thermal_gap 0.5)
			(thermal_bridge_width 0.5)
			(island_removal_mode 0)
		)
		(polygon
			(pts
				(arc
					(start 327.49998 -66.73723)
					(mid 331.499972 -62.737238)
					(end 335.499964 -66.73723)
				)
				(arc
					(start 335.499964 -66.73723)
					(mid 331.499972 -70.737222)
					(end 327.49998 -66.73723)
				)
			)
		)
	)
	(zone
		(layer "B.Cu")
		(hatch none 0.5)
		(connect_pads
			(clearance 0)
		)
		(min_thickness 0.25)
		(keepout
			(tracks not_allowed)
			(vias allowed)
			(pads allowed)
			(copperpour not_allowed)
			(footprints allowed)
		)
		(placement
			(enabled no)
			(sheetname "")
		)
		(fill
			(thermal_gap 0.5)
			(thermal_bridge_width 0.5)
			(island_removal_mode 0)
		)
		(polygon
			(pts
				(arc
					(start 159.947102 -76.64196)
					(mid 159.563308 -77.025373)
					(end 159.946848 -77.40904)
				)
				(arc
					(start 160.157668 -77.40904)
					(mid 160.126509 -77.342987)
					(end 160.08477 -77.283056)
				)
				(arc
					(start 160.08477 -77.283056)
					(mid 159.74159 -76.81759)
					(end 160.202626 -77.166724)
				)
				(arc
					(start 160.202626 -77.166724)
					(mid 160.280622 -77.280494)
					(end 160.330642 -77.40904)
				)
				(arc
					(start 160.547304 -77.40904)
					(mid 160.596552 -77.280857)
					(end 160.673288 -77.166978)
				)
				(arc
					(start 160.673288 -77.166978)
					(mid 161.133686 -76.817329)
					(end 160.791398 -77.28331)
				)
				(arc
					(start 160.791398 -77.28331)
					(mid 160.750548 -77.343244)
					(end 160.720024 -77.40904)
				)
				(arc
					(start 160.928812 -77.40904)
					(mid 161.312352 -77.0255)
					(end 160.928812 -76.64196)
				)
			)
		)
	)
	(zone
		(net "P3V3_STBY")
		(layer "B.Cu")
		(hatch none 0.5)
		(connect_pads
			(clearance 0.5)
		)
		(min_thickness 0.25)
		(fill yes
			(thermal_gap 0.5)
			(thermal_bridge_width 0.5)
			(island_removal_mode 0)
		)
		(polygon
			(pts
				(xy 305.562 -51.816) (xy 305.308 -52.07) (xy 305.308 -54.356) (xy 304.292 -55.372) (xy 281.559 -55.372)
				(xy 279.781 -57.15) (xy 271.018 -57.15) (xy 270.002 -56.134) (xy 267.97 -56.134) (xy 266.954 -57.15)
				(xy 266.954 -59.309) (xy 267.462 -59.817) (xy 283.591 -59.817) (xy 284.226 -60.452) (xy 284.226 -73.025)
				(xy 284.861 -73.66) (xy 289.052 -73.66) (xy 289.56 -73.152) (xy 289.56 -60.325) (xy 290.068 -59.817)
				(xy 299.593 -59.817) (xy 302.895 -56.515) (xy 306.959 -56.515) (xy 307.975 -55.499) (xy 307.975 -52.959)
				(xy 307.086 -52.07) (xy 306.451 -52.07) (xy 306.197 -51.816)
			)
		)
	)
	(zone
		(net "GND")
		(layer "B.Cu")
		(hatch none 0.5)
		(connect_pads
			(clearance 0.5)
		)
		(min_thickness 0.25)
		(fill yes
			(thermal_gap 0.5)
			(thermal_bridge_width 0.5)
			(island_removal_mode 0)
		)
		(polygon
			(pts
				(xy 152.781 -83.185) (xy 152.4 -83.566) (xy 152.4 -103.632) (xy 152.908 -104.14) (xy 158.242 -104.14)
				(xy 158.496 -104.394) (xy 158.496 -111.76) (xy 159.131 -112.395) (xy 162.306 -112.395) (xy 162.687 -112.014)
				(xy 162.687 -107.442) (xy 176.657 -93.472) (xy 176.657 -83.947) (xy 175.895 -83.185)
			)
		)
		(polygon
			(pts
				(xy 159.01416 -110.668054) (xy 158.81096 -110.668054) (xy 158.81096 -110.871254) (xy 159.01416 -110.871254)
			)
		)
		(polygon
			(pts
				(xy 159.01416 -110.312454) (xy 158.81096 -110.312454) (xy 158.81096 -110.515654) (xy 159.01416 -110.515654)
			)
		)
		(polygon
			(pts
				(xy 159.01416 -109.550454) (xy 158.81096 -109.550454) (xy 158.81096 -109.753654) (xy 159.01416 -109.753654)
			)
		)
		(polygon
			(pts
				(xy 159.01416 -109.194854) (xy 158.81096 -109.194854) (xy 158.81096 -109.398054) (xy 159.01416 -109.398054)
			)
		)
		(polygon
			(pts
				(xy 159.01416 -108.432854) (xy 158.81096 -108.432854) (xy 158.81096 -108.636054) (xy 159.01416 -108.636054)
			)
		)
		(polygon
			(pts
				(xy 159.01416 -108.077254) (xy 158.81096 -108.077254) (xy 158.81096 -108.280454) (xy 159.01416 -108.280454)
			)
		)
		(polygon
			(pts
				(xy 159.01416 -107.315254) (xy 158.81096 -107.315254) (xy 158.81096 -107.518454) (xy 159.01416 -107.518454)
			)
		)
		(polygon
			(pts
				(xy 159.01416 -106.959654) (xy 158.81096 -106.959654) (xy 158.81096 -107.162854) (xy 159.01416 -107.162854)
			)
		)
		(polygon
			(pts
				(xy 159.01416 -106.197654) (xy 158.81096 -106.197654) (xy 158.81096 -106.400854) (xy 159.01416 -106.400854)
			)
		)
		(polygon
			(pts
				(xy 159.01416 -105.842054) (xy 158.81096 -105.842054) (xy 158.81096 -106.045254) (xy 159.01416 -106.045254)
			)
		)
		(polygon
			(pts
				(xy 159.01416 -105.080054) (xy 158.81096 -105.080054) (xy 158.81096 -105.283254) (xy 159.01416 -105.283254)
			)
		)
		(polygon
			(pts
				(xy 159.01416 -104.724454) (xy 158.81096 -104.724454) (xy 158.81096 -104.927654) (xy 159.01416 -104.927654)
			)
		)
		(polygon
			(pts
				(xy 163.2204 -88.773) (xy 163.0172 -88.773) (xy 163.0172 -88.9762) (xy 163.2204 -88.9762)
			)
		)
		(polygon
			(pts
				(xy 162.3568 -88.773) (xy 162.1536 -88.773) (xy 162.1536 -88.9762) (xy 162.3568 -88.9762)
			)
		)
		(polygon
			(pts
				(xy 161.9504 -88.773) (xy 161.7472 -88.773) (xy 161.7472 -88.9762) (xy 161.9504 -88.9762)
			)
		)
		(polygon
			(pts
				(xy 161.0868 -88.773) (xy 160.8836 -88.773) (xy 160.8836 -88.9762) (xy 161.0868 -88.9762)
			)
		)
		(polygon
			(pts
				(xy 160.6804 -88.773) (xy 160.4772 -88.773) (xy 160.4772 -88.9762) (xy 160.6804 -88.9762)
			)
		)
		(polygon
			(pts
				(xy 159.8168 -88.773) (xy 159.6136 -88.773) (xy 159.6136 -88.9762) (xy 159.8168 -88.9762)
			)
		)
		(polygon
			(pts
				(xy 159.4104 -88.773) (xy 159.2072 -88.773) (xy 159.2072 -88.9762) (xy 159.4104 -88.9762)
			)
		)
		(polygon
			(pts
				(xy 158.5468 -88.773) (xy 158.3436 -88.773) (xy 158.3436 -88.9762) (xy 158.5468 -88.9762)
			)
		)
		(polygon
			(pts
				(xy 163.2204 -87.9094) (xy 163.0172 -87.9094) (xy 163.0172 -88.1126) (xy 163.2204 -88.1126)
			)
		)
		(polygon
			(pts
				(xy 162.3568 -87.9094) (xy 162.1536 -87.9094) (xy 162.1536 -88.1126) (xy 162.3568 -88.1126)
			)
		)
		(polygon
			(pts
				(xy 161.9504 -87.9094) (xy 161.7472 -87.9094) (xy 161.7472 -88.1126) (xy 161.9504 -88.1126)
			)
		)
		(polygon
			(pts
				(xy 161.0868 -87.9094) (xy 160.8836 -87.9094) (xy 160.8836 -88.1126) (xy 161.0868 -88.1126)
			)
		)
		(polygon
			(pts
				(xy 160.6804 -87.9094) (xy 160.4772 -87.9094) (xy 160.4772 -88.1126) (xy 160.6804 -88.1126)
			)
		)
		(polygon
			(pts
				(xy 159.8168 -87.9094) (xy 159.6136 -87.9094) (xy 159.6136 -88.1126) (xy 159.8168 -88.1126)
			)
		)
		(polygon
			(pts
				(xy 159.4104 -87.9094) (xy 159.2072 -87.9094) (xy 159.2072 -88.1126) (xy 159.4104 -88.1126)
			)
		)
		(polygon
			(pts
				(xy 158.5468 -87.9094) (xy 158.3436 -87.9094) (xy 158.3436 -88.1126) (xy 158.5468 -88.1126)
			)
		)
	)
	(zone
		(layer "B.Cu")
		(hatch none 0.5)
		(connect_pads
			(clearance 0)
		)
		(min_thickness 0.25)
		(keepout
			(tracks allowed)
			(vias allowed)
			(pads allowed)
			(copperpour allowed)
			(footprints allowed)
		)
		(placement
			(enabled no)
			(sheetname "")
		)
		(fill
			(thermal_gap 0.5)
			(thermal_bridge_width 0.5)
			(island_removal_mode 0)
		)
		(polygon
			(pts
				(xy 53.34254 -76.083668) (xy 55.14594 -76.083668) (xy 55.14594 -79.233268) (xy 53.34254 -79.233268)
				(xy 49.911 -79.233268) (xy 49.911 -76.083668)
			)
		)
	)
	(zone
		(layer "B.Cu")
		(hatch none 0.5)
		(connect_pads
			(clearance 0)
		)
		(min_thickness 0.25)
		(keepout
			(tracks allowed)
			(vias allowed)
			(pads allowed)
			(copperpour allowed)
			(footprints not_allowed)
		)
		(placement
			(enabled no)
			(sheetname "")
		)
		(fill
			(thermal_gap 0.5)
			(thermal_bridge_width 0.5)
			(island_removal_mode 0)
		)
		(polygon
			(pts
				(arc
					(start 0 -246.000016)
					(mid 1.12701 -249.162282)
					(end 3.999992 -250.898914)
				)
				(xy 3.999992 -109.000036) (xy 0 -109.000036)
			)
		)
	)
	(zone
		(layer "B.Cu")
		(hatch none 0.5)
		(connect_pads
			(clearance 0)
		)
		(min_thickness 0.25)
		(keepout
			(tracks allowed)
			(vias allowed)
			(pads allowed)
			(copperpour allowed)
			(footprints not_allowed)
		)
		(placement
			(enabled no)
			(sheetname "")
		)
		(fill
			(thermal_gap 0.5)
			(thermal_bridge_width 0.5)
			(island_removal_mode 0)
		)
		(polygon
			(pts
				(arc
					(start 184.9501 -104.30002)
					(mid 188.950092 -100.300028)
					(end 192.950084 -104.30002)
				)
				(arc
					(start 192.950084 -104.30002)
					(mid 188.950092 -108.300012)
					(end 184.9501 -104.30002)
				)
			)
		)
	)
	(zone
		(layer "B.Cu")
		(hatch none 0.5)
		(connect_pads
			(clearance 0)
		)
		(min_thickness 0.25)
		(keepout
			(tracks not_allowed)
			(vias allowed)
			(pads allowed)
			(copperpour not_allowed)
			(footprints allowed)
		)
		(placement
			(enabled no)
			(sheetname "")
		)
		(fill
			(thermal_gap 0.5)
			(thermal_bridge_width 0.5)
			(island_removal_mode 0)
		)
		(polygon
			(pts
				(arc
					(start 83.46694 -34.61893)
					(mid 83.083527 -34.235136)
					(end 82.69986 -34.618676)
				)
				(xy 82.69986 -34.8361)
				(arc
					(start 82.760312 -34.8361)
					(mid 82.774892 -34.8332)
					(end 82.787236 -34.824924)
				)
				(arc
					(start 82.836766 -34.775394)
					(mid 83.290026 -34.41205)
					(end 82.926682 -34.86531)
				)
				(xy 82.85861 -34.933382)
				(arc
					(start 82.8548 -34.933382)
					(mid 82.8235 -34.950496)
					(end 82.789268 -34.96056)
				)
				(xy 82.786728 -34.9631) (xy 82.69986 -34.9631) (xy 82.69986 -35.179) (xy 82.786474 -35.179)
				(arc
					(start 82.789014 -35.18154)
					(mid 82.823271 -35.191544)
					(end 82.854546 -35.208718)
				)
				(xy 82.858356 -35.208718)
				(arc
					(start 82.926682 -35.277044)
					(mid 83.290026 -35.730304)
					(end 82.836766 -35.36696)
				)
				(arc
					(start 82.786982 -35.317176)
					(mid 82.774629 -35.308922)
					(end 82.760058 -35.306)
				)
				(xy 82.69986 -35.306)
				(arc
					(start 82.69986 -35.523678)
					(mid 83.0834 -35.907218)
					(end 83.46694 -35.523678)
				)
			)
		)
	)
	(zone
		(layer "B.Cu")
		(hatch none 0.5)
		(connect_pads
			(clearance 0)
		)
		(min_thickness 0.25)
		(keepout
			(tracks allowed)
			(vias allowed)
			(pads allowed)
			(copperpour allowed)
			(footprints not_allowed)
		)
		(placement
			(enabled no)
			(sheetname "")
		)
		(fill
			(thermal_gap 0.5)
			(thermal_bridge_width 0.5)
			(island_removal_mode 0)
		)
		(polygon
			(pts
				(arc
					(start 335.499964 -22.237192)
					(mid 331.499972 -26.237184)
					(end 327.49998 -22.237192)
				)
				(arc
					(start 327.49998 -22.237192)
					(mid 331.499972 -18.2372)
					(end 335.499964 -22.237192)
				)
			)
		)
	)
	(zone
		(layer "B.Cu")
		(hatch none 0.5)
		(connect_pads
			(clearance 0)
		)
		(min_thickness 0.25)
		(keepout
			(tracks allowed)
			(vias allowed)
			(pads allowed)
			(copperpour allowed)
			(footprints not_allowed)
		)
		(placement
			(enabled no)
			(sheetname "")
		)
		(fill
			(thermal_gap 0.5)
			(thermal_bridge_width 0.5)
			(island_removal_mode 0)
		)
		(polygon
			(pts
				(arc
					(start 141.85011 -85.849968)
					(mid 145.35023 -82.349848)
					(end 148.850096 -85.849968)
				)
				(arc
					(start 148.850096 -85.849968)
					(mid 145.35023 -89.349834)
					(end 141.85011 -85.849968)
				)
			)
		)
	)
	(zone
		(layer "B.Cu")
		(hatch none 0.5)
		(connect_pads
			(clearance 0)
		)
		(min_thickness 0.25)
		(keepout
			(tracks allowed)
			(vias allowed)
			(pads allowed)
			(copperpour allowed)
			(footprints not_allowed)
		)
		(placement
			(enabled no)
			(sheetname "")
		)
		(fill
			(thermal_gap 0.5)
			(thermal_bridge_width 0.5)
			(island_removal_mode 0)
		)
		(polygon
			(pts
				(arc
					(start 192.950084 -104.30002)
					(mid 188.950092 -108.300012)
					(end 184.9501 -104.30002)
				)
				(arc
					(start 184.9501 -104.30002)
					(mid 188.950092 -100.300028)
					(end 192.950084 -104.30002)
				)
			)
		)
	)
	(zone
		(net "P1V8_STBY")
		(layer "B.Cu")
		(hatch none 0.5)
		(connect_pads
			(clearance 0.5)
		)
		(min_thickness 0.25)
		(fill yes
			(thermal_gap 0.5)
			(thermal_bridge_width 0.5)
			(island_removal_mode 0)
		)
		(polygon
			(pts
				(xy 226.949 -97.536) (xy 226.06 -98.425) (xy 226.06 -104.521) (xy 226.822 -105.283) (xy 228.473 -105.283)
				(xy 233.807 -110.617) (xy 237.617 -110.617) (xy 239.776 -112.776) (xy 306.451 -112.776) (xy 318.643 -124.968)
				(xy 337.693 -124.968) (xy 337.7184 -124.9934) (xy 338.7852 -124.9934) (xy 341.8078 -128.016) (xy 346.583 -128.016)
				(xy 348.996 -130.429) (xy 348.996 -135.128) (xy 347.599 -136.525) (xy 341.376 -136.525) (xy 338.582 -139.319)
				(xy 338.582 -161.29) (xy 341.884 -164.592) (xy 341.884 -172.466) (xy 342.392 -172.974) (xy 349.758 -172.974)
				(xy 352.552 -170.18) (xy 352.552 -125.349) (xy 350.647 -123.444) (xy 342.773 -123.444) (xy 341.122 -121.793)
				(xy 322.199 -121.793) (xy 307.34 -106.934) (xy 255.143 -106.934) (xy 245.745 -97.536)
			)
		)
	)
	(zone
		(layer "B.Cu")
		(hatch none 0.5)
		(connect_pads
			(clearance 0)
		)
		(min_thickness 0.25)
		(keepout
			(tracks allowed)
			(vias allowed)
			(pads allowed)
			(copperpour allowed)
			(footprints not_allowed)
		)
		(placement
			(enabled no)
			(sheetname "")
		)
		(fill
			(thermal_gap 0.5)
			(thermal_bridge_width 0.5)
			(island_removal_mode 0)
		)
		(polygon
			(pts
				(arc
					(start 148.850096 -85.849968)
					(mid 145.35023 -89.349834)
					(end 141.85011 -85.849968)
				)
				(arc
					(start 141.85011 -85.849968)
					(mid 145.35023 -82.349848)
					(end 148.850096 -85.849968)
				)
			)
		)
	)
	(zone
		(net "GND")
		(layer "B.Cu")
		(hatch none 0.5)
		(connect_pads
			(clearance 0.5)
		)
		(min_thickness 0.25)
		(fill yes
			(thermal_gap 0.5)
			(thermal_bridge_width 0.5)
			(island_removal_mode 0)
		)
		(polygon
			(pts
				(xy 128.02997 -84.074) (xy 127.77597 -84.328) (xy 127.77597 -86.487) (xy 127.26797 -86.995) (xy 127.26797 -90.551)
				(xy 127.52197 -90.805) (xy 130.06197 -90.805) (xy 130.44297 -90.424) (xy 130.44297 -84.582) (xy 129.93497 -84.074)
			)
		)
		(polygon
			(pts
				(xy 127.97917 -89.4842) (xy 127.77597 -89.4842) (xy 127.77597 -89.6874) (xy 127.97917 -89.6874)
			)
		)
		(polygon
			(pts
				(xy 127.97917 -88.8746) (xy 127.77597 -88.8746) (xy 127.77597 -89.0778) (xy 127.97917 -89.0778)
			)
		)
		(polygon
			(pts
				(xy 127.97917 -88.4682) (xy 127.77597 -88.4682) (xy 127.77597 -88.6714) (xy 127.97917 -88.6714)
			)
		)
		(polygon
			(pts
				(xy 127.97917 -87.8586) (xy 127.77597 -87.8586) (xy 127.77597 -88.0618) (xy 127.97917 -88.0618)
			)
		)
		(polygon
			(pts
				(xy 127.67437 -87.5538) (xy 127.47117 -87.5538) (xy 127.47117 -87.757) (xy 127.67437 -87.757)
			)
		)
		(polygon
			(pts
				(xy 127.67437 -87.1982) (xy 127.47117 -87.1982) (xy 127.47117 -87.4014) (xy 127.67437 -87.4014)
			)
		)
	)
	(zone
		(net "P1V53_STBY")
		(layer "B.Cu")
		(hatch none 0.5)
		(connect_pads
			(clearance 0.5)
		)
		(min_thickness 0.25)
		(fill yes
			(thermal_gap 0.5)
			(thermal_bridge_width 0.5)
			(island_removal_mode 0)
		)
		(polygon
			(pts
				(xy 294.894 -201.168) (xy 294.386 -201.676) (xy 290.068 -201.676) (xy 289.687 -202.057) (xy 289.687 -203.581)
				(xy 289.433 -203.835) (xy 283.845 -203.835) (xy 281.94 -205.74) (xy 281.94 -206.756) (xy 284.226 -209.042)
				(xy 300.609 -209.042) (xy 301.117 -208.534) (xy 301.117 -203.327) (xy 298.958 -201.168)
			)
		)
		(polygon
			(pts
				(xy 293.624 -203.454) (xy 293.37 -203.454) (xy 293.37 -203.708) (xy 293.624 -203.708)
			)
		)
		(polygon
			(pts
				(xy 293.0144 -203.454) (xy 292.7604 -203.454) (xy 292.7604 -203.708) (xy 293.0144 -203.708)
			)
		)
		(polygon
			(pts
				(xy 297.688 -203.073) (xy 297.434 -203.073) (xy 297.434 -203.327) (xy 297.688 -203.327)
			)
		)
		(polygon
			(pts
				(xy 297.0784 -203.073) (xy 296.8244 -203.073) (xy 296.8244 -203.327) (xy 297.0784 -203.327)
			)
		)
		(polygon
			(pts
				(xy 296.418 -203.073) (xy 296.164 -203.073) (xy 296.164 -203.327) (xy 296.418 -203.327)
			)
		)
		(polygon
			(pts
				(xy 295.8084 -203.073) (xy 295.5544 -203.073) (xy 295.5544 -203.327) (xy 295.8084 -203.327)
			)
		)
		(polygon
			(pts
				(xy 295.148 -203.073) (xy 294.894 -203.073) (xy 294.894 -203.327) (xy 295.148 -203.327)
			)
		)
		(polygon
			(pts
				(xy 294.5384 -203.073) (xy 294.2844 -203.073) (xy 294.2844 -203.327) (xy 294.5384 -203.327)
			)
		)
		(polygon
			(pts
				(xy 290.6268 -202.565) (xy 290.3728 -202.565) (xy 290.3728 -202.819) (xy 290.6268 -202.819)
			)
		)
	)
	(zone
		(layer "B.Cu")
		(hatch none 0.5)
		(connect_pads
			(clearance 0)
		)
		(min_thickness 0.25)
		(keepout
			(tracks not_allowed)
			(vias allowed)
			(pads allowed)
			(copperpour not_allowed)
			(footprints allowed)
		)
		(placement
			(enabled no)
			(sheetname "")
		)
		(fill
			(thermal_gap 0.5)
			(thermal_bridge_width 0.5)
			(island_removal_mode 0)
		)
		(polygon
			(pts
				(arc
					(start 167.946832 -76.64196)
					(mid 167.563038 -77.025373)
					(end 167.946578 -77.40904)
				)
				(arc
					(start 168.175178 -77.40904)
					(mid 168.158912 -77.364237)
					(end 168.130474 -77.325982)
				)
				(arc
					(start 168.086532 -77.28204)
					(mid 167.739434 -76.819509)
					(end 168.203118 -77.1652)
				)
				(xy 168.271444 -77.233272)
				(arc
					(start 168.271444 -77.23632)
					(mid 168.318557 -77.316171)
					(end 168.341548 -77.405992)
				)
				(xy 168.34358 -77.40777) (xy 168.34358 -77.40904) (xy 168.52138 -77.40904) (xy 168.52138 -77.40777)
				(arc
					(start 168.523666 -77.405738)
					(mid 168.544639 -77.32562)
					(end 168.586404 -77.2541)
				)
				(xy 168.586404 -77.250798) (xy 168.610534 -77.226668)
				(arc
					(start 168.672002 -77.1652)
					(mid 169.135096 -76.818946)
					(end 168.788842 -77.28204)
				)
				(arc
					(start 168.727374 -77.343508)
					(mid 168.704446 -77.37374)
					(end 168.690544 -77.40904)
				)
				(arc
					(start 168.928542 -77.40904)
					(mid 169.312082 -77.0255)
					(end 168.928542 -76.64196)
				)
			)
		)
	)
	(zone
		(net "GND")
		(layer "B.Cu")
		(hatch none 0.5)
		(connect_pads
			(clearance 0.5)
		)
		(min_thickness 0.25)
		(fill yes
			(thermal_gap 0.5)
			(thermal_bridge_width 0.5)
			(island_removal_mode 0)
		)
		(polygon
			(pts
				(xy 64.77 -184.15) (xy 64.516 -184.404) (xy 64.516 -185.801) (xy 64.135 -186.182) (xy 47.752 -186.182)
				(xy 47.117 -186.817) (xy 47.117 -188.468) (xy 42.037 -193.548) (xy 42.037 -198.755) (xy 44.958 -201.676)
				(xy 65.913 -201.676) (xy 69.977 -197.612) (xy 69.977 -184.531) (xy 69.596 -184.15)
			)
		)
	)
	(zone
		(layer "B.Cu")
		(hatch none 0.5)
		(connect_pads
			(clearance 0)
		)
		(min_thickness 0.25)
		(keepout
			(tracks allowed)
			(vias allowed)
			(pads allowed)
			(copperpour allowed)
			(footprints not_allowed)
		)
		(placement
			(enabled no)
			(sheetname "")
		)
		(fill
			(thermal_gap 0.5)
			(thermal_bridge_width 0.5)
			(island_removal_mode 0)
		)
		(polygon
			(pts
				(arc
					(start 316.099952 -104.499918)
					(mid 311.700164 -108.899706)
					(end 307.300122 -104.499918)
				)
				(arc
					(start 307.300122 -104.499918)
					(mid 311.700164 -100.099876)
					(end 316.099952 -104.499918)
				)
			)
		)
	)
	(zone
		(layer "B.Cu")
		(hatch none 0.5)
		(connect_pads
			(clearance 0)
		)
		(min_thickness 0.25)
		(keepout
			(tracks allowed)
			(vias allowed)
			(pads allowed)
			(copperpour allowed)
			(footprints not_allowed)
		)
		(placement
			(enabled no)
			(sheetname "")
		)
		(fill
			(thermal_gap 0.5)
			(thermal_bridge_width 0.5)
			(island_removal_mode 0)
		)
		(polygon
			(pts
				(arc
					(start 7.400036 -100.7999)
					(mid 4.900168 -103.299768)
					(end 2.400046 -100.7999)
				)
				(arc
					(start 2.400046 -100.7999)
					(mid 4.900168 -98.299778)
					(end 7.400036 -100.7999)
				)
			)
		)
	)
	(zone
		(net "GND")
		(layer "B.Cu")
		(hatch none 0.5)
		(connect_pads
			(clearance 0.5)
		)
		(min_thickness 0.25)
		(fill yes
			(thermal_gap 0.5)
			(thermal_bridge_width 0.5)
			(island_removal_mode 0)
		)
		(polygon
			(pts
				(xy 121.45137 -78.8162) (xy 121.17197 -79.0956) (xy 121.17197 -80.7974) (xy 121.55297 -81.1784)
				(xy 121.55297 -84.0486) (xy 121.65457 -84.1502) (xy 122.18797 -84.1502) (xy 122.28957 -84.0486)
				(xy 122.28957 -83.3374) (xy 122.27687 -83.3247) (xy 122.27687 -81.7753) (xy 123.07697 -80.9752)
				(xy 123.07697 -80.518) (xy 123.825 -79.76997) (xy 123.825 -79.121) (xy 123.5202 -78.8162)
			)
		)
		(polygon
			(pts
				(xy 122.129042 -83.383882) (xy 121.925842 -83.383882) (xy 121.925842 -83.587082) (xy 122.129042 -83.587082)
			)
		)
		(polygon
			(pts
				(xy 122.129042 -82.774282) (xy 121.925842 -82.774282) (xy 121.925842 -83.231482) (xy 122.129042 -83.231482)
			)
		)
		(polygon
			(pts
				(xy 122.129042 -82.418682) (xy 121.925842 -82.418682) (xy 121.925842 -82.621882) (xy 122.129042 -82.621882)
			)
		)
	)
	(zone
		(net "P12V_MSB")
		(layer "B.Cu")
		(hatch none 0.5)
		(connect_pads
			(clearance 0.5)
		)
		(min_thickness 0.25)
		(fill yes
			(thermal_gap 0.5)
			(thermal_bridge_width 0.5)
			(island_removal_mode 0)
		)
		(polygon
			(pts
				(xy 218.07297 -72.39) (xy 217.69197 -72.771) (xy 217.69197 -82.55) (xy 218.19997 -83.058) (xy 265.811 -83.058)
				(xy 266.192 -82.677) (xy 266.192 -72.771) (xy 265.811 -72.39)
			)
		)
	)
	(zone
		(layer "B.Cu")
		(hatch none 0.5)
		(connect_pads
			(clearance 0)
		)
		(min_thickness 0.25)
		(keepout
			(tracks not_allowed)
			(vias allowed)
			(pads allowed)
			(copperpour not_allowed)
			(footprints allowed)
		)
		(placement
			(enabled no)
			(sheetname "")
		)
		(fill
			(thermal_gap 0.5)
			(thermal_bridge_width 0.5)
			(island_removal_mode 0)
		)
		(polygon
			(pts
				(arc
					(start 79.604108 -39.24046)
					(mid 79.220568 -39.624)
					(end 79.604108 -40.00754)
				)
				(arc
					(start 80.580738 -40.00754)
					(mid 80.964532 -39.624127)
					(end 80.580992 -39.24046)
				)
				(arc
					(start 80.29067 -39.24046)
					(mid 80.296571 -39.248817)
					(end 80.30337 -39.256462)
				)
				(arc
					(start 80.424274 -39.377366)
					(mid 80.787618 -39.830626)
					(end 80.334358 -39.467282)
				)
				(xy 80.194912 -39.327836)
				(arc
					(start 80.194912 -39.325042)
					(mid 80.170391 -39.284912)
					(end 80.155034 -39.24046)
				)
				(arc
					(start 79.93126 -39.24046)
					(mid 79.903606 -39.356662)
					(end 79.847186 -39.461948)
				)
				(arc
					(start 79.847186 -39.461948)
					(mid 79.402678 -39.835598)
					(end 79.753968 -39.373302)
				)
				(arc
					(start 79.753968 -39.373302)
					(mid 79.785687 -39.309507)
					(end 79.803244 -39.24046)
				)
			)
		)
	)
	(zone
		(net "GND")
		(layer "B.Cu")
		(hatch none 0.5)
		(connect_pads
			(clearance 0.5)
		)
		(min_thickness 0.25)
		(fill yes
			(thermal_gap 0.5)
			(thermal_bridge_width 0.5)
			(island_removal_mode 0)
		)
		(polygon
			(pts
				(xy 121.901966 -31.369) (xy 121.647966 -31.623) (xy 121.647966 -32.639) (xy 122.409966 -33.401)
				(xy 128.378966 -33.401) (xy 128.505966 -33.274) (xy 128.505966 -31.75) (xy 128.124966 -31.369)
			)
		)
		(polygon
			(pts
				(xy 123.451366 -32.9438) (xy 123.248166 -32.9438) (xy 123.248166 -33.147) (xy 123.451366 -33.147)
			)
		)
		(polygon
			(pts
				(xy 123.095766 -32.9438) (xy 122.892566 -32.9438) (xy 122.892566 -33.147) (xy 123.095766 -33.147)
			)
		)
		(polygon
			(pts
				(xy 122.7074 -32.9438) (xy 122.5042 -32.9438) (xy 122.5042 -33.147) (xy 122.7074 -33.147)
			)
		)
	)
	(zone
		(net "P12V")
		(layer "B.Cu")
		(hatch none 0.5)
		(connect_pads
			(clearance 0.5)
		)
		(min_thickness 0.25)
		(fill yes
			(thermal_gap 0.5)
			(thermal_bridge_width 0.5)
			(island_removal_mode 0)
		)
		(polygon
			(pts
				(xy 83.185 -153.035) (xy 70.358 -165.862) (xy 70.358 -200.025) (xy 59.563 -210.82) (xy 59.563 -224.536)
				(xy 60.071 -225.044) (xy 67.564 -225.044) (xy 68.072 -224.536) (xy 68.072 -218.186) (xy 81.153 -205.105)
				(xy 81.153 -169.926) (xy 91.7194 -159.3596) (xy 94.8182 -159.3596) (xy 96.52 -157.6578) (xy 96.52 -153.67)
				(xy 95.885 -153.035)
			)
		)
	)
	(zone
		(layer "B.Cu")
		(hatch none 0.5)
		(connect_pads
			(clearance 0)
		)
		(min_thickness 0.25)
		(keepout
			(tracks not_allowed)
			(vias allowed)
			(pads allowed)
			(copperpour not_allowed)
			(footprints allowed)
		)
		(placement
			(enabled no)
			(sheetname "")
		)
		(fill
			(thermal_gap 0.5)
			(thermal_bridge_width 0.5)
			(island_removal_mode 0)
		)
		(polygon
			(pts
				(arc
					(start 124.779532 -79.868268)
					(mid 124.395738 -80.251681)
					(end 124.779278 -80.635348)
				)
				(arc
					(start 124.983748 -80.635348)
					(mid 124.954844 -80.570039)
					(end 124.91974 -80.50784)
				)
				(arc
					(start 124.91974 -80.50784)
					(mid 124.585932 -80.032949)
					(end 125.016006 -80.42275)
				)
				(arc
					(start 125.016006 -80.42275)
					(mid 125.074514 -80.525522)
					(end 125.118368 -80.635348)
				)
				(arc
					(start 125.417072 -80.635348)
					(mid 125.460941 -80.525529)
					(end 125.519434 -80.42275)
				)
				(arc
					(start 125.519434 -80.42275)
					(mid 125.949485 -80.032975)
					(end 125.6157 -80.50784)
				)
				(arc
					(start 125.6157 -80.50784)
					(mid 125.580581 -80.570031)
					(end 125.551692 -80.635348)
				)
				(arc
					(start 125.756162 -80.635348)
					(mid 126.139702 -80.251808)
					(end 125.756162 -79.868268)
				)
			)
		)
	)
	(zone
		(net "P5V_USB")
		(layer "B.Cu")
		(hatch none 0.5)
		(connect_pads
			(clearance 0.5)
		)
		(min_thickness 0.25)
		(fill yes
			(thermal_gap 0.5)
			(thermal_bridge_width 0.5)
			(island_removal_mode 0)
		)
		(polygon
			(pts
				(xy 258.191 -10.033) (xy 257.683 -10.541) (xy 257.683 -13.716) (xy 257.937 -13.97) (xy 260.223 -13.97)
				(xy 260.731 -14.478) (xy 260.731 -16.637) (xy 260.985 -16.891) (xy 267.97 -16.891) (xy 269.621 -15.24)
				(xy 269.621 -10.541) (xy 269.113 -10.033)
			)
		)
		(polygon
			(pts
				(xy 267.6398 -15.621) (xy 267.3858 -15.621) (xy 267.3858 -15.875) (xy 267.6398 -15.875)
			)
		)
		(polygon
			(pts
				(xy 266.7762 -15.621) (xy 266.5222 -15.621) (xy 266.5222 -15.875) (xy 266.7762 -15.875)
			)
		)
		(polygon
			(pts
				(xy 266.3698 -15.621) (xy 266.1158 -15.621) (xy 266.1158 -15.875) (xy 266.3698 -15.875)
			)
		)
		(polygon
			(pts
				(xy 265.5062 -15.621) (xy 265.2522 -15.621) (xy 265.2522 -15.875) (xy 265.5062 -15.875)
			)
		)
		(polygon
			(pts
				(xy 265.0998 -15.621) (xy 264.8458 -15.621) (xy 264.8458 -15.875) (xy 265.0998 -15.875)
			)
		)
		(polygon
			(pts
				(xy 264.2362 -15.621) (xy 263.9822 -15.621) (xy 263.9822 -15.875) (xy 264.2362 -15.875)
			)
		)
		(polygon
			(pts
				(xy 263.8298 -15.621) (xy 263.5758 -15.621) (xy 263.5758 -15.875) (xy 263.8298 -15.875)
			)
		)
		(polygon
			(pts
				(xy 262.9662 -15.621) (xy 262.7122 -15.621) (xy 262.7122 -15.875) (xy 262.9662 -15.875)
			)
		)
		(polygon
			(pts
				(xy 262.5598 -15.621) (xy 262.3058 -15.621) (xy 262.3058 -15.875) (xy 262.5598 -15.875)
			)
		)
		(polygon
			(pts
				(xy 261.6962 -15.621) (xy 261.4422 -15.621) (xy 261.4422 -15.875) (xy 261.6962 -15.875)
			)
		)
	)
	(zone
		(layer "B.Cu")
		(hatch none 0.5)
		(connect_pads
			(clearance 0)
		)
		(min_thickness 0.25)
		(keepout
			(tracks allowed)
			(vias allowed)
			(pads allowed)
			(copperpour allowed)
			(footprints not_allowed)
		)
		(placement
			(enabled no)
			(sheetname "")
		)
		(fill
			(thermal_gap 0.5)
			(thermal_bridge_width 0.5)
			(island_removal_mode 0)
		)
		(polygon
			(pts
				(arc
					(start 27.599894 -100.7999)
					(mid 25.100026 -103.299768)
					(end 22.599904 -100.7999)
				)
				(arc
					(start 22.599904 -100.7999)
					(mid 25.100026 -98.299778)
					(end 27.599894 -100.7999)
				)
			)
		)
	)
	(zone
		(layer "B.Cu")
		(hatch none 0.5)
		(connect_pads
			(clearance 0)
		)
		(min_thickness 0.25)
		(keepout
			(tracks allowed)
			(vias allowed)
			(pads allowed)
			(copperpour allowed)
			(footprints not_allowed)
		)
		(placement
			(enabled no)
			(sheetname "")
		)
		(fill
			(thermal_gap 0.5)
			(thermal_bridge_width 0.5)
			(island_removal_mode 0)
		)
		(polygon
			(pts
				(arc
					(start 80.849978 -103.849932)
					(mid 84.350098 -100.349812)
					(end 87.849964 -103.849932)
				)
				(arc
					(start 87.849964 -103.849932)
					(mid 84.350098 -107.349798)
					(end 80.849978 -103.849932)
				)
			)
		)
	)
	(zone
		(layer "B.Cu")
		(hatch none 0.5)
		(connect_pads
			(clearance 0)
		)
		(min_thickness 0.25)
		(keepout
			(tracks not_allowed)
			(vias allowed)
			(pads allowed)
			(copperpour not_allowed)
			(footprints allowed)
		)
		(placement
			(enabled no)
			(sheetname "")
		)
		(fill
			(thermal_gap 0.5)
			(thermal_bridge_width 0.5)
			(island_removal_mode 0)
		)
		(polygon
			(pts
				(arc
					(start 84.413852 -37.734494)
					(mid 84.04606 -37.386514)
					(end 83.69808 -37.754306)
				)
				(xy 83.69554 -37.754306) (xy 83.703668 -38.0492)
				(arc
					(start 83.852766 -38.0492)
					(mid 83.914513 -38.034813)
					(end 83.96351 -37.99459)
				)
				(arc
					(start 83.96351 -37.99459)
					(mid 84.08055 -37.478809)
					(end 84.100924 -38.00729)
				)
				(arc
					(start 84.100924 -38.00729)
					(mid 84.014129 -38.121885)
					(end 83.880452 -38.174676)
				)
				(xy 83.879182 -38.1762) (xy 83.707224 -38.1762) (xy 83.71332 -38.3921) (xy 83.91525 -38.3921)
				(arc
					(start 83.91652 -38.393624)
					(mid 84.016027 -38.425553)
					(end 84.094828 -38.494208)
				)
				(arc
					(start 84.094828 -38.494208)
					(mid 84.150085 -39.018982)
					(end 83.946238 -38.532308)
				)
				(arc
					(start 83.946238 -38.532308)
					(mid 83.918281 -38.52248)
					(end 83.888834 -38.5191)
				)
				(xy 83.716876 -38.5191) (xy 83.723734 -38.770306) (xy 83.723988 -38.77056)
				(arc
					(start 83.726274 -38.77056)
					(mid 84.094066 -39.11854)
					(end 84.442046 -38.750748)
				)
				(xy 84.444586 -38.750748) (xy 84.416392 -37.734494)
			)
		)
	)
	(zone
		(net "GND")
		(layer "B.Cu")
		(hatch none 0.5)
		(connect_pads
			(clearance 0.5)
		)
		(min_thickness 0.25)
		(fill yes
			(thermal_gap 0.5)
			(thermal_bridge_width 0.5)
			(island_removal_mode 0)
		)
		(polygon
			(pts
				(xy 77.578966 -55.372) (xy 76.435966 -56.515) (xy 76.435966 -60.198) (xy 77.070966 -60.833) (xy 78.594966 -60.833)
				(xy 78.975966 -60.452) (xy 78.975966 -55.499) (xy 78.848966 -55.372)
			)
		)
	)
	(zone
		(net "GND")
		(layer "B.Cu")
		(hatch none 0.5)
		(connect_pads
			(clearance 0.5)
		)
		(min_thickness 0.25)
		(fill yes
			(thermal_gap 0.5)
			(thermal_bridge_width 0.5)
			(island_removal_mode 0)
		)
		(polygon
			(pts
				(xy 234.569 -168.402) (xy 230.251 -172.72) (xy 230.251 -187.706) (xy 231.14 -188.595) (xy 268.097 -188.595)
				(xy 269.494 -187.198) (xy 269.494 -177.038) (xy 260.858 -168.402)
			)
		)
	)
	(zone
		(net "P0V9_E")
		(layer "B.Cu")
		(hatch none 0.5)
		(connect_pads
			(clearance 0.5)
		)
		(min_thickness 0.25)
		(fill yes
			(thermal_gap 0.5)
			(thermal_bridge_width 0.5)
			(island_removal_mode 0)
		)
		(polygon
			(pts
				(xy 152.908 -104.394) (xy 152.4 -104.902) (xy 152.4 -119.888) (xy 152.654 -120.142) (xy 159.766 -120.142)
				(xy 160.02 -119.888) (xy 160.02 -113.792) (xy 158.2801 -112.0521) (xy 158.2801 -104.6861) (xy 157.988 -104.394)
			)
		)
	)
	(zone
		(layer "B.Cu")
		(hatch none 0.5)
		(connect_pads
			(clearance 0)
		)
		(min_thickness 0.25)
		(keepout
			(tracks not_allowed)
			(vias allowed)
			(pads allowed)
			(copperpour not_allowed)
			(footprints allowed)
		)
		(placement
			(enabled no)
			(sheetname "")
		)
		(fill
			(thermal_gap 0.5)
			(thermal_bridge_width 0.5)
			(island_removal_mode 0)
		)
		(polygon
			(pts
				(arc
					(start 163.946332 -76.64196)
					(mid 163.562538 -77.025373)
					(end 163.946078 -77.40904)
				)
				(arc
					(start 164.174678 -77.40904)
					(mid 164.158412 -77.364237)
					(end 164.129974 -77.325982)
				)
				(arc
					(start 164.086032 -77.28204)
					(mid 163.738934 -76.819509)
					(end 164.202618 -77.1652)
				)
				(xy 164.270944 -77.233272)
				(arc
					(start 164.270944 -77.23632)
					(mid 164.318057 -77.316171)
					(end 164.341048 -77.405992)
				)
				(xy 164.34308 -77.40777) (xy 164.34308 -77.40904) (xy 164.52088 -77.40904) (xy 164.52088 -77.40777)
				(arc
					(start 164.523166 -77.405738)
					(mid 164.544139 -77.32562)
					(end 164.585904 -77.2541)
				)
				(xy 164.585904 -77.250798) (xy 164.610034 -77.226668)
				(arc
					(start 164.671502 -77.1652)
					(mid 165.134596 -76.818946)
					(end 164.788342 -77.28204)
				)
				(arc
					(start 164.726874 -77.343508)
					(mid 164.703946 -77.37374)
					(end 164.690044 -77.40904)
				)
				(arc
					(start 164.928042 -77.40904)
					(mid 165.311582 -77.0255)
					(end 164.928042 -76.64196)
				)
			)
		)
	)
	(zone
		(net "P1V8_C")
		(layer "B.Cu")
		(hatch none 0.5)
		(connect_pads
			(clearance 0.5)
		)
		(min_thickness 0.25)
		(fill yes
			(thermal_gap 0.5)
			(thermal_bridge_width 0.5)
			(island_removal_mode 0)
		)
		(polygon
			(pts
				(xy 119.488966 -39.624) (xy 117.964966 -41.148) (xy 117.964966 -46.355) (xy 118.345966 -46.736)
				(xy 121.2342 -46.736) (xy 121.539 -47.0408) (xy 121.539 -48.6918) (xy 121.793 -48.9458) (xy 122.809 -48.9458)
				(xy 123.044966 -48.709834) (xy 123.044966 -40.005) (xy 122.663966 -39.624)
			)
		)
		(polygon
			(pts
				(xy 122.258074 -48.486314) (xy 122.004074 -48.486314) (xy 122.004074 -48.740314) (xy 122.258074 -48.740314)
			)
		)
		(polygon
			(pts
				(xy 122.258074 -47.927514) (xy 122.004074 -47.927514) (xy 122.004074 -48.181514) (xy 122.258074 -48.181514)
			)
		)
		(polygon
			(pts
				(xy 122.2502 -47.455074) (xy 121.9962 -47.455074) (xy 121.9962 -47.709074) (xy 122.2502 -47.709074)
			)
		)
		(polygon
			(pts
				(xy 122.2502 -46.896274) (xy 121.9962 -46.896274) (xy 121.9962 -47.150274) (xy 122.2502 -47.150274)
			)
		)
		(polygon
			(pts
				(xy 122.663966 -45.6438) (xy 122.409966 -45.6438) (xy 122.409966 -45.8978) (xy 122.663966 -45.8978)
			)
		)
		(polygon
			(pts
				(xy 122.663966 -45.0342) (xy 122.409966 -45.0342) (xy 122.409966 -45.2882) (xy 122.663966 -45.2882)
			)
		)
		(polygon
			(pts
				(xy 119.7102 -44.8564) (xy 119.4562 -44.8564) (xy 119.4562 -45.1104) (xy 119.7102 -45.1104)
			)
		)
		(polygon
			(pts
				(xy 119.7102 -44.2976) (xy 119.4562 -44.2976) (xy 119.4562 -44.5516) (xy 119.7102 -44.5516)
			)
		)
		(polygon
			(pts
				(xy 122.663966 -43.9928) (xy 122.409966 -43.9928) (xy 122.409966 -44.2468) (xy 122.663966 -44.2468)
			)
		)
		(polygon
			(pts
				(xy 122.663966 -43.3832) (xy 122.409966 -43.3832) (xy 122.409966 -43.6372) (xy 122.663966 -43.6372)
			)
		)
		(polygon
			(pts
				(xy 119.7102 -43.0784) (xy 119.4562 -43.0784) (xy 119.4562 -43.3324) (xy 119.7102 -43.3324)
			)
		)
		(polygon
			(pts
				(xy 119.7102 -42.5196) (xy 119.4562 -42.5196) (xy 119.4562 -42.7736) (xy 119.7102 -42.7736)
			)
		)
		(polygon
			(pts
				(xy 122.663966 -42.3418) (xy 122.409966 -42.3418) (xy 122.409966 -42.5958) (xy 122.663966 -42.5958)
			)
		)
		(polygon
			(pts
				(xy 122.663966 -41.7322) (xy 122.409966 -41.7322) (xy 122.409966 -41.9862) (xy 122.663966 -41.9862)
			)
		)
		(polygon
			(pts
				(xy 120.8532 -41.3004) (xy 120.5992 -41.3004) (xy 120.5992 -41.5544) (xy 120.8532 -41.5544)
			)
		)
		(polygon
			(pts
				(xy 120.8532 -40.7416) (xy 120.5992 -40.7416) (xy 120.5992 -40.9956) (xy 120.8532 -40.9956)
			)
		)
		(polygon
			(pts
				(xy 122.663966 -40.4368) (xy 122.409966 -40.4368) (xy 122.409966 -40.6908) (xy 122.663966 -40.6908)
			)
		)
		(polygon
			(pts
				(xy 120.9802 -40.1574) (xy 120.7262 -40.1574) (xy 120.7262 -40.4114) (xy 120.9802 -40.4114)
			)
		)
	)
	(zone
		(layer "B.Cu")
		(hatch none 0.5)
		(connect_pads
			(clearance 0)
		)
		(min_thickness 0.25)
		(keepout
			(tracks allowed)
			(vias allowed)
			(pads allowed)
			(copperpour allowed)
			(footprints not_allowed)
		)
		(placement
			(enabled no)
			(sheetname "")
		)
		(fill
			(thermal_gap 0.5)
			(thermal_bridge_width 0.5)
			(island_removal_mode 0)
		)
		(polygon
			(pts
				(arc
					(start 327.49998 -22.237192)
					(mid 331.499972 -18.2372)
					(end 335.499964 -22.237192)
				)
				(arc
					(start 335.499964 -22.237192)
					(mid 331.499972 -26.237184)
					(end 327.49998 -22.237192)
				)
			)
		)
	)
	(zone
		(net "P3V3_STBY")
		(layer "B.Cu")
		(hatch none 0.5)
		(connect_pads
			(clearance 0.5)
		)
		(min_thickness 0.25)
		(fill yes
			(thermal_gap 0.5)
			(thermal_bridge_width 0.5)
			(island_removal_mode 0)
		)
		(polygon
			(pts
				(xy 320.167 -163.83) (xy 319.913 -164.084) (xy 319.913 -165.608) (xy 320.04 -165.735) (xy 320.548 -165.735)
				(xy 321.056 -165.227) (xy 321.691 -165.227) (xy 321.818 -165.1) (xy 321.818 -163.957) (xy 321.691 -163.83)
			)
		)
		(polygon
			(pts
				(xy 320.7512 -164.4904) (xy 320.4972 -164.4904) (xy 320.4972 -164.7444) (xy 320.7512 -164.7444)
			)
		)
	)
	(zone
		(net "P5V_STBY")
		(layer "B.Cu")
		(hatch none 0.5)
		(connect_pads
			(clearance 0.5)
		)
		(min_thickness 0.25)
		(fill yes
			(thermal_gap 0.5)
			(thermal_bridge_width 0.5)
			(island_removal_mode 0)
		)
		(polygon
			(pts
				(xy 338.963 -4.191) (xy 338.582 -4.572) (xy 338.582 -8.3312) (xy 336.6262 -10.287) (xy 326.644 -10.287)
				(xy 314.325 -22.606) (xy 314.325 -46.863) (xy 314.706 -47.244) (xy 315.468 -47.244) (xy 316.0395 -46.6725)
				(xy 318.1985 -46.6725) (xy 321.183 -43.688) (xy 321.183 -26.162) (xy 329.565 -17.78) (xy 334.2386 -17.78)
				(xy 341.249 -10.7696) (xy 341.249 -4.6736) (xy 340.7664 -4.191)
			)
		)
	)
	(zone
		(net "P1V5_E")
		(layer "B.Cu")
		(hatch none 0.5)
		(connect_pads
			(clearance 0.5)
		)
		(min_thickness 0.25)
		(fill yes
			(thermal_gap 0.5)
			(thermal_bridge_width 0.5)
			(island_removal_mode 0)
		)
		(polygon
			(pts
				(xy 319.659 -181.229) (xy 319.532 -181.356) (xy 319.532 -181.991) (xy 319.659 -182.118) (xy 320.167 -182.118)
				(xy 320.548 -182.499) (xy 321.056 -182.499) (xy 321.31 -182.245) (xy 321.31 -181.864) (xy 320.675 -181.229)
			)
		)
	)
	(zone
		(layer "B.Cu")
		(hatch none 0.5)
		(connect_pads
			(clearance 0)
		)
		(min_thickness 0.25)
		(keepout
			(tracks allowed)
			(vias allowed)
			(pads allowed)
			(copperpour allowed)
			(footprints not_allowed)
		)
		(placement
			(enabled no)
			(sheetname "")
		)
		(fill
			(thermal_gap 0.5)
			(thermal_bridge_width 0.5)
			(island_removal_mode 0)
		)
		(polygon
			(pts
				(arc
					(start 27.599894 -85.79993)
					(mid 25.100026 -88.299798)
					(end 22.599904 -85.79993)
				)
				(arc
					(start 22.599904 -85.79993)
					(mid 25.100026 -83.299808)
					(end 27.599894 -85.79993)
				)
			)
		)
	)
	(zone
		(layer "B.Cu")
		(hatch none 0.5)
		(connect_pads
			(clearance 0)
		)
		(min_thickness 0.25)
		(keepout
			(tracks allowed)
			(vias allowed)
			(pads allowed)
			(copperpour allowed)
			(footprints not_allowed)
		)
		(placement
			(enabled no)
			(sheetname "")
		)
		(fill
			(thermal_gap 0.5)
			(thermal_bridge_width 0.5)
			(island_removal_mode 0)
		)
		(polygon
			(pts
				(arc
					(start 2.400046 -85.79993)
					(mid 4.900168 -83.299808)
					(end 7.400036 -85.79993)
				)
				(arc
					(start 7.400036 -85.79993)
					(mid 4.900168 -88.299798)
					(end 2.400046 -85.79993)
				)
			)
		)
	)
	(zone
		(net "SAS0_AVDD")
		(layer "B.Cu")
		(hatch none 0.5)
		(connect_pads
			(clearance 0.5)
		)
		(min_thickness 0.25)
		(fill yes
			(thermal_gap 0.5)
			(thermal_bridge_width 0.5)
			(island_removal_mode 0)
		)
		(polygon
			(pts
				(xy 81.407 -29.718) (xy 81.153 -29.972) (xy 81.153 -31.623) (xy 81.407 -31.877) (xy 85.217 -31.877)
				(xy 85.471 -31.623) (xy 85.471 -29.972) (xy 85.217 -29.718)
			)
		)
	)
	(zone
		(layer "B.Cu")
		(hatch none 0.5)
		(connect_pads
			(clearance 0)
		)
		(min_thickness 0.25)
		(keepout
			(tracks not_allowed)
			(vias allowed)
			(pads allowed)
			(copperpour not_allowed)
			(footprints allowed)
		)
		(placement
			(enabled no)
			(sheetname "")
		)
		(fill
			(thermal_gap 0.5)
			(thermal_bridge_width 0.5)
			(island_removal_mode 0)
		)
		(polygon
			(pts
				(arc
					(start 319.139316 -68.216272)
					(mid 318.755903 -67.832478)
					(end 318.372236 -68.216018)
				)
				(arc
					(start 318.372236 -69.197982)
					(mid 318.755776 -69.581522)
					(end 319.139316 -69.197982)
				)
				(xy 319.139316 -68.961)
				(arc
					(start 319.13322 -68.961)
					(mid 319.11135 -68.96535)
					(end 319.092834 -68.977764)
				)
				(arc
					(start 319.012316 -69.058282)
					(mid 318.549222 -69.404536)
					(end 318.895476 -68.941442)
				)
				(xy 319.000124 -68.836794)
				(arc
					(start 319.004696 -68.836794)
					(mid 319.048159 -68.812735)
					(end 319.095882 -68.798948)
				)
				(xy 319.09893 -68.7959) (xy 319.139316 -68.7959) (xy 319.139316 -68.6181) (xy 319.09893 -68.6181)
				(arc
					(start 319.095882 -68.615052)
					(mid 319.048169 -68.601241)
					(end 319.004696 -68.577206)
				)
				(xy 319.000124 -68.577206)
				(arc
					(start 318.895476 -68.472558)
					(mid 318.549222 -68.009464)
					(end 319.012316 -68.355718)
				)
				(arc
					(start 319.092834 -68.436236)
					(mid 319.111363 -68.448617)
					(end 319.13322 -68.453)
				)
				(xy 319.139316 -68.453)
			)
		)
	)
	(zone
		(net "Net_9")
		(layer "B.Cu")
		(hatch none 0.5)
		(connect_pads
			(clearance 0.5)
		)
		(min_thickness 0.25)
		(fill yes
			(thermal_gap 0.5)
			(thermal_bridge_width 0.5)
			(island_removal_mode 0)
		)
		(polygon
			(pts
				(xy 334.772 -4.572) (xy 334.772 -8.636) (xy 337.82 -8.636) (xy 337.82 -4.572)
			)
		)
	)
	(zone
		(layer "B.Cu")
		(hatch none 0.5)
		(connect_pads
			(clearance 0)
		)
		(min_thickness 0.25)
		(keepout
			(tracks allowed)
			(vias allowed)
			(pads allowed)
			(copperpour allowed)
			(footprints not_allowed)
		)
		(placement
			(enabled no)
			(sheetname "")
		)
		(fill
			(thermal_gap 0.5)
			(thermal_bridge_width 0.5)
			(island_removal_mode 0)
		)
		(polygon
			(pts
				(arc
					(start 22.599904 -100.7999)
					(mid 25.100026 -98.299778)
					(end 27.599894 -100.7999)
				)
				(arc
					(start 27.599894 -100.7999)
					(mid 25.100026 -103.299768)
					(end 22.599904 -100.7999)
				)
			)
		)
	)
	(zone
		(layer "B.Cu")
		(hatch none 0.5)
		(connect_pads
			(clearance 0)
		)
		(min_thickness 0.25)
		(keepout
			(tracks not_allowed)
			(vias allowed)
			(pads allowed)
			(copperpour not_allowed)
			(footprints allowed)
		)
		(placement
			(enabled no)
			(sheetname "")
		)
		(fill
			(thermal_gap 0.5)
			(thermal_bridge_width 0.5)
			(island_removal_mode 0)
		)
		(polygon
			(pts
				(arc
					(start 13.519404 -98.76155)
					(mid 13.432612 -98.187759)
					(end 13.646404 -98.72726)
				)
				(xy 13.646404 -98.861372) (xy 14.408404 -98.90252)
				(arc
					(start 14.408404 -98.80981)
					(mid 14.424596 -98.229411)
					(end 14.535404 -98.799396)
				)
				(arc
					(start 14.535404 -98.894138)
					(mid 14.830672 -98.487025)
					(end 14.46911 -98.137472)
				)
				(arc
					(start 13.52931 -98.086672)
					(mid 13.12545 -98.448876)
					(end 13.487654 -98.852736)
				)
				(xy 13.519404 -98.854514)
			)
		)
	)
	(zone
		(net "P5V_STBY")
		(layer "B.Cu")
		(hatch none 0.5)
		(connect_pads
			(clearance 0.5)
		)
		(min_thickness 0.25)
		(fill yes
			(thermal_gap 0.5)
			(thermal_bridge_width 0.5)
			(island_removal_mode 0)
		)
		(polygon
			(pts
				(xy 342.138 -86.614) (xy 339.979 -88.773) (xy 314.452 -88.773) (xy 309.118 -94.107) (xy 249.809 -94.107)
				(xy 248.539 -95.377) (xy 248.539 -99.822) (xy 249.555 -100.838) (xy 263.779 -100.838) (xy 265.049 -99.568)
				(xy 294.64 -99.568) (xy 295.656 -98.552) (xy 299.085 -98.552) (xy 300.101 -99.568) (xy 327.152 -99.568)
				(xy 334.01 -92.71) (xy 346.583 -92.71) (xy 347.091 -92.202) (xy 347.091 -87.884) (xy 345.821 -86.614)
			)
		)
	)
	(zone
		(net "GND")
		(layer "B.Cu")
		(hatch none 0.5)
		(connect_pads
			(clearance 0.5)
		)
		(min_thickness 0.25)
		(fill yes
			(thermal_gap 0.5)
			(thermal_bridge_width 0.5)
			(island_removal_mode 0)
		)
		(polygon
			(pts
				(xy 306.451 -51.181) (xy 306.324 -51.308) (xy 306.324 -51.562) (xy 306.578 -51.816) (xy 307.213 -51.816)
				(xy 308.356 -52.959) (xy 314.579 -52.959) (xy 315.595 -51.943) (xy 315.595 -51.435) (xy 315.341 -51.181)
			)
		)
		(polygon
			(pts
				(xy 308.5338 -51.943) (xy 308.2798 -51.943) (xy 308.2798 -52.197) (xy 308.5338 -52.197)
			)
		)
		(polygon
			(pts
				(xy 310.4388 -51.562) (xy 310.1848 -51.562) (xy 310.1848 -51.816) (xy 310.4388 -51.816)
			)
		)
		(polygon
			(pts
				(xy 309.8292 -51.562) (xy 309.2958 -51.562) (xy 309.2958 -51.816) (xy 309.8292 -51.816)
			)
		)
		(polygon
			(pts
				(xy 308.9402 -51.562) (xy 308.6862 -51.562) (xy 308.6862 -51.816) (xy 308.9402 -51.816)
			)
		)
	)
	(zone
		(net "GND")
		(layer "B.Cu")
		(hatch none 0.5)
		(connect_pads
			(clearance 0.5)
		)
		(min_thickness 0.25)
		(fill yes
			(thermal_gap 0.5)
			(thermal_bridge_width 0.5)
			(island_removal_mode 0)
		)
		(polygon
			(pts
				(xy 178.308 -83.439) (xy 177.927 -83.82) (xy 177.927 -113.157) (xy 176.657 -114.427) (xy 168.402 -114.427)
				(xy 167.894 -114.935) (xy 167.894 -116.967) (xy 168.402 -117.475) (xy 172.847 -117.475) (xy 173.609 -118.237)
				(xy 173.609 -119.888) (xy 168.529 -124.968) (xy 164.973 -124.968) (xy 164.719 -125.222) (xy 164.719 -127.508)
				(xy 171.831 -134.62) (xy 190.754 -134.62) (xy 192.405 -132.969) (xy 192.405 -124.206) (xy 192.151 -123.952)
				(xy 185.293 -123.952) (xy 183.769 -122.428) (xy 183.769 -83.693) (xy 183.515 -83.439)
			)
		)
	)
	(zone
		(layer "B.Cu")
		(hatch none 0.5)
		(connect_pads
			(clearance 0)
		)
		(min_thickness 0.25)
		(keepout
			(tracks not_allowed)
			(vias allowed)
			(pads allowed)
			(copperpour not_allowed)
			(footprints allowed)
		)
		(placement
			(enabled no)
			(sheetname "")
		)
		(fill
			(thermal_gap 0.5)
			(thermal_bridge_width 0.5)
			(island_removal_mode 0)
		)
		(polygon
			(pts
				(arc
					(start 85.37194 -32.885126)
					(mid 84.988527 -32.501332)
					(end 84.60486 -32.884872)
				)
				(arc
					(start 84.60486 -33.043622)
					(mid 84.663537 -33.024701)
					(end 84.72043 -33.00095)
				)
				(arc
					(start 84.72043 -33.00095)
					(mid 85.224722 -32.712989)
					(end 84.796376 -33.10509)
				)
				(arc
					(start 84.796376 -33.10509)
					(mid 84.702674 -33.145547)
					(end 84.60486 -33.174686)
				)
				(arc
					(start 84.60486 -33.476438)
					(mid 84.704915 -33.5166)
					(end 84.800694 -33.5661)
				)
				(arc
					(start 84.800694 -33.5661)
					(mid 85.220615 -33.967031)
					(end 84.72297 -33.667954)
				)
				(arc
					(start 84.72297 -33.667954)
					(mid 84.664832 -33.637957)
					(end 84.60486 -33.61182)
				)
				(arc
					(start 84.60486 -33.789874)
					(mid 84.9884 -34.173414)
					(end 85.37194 -33.789874)
				)
			)
		)
	)
	(zone
		(layer "B.Cu")
		(hatch none 0.5)
		(connect_pads
			(clearance 0)
		)
		(min_thickness 0.25)
		(keepout
			(tracks not_allowed)
			(vias allowed)
			(pads allowed)
			(copperpour not_allowed)
			(footprints allowed)
		)
		(placement
			(enabled no)
			(sheetname "")
		)
		(fill
			(thermal_gap 0.5)
			(thermal_bridge_width 0.5)
			(island_removal_mode 0)
		)
		(polygon
			(pts
				(arc
					(start 11.106404 -98.782632)
					(mid 11.122596 -98.202233)
					(end 11.233404 -98.772218)
				)
				(xy 11.233404 -98.87712) (xy 11.997182 -98.878644)
				(arc
					(start 11.997182 -98.780092)
					(mid 12.060682 -98.203127)
					(end 12.124182 -98.780092)
				)
				(arc
					(start 12.124182 -98.87331)
					(mid 12.442887 -98.463624)
					(end 12.061444 -98.111564)
				)
				(arc
					(start 11.147044 -98.109786)
					(mid 10.763027 -98.472981)
					(end 11.106404 -98.874834)
				)
			)
		)
	)
	(zone
		(net "P3V3_STBY")
		(layer "B.Cu")
		(hatch none 0.5)
		(connect_pads
			(clearance 0.5)
		)
		(min_thickness 0.25)
		(fill yes
			(thermal_gap 0.5)
			(thermal_bridge_width 0.5)
			(island_removal_mode 0)
		)
		(polygon
			(pts
				(xy 272.542 -174.117) (xy 272.288 -174.371) (xy 272.288 -187.071) (xy 272.669 -187.452) (xy 274.193 -187.452)
				(xy 274.32 -187.325) (xy 274.32 -186.69) (xy 274.066 -186.436) (xy 274.066 -174.371) (xy 273.812 -174.117)
			)
		)
		(polygon
			(pts
				(xy 273.8628 -186.6646) (xy 273.6088 -186.6646) (xy 273.6088 -186.9186) (xy 273.8628 -186.9186)
			)
		)
		(polygon
			(pts
				(xy 273.6088 -184.9374) (xy 273.3548 -184.9374) (xy 273.3548 -185.1914) (xy 273.6088 -185.1914)
			)
		)
		(polygon
			(pts
				(xy 273.6088 -184.3786) (xy 273.3548 -184.3786) (xy 273.3548 -184.6326) (xy 273.6088 -184.6326)
			)
		)
		(polygon
			(pts
				(xy 273.6088 -183.9214) (xy 273.3548 -183.9214) (xy 273.3548 -184.1754) (xy 273.6088 -184.1754)
			)
		)
		(polygon
			(pts
				(xy 273.6088 -183.3626) (xy 273.3548 -183.3626) (xy 273.3548 -183.6166) (xy 273.6088 -183.6166)
			)
		)
		(polygon
			(pts
				(xy 273.6088 -182.9054) (xy 273.3548 -182.9054) (xy 273.3548 -183.1594) (xy 273.6088 -183.1594)
			)
		)
		(polygon
			(pts
				(xy 273.6088 -182.3466) (xy 273.3548 -182.3466) (xy 273.3548 -182.6006) (xy 273.6088 -182.6006)
			)
		)
		(polygon
			(pts
				(xy 273.6088 -181.8894) (xy 273.3548 -181.8894) (xy 273.3548 -182.1434) (xy 273.6088 -182.1434)
			)
		)
		(polygon
			(pts
				(xy 273.6088 -181.3306) (xy 273.3548 -181.3306) (xy 273.3548 -181.5846) (xy 273.6088 -181.5846)
			)
		)
		(polygon
			(pts
				(xy 273.6088 -180.8734) (xy 273.3548 -180.8734) (xy 273.3548 -181.1274) (xy 273.6088 -181.1274)
			)
		)
		(polygon
			(pts
				(xy 273.6088 -180.3146) (xy 273.3548 -180.3146) (xy 273.3548 -180.5686) (xy 273.6088 -180.5686)
			)
		)
		(polygon
			(pts
				(xy 273.6088 -179.8574) (xy 273.3548 -179.8574) (xy 273.3548 -180.1114) (xy 273.6088 -180.1114)
			)
		)
		(polygon
			(pts
				(xy 273.6088 -179.2986) (xy 273.3548 -179.2986) (xy 273.3548 -179.5526) (xy 273.6088 -179.5526)
			)
		)
		(polygon
			(pts
				(xy 273.6088 -178.8414) (xy 273.3548 -178.8414) (xy 273.3548 -179.0954) (xy 273.6088 -179.0954)
			)
		)
		(polygon
			(pts
				(xy 273.6088 -178.2826) (xy 273.3548 -178.2826) (xy 273.3548 -178.5366) (xy 273.6088 -178.5366)
			)
		)
		(polygon
			(pts
				(xy 273.6088 -177.8254) (xy 273.3548 -177.8254) (xy 273.3548 -178.0794) (xy 273.6088 -178.0794)
			)
		)
		(polygon
			(pts
				(xy 273.6088 -177.2666) (xy 273.3548 -177.2666) (xy 273.3548 -177.5206) (xy 273.6088 -177.5206)
			)
		)
		(polygon
			(pts
				(xy 273.6088 -176.8094) (xy 273.3548 -176.8094) (xy 273.3548 -177.0634) (xy 273.6088 -177.0634)
			)
		)
		(polygon
			(pts
				(xy 273.6088 -176.2506) (xy 273.3548 -176.2506) (xy 273.3548 -176.5046) (xy 273.6088 -176.5046)
			)
		)
		(polygon
			(pts
				(xy 273.6088 -175.7934) (xy 273.3548 -175.7934) (xy 273.3548 -176.0474) (xy 273.6088 -176.0474)
			)
		)
		(polygon
			(pts
				(xy 273.6088 -175.2346) (xy 273.3548 -175.2346) (xy 273.3548 -175.4886) (xy 273.6088 -175.4886)
			)
		)
		(polygon
			(pts
				(xy 273.6088 -174.7774) (xy 273.3548 -174.7774) (xy 273.3548 -175.0314) (xy 273.6088 -175.0314)
			)
		)
	)
	(zone
		(net "GND")
		(layer "B.Cu")
		(hatch none 0.5)
		(connect_pads
			(clearance 0.5)
		)
		(min_thickness 0.25)
		(fill yes
			(thermal_gap 0.5)
			(thermal_bridge_width 0.5)
			(island_removal_mode 0)
		)
		(polygon
			(pts
				(xy 307.720746 -0.762254) (xy 307.34 -1.143) (xy 307.34 -42.291) (xy 307.721 -42.672) (xy 312.928 -42.672)
				(xy 313.817 -41.783) (xy 313.817 -4.953) (xy 314.96 -3.81) (xy 345.059 -3.81) (xy 346.202 -4.953)
				(xy 346.202 -12.319) (xy 349.25 -15.367) (xy 349.25 -30.734) (xy 354.076 -35.56) (xy 354.076 -38.989)
				(xy 353.568 -39.497) (xy 353.568 -173.99) (xy 341.503 -186.055) (xy 341.503 -239.903) (xy 340.614 -240.792)
				(xy 301.879 -240.792) (xy 297.688 -244.983) (xy 293.878 -244.983) (xy 280.67 -231.775) (xy 280.67 -215.519)
				(xy 279.527 -214.376) (xy 264.287 -214.376) (xy 258.191 -220.472) (xy 258.191 -224.79) (xy 263.017 -229.616)
				(xy 263.017 -231.902) (xy 261.874 -233.045) (xy 258.064 -233.045) (xy 255.016 -229.997) (xy 255.016 -228.854)
				(xy 255.778 -228.092) (xy 257.302 -228.092) (xy 257.937 -227.457) (xy 257.937 -225.806) (xy 257.302 -225.171)
				(xy 257.302 -217.805) (xy 261.112 -213.995) (xy 261.112 -194.564) (xy 260.35 -193.802) (xy 221.869 -193.802)
				(xy 219.456 -196.215) (xy 219.456 -199.644) (xy 218.44 -200.66) (xy 215.265 -200.66) (xy 213.995 -199.39)
				(xy 213.995 -188.341) (xy 212.344 -186.69) (xy 198.12 -186.69) (xy 195.707 -189.103) (xy 195.707 -209.296)
				(xy 196.215 -209.804) (xy 217.551 -209.804) (xy 220.345 -212.598) (xy 220.345 -225.552) (xy 215.265 -230.632)
				(xy 204.343 -230.632) (xy 201.295 -233.68) (xy 201.295 -249.555) (xy 201.803 -250.063) (xy 229.108 -250.063)
				(xy 233.299 -245.872) (xy 233.299 -196.215) (xy 234.315 -195.199) (xy 250.952 -195.199) (xy 251.968 -196.215)
				(xy 251.968 -245.999) (xy 256.159 -250.19) (xy 350.647 -250.19) (xy 354.838 -245.999) (xy 354.838 -1.397254)
				(xy 354.203 -0.762254)
			)
		)
	)
	(zone
		(layer "B.Cu")
		(hatch none 0.5)
		(connect_pads
			(clearance 0)
		)
		(min_thickness 0.25)
		(keepout
			(tracks allowed)
			(vias allowed)
			(pads allowed)
			(copperpour allowed)
			(footprints not_allowed)
		)
		(placement
			(enabled no)
			(sheetname "")
		)
		(fill
			(thermal_gap 0.5)
			(thermal_bridge_width 0.5)
			(island_removal_mode 0)
		)
		(polygon
			(pts
				(arc
					(start 22.599904 -85.79993)
					(mid 25.100026 -83.299808)
					(end 27.599894 -85.79993)
				)
				(arc
					(start 27.599894 -85.79993)
					(mid 25.100026 -88.299798)
					(end 22.599904 -85.79993)
				)
			)
		)
	)
	(zone
		(layer "B.Cu")
		(hatch none 0.5)
		(connect_pads
			(clearance 0)
		)
		(min_thickness 0.25)
		(keepout
			(tracks allowed)
			(vias allowed)
			(pads allowed)
			(copperpour allowed)
			(footprints not_allowed)
		)
		(placement
			(enabled no)
			(sheetname "")
		)
		(fill
			(thermal_gap 0.5)
			(thermal_bridge_width 0.5)
			(island_removal_mode 0)
		)
		(polygon
			(pts
				(arc
					(start 72.600058 -23.400004)
					(mid 68.600066 -27.399996)
					(end 64.600074 -23.400004)
				)
				(arc
					(start 64.600074 -23.400004)
					(mid 68.600066 -19.400012)
					(end 72.600058 -23.400004)
				)
			)
		)
	)
	(zone
		(net "XTAL_VDDA18")
		(layer "B.Cu")
		(hatch none 0.5)
		(connect_pads
			(clearance 0.5)
		)
		(min_thickness 0.25)
		(fill yes
			(thermal_gap 0.5)
			(thermal_bridge_width 0.5)
			(island_removal_mode 0)
		)
		(polygon
			(pts
				(xy 119.26697 -76.073) (xy 119.01297 -76.327) (xy 119.01297 -77.9018) (xy 119.16537 -78.0542) (xy 119.16537 -78.8924)
				(xy 118.93677 -79.121) (xy 117.74297 -79.121) (xy 117.61597 -79.248) (xy 117.61597 -80.518) (xy 117.85727 -80.7593)
				(xy 118.51767 -80.7593) (xy 118.55577 -80.7974) (xy 119.54637 -80.7974) (xy 120.40997 -81.661) (xy 120.40997 -84.074)
				(xy 121.17197 -84.074) (xy 121.42597 -83.82) (xy 121.42597 -81.4578) (xy 120.91797 -80.9498) (xy 120.91797 -79.0956)
				(xy 121.42597 -78.5876) (xy 121.42597 -76.327) (xy 121.17197 -76.073)
			)
		)
		(polygon
			(pts
				(xy 121.163842 -83.383882) (xy 120.960642 -83.383882) (xy 120.960642 -83.587082) (xy 121.163842 -83.587082)
			)
		)
		(polygon
			(pts
				(xy 121.163842 -82.774282) (xy 120.960642 -82.774282) (xy 120.960642 -83.231482) (xy 121.163842 -83.231482)
			)
		)
		(polygon
			(pts
				(xy 121.163842 -82.418682) (xy 120.960642 -82.418682) (xy 120.960642 -82.621882) (xy 121.163842 -82.621882)
			)
		)
	)
	(zone
		(layer "B.Cu")
		(hatch none 0.5)
		(connect_pads
			(clearance 0)
		)
		(min_thickness 0.25)
		(keepout
			(tracks allowed)
			(vias allowed)
			(pads allowed)
			(copperpour allowed)
			(footprints not_allowed)
		)
		(placement
			(enabled no)
			(sheetname "")
		)
		(fill
			(thermal_gap 0.5)
			(thermal_bridge_width 0.5)
			(island_removal_mode 0)
		)
		(polygon
			(pts
				(arc
					(start 316.099952 -39.500048)
					(mid 311.700164 -43.899836)
					(end 307.300122 -39.500048)
				)
				(arc
					(start 307.300122 -39.500048)
					(mid 311.700164 -35.100006)
					(end 316.099952 -39.500048)
				)
			)
		)
	)
	(zone
		(net "GND")
		(layer "B.Cu")
		(hatch none 0.5)
		(connect_pads
			(clearance 0.5)
		)
		(min_thickness 0.25)
		(fill yes
			(thermal_gap 0.5)
			(thermal_bridge_width 0.5)
			(island_removal_mode 0)
		)
		(polygon
			(pts
				(xy 95.866966 -47.752) (xy 95.485966 -48.133) (xy 95.485966 -51.689) (xy 94.850966 -52.324) (xy 94.850966 -54.102)
				(xy 94.342966 -54.61) (xy 94.342966 -55.245) (xy 86.976966 -55.245) (xy 84.563966 -52.832) (xy 84.182966 -52.832)
				(xy 83.801966 -53.213) (xy 83.801966 -54.229) (xy 86.341966 -56.769) (xy 93.326966 -56.769) (xy 94.342966 -57.785)
				(xy 99.295966 -57.785) (xy 99.549966 -57.531) (xy 99.549966 -55.245) (xy 99.6188 -55.176166) (xy 99.6188 -55.1434)
				(xy 99.695 -55.0672) (xy 100.6348 -55.0672) (xy 100.965 -54.737) (xy 100.965 -53.8226) (xy 101.2952 -53.4924)
				(xy 101.8032 -53.4924) (xy 102.0572 -53.7464) (xy 102.0572 -54.0258) (xy 102.108 -54.0766) (xy 102.489 -54.0766)
				(xy 103.124 -53.4416) (xy 103.886 -53.4416) (xy 104.3178 -53.8734) (xy 104.3178 -54.7624) (xy 104.4956 -54.9402)
				(xy 104.9274 -54.9402) (xy 105.1052 -54.7624) (xy 105.1052 -53.6448) (xy 105.2576 -53.4924) (xy 105.8418 -53.4924)
				(xy 106.0196 -53.6702) (xy 106.0196 -54.4576) (xy 106.4006 -54.8386) (xy 106.934 -54.8386) (xy 107.0356 -54.737)
				(xy 107.0356 -54.1782) (xy 106.7562 -53.8988) (xy 106.7562 -53.5432) (xy 106.8578 -53.4416) (xy 107.2134 -53.4416)
				(xy 107.8484 -54.0766) (xy 108.1278 -54.0766) (xy 108.2802 -53.9242) (xy 108.2802 -51.9938) (xy 108.585 -51.689)
				(xy 108.966 -51.689) (xy 109.093 -51.562) (xy 109.093 -50.419) (xy 108.966 -50.292) (xy 107.696 -50.292)
				(xy 107.0356 -50.9524) (xy 105.2068 -50.9524) (xy 104.6988 -50.4444) (xy 103.0986 -50.4444) (xy 102.6922 -50.8508)
				(xy 101.2698 -50.8508) (xy 100.7618 -50.3428) (xy 99.8728 -50.3428) (xy 99.695 -50.5206) (xy 99.695 -53.3146)
				(xy 99.441 -53.5686) (xy 98.2726 -53.5686) (xy 98.1202 -53.4162) (xy 98.1202 -51.7906) (xy 98.2218 -51.689)
				(xy 98.2472 -51.689) (xy 98.552 -51.3842) (xy 98.552 -49.7586) (xy 98.4504 -49.657) (xy 97.975166 -49.657)
				(xy 97.771966 -49.4538) (xy 97.771966 -48.895) (xy 97.644966 -48.768) (xy 97.390966 -48.768) (xy 97.009966 -49.149)
				(xy 96.374966 -49.149) (xy 96.247966 -49.022) (xy 96.247966 -48.006) (xy 95.993966 -47.752)
			)
		)
		(polygon
			(pts
				(xy 98.330766 -56.896) (xy 98.076766 -56.896) (xy 98.076766 -57.15) (xy 98.330766 -57.15)
			)
		)
		(polygon
			(pts
				(xy 97.721166 -56.896) (xy 97.467166 -56.896) (xy 97.467166 -57.15) (xy 97.721166 -57.15)
			)
		)
		(polygon
			(pts
				(xy 91.091766 -55.88) (xy 90.837766 -55.88) (xy 90.837766 -56.134) (xy 91.091766 -56.134)
			)
		)
		(polygon
			(pts
				(xy 90.482166 -55.88) (xy 90.228166 -55.88) (xy 90.228166 -56.134) (xy 90.482166 -56.134)
			)
		)
		(polygon
			(pts
				(xy 93.250766 -55.8165) (xy 92.996766 -55.8165) (xy 92.996766 -56.0705) (xy 93.250766 -56.0705)
			)
		)
		(polygon
			(pts
				(xy 92.641166 -55.8165) (xy 92.387166 -55.8165) (xy 92.387166 -56.0705) (xy 92.641166 -56.0705)
			)
		)
		(polygon
			(pts
				(xy 87.789766 -55.8165) (xy 87.535766 -55.8165) (xy 87.535766 -56.0705) (xy 87.789766 -56.0705)
			)
		)
		(polygon
			(pts
				(xy 87.180166 -55.8165) (xy 86.926166 -55.8165) (xy 86.926166 -56.0705) (xy 87.180166 -56.0705)
			)
		)
		(polygon
			(pts
				(xy 95.247206 -54.89448) (xy 94.993206 -54.89448) (xy 94.993206 -55.14848) (xy 95.247206 -55.14848)
			)
		)
		(polygon
			(pts
				(xy 99.153726 -54.8894) (xy 98.899726 -54.8894) (xy 98.899726 -55.1434) (xy 99.153726 -55.1434)
			)
		)
		(polygon
			(pts
				(xy 97.203006 -54.88686) (xy 96.949006 -54.88686) (xy 96.949006 -55.14086) (xy 97.203006 -55.14086)
			)
		)
		(polygon
			(pts
				(xy 95.247206 -54.28488) (xy 94.993206 -54.28488) (xy 94.993206 -54.53888) (xy 95.247206 -54.53888)
			)
		)
		(polygon
			(pts
				(xy 99.153726 -54.2798) (xy 98.899726 -54.2798) (xy 98.899726 -54.5338) (xy 99.153726 -54.5338)
			)
		)
		(polygon
			(pts
				(xy 97.203006 -54.27726) (xy 96.949006 -54.27726) (xy 96.949006 -54.53126) (xy 97.203006 -54.53126)
			)
		)
		(polygon
			(pts
				(xy 100.344986 -54.22392) (xy 100.090986 -54.22392) (xy 100.090986 -54.47792) (xy 100.344986 -54.47792)
			)
		)
		(polygon
			(pts
				(xy 106.486706 -54.0893) (xy 106.232706 -54.0893) (xy 106.232706 -54.3433) (xy 106.486706 -54.3433)
			)
		)
		(polygon
			(pts
				(xy 107.754166 -52.2986) (xy 107.500166 -52.2986) (xy 107.500166 -52.5526) (xy 107.484926 -52.57038)
				(xy 107.484926 -52.82438) (xy 107.738926 -52.82438) (xy 107.738926 -52.57038) (xy 107.754166 -52.5526)
			)
		)
		(polygon
			(pts
				(xy 107.754166 -51.689) (xy 107.500166 -51.689) (xy 107.500166 -51.943) (xy 107.754166 -51.943)
			)
		)
		(polygon
			(pts
				(xy 96.171766 -51.689) (xy 95.917766 -51.689) (xy 95.917766 -51.943) (xy 96.171766 -51.943)
			)
		)
		(polygon
			(pts
				(xy 98.044 -51.1302) (xy 97.79 -51.1302) (xy 97.79 -51.3842) (xy 98.044 -51.3842)
			)
		)
		(polygon
			(pts
				(xy 103.254556 -50.9397) (xy 103.000556 -50.9397) (xy 103.000556 -51.1937) (xy 103.254556 -51.1937)
			)
		)
		(polygon
			(pts
				(xy 104.756966 -50.927) (xy 104.502966 -50.927) (xy 104.502966 -51.181) (xy 104.756966 -51.181)
			)
		)
		(polygon
			(pts
				(xy 104.147366 -50.927) (xy 103.893366 -50.927) (xy 103.864156 -50.9397) (xy 103.610156 -50.9397)
				(xy 103.610156 -51.1937) (xy 103.864156 -51.1937) (xy 103.893366 -51.181) (xy 104.147366 -51.181)
			)
		)
		(polygon
			(pts
				(xy 100.515166 -50.9016) (xy 100.261166 -50.9016) (xy 100.261166 -51.1556) (xy 100.515166 -51.1556)
			)
		)
		(polygon
			(pts
				(xy 98.044 -50.2666) (xy 97.79 -50.2666) (xy 97.79 -50.7746) (xy 98.044 -50.7746)
			)
		)
	)
	(zone
		(net "P0V955_C")
		(layer "B.Cu")
		(hatch none 0.5)
		(connect_pads
			(clearance 0.5)
		)
		(min_thickness 0.25)
		(fill yes
			(thermal_gap 0.5)
			(thermal_bridge_width 0.5)
			(island_removal_mode 0)
		)
		(polygon
			(pts
				(xy 74.93 -25.527) (xy 74.549 -25.908) (xy 74.549 -28.956) (xy 74.803 -29.21) (xy 77.978 -29.21)
				(xy 78.232 -28.956) (xy 78.232 -25.908) (xy 77.851 -25.527)
			)
		)
	)
	(zone
		(layer "B.Cu")
		(hatch none 0.5)
		(connect_pads
			(clearance 0)
		)
		(min_thickness 0.25)
		(keepout
			(tracks allowed)
			(vias allowed)
			(pads allowed)
			(copperpour allowed)
			(footprints not_allowed)
		)
		(placement
			(enabled no)
			(sheetname "")
		)
		(fill
			(thermal_gap 0.5)
			(thermal_bridge_width 0.5)
			(island_removal_mode 0)
		)
		(polygon
			(pts
				(arc
					(start 307.300122 -39.500048)
					(mid 311.700164 -35.100006)
					(end 316.099952 -39.500048)
				)
				(arc
					(start 316.099952 -39.500048)
					(mid 311.700164 -43.899836)
					(end 307.300122 -39.500048)
				)
			)
		)
	)
	(zone
		(layer "B.Cu")
		(hatch none 0.5)
		(connect_pads
			(clearance 0)
		)
		(min_thickness 0.25)
		(keepout
			(tracks allowed)
			(vias allowed)
			(pads allowed)
			(copperpour allowed)
			(footprints not_allowed)
		)
		(placement
			(enabled no)
			(sheetname "")
		)
		(fill
			(thermal_gap 0.5)
			(thermal_bridge_width 0.5)
			(island_removal_mode 0)
		)
		(polygon
			(pts
				(arc
					(start 93.849952 -24.500078)
					(mid 90.350086 -27.999944)
					(end 86.849966 -24.500078)
				)
				(arc
					(start 86.849966 -24.500078)
					(mid 90.350086 -20.999958)
					(end 93.849952 -24.500078)
				)
			)
		)
	)
	(zone
		(net "GND")
		(layer "B.Cu")
		(hatch none 0.5)
		(connect_pads
			(clearance 0.5)
		)
		(min_thickness 0.25)
		(fill yes
			(thermal_gap 0.5)
			(thermal_bridge_width 0.5)
			(island_removal_mode 0)
		)
		(polygon
			(pts
				(xy 103.740966 -36.957) (xy 103.613966 -37.084) (xy 103.613966 -38.862) (xy 103.359966 -39.116)
				(xy 98.152966 -39.116) (xy 98.025966 -39.243) (xy 98.025966 -40.2844) (xy 97.7646 -40.545766) (xy 97.7646 -41.3004)
				(xy 97.8408 -41.3766) (xy 98.3234 -41.3766) (xy 98.5012 -41.1988) (xy 98.5012 -40.767) (xy 98.7552 -40.513)
				(xy 100.819966 -40.513) (xy 101.073966 -40.259) (xy 107.5182 -40.259) (xy 107.696 -40.4368) (xy 107.696 -41.1734)
				(xy 107.823 -41.3004) (xy 108.2294 -41.3004) (xy 108.5088 -41.021) (xy 108.5088 -39.1414) (xy 108.3564 -38.989)
				(xy 107.569 -38.989) (xy 107.442 -39.116) (xy 106.280966 -39.116) (xy 105.391966 -38.227) (xy 105.391966 -37.973)
				(xy 104.375966 -36.957)
			)
		)
		(polygon
			(pts
				(xy 104.426766 -39.497) (xy 104.172766 -39.497) (xy 104.172766 -39.751) (xy 104.426766 -39.751)
			)
		)
		(polygon
			(pts
				(xy 103.817166 -39.497) (xy 103.563166 -39.497) (xy 103.563166 -39.751) (xy 103.817166 -39.751)
			)
		)
		(polygon
			(pts
				(xy 102.775766 -39.497) (xy 102.521766 -39.497) (xy 102.521766 -39.751) (xy 102.775766 -39.751)
			)
		)
		(polygon
			(pts
				(xy 102.166166 -39.497) (xy 101.632766 -39.497) (xy 101.632766 -39.751) (xy 102.166166 -39.751)
			)
		)
		(polygon
			(pts
				(xy 101.277166 -39.497) (xy 101.023166 -39.497) (xy 101.023166 -39.751) (xy 101.277166 -39.751)
			)
		)
		(polygon
			(pts
				(xy 106.175556 -39.4589) (xy 105.667556 -39.4589) (xy 105.667556 -39.7129) (xy 106.175556 -39.7129)
			)
		)
		(polygon
			(pts
				(xy 105.311956 -39.4589) (xy 105.057956 -39.4589) (xy 105.057956 -39.7129) (xy 105.311956 -39.7129)
			)
		)
		(polygon
			(pts
				(xy 107.6706 -39.4462) (xy 107.4166 -39.4462) (xy 107.4166 -39.7002) (xy 107.6706 -39.7002) (xy 107.78236 -39.7764)
				(xy 108.03636 -39.7764) (xy 108.03636 -39.5224) (xy 107.78236 -39.5224)
			)
		)
		(polygon
			(pts
				(xy 107.061 -39.4462) (xy 106.807 -39.4462) (xy 106.785156 -39.4589) (xy 106.531156 -39.4589) (xy 106.531156 -39.7129)
				(xy 106.785156 -39.7129) (xy 106.807 -39.7002) (xy 107.061 -39.7002)
			)
		)
		(polygon
			(pts
				(xy 98.610166 -39.3954) (xy 98.356166 -39.3954) (xy 98.356166 -39.6494) (xy 98.610166 -39.6494)
			)
		)
		(polygon
			(pts
				(xy 104.147366 -38.2016) (xy 103.893366 -38.2016) (xy 103.893366 -38.8112) (xy 104.147366 -38.8112)
			)
		)
	)
	(zone
		(net "P0V955_C")
		(layer "B.Cu")
		(hatch none 0.5)
		(connect_pads
			(clearance 0.5)
		)
		(min_thickness 0.25)
		(fill yes
			(thermal_gap 0.5)
			(thermal_bridge_width 0.5)
			(island_removal_mode 0)
		)
		(polygon
			(pts
				(xy 101.200966 -40.513) (xy 100.819966 -40.894) (xy 98.914966 -40.894) (xy 98.911156 -40.897556)
				(xy 98.777044 -40.897556) (xy 98.6536 -41.021) (xy 98.6536 -41.3766) (xy 98.4758 -41.5544) (xy 97.7392 -41.5544)
				(xy 97.5868 -41.7068) (xy 97.5868 -42.0878) (xy 97.7392 -42.2402) (xy 98.559366 -42.2402) (xy 98.787966 -42.4688)
				(xy 98.787966 -44.958) (xy 97.898966 -45.847) (xy 97.898966 -49.359566) (xy 98.0948 -49.5554) (xy 98.5012 -49.5554)
				(xy 98.6536 -49.7078) (xy 98.6536 -51.435) (xy 98.2472 -51.8414) (xy 98.2472 -53.213) (xy 98.4758 -53.4416)
				(xy 99.4156 -53.4416) (xy 99.5934 -53.2638) (xy 99.5934 -50.673) (xy 99.584256 -50.663856) (xy 99.584256 -50.384456)
				(xy 99.803966 -50.165) (xy 100.819966 -50.165) (xy 101.327966 -50.673) (xy 102.6668 -50.673) (xy 103.0478 -50.292)
				(xy 105.264966 -50.292) (xy 105.645966 -50.673) (xy 107.042966 -50.673) (xy 107.169966 -50.546)
				(xy 107.169966 -49.53) (xy 106.788966 -49.149) (xy 106.788966 -48.768) (xy 107.042966 -48.514) (xy 107.042966 -47.879)
				(xy 106.788966 -47.625) (xy 106.788966 -47.117) (xy 107.042966 -46.863) (xy 107.042966 -46.482)
				(xy 106.661966 -46.101) (xy 106.661966 -45.593) (xy 107.042966 -45.212) (xy 107.042966 -44.704)
				(xy 106.788966 -44.45) (xy 106.788966 -43.815) (xy 107.042966 -43.561) (xy 107.042966 -42.926) (xy 106.788966 -42.672)
				(xy 106.788966 -42.418) (xy 107.042966 -42.164) (xy 107.169966 -42.164) (xy 107.169966 -41.656)
				(xy 107.166156 -41.652444) (xy 107.5944 -41.2242) (xy 107.5944 -40.5892) (xy 107.5182 -40.513)
			)
		)
		(polygon
			(pts
				(xy 103.254556 -49.4157) (xy 103.000556 -49.4157) (xy 103.000556 -49.6697) (xy 103.254556 -49.6697)
			)
		)
		(polygon
			(pts
				(xy 104.756966 -49.403) (xy 104.502966 -49.403) (xy 104.502966 -49.657) (xy 104.756966 -49.657)
			)
		)
		(polygon
			(pts
				(xy 99.905566 -49.3776) (xy 99.651566 -49.3776) (xy 99.314 -49.657) (xy 99.314 -49.911) (xy 99.568 -49.911)
				(xy 99.905566 -49.6316)
			)
		)
		(polygon
			(pts
				(xy 99.695 -48.4378) (xy 99.441 -48.4378) (xy 99.441 -48.6918) (xy 99.695 -48.6918)
			)
		)
		(polygon
			(pts
				(xy 99.695 -47.8282) (xy 99.441 -47.8282) (xy 99.441 -48.0822) (xy 99.695 -48.0822)
			)
		)
		(polygon
			(pts
				(xy 99.676966 -44.3738) (xy 99.422966 -44.3738) (xy 99.422966 -44.6278) (xy 99.676966 -44.6278)
			)
		)
		(polygon
			(pts
				(xy 99.676966 -43.4848) (xy 99.422966 -43.4848) (xy 99.422966 -44.0182) (xy 99.676966 -44.0182)
			)
		)
		(polygon
			(pts
				(xy 102.750366 -41.4782) (xy 102.115366 -41.4782) (xy 102.115366 -41.7322) (xy 102.750366 -41.7322)
			)
		)
		(polygon
			(pts
				(xy 104.426766 -41.021) (xy 104.172766 -41.021) (xy 104.172766 -41.275) (xy 104.426766 -41.275)
			)
		)
		(polygon
			(pts
				(xy 103.817166 -41.021) (xy 103.563166 -41.021) (xy 103.563166 -41.275) (xy 103.817166 -41.275)
			)
		)
		(polygon
			(pts
				(xy 102.775766 -41.021) (xy 102.521766 -41.021) (xy 102.521766 -41.275) (xy 102.775766 -41.275)
			)
		)
		(polygon
			(pts
				(xy 102.166166 -41.021) (xy 101.632766 -41.021) (xy 101.632766 -41.275) (xy 102.166166 -41.275)
			)
		)
		(polygon
			(pts
				(xy 101.277166 -41.021) (xy 101.023166 -41.021) (xy 101.023166 -41.275) (xy 101.277166 -41.275)
			)
		)
		(polygon
			(pts
				(xy 106.175556 -40.9829) (xy 105.667556 -40.9829) (xy 105.667556 -41.2369) (xy 106.175556 -41.2369)
			)
		)
		(polygon
			(pts
				(xy 105.311956 -40.9829) (xy 105.057956 -40.9829) (xy 105.057956 -41.2369) (xy 105.311956 -41.2369)
			)
		)
		(polygon
			(pts
				(xy 107.061 -40.9702) (xy 106.807 -40.9702) (xy 106.785156 -40.9829) (xy 106.531156 -40.9829) (xy 106.531156 -41.2369)
				(xy 106.785156 -41.2369) (xy 106.807 -41.2242) (xy 107.061 -41.2242)
			)
		)
	)
	(zone
		(layer "B.Cu")
		(hatch none 0.5)
		(connect_pads
			(clearance 0)
		)
		(min_thickness 0.25)
		(keepout
			(tracks not_allowed)
			(vias allowed)
			(pads allowed)
			(copperpour not_allowed)
			(footprints allowed)
		)
		(placement
			(enabled no)
			(sheetname "")
		)
		(fill
			(thermal_gap 0.5)
			(thermal_bridge_width 0.5)
			(island_removal_mode 0)
		)
		(polygon
			(pts
				(arc
					(start 76.157328 -36.275772)
					(mid 75.773534 -36.659185)
					(end 76.157074 -37.042852)
				)
				(arc
					(start 77.133958 -37.042852)
					(mid 77.517498 -36.659312)
					(end 77.133958 -36.275772)
				)
				(xy 76.880466 -36.275772)
				(arc
					(start 76.880466 -36.415726)
					(mid 76.885247 -36.451893)
					(end 76.899262 -36.485576)
				)
				(arc
					(start 76.899262 -36.485576)
					(mid 77.40402 -36.771016)
					(end 76.844906 -36.617402)
				)
				(xy 76.812902 -36.585652)
				(arc
					(start 76.812902 -36.583366)
					(mid 76.773783 -36.517593)
					(end 76.75499 -36.443412)
				)
				(xy 76.753466 -36.442142) (xy 76.753466 -36.275772) (xy 76.52385 -36.275772) (xy 76.468986 -36.40836)
				(xy 76.468986 -36.408614) (xy 76.45908 -36.432744)
				(arc
					(start 76.457048 -36.433506)
					(mid 76.444302 -36.45485)
					(end 76.429616 -36.474908)
				)
				(xy 76.429616 -36.47694) (xy 76.411074 -36.495482)
				(arc
					(start 76.403708 -36.502848)
					(mid 75.950344 -36.865642)
					(end 76.314046 -36.412932)
				)
				(arc
					(start 76.321158 -36.405566)
					(mid 76.338652 -36.384343)
					(end 76.351638 -36.3601)
				)
				(xy 76.386436 -36.275772)
			)
		)
	)
	(zone
		(net "P12V_PCIE")
		(layer "B.Cu")
		(hatch none 0.5)
		(connect_pads
			(clearance 0.5)
		)
		(min_thickness 0.25)
		(fill yes
			(thermal_gap 0.5)
			(thermal_bridge_width 0.5)
			(island_removal_mode 0)
		)
		(polygon
			(pts
				(xy 193.421 -242.824) (xy 193.167 -243.078) (xy 193.167 -253.6698) (xy 193.3956 -253.8984) (xy 193.421 -253.873)
				(xy 200.279 -253.873) (xy 200.787 -253.365) (xy 200.787 -248.412) (xy 200.533 -248.158) (xy 197.866 -248.158)
				(xy 197.612 -247.904) (xy 197.612 -246.888) (xy 197.485 -246.761) (xy 197.104 -246.761) (xy 196.596 -246.253)
				(xy 196.596 -243.078) (xy 196.342 -242.824)
			)
		)
		(polygon
			(pts
				(xy 197.1548 -247.2944) (xy 196.9008 -247.2944) (xy 196.9008 -247.5484) (xy 197.1548 -247.5484)
			)
		)
	)
	(zone
		(net "P12V_PCIE")
		(layer "B.Cu")
		(hatch none 0.5)
		(connect_pads
			(clearance 0.5)
		)
		(min_thickness 0.25)
		(fill yes
			(thermal_gap 0.5)
			(thermal_bridge_width 0.5)
			(island_removal_mode 0)
		)
		(polygon
			(pts
				(xy 39.624 -237.871) (xy 38.735 -238.76) (xy 38.735 -244.856) (xy 42.545 -248.666) (xy 67.31 -248.666)
				(xy 67.990212 -249.346212)
				(arc
					(start 67.990212 -251.355352)
					(mid 68.081552 -251.671943)
					(end 68.112386 -252.000004)
				)
				(xy 68.112386 -253.360174) (xy 68.371212 -253.619) (xy 70.657212 -253.619) (xy 70.657212 -251.587)
				(xy 71.374 -250.870212) (xy 71.374 -244.856) (xy 71.12 -244.602) (xy 70.485 -244.602) (xy 70.104 -244.983)
				(xy 67.691 -244.983) (xy 67.183 -244.475) (xy 67.183 -238.506) (xy 66.548 -237.871)
			)
		)
		(polygon
			(pts
				(xy 69.946012 -245.491) (xy 69.692012 -245.491) (xy 69.692012 -245.745) (xy 69.946012 -245.745)
			)
		)
		(polygon
			(pts
				(xy 69.336412 -245.491) (xy 69.082412 -245.491) (xy 69.082412 -245.745) (xy 69.336412 -245.745)
			)
		)
		(polygon
			(pts
				(xy 68.930012 -245.491) (xy 68.676012 -245.491) (xy 68.676012 -245.745) (xy 68.930012 -245.745)
			)
		)
		(polygon
			(pts
				(xy 68.320412 -245.491) (xy 68.066412 -245.491) (xy 68.066412 -245.745) (xy 68.320412 -245.745)
			)
		)
	)
	(zone
		(net "P3V3_STBY")
		(layer "B.Cu")
		(hatch none 0.5)
		(connect_pads
			(clearance 0.5)
		)
		(min_thickness 0.25)
		(fill yes
			(thermal_gap 0.5)
			(thermal_bridge_width 0.5)
			(island_removal_mode 0)
		)
		(polygon
			(pts
				(xy 320.167 -166.497) (xy 320.04 -166.624) (xy 320.04 -168.148) (xy 320.167 -168.275) (xy 321.437 -168.275)
				(xy 321.691 -168.021) (xy 321.691 -166.624) (xy 321.564 -166.497)
			)
		)
		(polygon
			(pts
				(xy 320.7512 -167.4876) (xy 320.4972 -167.4876) (xy 320.4972 -167.7416) (xy 320.7512 -167.7416)
			)
		)
		(polygon
			(pts
				(xy 320.7512 -167.0304) (xy 320.4972 -167.0304) (xy 320.4972 -167.2844) (xy 320.7512 -167.2844)
			)
		)
	)
	(zone
		(net "P1V26_STBY")
		(layer "B.Cu")
		(hatch none 0.5)
		(connect_pads
			(clearance 0.5)
		)
		(min_thickness 0.25)
		(fill yes
			(thermal_gap 0.5)
			(thermal_bridge_width 0.5)
			(island_removal_mode 0)
		)
		(polygon
			(pts
				(xy 124.632212 -218.44) (xy 124.505212 -218.567) (xy 124.505212 -219.075) (xy 124.632212 -219.202)
				(xy 126.365 -219.202) (xy 127 -219.837) (xy 127 -221.107) (xy 126.492 -221.615) (xy 125.648212 -221.615)
				(xy 125.625606 -221.637606) (xy 124.945394 -221.637606) (xy 124.841 -221.742) (xy 124.841 -225.298)
				(xy 125.095 -225.552) (xy 127.762 -225.552) (xy 128.016 -225.298) (xy 128.016 -219.71) (xy 126.746 -218.44)
			)
		)
	)
	(zone
		(net "GB_VDDA")
		(layer "B.Cu")
		(hatch none 0.5)
		(connect_pads
			(clearance 0.5)
		)
		(min_thickness 0.25)
		(fill yes
			(thermal_gap 0.5)
			(thermal_bridge_width 0.5)
			(island_removal_mode 0)
		)
		(polygon
			(pts
				(xy 125.36297 -84.3788) (xy 125.26137 -84.4804) (xy 125.26137 -84.9884) (xy 125.03277 -85.217) (xy 122.56897 -85.217)
				(xy 122.18797 -85.598) (xy 121.04497 -85.598) (xy 121.04497 -86.36) (xy 121.29897 -86.614) (xy 121.29897 -89.535)
				(xy 121.55297 -89.789) (xy 122.31497 -89.789) (xy 122.56897 -89.535) (xy 124.09297 -89.535) (xy 124.60097 -90.043)
				(xy 126.25197 -90.043) (xy 127.01397 -89.281) (xy 127.01397 -84.5566) (xy 126.83617 -84.3788)
			)
		)
		(polygon
			(pts
				(xy 126.45517 -89.4842) (xy 126.25197 -89.4842) (xy 126.25197 -89.6874) (xy 126.45517 -89.6874)
			)
		)
		(polygon
			(pts
				(xy 121.95937 -89.3318) (xy 121.75617 -89.3318) (xy 121.75617 -89.535) (xy 121.95937 -89.535)
			)
		)
		(polygon
			(pts
				(xy 126.45517 -88.8746) (xy 126.25197 -88.8746) (xy 126.25197 -89.0778) (xy 126.45517 -89.0778)
			)
		)
		(polygon
			(pts
				(xy 126.45517 -88.4682) (xy 126.25197 -88.4682) (xy 126.25197 -88.6714) (xy 126.45517 -88.6714)
			)
		)
		(polygon
			(pts
				(xy 126.45517 -87.8586) (xy 126.25197 -87.8586) (xy 126.25197 -88.0618) (xy 126.45517 -88.0618)
			)
		)
		(polygon
			(pts
				(xy 121.88317 -87.5792) (xy 121.67997 -87.5792) (xy 121.67997 -87.7824) (xy 121.88317 -87.7824)
			)
		)
		(polygon
			(pts
				(xy 126.70917 -87.5538) (xy 126.50597 -87.5538) (xy 126.50597 -87.757) (xy 126.70917 -87.757)
			)
		)
		(polygon
			(pts
				(xy 121.88317 -87.2236) (xy 121.67997 -87.2236) (xy 121.67997 -87.4268) (xy 121.88317 -87.4268)
			)
		)
		(polygon
			(pts
				(xy 126.70917 -87.1982) (xy 126.50597 -87.1982) (xy 126.50597 -87.4014) (xy 126.70917 -87.4014)
			)
		)
	)
	(zone
		(layer "B.Cu")
		(hatch none 0.5)
		(connect_pads
			(clearance 0)
		)
		(min_thickness 0.25)
		(keepout
			(tracks allowed)
			(vias allowed)
			(pads allowed)
			(copperpour allowed)
			(footprints not_allowed)
		)
		(placement
			(enabled no)
			(sheetname "")
		)
		(fill
			(thermal_gap 0.5)
			(thermal_bridge_width 0.5)
			(island_removal_mode 0)
		)
		(polygon
			(pts
				(arc
					(start 64.600074 -39.399972)
					(mid 68.600066 -35.39998)
					(end 72.600058 -39.399972)
				)
				(arc
					(start 72.600058 -39.399972)
					(mid 68.600066 -43.399964)
					(end 64.600074 -39.399972)
				)
			)
		)
	)
	(zone
		(layer "B.Cu")
		(hatch none 0.5)
		(connect_pads
			(clearance 0)
		)
		(min_thickness 0.25)
		(keepout
			(tracks not_allowed)
			(vias allowed)
			(pads allowed)
			(copperpour not_allowed)
			(footprints allowed)
		)
		(placement
			(enabled no)
			(sheetname "")
		)
		(fill
			(thermal_gap 0.5)
			(thermal_bridge_width 0.5)
			(island_removal_mode 0)
		)
		(polygon
			(pts
				(arc
					(start 15.932404 -98.78695)
					(mid 15.896096 -98.207314)
					(end 16.059404 -98.764598)
				)
				(xy 16.059404 -98.884232) (xy 16.821404 -98.904806)
				(arc
					(start 16.821404 -98.805238)
					(mid 16.8885 -98.228389)
					(end 16.948404 -98.806)
				)
				(arc
					(start 16.948404 -98.898964)
					(mid 17.269062 -98.494735)
					(end 16.897096 -98.137218)
				)
				(xy 16.897096 -98.134678) (xy 15.95755 -98.109278) (xy 15.957296 -98.109532)
				(arc
					(start 15.957296 -98.111818)
					(mid 15.563657 -98.48266)
					(end 15.932404 -98.87839)
				)
			)
		)
	)
	(zone
		(net "P12V")
		(layer "B.Cu")
		(hatch none 0.5)
		(connect_pads
			(clearance 0.5)
		)
		(min_thickness 0.25)
		(fill yes
			(thermal_gap 0.5)
			(thermal_bridge_width 0.5)
			(island_removal_mode 0)
		)
		(polygon
			(pts
				(xy 316.103 -46.99) (xy 315.595 -47.498) (xy 305.562 -47.498) (xy 305.308 -47.752) (xy 305.308 -50.546)
				(xy 305.562 -50.8) (xy 312.210958 -50.8) (xy 312.251852 -50.758852) (xy 312.293 -50.8) (xy 322.453 -50.8)
				(xy 339.217 -67.564) (xy 348.488 -67.564) (xy 349.885 -66.167) (xy 349.885 -64.262) (xy 348.742 -63.119)
				(xy 340.868 -63.119) (xy 324.739 -46.99)
			)
		)
		(polygon
			(pts
				(xy 310.4388 -50.038) (xy 310.1848 -50.038) (xy 310.1848 -50.292) (xy 310.4388 -50.292)
			)
		)
		(polygon
			(pts
				(xy 309.8292 -50.038) (xy 309.2958 -50.038) (xy 309.2958 -50.292) (xy 309.8292 -50.292)
			)
		)
		(polygon
			(pts
				(xy 308.9402 -50.038) (xy 308.6862 -50.038) (xy 308.6862 -50.292) (xy 308.9402 -50.292)
			)
		)
		(polygon
			(pts
				(xy 308.5338 -49.657) (xy 308.2798 -49.657) (xy 308.2798 -49.911) (xy 308.5338 -49.911)
			)
		)
		(polygon
			(pts
				(xy 307.6702 -49.657) (xy 307.4162 -49.657) (xy 307.4162 -49.911) (xy 307.6702 -49.911)
			)
		)
	)
	(zone
		(layer "B.Cu")
		(hatch none 0.5)
		(connect_pads
			(clearance 0)
		)
		(min_thickness 0.25)
		(keepout
			(tracks allowed)
			(vias allowed)
			(pads allowed)
			(copperpour allowed)
			(footprints not_allowed)
		)
		(placement
			(enabled no)
			(sheetname "")
		)
		(fill
			(thermal_gap 0.5)
			(thermal_bridge_width 0.5)
			(island_removal_mode 0)
		)
		(polygon
			(pts
				(arc
					(start 353.750118 -37.399976)
					(mid 349.750126 -41.399968)
					(end 345.74988 -37.399976)
				)
				(arc
					(start 345.74988 -37.399976)
					(mid 349.750126 -33.39973)
					(end 353.750118 -37.399976)
				)
			)
		)
	)
	(zone
		(layer "B.Cu")
		(hatch none 0.5)
		(connect_pads
			(clearance 0)
		)
		(min_thickness 0.25)
		(keepout
			(tracks allowed)
			(vias allowed)
			(pads allowed)
			(copperpour allowed)
			(footprints not_allowed)
		)
		(placement
			(enabled no)
			(sheetname "")
		)
		(fill
			(thermal_gap 0.5)
			(thermal_bridge_width 0.5)
			(island_removal_mode 0)
		)
		(polygon
			(pts
				(arc
					(start 335.499964 -66.73723)
					(mid 331.499972 -70.737222)
					(end 327.49998 -66.73723)
				)
				(arc
					(start 327.49998 -66.73723)
					(mid 331.499972 -62.737238)
					(end 335.499964 -66.73723)
				)
			)
		)
	)
	(zone
		(layer "B.Cu")
		(hatch none 0.5)
		(connect_pads
			(clearance 0)
		)
		(min_thickness 0.25)
		(keepout
			(tracks allowed)
			(vias allowed)
			(pads allowed)
			(copperpour allowed)
			(footprints allowed)
		)
		(placement
			(enabled no)
			(sheetname "")
		)
		(fill
			(thermal_gap 0.5)
			(thermal_bridge_width 0.5)
			(island_removal_mode 0)
		)
		(polygon
			(pts
				(xy 44.196 -78.74) (xy 44.196 -76.454) (xy 45.974 -76.454) (xy 45.974 -78.74)
			)
		)
	)
	(zone
		(net "P3V3_STBY")
		(layer "B.Cu")
		(hatch none 0.5)
		(connect_pads
			(clearance 0.5)
		)
		(min_thickness 0.25)
		(fill yes
			(thermal_gap 0.5)
			(thermal_bridge_width 0.5)
			(island_removal_mode 0)
		)
		(polygon
			(pts
				(xy 173.355 -190.627) (xy 172.72 -191.262) (xy 172.72 -202.438) (xy 171.704 -203.454) (xy 171.704 -216.281)
				(xy 173.99 -218.567) (xy 173.99 -226.695) (xy 174.625 -227.33) (xy 182.753 -227.33) (xy 184.023 -226.06)
				(xy 184.023 -207.899) (xy 188.595 -203.327) (xy 188.595 -191.389) (xy 187.8965 -190.6905) (xy 183.8325 -190.6905)
				(xy 183.769 -190.627)
			)
		)
	)
	(zone
		(layer "B.Cu")
		(hatch none 0.5)
		(connect_pads
			(clearance 0)
		)
		(min_thickness 0.25)
		(keepout
			(tracks allowed)
			(vias allowed)
			(pads allowed)
			(copperpour allowed)
			(footprints not_allowed)
		)
		(placement
			(enabled no)
			(sheetname "")
		)
		(fill
			(thermal_gap 0.5)
			(thermal_bridge_width 0.5)
			(island_removal_mode 0)
		)
		(polygon
			(pts
				(arc
					(start 87.849964 -103.849932)
					(mid 84.350098 -107.349798)
					(end 80.849978 -103.849932)
				)
				(arc
					(start 80.849978 -103.849932)
					(mid 84.350098 -100.349812)
					(end 87.849964 -103.849932)
				)
			)
		)
	)
	(zone
		(net "GND")
		(layer "B.Cu")
		(hatch none 0.5)
		(connect_pads
			(clearance 0.5)
		)
		(min_thickness 0.25)
		(fill yes
			(thermal_gap 0.5)
			(thermal_bridge_width 0.5)
			(island_removal_mode 0)
		)
		(polygon
			(pts
				(xy 293.30904 -171.91736) (xy 292.93566 -172.29074) (xy 292.4556 -172.29074) (xy 292.11778 -171.95292)
				(xy 290.5379 -171.95292) (xy 289.79622 -172.6946) (xy 289.79622 -172.97146) (xy 289.8775 -173.05274)
				(xy 290.15944 -173.05274) (xy 290.2077 -173.101) (xy 290.2077 -175.91786) (xy 289.95878 -176.16678)
				(xy 289.95878 -178.65598) (xy 290.74364 -179.44084) (xy 295.70426 -179.44084) (xy 296.77106 -178.37404)
				(xy 296.77106 -173.09846) (xy 297.27652 -172.593) (xy 297.27652 -171.99356) (xy 297.20032 -171.91736)
			)
		)
		(polygon
			(pts
				(xy 292.9128 -178.6636) (xy 292.6588 -178.6636) (xy 292.6588 -178.9176) (xy 292.9128 -178.9176)
			)
		)
		(polygon
			(pts
				(xy 292.0492 -178.6636) (xy 291.7952 -178.6636) (xy 291.7952 -178.9176) (xy 292.0492 -178.9176)
			)
		)
		(polygon
			(pts
				(xy 294.386 -178.5112) (xy 294.132 -178.5112) (xy 294.132 -178.7652) (xy 294.386 -178.7652)
			)
		)
		(polygon
			(pts
				(xy 291.338 -178.2318) (xy 291.084 -178.2318) (xy 291.084 -178.4858) (xy 291.338 -178.4858)
			)
		)
		(polygon
			(pts
				(xy 296.155872 -178.049936) (xy 295.901872 -178.049936) (xy 295.901872 -178.303936) (xy 296.155872 -178.303936)
			)
		)
		(polygon
			(pts
				(xy 292.9128 -177.8) (xy 292.6588 -177.8) (xy 292.6588 -178.054) (xy 292.9128 -178.054)
			)
		)
		(polygon
			(pts
				(xy 292.0492 -177.8) (xy 291.7952 -177.8) (xy 291.7952 -178.054) (xy 292.0492 -178.054)
			)
		)
		(polygon
			(pts
				(xy 296.155872 -177.440336) (xy 295.901872 -177.440336) (xy 295.901872 -177.694336) (xy 296.155872 -177.694336)
			)
		)
		(polygon
			(pts
				(xy 291.329872 -177.033936) (xy 291.075872 -177.033936) (xy 291.075872 -177.287936) (xy 291.084 -177.3682)
				(xy 291.084 -177.6222) (xy 291.338 -177.6222) (xy 291.338 -177.3682) (xy 291.329872 -177.287936)
			)
		)
		(polygon
			(pts
				(xy 290.466272 -177.033936) (xy 290.212272 -177.033936) (xy 290.212272 -177.287936) (xy 290.2204 -177.3682)
				(xy 290.2204 -177.6222) (xy 290.4744 -177.6222) (xy 290.4744 -177.3682) (xy 290.466272 -177.287936)
			)
		)
		(polygon
			(pts
				(xy 296.155872 -176.779936) (xy 295.901872 -176.779936) (xy 295.901872 -177.033936) (xy 296.155872 -177.033936)
			)
		)
		(polygon
			(pts
				(xy 296.155872 -176.170336) (xy 295.901872 -176.170336) (xy 295.901872 -176.424336) (xy 296.155872 -176.424336)
			)
		)
		(polygon
			(pts
				(xy 291.329872 -176.170336) (xy 291.075872 -176.170336) (xy 291.075872 -176.424336) (xy 291.329872 -176.424336)
			)
		)
		(polygon
			(pts
				(xy 290.466272 -176.170336) (xy 290.212272 -176.170336) (xy 290.212272 -176.424336) (xy 290.466272 -176.424336)
			)
		)
		(polygon
			(pts
				(xy 296.155872 -175.255936) (xy 295.901872 -175.255936) (xy 295.901872 -175.509936) (xy 296.155872 -175.509936)
			)
		)
		(polygon
			(pts
				(xy 291.075872 -175.001936) (xy 290.821872 -175.001936) (xy 290.821872 -175.255936) (xy 291.075872 -175.255936)
			)
		)
		(polygon
			(pts
				(xy 296.164 -174.2948) (xy 295.91 -174.2948) (xy 295.91 -174.5488) (xy 295.901872 -174.646336) (xy 295.901872 -174.900336)
				(xy 296.155872 -174.900336) (xy 296.155872 -174.646336) (xy 296.164 -174.5488)
			)
		)
		(polygon
			(pts
				(xy 291.3634 -174.117) (xy 291.1094 -174.117) (xy 290.821872 -174.392336) (xy 290.821872 -174.646336)
				(xy 291.075872 -174.646336) (xy 291.3634 -174.371)
			)
		)
		(polygon
			(pts
				(xy 296.164 -173.6852) (xy 295.91 -173.6852) (xy 295.91 -173.9392) (xy 296.164 -173.9392)
			)
		)
		(polygon
			(pts
				(xy 291.202872 -173.173136) (xy 290.948872 -173.173136) (xy 290.948872 -173.427136) (xy 291.1094 -173.7614)
				(xy 291.3634 -173.7614) (xy 291.3634 -173.5074)
			)
		)
		(polygon
			(pts
				(xy 294.3098 -173.101) (xy 294.0558 -173.101) (xy 294.0558 -173.355) (xy 294.3098 -173.355)
			)
		)
		(polygon
			(pts
				(xy 293.7002 -173.101) (xy 293.4462 -173.101) (xy 293.4462 -173.355) (xy 293.7002 -173.355)
			)
		)
		(polygon
			(pts
				(xy 292.345872 -172.766736) (xy 292.091872 -172.766736) (xy 292.091872 -173.020736) (xy 292.345872 -173.020736)
			)
		)
		(polygon
			(pts
				(xy 291.736272 -172.766736) (xy 291.482272 -172.766736) (xy 291.482272 -173.020736) (xy 291.736272 -173.020736)
			)
		)
		(polygon
			(pts
				(xy 296.1894 -172.72) (xy 295.9354 -172.72) (xy 295.9354 -172.974) (xy 296.1894 -172.974)
			)
		)
		(polygon
			(pts
				(xy 296.6466 -172.6946) (xy 296.3926 -172.6946) (xy 296.3926 -172.9486) (xy 296.6466 -172.9486)
			)
		)
		(polygon
			(pts
				(xy 296.6466 -172.1358) (xy 296.3926 -172.1358) (xy 296.3926 -172.3898) (xy 296.6466 -172.3898)
			)
		)
		(polygon
			(pts
				(xy 296.1894 -172.1104) (xy 295.9354 -172.1104) (xy 295.9354 -172.3644) (xy 296.1894 -172.3644)
			)
		)
	)
	(zone
		(layer "B.Cu")
		(hatch none 0.5)
		(connect_pads
			(clearance 0)
		)
		(min_thickness 0.25)
		(keepout
			(tracks not_allowed)
			(vias allowed)
			(pads allowed)
			(copperpour not_allowed)
			(footprints allowed)
		)
		(placement
			(enabled no)
			(sheetname "")
		)
		(fill
			(thermal_gap 0.5)
			(thermal_bridge_width 0.5)
			(island_removal_mode 0)
		)
		(polygon
			(pts
				(arc
					(start 123.563888 -80.964024)
					(mid 124.114911 -80.795795)
					(end 123.64847 -81.13395)
				)
				(xy 123.64847 -81.303622) (xy 123.831858 -81.308956)
				(arc
					(start 123.85294 -81.309464)
					(mid 123.88685 -81.30803)
					(end 123.920504 -81.303622)
				)
				(arc
					(start 123.920504 -81.303622)
					(mid 124.235595 -80.892519)
					(end 123.853956 -80.542384)
				)
				(xy 123.833128 -80.542892)
				(arc
					(start 122.925332 -80.56626)
					(mid 122.56741 -80.897915)
					(end 122.8725 -81.27873)
				)
				(arc
					(start 122.8725 -81.18602)
					(mid 122.912804 -80.657908)
					(end 122.9995 -81.180432)
				)
				(xy 122.9995 -81.284826) (xy 123.52147 -81.299812) (xy 123.52147 -81.07299)
				(arc
					(start 123.523248 -81.071466)
					(mid 123.536969 -81.01525)
					(end 123.563888 -80.964024)
				)
			)
		)
	)
	(zone
		(layer "B.Cu")
		(hatch none 0.5)
		(connect_pads
			(clearance 0)
		)
		(min_thickness 0.25)
		(keepout
			(tracks allowed)
			(vias allowed)
			(pads allowed)
			(copperpour allowed)
			(footprints not_allowed)
		)
		(placement
			(enabled no)
			(sheetname "")
		)
		(fill
			(thermal_gap 0.5)
			(thermal_bridge_width 0.5)
			(island_removal_mode 0)
		)
		(polygon
			(pts
				(arc
					(start 7.400036 -85.79993)
					(mid 4.900168 -88.299798)
					(end 2.400046 -85.79993)
				)
				(arc
					(start 2.400046 -85.79993)
					(mid 4.900168 -83.299808)
					(end 7.400036 -85.79993)
				)
			)
		)
	)
	(zone
		(net "GND")
		(layer "B.Cu")
		(hatch none 0.5)
		(connect_pads
			(clearance 0.5)
		)
		(min_thickness 0.25)
		(fill yes
			(thermal_gap 0.5)
			(thermal_bridge_width 0.5)
			(island_removal_mode 0)
		)
		(polygon
			(pts
				(xy 122.917966 -38.481) (xy 122.790966 -38.608) (xy 122.790966 -39.37) (xy 123.044966 -39.624) (xy 123.425966 -39.624)
				(xy 123.425966 -46.228) (xy 123.679966 -46.482) (xy 127.108966 -46.482) (xy 127.489966 -46.101)
				(xy 127.489966 -39.497) (xy 127.108966 -39.116) (xy 125.203966 -39.116) (xy 124.568966 -38.481)
			)
		)
		(polygon
			(pts
				(xy 124.187966 -45.6438) (xy 123.933966 -45.6438) (xy 123.933966 -45.8978) (xy 124.187966 -45.8978)
			)
		)
		(polygon
			(pts
				(xy 124.187966 -45.0342) (xy 123.933966 -45.0342) (xy 123.933966 -45.2882) (xy 124.187966 -45.2882)
			)
		)
		(polygon
			(pts
				(xy 124.187966 -43.9928) (xy 123.933966 -43.9928) (xy 123.933966 -44.2468) (xy 124.187966 -44.2468)
			)
		)
		(polygon
			(pts
				(xy 124.187966 -43.3832) (xy 123.933966 -43.3832) (xy 123.933966 -43.6372) (xy 124.187966 -43.6372)
			)
		)
		(polygon
			(pts
				(xy 124.187966 -42.3418) (xy 123.933966 -42.3418) (xy 123.933966 -42.5958) (xy 124.187966 -42.5958)
			)
		)
		(polygon
			(pts
				(xy 124.187966 -41.7322) (xy 123.933966 -41.7322) (xy 123.933966 -41.9862) (xy 124.187966 -41.9862)
			)
		)
		(polygon
			(pts
				(xy 124.187966 -40.4368) (xy 123.933966 -40.4368) (xy 123.933966 -40.6908) (xy 124.187966 -40.6908)
			)
		)
		(polygon
			(pts
				(xy 124.187966 -39.8272) (xy 123.933966 -39.8272) (xy 123.933966 -40.0812) (xy 124.187966 -40.0812)
			)
		)
	)
	(zone
		(layer "B.Cu")
		(hatch none 0.5)
		(connect_pads
			(clearance 0)
		)
		(min_thickness 0.25)
		(keepout
			(tracks allowed)
			(vias allowed)
			(pads allowed)
			(copperpour allowed)
			(footprints allowed)
		)
		(placement
			(enabled no)
			(sheetname "")
		)
		(fill
			(thermal_gap 0.5)
			(thermal_bridge_width 0.5)
			(island_removal_mode 0)
		)
		(polygon
			(pts
				(xy 170.18 -74.803) (xy 170.18 -73.787) (xy 171.196 -73.787) (xy 171.196 -74.803)
			)
		)
	)
	(zone
		(net "P1V8_C")
		(layer "B.Cu")
		(hatch none 0.5)
		(connect_pads
			(clearance 0.5)
		)
		(min_thickness 0.25)
		(fill yes
			(thermal_gap 0.5)
			(thermal_bridge_width 0.5)
			(island_removal_mode 0)
		)
		(polygon
			(pts
				(xy 129.902966 -33.655) (xy 129.775966 -33.782) (xy 129.775966 -36.83) (xy 131.245356 -38.29939)
				(xy 131.245356 -39.551356) (xy 133.985 -42.291) (xy 137.922 -42.291) (xy 145.161 -49.53) (xy 149.86 -49.53)
				(xy 153.162 -52.832) (xy 153.162 -56.134) (xy 152.908 -56.388) (xy 152.908 -58.166) (xy 153.289 -58.547)
				(xy 155.448 -58.547) (xy 155.702 -58.293) (xy 155.702 -49.53) (xy 151.384 -45.212) (xy 147.701 -45.212)
				(xy 140.97 -38.481) (xy 134.474966 -38.481) (xy 132.823966 -36.83) (xy 132.823966 -33.782) (xy 132.696966 -33.655)
			)
		)
		(polygon
			(pts
				(xy 132.442966 -35.9918) (xy 132.188966 -35.9918) (xy 132.188966 -36.2458) (xy 132.442966 -36.2458)
			)
		)
		(polygon
			(pts
				(xy 132.442966 -35.3822) (xy 132.188966 -35.3822) (xy 132.188966 -35.6362) (xy 132.442966 -35.6362)
			)
		)
		(polygon
			(pts
				(xy 130.360166 -34.4424) (xy 130.106166 -34.4424) (xy 130.106166 -34.6964) (xy 130.360166 -34.6964)
			)
		)
		(polygon
			(pts
				(xy 130.360166 -33.8836) (xy 130.106166 -33.8836) (xy 130.106166 -34.1376) (xy 130.360166 -34.1376)
			)
		)
	)
	(zone
		(layer "B.Cu")
		(hatch none 0.5)
		(connect_pads
			(clearance 0)
		)
		(min_thickness 0.25)
		(keepout
			(tracks allowed)
			(vias allowed)
			(pads allowed)
			(copperpour allowed)
			(footprints not_allowed)
		)
		(placement
			(enabled no)
			(sheetname "")
		)
		(fill
			(thermal_gap 0.5)
			(thermal_bridge_width 0.5)
			(island_removal_mode 0)
		)
		(polygon
			(pts
				(arc
					(start 72.600058 -39.399972)
					(mid 68.600066 -43.399964)
					(end 64.600074 -39.399972)
				)
				(arc
					(start 64.600074 -39.399972)
					(mid 68.600066 -35.39998)
					(end 72.600058 -39.399972)
				)
			)
		)
	)
	(zone
		(net "PLL_VDD")
		(layer "B.Cu")
		(hatch none 0.5)
		(connect_pads
			(clearance 0.5)
		)
		(min_thickness 0.25)
		(fill yes
			(thermal_gap 0.5)
			(thermal_bridge_width 0.5)
			(island_removal_mode 0)
		)
		(polygon
			(pts
				(xy 122.409966 -33.655) (xy 121.901966 -34.163) (xy 121.901966 -36.195) (xy 122.282966 -36.576)
				(xy 129.267966 -36.576) (xy 129.394966 -36.449) (xy 129.394966 -33.782) (xy 129.267966 -33.655)
			)
		)
		(polygon
			(pts
				(xy 128.937766 -34.4424) (xy 128.683766 -34.4424) (xy 128.683766 -34.6964) (xy 128.937766 -34.6964)
			)
		)
		(polygon
			(pts
				(xy 128.937766 -33.8836) (xy 128.683766 -33.8836) (xy 128.683766 -34.1376) (xy 128.937766 -34.1376)
			)
		)
		(polygon
			(pts
				(xy 123.476766 -33.8836) (xy 122.867166 -33.8836) (xy 122.867166 -34.1376) (xy 123.476766 -34.1376)
			)
		)
		(polygon
			(pts
				(xy 122.7328 -33.8836) (xy 122.4788 -33.8836) (xy 122.4788 -34.1376) (xy 122.7328 -34.1376)
			)
		)
	)
	(zone
		(net "P1V8_C")
		(layer "B.Cu")
		(hatch none 0.5)
		(connect_pads
			(clearance 0.5)
		)
		(min_thickness 0.25)
		(fill yes
			(thermal_gap 0.5)
			(thermal_bridge_width 0.5)
			(island_removal_mode 0)
		)
		(polygon
			(pts
				(xy 77.197966 -62.865) (xy 76.689966 -63.373) (xy 76.689966 -67.818) (xy 76.708 -67.818) (xy 76.708 -72.771)
				(xy 77.724 -73.787) (xy 79.502 -73.787) (xy 80.137 -73.152) (xy 81.026 -73.152) (xy 81.28 -72.898)
				(xy 81.28 -69.469) (xy 82.423 -68.326) (xy 92.329 -68.326) (xy 96.266 -72.263) (xy 103.759 -72.263)
				(xy 108.331 -67.691) (xy 110.49 -67.691) (xy 110.617 -67.564) (xy 110.617 -66.675) (xy 109.855 -65.913)
				(xy 107.061 -65.913) (xy 104.267 -63.119) (xy 81.007966 -63.119) (xy 80.753966 -62.865)
			)
		)
		(polygon
			(pts
				(xy 79.6544 -73.0758) (xy 79.4004 -73.0758) (xy 79.4004 -73.3298) (xy 79.6544 -73.3298)
			)
		)
		(polygon
			(pts
				(xy 79.0956 -73.0758) (xy 78.8416 -73.0758) (xy 78.8416 -73.3298) (xy 79.0956 -73.3298)
			)
		)
		(polygon
			(pts
				(xy 78.6638 -72.771) (xy 78.4098 -72.771) (xy 78.4098 -73.025) (xy 78.6638 -73.025)
			)
		)
		(polygon
			(pts
				(xy 77.8002 -72.771) (xy 77.5462 -72.771) (xy 77.5462 -73.025) (xy 77.8002 -73.025)
			)
		)
		(polygon
			(pts
				(xy 80.277462 -63.284608) (xy 80.023462 -63.284608) (xy 80.023462 -63.538608) (xy 80.277462 -63.538608)
			)
		)
		(polygon
			(pts
				(xy 79.718662 -63.284608) (xy 79.464662 -63.284608) (xy 79.464662 -63.538608) (xy 79.718662 -63.538608)
			)
		)
	)
	(zone
		(layer "B.Cu")
		(hatch none 0.5)
		(connect_pads
			(clearance 0)
		)
		(min_thickness 0.25)
		(keepout
			(tracks allowed)
			(vias allowed)
			(pads allowed)
			(copperpour allowed)
			(footprints not_allowed)
		)
		(placement
			(enabled no)
			(sheetname "")
		)
		(fill
			(thermal_gap 0.5)
			(thermal_bridge_width 0.5)
			(island_removal_mode 0)
		)
		(polygon
			(pts
				(arc
					(start 345.74988 -54.99989)
					(mid 349.750126 -50.999644)
					(end 353.750118 -54.99989)
				)
				(arc
					(start 353.750118 -54.99989)
					(mid 349.750126 -58.999882)
					(end 345.74988 -54.99989)
				)
			)
		)
	)
	(zone
		(layer "B.Cu")
		(hatch none 0.5)
		(connect_pads
			(clearance 0)
		)
		(min_thickness 0.25)
		(keepout
			(tracks allowed)
			(vias allowed)
			(pads allowed)
			(copperpour allowed)
			(footprints not_allowed)
		)
		(placement
			(enabled no)
			(sheetname "")
		)
		(fill
			(thermal_gap 0.5)
			(thermal_bridge_width 0.5)
			(island_removal_mode 0)
		)
		(polygon
			(pts
				(xy 355.6 -109.000036)
				(arc
					(start 355.6 -246.000016)
					(mid 354.47299 -249.162282)
					(end 351.600008 -250.898914)
				)
				(xy 351.600008 -109.000036)
			)
		)
	)
	(zone
		(net "GND")
		(layer "B.Cu")
		(hatch none 0.5)
		(connect_pads
			(clearance 0.5)
		)
		(min_thickness 0.25)
		(fill yes
			(thermal_gap 0.5)
			(thermal_bridge_width 0.5)
			(island_removal_mode 0)
		)
		(polygon
			(pts
				(xy 150.495 -177.8) (xy 149.352 -178.943) (xy 149.352 -248.158) (xy 151.384 -250.19) (xy 182.118 -250.19)
				(xy 183.007 -251.079) (xy 183.007 -253.238) (xy 183.515 -253.746) (xy 188.087 -253.746) (xy 188.468 -253.365)
				(xy 188.468 -249.428) (xy 185.42 -246.38) (xy 185.42 -229.489) (xy 183.642 -227.711) (xy 172.847 -227.711)
				(xy 171.704 -228.854) (xy 171.704 -246.38) (xy 171.323 -246.761) (xy 169.164 -246.761) (xy 168.783 -246.38)
				(xy 168.783 -180.34) (xy 166.243 -177.8)
			)
		)
	)
	(zone
		(layer "B.Cu")
		(hatch none 0.5)
		(connect_pads
			(clearance 0)
		)
		(min_thickness 0.25)
		(keepout
			(tracks not_allowed)
			(vias allowed)
			(pads allowed)
			(copperpour not_allowed)
			(footprints allowed)
		)
		(placement
			(enabled no)
			(sheetname "")
		)
		(fill
			(thermal_gap 0.5)
			(thermal_bridge_width 0.5)
			(island_removal_mode 0)
		)
		(polygon
			(pts
				(arc
					(start 195.947792 -76.64196)
					(mid 195.563998 -77.025373)
					(end 195.947538 -77.40904)
				)
				(arc
					(start 196.176138 -77.40904)
					(mid 196.159872 -77.364237)
					(end 196.131434 -77.325982)
				)
				(arc
					(start 196.087492 -77.28204)
					(mid 195.740394 -76.819509)
					(end 196.204078 -77.1652)
				)
				(xy 196.272404 -77.233272)
				(arc
					(start 196.272404 -77.23632)
					(mid 196.319517 -77.316171)
					(end 196.342508 -77.405992)
				)
				(xy 196.34454 -77.40777) (xy 196.34454 -77.40904) (xy 196.52234 -77.40904) (xy 196.52234 -77.40777)
				(arc
					(start 196.524626 -77.405738)
					(mid 196.545599 -77.32562)
					(end 196.587364 -77.2541)
				)
				(xy 196.587364 -77.250798) (xy 196.611494 -77.226668)
				(arc
					(start 196.672962 -77.1652)
					(mid 197.136056 -76.818946)
					(end 196.789802 -77.28204)
				)
				(arc
					(start 196.728334 -77.343508)
					(mid 196.705406 -77.37374)
					(end 196.691504 -77.40904)
				)
				(arc
					(start 196.929502 -77.40904)
					(mid 197.313042 -77.0255)
					(end 196.929502 -76.64196)
				)
			)
		)
	)
	(zone
		(net "VDDA_SAS_REF_CLK")
		(layer "B.Cu")
		(hatch none 0.5)
		(connect_pads
			(clearance 0.5)
		)
		(min_thickness 0.25)
		(fill yes
			(thermal_gap 0.5)
			(thermal_bridge_width 0.5)
			(island_removal_mode 0)
		)
		(polygon
			(pts
				(xy 79.737966 -55.372) (xy 79.356966 -55.753) (xy 79.356966 -60.833) (xy 79.102966 -61.087) (xy 77.451966 -61.087)
				(xy 77.324966 -61.214) (xy 77.324966 -62.357) (xy 77.451966 -62.484) (xy 80.753966 -62.484) (xy 81.007966 -62.23)
				(xy 81.007966 -55.499) (xy 80.880966 -55.372)
			)
		)
		(polygon
			(pts
				(xy 80.252062 -61.887608) (xy 80.048862 -61.887608) (xy 80.048862 -62.090808) (xy 80.252062 -62.090808)
			)
		)
		(polygon
			(pts
				(xy 79.693262 -61.887608) (xy 79.490062 -61.887608) (xy 79.490062 -62.090808) (xy 79.693262 -62.090808)
			)
		)
		(polygon
			(pts
				(xy 79.814166 -56.5912) (xy 79.610966 -56.5912) (xy 79.610966 -56.7944) (xy 79.814166 -56.7944)
			)
		)
		(polygon
			(pts
				(xy 79.814166 -56.2356) (xy 79.610966 -56.2356) (xy 79.610966 -56.4388) (xy 79.814166 -56.4388)
			)
		)
		(polygon
			(pts
				(xy 79.814166 -55.8292) (xy 79.610966 -55.8292) (xy 79.610966 -56.0324) (xy 79.814166 -56.0324)
			)
		)
	)
	(zone
		(net "P3V3_STBY")
		(layer "B.Cu")
		(hatch none 0.5)
		(connect_pads
			(clearance 0.5)
		)
		(min_thickness 0.25)
		(fill yes
			(thermal_gap 0.5)
			(thermal_bridge_width 0.5)
			(island_removal_mode 0)
		)
		(polygon
			(pts
				(xy 98.044 -238.379) (xy 97.79 -238.633) (xy 97.79 -240.538) (xy 98.044 -240.792) (xy 99.314 -240.792)
				(xy 99.441 -240.665) (xy 99.441 -239.522) (xy 99.695 -239.268) (xy 106.045 -239.268) (xy 106.172 -239.141)
				(xy 106.172 -238.506) (xy 106.045 -238.379)
			)
		)
		(polygon
			(pts
				(xy 105.7656 -238.5568) (xy 105.5116 -238.5568) (xy 105.5116 -238.8108) (xy 105.7656 -238.8108)
			)
		)
		(polygon
			(pts
				(xy 105.3084 -238.5568) (xy 105.0544 -238.5568) (xy 105.0544 -238.8108) (xy 105.3084 -238.8108)
			)
		)
		(polygon
			(pts
				(xy 104.7496 -238.5568) (xy 104.4956 -238.5568) (xy 104.4956 -238.8108) (xy 104.7496 -238.8108)
			)
		)
		(polygon
			(pts
				(xy 104.2924 -238.5568) (xy 104.0384 -238.5568) (xy 104.0384 -238.8108) (xy 104.2924 -238.8108)
			)
		)
		(polygon
			(pts
				(xy 103.7336 -238.5568) (xy 103.4796 -238.5568) (xy 103.4796 -238.8108) (xy 103.7336 -238.8108)
			)
		)
		(polygon
			(pts
				(xy 103.2764 -238.5568) (xy 103.0224 -238.5568) (xy 103.0224 -238.8108) (xy 103.2764 -238.8108)
			)
		)
		(polygon
			(pts
				(xy 102.7176 -238.5568) (xy 102.4636 -238.5568) (xy 102.4636 -238.8108) (xy 102.7176 -238.8108)
			)
		)
		(polygon
			(pts
				(xy 102.2604 -238.5568) (xy 102.0064 -238.5568) (xy 102.0064 -238.8108) (xy 102.2604 -238.8108)
			)
		)
		(polygon
			(pts
				(xy 101.7016 -238.5568) (xy 101.4476 -238.5568) (xy 101.4476 -238.8108) (xy 101.7016 -238.8108)
			)
		)
		(polygon
			(pts
				(xy 101.2444 -238.5568) (xy 100.9904 -238.5568) (xy 100.9904 -238.8108) (xy 101.2444 -238.8108)
			)
		)
		(polygon
			(pts
				(xy 100.6856 -238.5568) (xy 100.4316 -238.5568) (xy 100.4316 -238.8108) (xy 100.6856 -238.8108)
			)
		)
		(polygon
			(pts
				(xy 100.2284 -238.5568) (xy 99.9744 -238.5568) (xy 99.9744 -238.8108) (xy 100.2284 -238.8108)
			)
		)
		(polygon
			(pts
				(xy 99.6696 -238.5568) (xy 99.4156 -238.5568) (xy 99.4156 -238.8108) (xy 99.6696 -238.8108)
			)
		)
	)
	(zone
		(layer "B.Cu")
		(hatch none 0.5)
		(connect_pads
			(clearance 0)
		)
		(min_thickness 0.25)
		(keepout
			(tracks allowed)
			(vias allowed)
			(pads allowed)
			(copperpour allowed)
			(footprints not_allowed)
		)
		(placement
			(enabled no)
			(sheetname "")
		)
		(fill
			(thermal_gap 0.5)
			(thermal_bridge_width 0.5)
			(island_removal_mode 0)
		)
		(polygon
			(pts
				(arc
					(start 2.400046 -100.7999)
					(mid 4.900168 -98.299778)
					(end 7.400036 -100.7999)
				)
				(arc
					(start 7.400036 -100.7999)
					(mid 4.900168 -103.299768)
					(end 2.400046 -100.7999)
				)
			)
		)
	)
	(zone
		(layer "B.Cu")
		(hatch none 0.5)
		(connect_pads
			(clearance 0)
		)
		(min_thickness 0.25)
		(keepout
			(tracks allowed)
			(vias allowed)
			(pads allowed)
			(copperpour allowed)
			(footprints not_allowed)
		)
		(placement
			(enabled no)
			(sheetname "")
		)
		(fill
			(thermal_gap 0.5)
			(thermal_bridge_width 0.5)
			(island_removal_mode 0)
		)
		(polygon
			(pts
				(arc
					(start 128.800098 -64.799972)
					(mid 124.800106 -68.799964)
					(end 120.800114 -64.799972)
				)
				(arc
					(start 120.800114 -64.799972)
					(mid 124.800106 -60.79998)
					(end 128.800098 -64.799972)
				)
			)
		)
	)
	(zone
		(layer "B.Cu")
		(hatch none 0.5)
		(connect_pads
			(clearance 0)
		)
		(min_thickness 0.25)
		(keepout
			(tracks not_allowed)
			(vias allowed)
			(pads allowed)
			(copperpour not_allowed)
			(footprints allowed)
		)
		(placement
			(enabled no)
			(sheetname "")
		)
		(fill
			(thermal_gap 0.5)
			(thermal_bridge_width 0.5)
			(island_removal_mode 0)
		)
		(polygon
			(pts
				(arc
					(start 129.159 -80.89646)
					(mid 128.77546 -81.28)
					(end 129.159 -81.66354)
				)
				(xy 129.35077 -81.66354) (xy 129.35077 -81.561686)
				(arc
					(start 129.315718 -81.526634)
					(mid 128.952374 -81.073374)
					(end 129.405634 -81.436718)
				)
				(xy 129.440686 -81.47177) (xy 129.47777 -81.508854) (xy 129.47777 -81.561686) (xy 129.47777 -81.66354)
				(xy 129.69367 -81.66354) (xy 129.69367 -81.597246) (xy 129.69367 -81.544414) (xy 129.730754 -81.50733)
				(arc
					(start 129.801366 -81.436718)
					(mid 130.254626 -81.073374)
					(end 129.891282 -81.526634)
				)
				(xy 129.82067 -81.597246) (xy 129.82067 -81.66354)
				(arc
					(start 130.047746 -81.66354)
					(mid 130.43154 -81.280127)
					(end 130.048 -80.89646)
				)
			)
		)
	)
	(zone
		(layer "B.Cu")
		(hatch none 0.5)
		(connect_pads
			(clearance 0)
		)
		(min_thickness 0.25)
		(keepout
			(tracks allowed)
			(vias allowed)
			(pads allowed)
			(copperpour allowed)
			(footprints not_allowed)
		)
		(placement
			(enabled no)
			(sheetname "")
		)
		(fill
			(thermal_gap 0.5)
			(thermal_bridge_width 0.5)
			(island_removal_mode 0)
		)
		(polygon
			(pts
				(arc
					(start 4.99999 -251.000006)
					(mid 4.497443 -250.974661)
					(end 3.999992 -250.898914)
				)
				(xy 3.999992 -109.000036) (xy 0 -109.000036)
				(arc
					(start 0 -69.60997)
					(mid 0.878678 -67.488654)
					(end 2.999994 -66.609976)
				)
				(arc
					(start 60.950094 -66.609976)
					(mid 61.657199 -66.317083)
					(end 61.950092 -65.609978)
				)
				(arc
					(start 61.950092 -17.999964)
					(mid 62.242985 -17.292859)
					(end 62.95009 -16.999966)
				)
				(arc
					(start 73.449942 -16.999966)
					(mid 74.157047 -16.707073)
					(end 74.44994 -15.999968)
				)
				(arc
					(start 74.44994 -0.999998)
					(mid 74.742833 -0.292893)
					(end 75.449938 0)
				)
				(arc
					(start 281.485086 0)
					(mid 282.192191 -0.292893)
					(end 282.485084 -0.999998)
				)
				(arc
					(start 282.485084 -53.50002)
					(mid 282.777977 -54.207125)
					(end 283.485082 -54.500018)
				)
				(arc
					(start 303.485042 -54.500018)
					(mid 304.192147 -54.207125)
					(end 304.48504 -53.50002)
				)
				(arc
					(start 304.48504 -45.500036)
					(mid 304.777933 -44.792931)
					(end 305.485038 -44.500038)
				)
				(arc
					(start 305.485038 -44.500038)
					(mid 306.192143 -44.207145)
					(end 306.485036 -43.50004)
				)
				(arc
					(start 306.485036 -0.999998)
					(mid 306.777929 -0.292893)
					(end 307.485034 0)
				)
				(arc
					(start 354.600002 0)
					(mid 355.307107 -0.292893)
					(end 355.6 -0.999998)
				)
				(xy 355.6 -109.000036) (xy 351.600008 -109.000036)
				(arc
					(start 351.600008 -250.898914)
					(mid 351.102555 -250.974641)
					(end 350.60001 -251.000006)
				)
				(arc
					(start 256.15011 -251.000006)
					(mid 252.614583 -249.535543)
					(end 251.15012 -246.000016)
				)
				(arc
					(start 251.15012 -197.000114)
					(mid 250.857227 -196.293009)
					(end 250.150122 -196.000116)
				)
				(arc
					(start 235.149898 -196.000116)
					(mid 234.442793 -196.293009)
					(end 234.1499 -197.000114)
				)
				(arc
					(start 234.1499 -246.000016)
					(mid 232.685437 -249.535543)
					(end 229.14991 -251.000006)
				)
			)
		)
	)
	(zone
		(net "P3V3_STBY")
		(layer "B.Cu")
		(hatch none 0.5)
		(connect_pads
			(clearance 0.5)
		)
		(min_thickness 0.25)
		(fill yes
			(thermal_gap 0.5)
			(thermal_bridge_width 0.5)
			(island_removal_mode 0)
		)
		(polygon
			(pts
				(xy 351.409 -71.755) (xy 351.155 -72.009) (xy 351.155 -74.422) (xy 350.901 -74.676) (xy 349.377 -74.676)
				(xy 348.996 -74.295) (xy 348.996 -72.136) (xy 348.742 -71.882) (xy 347.98 -71.882) (xy 345.821 -74.041)
				(xy 343.535 -74.041) (xy 343.281 -73.787) (xy 343.281 -72.009) (xy 343.154 -71.882) (xy 335.788 -71.882)
				(xy 331.724 -75.946) (xy 331.724 -81.788) (xy 331.978 -82.042) (xy 338.709 -82.042) (xy 339.344 -81.407)
				(xy 352.171 -81.407) (xy 352.425 -81.153) (xy 352.425 -72.009) (xy 352.171 -71.755)
			)
		)
		(polygon
			(pts
				(xy 352.0694 -80.6958) (xy 351.8154 -80.6958) (xy 351.8154 -80.9498) (xy 352.0694 -80.9498)
			)
		)
		(polygon
			(pts
				(xy 351.5106 -80.6958) (xy 351.2566 -80.6958) (xy 351.2566 -80.9498) (xy 351.5106 -80.9498)
			)
		)
		(polygon
			(pts
				(xy 350.8248 -80.645) (xy 350.5708 -80.645) (xy 350.5708 -80.899) (xy 350.8248 -80.899)
			)
		)
		(polygon
			(pts
				(xy 350.2152 -80.645) (xy 349.9612 -80.645) (xy 349.9612 -80.899) (xy 350.2152 -80.899)
			)
		)
		(polygon
			(pts
				(xy 352.0186 -72.39) (xy 351.7646 -72.39) (xy 351.7646 -72.644) (xy 352.0186 -72.644)
			)
		)
		(polygon
			(pts
				(xy 348.4118 -72.39) (xy 348.1578 -72.39) (xy 348.1578 -72.644) (xy 348.4118 -72.644)
			)
		)
	)
	(zone
		(layer "B.Cu")
		(hatch none 0.5)
		(connect_pads
			(clearance 0)
		)
		(min_thickness 0.25)
		(keepout
			(tracks not_allowed)
			(vias allowed)
			(pads allowed)
			(copperpour not_allowed)
			(footprints allowed)
		)
		(placement
			(enabled no)
			(sheetname "")
		)
		(fill
			(thermal_gap 0.5)
			(thermal_bridge_width 0.5)
			(island_removal_mode 0)
		)
		(polygon
			(pts
				(arc
					(start 199.946768 -76.64196)
					(mid 199.563228 -77.0255)
					(end 199.946768 -77.40904)
				)
				(arc
					(start 200.175368 -77.40904)
					(mid 200.159102 -77.364237)
					(end 200.130664 -77.325982)
				)
				(arc
					(start 200.086722 -77.28204)
					(mid 199.739624 -76.819509)
					(end 200.203308 -77.1652)
				)
				(xy 200.271634 -77.233272)
				(arc
					(start 200.271634 -77.23632)
					(mid 200.318747 -77.316171)
					(end 200.341738 -77.405992)
				)
				(xy 200.34377 -77.40777) (xy 200.34377 -77.40904) (xy 200.52157 -77.40904) (xy 200.52157 -77.40777)
				(arc
					(start 200.523856 -77.405738)
					(mid 200.544829 -77.32562)
					(end 200.586594 -77.2541)
				)
				(xy 200.586594 -77.250798) (xy 200.610724 -77.226668)
				(arc
					(start 200.672192 -77.1652)
					(mid 201.135286 -76.818946)
					(end 200.789032 -77.28204)
				)
				(arc
					(start 200.727564 -77.343508)
					(mid 200.704636 -77.37374)
					(end 200.690734 -77.40904)
				)
				(arc
					(start 200.928478 -77.40904)
					(mid 201.312272 -77.025627)
					(end 200.928732 -76.64196)
				)
			)
		)
	)
	(zone
		(net "GND")
		(layer "B.Cu")
		(hatch none 0.5)
		(connect_pads
			(clearance 0.5)
		)
		(min_thickness 0.25)
		(fill yes
			(thermal_gap 0.5)
			(thermal_bridge_width 0.5)
			(island_removal_mode 0)
		)
		(polygon
			(pts
				(xy 95.739966 -44.704) (xy 95.612966 -44.831) (xy 95.612966 -46.228) (xy 96.247966 -46.863) (xy 97.517966 -46.863)
				(xy 97.644966 -46.736) (xy 97.644966 -45.466) (xy 96.882966 -44.704)
			)
		)
	)
	(zone
		(layer "B.Cu")
		(hatch none 0.5)
		(connect_pads
			(clearance 0)
		)
		(min_thickness 0.25)
		(keepout
			(tracks not_allowed)
			(vias allowed)
			(pads allowed)
			(copperpour not_allowed)
			(footprints allowed)
		)
		(placement
			(enabled no)
			(sheetname "")
		)
		(fill
			(thermal_gap 0.5)
			(thermal_bridge_width 0.5)
			(island_removal_mode 0)
		)
		(polygon
			(pts
				(arc
					(start 81.61274 -36.335462)
					(mid 81.229327 -35.951668)
					(end 80.84566 -36.335208)
				)
				(xy 80.84566 -36.5887)
				(arc
					(start 80.870044 -36.5887)
					(mid 80.884624 -36.5858)
					(end 80.896968 -36.577524)
				)
				(arc
					(start 80.982566 -36.491926)
					(mid 81.435826 -36.128582)
					(end 81.072482 -36.581842)
				)
				(xy 80.968342 -36.685982)
				(arc
					(start 80.964532 -36.685982)
					(mid 80.933232 -36.703096)
					(end 80.899 -36.71316)
				)
				(xy 80.89646 -36.7157) (xy 80.84566 -36.7157) (xy 80.84566 -36.9316) (xy 80.89646 -36.9316)
				(arc
					(start 80.899 -36.93414)
					(mid 80.933257 -36.944144)
					(end 80.964532 -36.961318)
				)
				(xy 80.968342 -36.961318)
				(arc
					(start 81.072482 -37.065458)
					(mid 81.435826 -37.518718)
					(end 80.982566 -37.155374)
				)
				(arc
					(start 80.896968 -37.069776)
					(mid 80.884615 -37.061522)
					(end 80.870044 -37.0586)
				)
				(xy 80.84566 -37.0586)
				(arc
					(start 80.84566 -37.312092)
					(mid 81.2292 -37.695632)
					(end 81.61274 -37.312092)
				)
			)
		)
	)
	(zone
		(net "GND")
		(layer "B.Cu")
		(hatch none 0.5)
		(connect_pads
			(clearance 0.5)
		)
		(min_thickness 0.25)
		(fill yes
			(thermal_gap 0.5)
			(thermal_bridge_width 0.5)
			(island_removal_mode 0)
		)
		(polygon
			(pts
				(xy 323.215 -175.133) (xy 323.088 -175.26) (xy 323.088 -177.546) (xy 323.215 -177.673) (xy 324.485 -177.673)
				(xy 324.612 -177.546) (xy 324.612 -175.26) (xy 324.485 -175.133)
			)
		)
		(polygon
			(pts
				(xy 323.7484 -176.9618) (xy 323.4944 -176.9618) (xy 323.4944 -177.2158) (xy 323.7484 -177.2158)
			)
		)
		(polygon
			(pts
				(xy 324.1802 -176.911) (xy 323.9262 -176.911) (xy 323.9262 -177.165) (xy 324.1802 -177.165)
			)
		)
		(polygon
			(pts
				(xy 324.2056 -175.5902) (xy 323.9516 -175.5902) (xy 323.833744 -175.610012) (xy 323.579744 -175.610012)
				(xy 323.579744 -175.864012) (xy 323.833744 -175.864012) (xy 323.9516 -175.8442) (xy 324.2056 -175.8442)
			)
		)
	)
	(zone
		(layer "B.Cu")
		(hatch none 0.5)
		(connect_pads
			(clearance 0)
		)
		(min_thickness 0.25)
		(keepout
			(tracks not_allowed)
			(vias allowed)
			(pads allowed)
			(copperpour not_allowed)
			(footprints allowed)
		)
		(placement
			(enabled no)
			(sheetname "")
		)
		(fill
			(thermal_gap 0.5)
			(thermal_bridge_width 0.5)
			(island_removal_mode 0)
		)
		(polygon
			(pts
				(arc
					(start 49.147476 -84.667852)
					(mid 49.253126 -84.594191)
					(end 49.373536 -84.548472)
				)
				(arc
					(start 49.373536 -84.3026)
					(mid 49.253113 -84.256905)
					(end 49.147476 -84.18322)
				)
				(arc
					(start 49.147476 -84.18322)
					(mid 48.782214 -83.731763)
					(end 49.237138 -84.092796)
				)
				(arc
					(start 49.237138 -84.092796)
					(mid 49.301463 -84.138455)
					(end 49.373536 -84.17052)
				)
				(arc
					(start 49.373536 -83.937094)
					(mid 48.989996 -83.553554)
					(end 48.606456 -83.937094)
				)
				(arc
					(start 48.606456 -84.913724)
					(mid 48.989869 -85.297518)
					(end 49.373536 -84.913978)
				)
				(arc
					(start 49.373536 -84.680552)
					(mid 49.30146 -84.712611)
					(end 49.237138 -84.758276)
				)
				(arc
					(start 49.237138 -84.758276)
					(mid 48.782171 -85.119353)
					(end 49.147476 -84.667852)
				)
			)
		)
	)
	(zone
		(layer "B.Cu")
		(hatch none 0.5)
		(connect_pads
			(clearance 0)
		)
		(min_thickness 0.25)
		(keepout
			(tracks not_allowed)
			(vias allowed)
			(pads allowed)
			(copperpour not_allowed)
			(footprints allowed)
		)
		(placement
			(enabled no)
			(sheetname "")
		)
		(fill
			(thermal_gap 0.5)
			(thermal_bridge_width 0.5)
			(island_removal_mode 0)
		)
		(polygon
			(pts
				(arc
					(start 127.154178 -79.42326)
					(mid 126.770638 -79.8068)
					(end 127.154178 -80.19034)
				)
				(arc
					(start 127.372872 -80.19034)
					(mid 127.348328 -80.118928)
					(end 127.30861 -80.054704)
				)
				(arc
					(start 127.30861 -80.054704)
					(mid 126.949354 -79.598587)
					(end 127.399542 -79.965296)
				)
				(arc
					(start 127.399542 -79.965296)
					(mid 127.466041 -80.07089)
					(end 127.502158 -80.19034)
				)
				(xy 127.7239 -80.19034) (xy 127.7239 -80.186784)
				(arc
					(start 127.724662 -80.186022)
					(mid 127.761921 -80.026799)
					(end 127.8509 -79.889604)
				)
				(arc
					(start 127.8509 -79.889604)
					(mid 128.383827 -79.660846)
					(end 127.918464 -80.006952)
				)
				(arc
					(start 127.918464 -80.006952)
					(mid 127.871981 -80.093879)
					(end 127.851662 -80.19034)
				)
				(arc
					(start 128.130808 -80.19034)
					(mid 128.514602 -79.806927)
					(end 128.131062 -79.42326)
				)
			)
		)
	)
	(zone
		(net "GND")
		(layer "B.Cu")
		(hatch none 0.5)
		(connect_pads
			(clearance 0.5)
		)
		(min_thickness 0.25)
		(fill yes
			(thermal_gap 0.5)
			(thermal_bridge_width 0.5)
			(island_removal_mode 0)
		)
		(polygon
			(pts
				(xy 75.564746 -0.762254) (xy 75.311 -1.016) (xy 75.311 -16.764) (xy 74.295 -17.78) (xy 63.246 -17.78)
				(xy 62.865 -18.161) (xy 62.865 -57.658) (xy 61.722 -58.801) (xy 29.591 -58.801) (xy 28.321 -60.071)
				(xy 28.321 -77.216) (xy 26.67 -78.867) (xy 2.921 -78.867) (xy 0.889 -80.899) (xy 0.889 -246.38)
				(xy 4.699 -250.19) (xy 27.051 -250.19) (xy 28.194 -251.333) (xy 28.194 -251.714) (xy 28.321 -251.841)
				(xy 28.829 -251.841) (xy 29.083 -251.587) (xy 29.083 -250.952) (xy 25.019 -246.888) (xy 10.795 -246.888)
				(xy 2.413 -238.506) (xy 2.413 -200.914) (xy 8.89 -194.437) (xy 9.525 -194.437) (xy 16.764 -187.198)
				(xy 16.764 -180.086) (xy 17.145 -179.705) (xy 19.05 -179.705) (xy 27.686 -171.069) (xy 29.972 -171.069)
				(xy 32.385 -168.656) (xy 38.735 -168.656) (xy 40.64 -166.751) (xy 40.64 -159.766) (xy 29.845 -148.971)
				(xy 29.845 -148.082) (xy 30.734 -147.193) (xy 39.37 -147.193) (xy 41.656 -144.907) (xy 41.656 -116.6876)
				(xy 38.0238 -113.0554) (xy 12.7508 -113.0554) (xy 5.715 -106.0196) (xy 5.715 -98.425) (xy 6.096 -98.044)
				(xy 37.465 -98.044) (xy 47.371 -88.138) (xy 47.371 -83.439) (xy 46.863 -82.931) (xy 38.608 -82.931)
				(xy 37.211 -81.534) (xy 37.211 -71.755) (xy 38.862 -70.104) (xy 63.5 -70.104) (xy 66.802 -66.802)
				(xy 66.802 -53.848) (xy 73.406 -47.244) (xy 73.406 -22.733) (xy 74.422 -21.717) (xy 77.343 -21.717)
				(xy 77.47 -21.844) (xy 78.486 -21.844) (xy 78.74 -21.59) (xy 78.74 -21.082) (xy 78.105 -20.447)
				(xy 78.105 -18.034) (xy 78.994 -17.145) (xy 81.407 -17.145) (xy 82.296 -16.256) (xy 85.979 -16.256)
				(xy 87.122 -17.399) (xy 94.488 -17.399) (xy 96.012 -15.875) (xy 96.012 -11.176) (xy 95.504 -10.668)
				(xy 83.312 -10.668) (xy 83.058 -10.414) (xy 83.058 -3.937) (xy 83.566 -3.429) (xy 102.489 -3.429)
				(xy 103.124 -4.064) (xy 131.953 -4.064) (xy 144.145 -16.256) (xy 147.701 -16.256) (xy 148.209 -15.748)
				(xy 148.209 -14.605) (xy 149.606 -13.208) (xy 169.799 -13.208) (xy 180.594 -24.003) (xy 180.594 -30.226)
				(xy 180.086 -30.734) (xy 180.086 -34.163) (xy 180.594 -34.671) (xy 183.769 -34.671) (xy 184.531 -33.909)
				(xy 186.69 -33.909) (xy 187.071 -33.528) (xy 189.103 -33.528) (xy 199.644 -44.069) (xy 199.644 -52.197)
				(xy 205.105 -57.658) (xy 208.28 -57.658) (xy 212.09 -53.848) (xy 253.238 -53.848) (xy 257.175 -49.911)
				(xy 257.175 -25.908) (xy 253.619 -22.352) (xy 253.619 -20.574) (xy 254.889 -19.304) (xy 255.778 -19.304)
				(xy 256.032 -19.05) (xy 256.032 -16.764) (xy 253.619 -14.351) (xy 253.619 -11.303) (xy 255.524 -9.398)
				(xy 269.367 -9.398) (xy 270.256 -10.287) (xy 270.256 -12.7) (xy 271.145 -13.589) (xy 271.145 -18.288)
				(xy 272.415 -19.558) (xy 272.415 -32.131) (xy 277.749 -37.465) (xy 277.749 -52.959) (xy 278.638 -53.848)
				(xy 280.797 -53.848) (xy 281.686 -52.959) (xy 281.686 -1.524) (xy 281.051 -0.889) (xy 84.328 -0.889)
				(xy 84.201254 -0.762254)
			)
		)
		(polygon
			(pts
				(xy 16.722344 -176.327562) (xy 16.468344 -176.327562) (xy 16.468344 -176.581562) (xy 16.722344 -176.581562)
			)
		)
		(polygon
			(pts
				(xy 16.722344 -175.438562) (xy 16.468344 -175.438562) (xy 16.468344 -175.971962) (xy 16.722344 -175.971962)
			)
		)
		(polygon
			(pts
				(xy 16.722344 -174.828962) (xy 16.468344 -174.828962) (xy 16.468344 -175.082962) (xy 16.722344 -175.082962)
			)
		)
		(polygon
			(pts
				(xy 25.350216 -170.28668) (xy 25.096216 -170.28668) (xy 25.096216 -170.54068) (xy 25.350216 -170.54068)
			)
		)
		(polygon
			(pts
				(xy 25.350216 -169.67708) (xy 25.096216 -169.67708) (xy 25.096216 -169.93108) (xy 25.350216 -169.93108)
			)
		)
		(polygon
			(pts
				(xy 16.460216 -169.67708) (xy 16.206216 -169.67708) (xy 16.206216 -169.93108) (xy 16.460216 -169.93108)
			)
		)
		(polygon
			(pts
				(xy 180.902864 -34.031936) (xy 180.648864 -34.031936) (xy 180.648864 -34.285936) (xy 180.902864 -34.285936)
			)
		)
		(polygon
			(pts
				(xy 180.902864 -33.142936) (xy 180.648864 -33.142936) (xy 180.648864 -33.676336) (xy 180.902864 -33.676336)
			)
		)
		(polygon
			(pts
				(xy 186.795664 -33.092136) (xy 186.541664 -33.092136) (xy 186.541664 -33.346136) (xy 186.795664 -33.346136)
			)
		)
		(polygon
			(pts
				(xy 186.186064 -33.092136) (xy 185.652664 -33.092136) (xy 185.652664 -33.346136) (xy 186.186064 -33.346136)
			)
		)
		(polygon
			(pts
				(xy 185.297064 -33.092136) (xy 185.043064 -33.092136) (xy 185.043064 -33.346136) (xy 185.297064 -33.346136)
			)
		)
		(polygon
			(pts
				(xy 180.902864 -32.253936) (xy 180.648864 -32.253936) (xy 180.648864 -32.787336) (xy 180.902864 -32.787336)
			)
		)
		(polygon
			(pts
				(xy 180.902864 -31.364936) (xy 180.648864 -31.364936) (xy 180.648864 -31.898336) (xy 180.902864 -31.898336)
			)
		)
		(polygon
			(pts
				(xy 180.902864 -30.755336) (xy 180.648864 -30.755336) (xy 180.648864 -31.009336) (xy 180.902864 -31.009336)
			)
		)
		(polygon
			(pts
				(xy 181.545992 -30.0228) (xy 181.291992 -30.0228) (xy 181.291992 -30.2768) (xy 181.545992 -30.2768)
			)
		)
		(polygon
			(pts
				(xy 181.545992 -29.1592) (xy 181.291992 -29.1592) (xy 181.291992 -29.4132) (xy 181.545992 -29.4132)
			)
		)
		(polygon
			(pts
				(xy 187.176664 -28.901136) (xy 186.922664 -28.901136) (xy 186.922664 -29.155136) (xy 187.176664 -29.155136)
			)
		)
		(polygon
			(pts
				(xy 186.567064 -28.901136) (xy 186.033664 -28.901136) (xy 186.033664 -29.155136) (xy 186.567064 -29.155136)
			)
		)
		(polygon
			(pts
				(xy 185.678064 -28.901136) (xy 185.424064 -28.901136) (xy 185.424064 -29.155136) (xy 185.678064 -29.155136)
			)
		)
		(polygon
			(pts
				(xy 255.4732 -18.542) (xy 255.2192 -18.542) (xy 255.2192 -18.796) (xy 255.4732 -18.796)
			)
		)
		(polygon
			(pts
				(xy 255.524 -18.0848) (xy 255.27 -18.0848) (xy 255.27 -18.3388) (xy 255.524 -18.3388)
			)
		)
		(polygon
			(pts
				(xy 255.524 -17.4752) (xy 255.27 -17.4752) (xy 255.27 -17.7292) (xy 255.524 -17.7292)
			)
		)
		(polygon
			(pts
				(xy 255.5748 -17.0434) (xy 255.3208 -17.0434) (xy 255.3208 -17.2974) (xy 255.5748 -17.2974)
			)
		)
		(polygon
			(pts
				(xy 90.1954 -2.5908) (xy 89.9414 -2.5908) (xy 89.9414 -2.8448) (xy 90.1954 -2.8448)
			)
		)
		(polygon
			(pts
				(xy 89.6366 -2.5908) (xy 89.3826 -2.5908) (xy 89.3826 -2.8448) (xy 89.6366 -2.8448)
			)
		)
		(polygon
			(pts
				(xy 92.2528 -2.54) (xy 91.9988 -2.54) (xy 91.9988 -2.794) (xy 92.2528 -2.794)
			)
		)
		(polygon
			(pts
				(xy 91.6432 -2.54) (xy 91.1098 -2.54) (xy 91.1098 -2.794) (xy 91.6432 -2.794)
			)
		)
		(polygon
			(pts
				(xy 90.7542 -2.54) (xy 90.5002 -2.54) (xy 90.5002 -2.794) (xy 90.7542 -2.794)
			)
		)
		(polygon
			(pts
				(xy 89.0778 -2.54) (xy 88.8238 -2.54) (xy 88.8238 -2.794) (xy 89.0778 -2.794)
			)
		)
		(polygon
			(pts
				(xy 88.4682 -2.54) (xy 88.2142 -2.54) (xy 88.2142 -2.794) (xy 88.4682 -2.794)
			)
		)
		(polygon
			(pts
				(xy 97.3328 -2.159) (xy 97.0788 -2.159) (xy 97.0788 -2.413) (xy 97.3328 -2.413)
			)
		)
		(polygon
			(pts
				(xy 96.4692 -2.159) (xy 96.2152 -2.159) (xy 96.2152 -2.413) (xy 96.4692 -2.413)
			)
		)
		(polygon
			(pts
				(xy 96.0628 -2.159) (xy 95.8088 -2.159) (xy 95.8088 -2.413) (xy 96.0628 -2.413)
			)
		)
		(polygon
			(pts
				(xy 95.1992 -2.159) (xy 94.9452 -2.159) (xy 94.9452 -2.413) (xy 95.1992 -2.413)
			)
		)
	)
	(zone
		(net "GND")
		(layer "B.Cu")
		(hatch none 0.5)
		(connect_pads
			(clearance 0.5)
		)
		(min_thickness 0.25)
		(fill yes
			(thermal_gap 0.5)
			(thermal_bridge_width 0.5)
			(island_removal_mode 0)
		)
		(polygon
			(pts
				(xy 124.911612 -210.82) (xy 124.530612 -211.201) (xy 124.530612 -215.646) (xy 124.657612 -215.773)
				(xy 126.435612 -215.773) (xy 126.943612 -215.265) (xy 126.943612 -211.201) (xy 126.562612 -210.82)
			)
		)
		(polygon
			(pts
				(xy 125.241812 -215.1126) (xy 124.987812 -215.1126) (xy 124.987812 -215.3666) (xy 125.241812 -215.3666)
			)
		)
		(polygon
			(pts
				(xy 125.241812 -214.5284) (xy 124.987812 -214.5284) (xy 124.987812 -214.7824) (xy 125.241812 -214.7824)
			)
		)
		(polygon
			(pts
				(xy 125.241812 -213.9696) (xy 124.987812 -213.9696) (xy 124.987812 -214.2236) (xy 125.241812 -214.2236)
			)
		)
		(polygon
			(pts
				(xy 125.241812 -213.5124) (xy 124.987812 -213.5124) (xy 124.987812 -213.7664) (xy 125.241812 -213.7664)
			)
		)
		(polygon
			(pts
				(xy 125.241812 -212.9536) (xy 124.987812 -212.9536) (xy 124.987812 -213.2076) (xy 125.241812 -213.2076)
			)
		)
		(polygon
			(pts
				(xy 125.241812 -212.4964) (xy 124.987812 -212.4964) (xy 124.987812 -212.7504) (xy 125.241812 -212.7504)
			)
		)
		(polygon
			(pts
				(xy 125.241812 -211.9376) (xy 124.987812 -211.9376) (xy 124.987812 -212.1916) (xy 125.241812 -212.1916)
			)
		)
		(polygon
			(pts
				(xy 125.292612 -211.5058) (xy 125.038612 -211.5058) (xy 125.038612 -211.7598) (xy 125.292612 -211.7598)
			)
		)
	)
	(zone
		(net "P1V53_STBY")
		(layer "B.Cu")
		(hatch none 0.5)
		(connect_pads
			(clearance 0.5)
		)
		(min_thickness 0.25)
		(fill yes
			(thermal_gap 0.5)
			(thermal_bridge_width 0.5)
			(island_removal_mode 0)
		)
		(polygon
			(pts
				(xy 294.2082 -179.578) (xy 293.8272 -179.959) (xy 293.8272 -183.2356) (xy 294.1193 -183.5277) (xy 294.1193 -184.6453)
				(xy 295.91 -186.436) (xy 295.91 -193.421) (xy 293.878 -195.453) (xy 293.878 -195.834) (xy 294.132 -196.088)
				(xy 299.085 -196.088) (xy 299.593 -195.58) (xy 299.593 -186.055) (xy 297.434 -183.896) (xy 295.529 -183.896)
				(xy 295.021 -183.388) (xy 295.021 -179.832) (xy 294.767 -179.578)
			)
		)
	)
	(zone
		(layer "B.Cu")
		(hatch none 0.5)
		(connect_pads
			(clearance 0)
		)
		(min_thickness 0.25)
		(keepout
			(tracks not_allowed)
			(vias allowed)
			(pads allowed)
			(copperpour not_allowed)
			(footprints allowed)
		)
		(placement
			(enabled no)
			(sheetname "")
		)
		(fill
			(thermal_gap 0.5)
			(thermal_bridge_width 0.5)
			(island_removal_mode 0)
		)
		(polygon
			(pts
				(arc
					(start 155.946602 -76.64196)
					(mid 155.562808 -77.025373)
					(end 155.946348 -77.40904)
				)
				(arc
					(start 156.174948 -77.40904)
					(mid 156.158682 -77.364237)
					(end 156.130244 -77.325982)
				)
				(arc
					(start 156.086302 -77.28204)
					(mid 155.739204 -76.819509)
					(end 156.202888 -77.1652)
				)
				(xy 156.271214 -77.233272)
				(arc
					(start 156.271214 -77.23632)
					(mid 156.318327 -77.316171)
					(end 156.341318 -77.405992)
				)
				(xy 156.34335 -77.40777) (xy 156.34335 -77.40904) (xy 156.52115 -77.40904) (xy 156.52115 -77.40777)
				(arc
					(start 156.523436 -77.405738)
					(mid 156.544409 -77.32562)
					(end 156.586174 -77.2541)
				)
				(xy 156.586174 -77.250798) (xy 156.610304 -77.226668)
				(arc
					(start 156.671772 -77.1652)
					(mid 157.134866 -76.818946)
					(end 156.788612 -77.28204)
				)
				(arc
					(start 156.727144 -77.343508)
					(mid 156.704216 -77.37374)
					(end 156.690314 -77.40904)
				)
				(arc
					(start 156.928312 -77.40904)
					(mid 157.311852 -77.0255)
					(end 156.928312 -76.64196)
				)
			)
		)
	)
	(zone
		(layer "B.Cu")
		(hatch none 0.5)
		(connect_pads
			(clearance 0)
		)
		(min_thickness 0.25)
		(keepout
			(tracks not_allowed)
			(vias allowed)
			(pads allowed)
			(copperpour not_allowed)
			(footprints allowed)
		)
		(placement
			(enabled no)
			(sheetname "")
		)
		(fill
			(thermal_gap 0.5)
			(thermal_bridge_width 0.5)
			(island_removal_mode 0)
		)
		(polygon
			(pts
				(arc
					(start 203.947522 -76.64196)
					(mid 203.563728 -77.025373)
					(end 203.947268 -77.40904)
				)
				(arc
					(start 204.175868 -77.40904)
					(mid 204.159602 -77.364237)
					(end 204.131164 -77.325982)
				)
				(arc
					(start 204.087222 -77.28204)
					(mid 203.740124 -76.819509)
					(end 204.203808 -77.1652)
				)
				(xy 204.272134 -77.233272)
				(arc
					(start 204.272134 -77.23632)
					(mid 204.319247 -77.316171)
					(end 204.342238 -77.405992)
				)
				(xy 204.34427 -77.40777) (xy 204.34427 -77.40904) (xy 204.52207 -77.40904) (xy 204.52207 -77.40777)
				(arc
					(start 204.524356 -77.405738)
					(mid 204.545329 -77.32562)
					(end 204.587094 -77.2541)
				)
				(xy 204.587094 -77.250798) (xy 204.611224 -77.226668)
				(arc
					(start 204.672692 -77.1652)
					(mid 205.135786 -76.818946)
					(end 204.789532 -77.28204)
				)
				(arc
					(start 204.728064 -77.343508)
					(mid 204.705136 -77.37374)
					(end 204.691234 -77.40904)
				)
				(arc
					(start 204.929232 -77.40904)
					(mid 205.312772 -77.0255)
					(end 204.929232 -76.64196)
				)
			)
		)
	)
	(zone
		(net "GND")
		(layer "B.Cu")
		(hatch none 0.5)
		(connect_pads
			(clearance 0.5)
		)
		(min_thickness 0.25)
		(fill yes
			(thermal_gap 0.5)
			(thermal_bridge_width 0.5)
			(island_removal_mode 0)
		)
		(polygon
			(pts
				(xy 261.112 -17.272) (xy 260.858 -17.526) (xy 260.858 -28.321) (xy 261.366 -28.829) (xy 267.335 -28.829)
				(xy 267.716 -28.448) (xy 267.716 -17.399) (xy 267.589 -17.272)
			)
		)
		(polygon
			(pts
				(xy 266.7762 -17.907) (xy 266.5222 -17.907) (xy 266.5222 -18.161) (xy 266.7762 -18.161)
			)
		)
		(polygon
			(pts
				(xy 266.3698 -17.907) (xy 266.1158 -17.907) (xy 266.1158 -18.161) (xy 266.3698 -18.161)
			)
		)
		(polygon
			(pts
				(xy 265.5062 -17.907) (xy 265.2522 -17.907) (xy 265.2522 -18.161) (xy 265.5062 -18.161)
			)
		)
		(polygon
			(pts
				(xy 265.0998 -17.907) (xy 264.8458 -17.907) (xy 264.8458 -18.161) (xy 265.0998 -18.161)
			)
		)
		(polygon
			(pts
				(xy 264.2362 -17.907) (xy 263.9822 -17.907) (xy 263.9822 -18.161) (xy 264.2362 -18.161)
			)
		)
		(polygon
			(pts
				(xy 263.8298 -17.907) (xy 263.5758 -17.907) (xy 263.5758 -18.161) (xy 263.8298 -18.161)
			)
		)
		(polygon
			(pts
				(xy 262.9662 -17.907) (xy 262.7122 -17.907) (xy 262.7122 -18.161) (xy 262.9662 -18.161)
			)
		)
		(polygon
			(pts
				(xy 262.5598 -17.907) (xy 262.3058 -17.907) (xy 262.3058 -18.161) (xy 262.5598 -18.161)
			)
		)
		(polygon
			(pts
				(xy 261.6962 -17.907) (xy 261.4422 -17.907) (xy 261.4422 -18.161) (xy 261.6962 -18.161)
			)
		)
	)
	(zone
		(net "P3V3_STBY")
		(layer "B.Cu")
		(hatch none 0.5)
		(connect_pads
			(clearance 0.5)
		)
		(min_thickness 0.25)
		(fill yes
			(thermal_gap 0.5)
			(thermal_bridge_width 0.5)
			(island_removal_mode 0)
		)
		(polygon
			(pts
				(xy 198.501 -210.439) (xy 194.31 -214.63) (xy 194.31 -237.617) (xy 194.691 -237.998) (xy 195.707 -237.998)
				(xy 203.581 -230.124) (xy 215.011 -230.124) (xy 219.837 -225.298) (xy 219.837 -212.979) (xy 217.297 -210.439)
			)
		)
	)
	(zone
		(layer "B.Cu")
		(hatch none 0.5)
		(connect_pads
			(clearance 0)
		)
		(min_thickness 0.25)
		(keepout
			(tracks not_allowed)
			(vias allowed)
			(pads allowed)
			(copperpour not_allowed)
			(footprints allowed)
		)
		(placement
			(enabled no)
			(sheetname "")
		)
		(fill
			(thermal_gap 0.5)
			(thermal_bridge_width 0.5)
			(island_removal_mode 0)
		)
		(polygon
			(pts
				(arc
					(start 296.29354 -77.35951)
					(mid 295.91 -76.97597)
					(end 295.52646 -77.35951)
				)
				(arc
					(start 295.52646 -78.276196)
					(mid 295.909873 -78.65999)
					(end 296.29354 -78.27645)
				)
				(arc
					(start 296.29354 -78.08722)
					(mid 296.231903 -78.115588)
					(end 296.173398 -78.149958)
				)
				(arc
					(start 296.173398 -78.149958)
					(mid 295.69427 -78.473326)
					(end 296.06113 -78.026514)
				)
				(arc
					(start 296.06113 -78.026514)
					(mid 296.172918 -77.960382)
					(end 296.29354 -77.912214)
				)
				(arc
					(start 296.29354 -77.667866)
					(mid 296.188822 -77.635177)
					(end 296.088562 -77.59065)
				)
				(arc
					(start 296.088562 -77.59065)
					(mid 295.672728 -77.18918)
					(end 296.186098 -77.45476)
				)
				(arc
					(start 296.186098 -77.45476)
					(mid 296.239047 -77.477695)
					(end 296.29354 -77.49667)
				)
			)
		)
	)
	(zone
		(net "P1V26_STBY")
		(layer "B.Cu")
		(hatch none 0.5)
		(connect_pads
			(clearance 0.5)
		)
		(min_thickness 0.25)
		(fill yes
			(thermal_gap 0.5)
			(thermal_bridge_width 0.5)
			(island_removal_mode 0)
		)
		(polygon
			(pts
				(xy 151.892 -196.723) (xy 151.638 -196.977) (xy 151.638 -223.266) (xy 151.892 -223.52) (xy 155.067 -223.52)
				(xy 155.575 -223.012) (xy 155.575 -196.977) (xy 155.321 -196.723)
			)
		)
	)
	(zone
		(net "GND")
		(layer "B.Cu")
		(hatch none 0.5)
		(connect_pads
			(clearance 0.5)
		)
		(min_thickness 0.25)
		(fill yes
			(thermal_gap 0.5)
			(thermal_bridge_width 0.5)
			(island_removal_mode 0)
		)
		(polygon
			(pts
				(xy 323.088 -179.832) (xy 322.961 -179.959) (xy 322.961 -182.118) (xy 323.088 -182.245) (xy 324.612 -182.245)
				(xy 324.739 -182.118) (xy 324.739 -179.959) (xy 324.612 -179.832)
			)
		)
		(polygon
			(pts
				(xy 324.2056 -181.5338) (xy 323.9516 -181.5338) (xy 323.9516 -181.7878) (xy 324.2056 -181.7878)
			)
		)
		(polygon
			(pts
				(xy 323.7738 -181.483) (xy 323.5198 -181.483) (xy 323.5198 -181.737) (xy 323.7738 -181.737)
			)
		)
		(polygon
			(pts
				(xy 324.1802 -180.34) (xy 323.9262 -180.34) (xy 323.9262 -180.594) (xy 324.1802 -180.594)
			)
		)
		(polygon
			(pts
				(xy 323.7484 -180.2892) (xy 323.4944 -180.2892) (xy 323.4944 -180.5432) (xy 323.7484 -180.5432)
			)
		)
	)
	(zone
		(layer "B.Cu")
		(hatch none 0.5)
		(connect_pads
			(clearance 0)
		)
		(min_thickness 0.25)
		(keepout
			(tracks allowed)
			(vias allowed)
			(pads allowed)
			(copperpour allowed)
			(footprints not_allowed)
		)
		(placement
			(enabled no)
			(sheetname "")
		)
		(fill
			(thermal_gap 0.5)
			(thermal_bridge_width 0.5)
			(island_removal_mode 0)
		)
		(polygon
			(pts
				(arc
					(start 64.600074 -23.400004)
					(mid 68.600066 -19.400012)
					(end 72.600058 -23.400004)
				)
				(arc
					(start 72.600058 -23.400004)
					(mid 68.600066 -27.399996)
					(end 64.600074 -23.400004)
				)
			)
		)
	)
	(zone
		(layer "B.Cu")
		(hatch none 0.5)
		(connect_pads
			(clearance 0)
		)
		(min_thickness 0.25)
		(keepout
			(tracks allowed)
			(vias allowed)
			(pads allowed)
			(copperpour allowed)
			(footprints not_allowed)
		)
		(placement
			(enabled no)
			(sheetname "")
		)
		(fill
			(thermal_gap 0.5)
			(thermal_bridge_width 0.5)
			(island_removal_mode 0)
		)
		(polygon
			(pts
				(arc
					(start 307.300122 -104.499918)
					(mid 311.700164 -100.099876)
					(end 316.099952 -104.499918)
				)
				(arc
					(start 316.099952 -104.499918)
					(mid 311.700164 -108.899706)
					(end 307.300122 -104.499918)
				)
			)
		)
	)
	(zone
		(net "P0V955_C")
		(layer "B.Cu")
		(hatch none 0.5)
		(connect_pads
			(clearance 0.5)
		)
		(min_thickness 0.25)
		(fill yes
			(thermal_gap 0.5)
			(thermal_bridge_width 0.5)
			(island_removal_mode 0)
		)
		(polygon
			(pts
				(xy 83.947 -3.81) (xy 83.566 -4.191) (xy 83.566 -9.906) (xy 83.947 -10.287) (xy 100.965 -10.287)
				(xy 102.235 -9.017) (xy 102.235 -4.191) (xy 101.854 -3.81)
			)
		)
		(polygon
			(pts
				(xy 97.3328 -4.445) (xy 97.0788 -4.445) (xy 97.0788 -4.699) (xy 97.3328 -4.699)
			)
		)
		(polygon
			(pts
				(xy 96.4692 -4.445) (xy 96.2152 -4.445) (xy 96.2152 -4.699) (xy 96.4692 -4.699)
			)
		)
		(polygon
			(pts
				(xy 96.0628 -4.445) (xy 95.8088 -4.445) (xy 95.8088 -4.699) (xy 96.0628 -4.699)
			)
		)
		(polygon
			(pts
				(xy 95.1992 -4.445) (xy 94.9452 -4.445) (xy 94.9452 -4.699) (xy 95.1992 -4.699)
			)
		)
		(polygon
			(pts
				(xy 92.2528 -4.064) (xy 91.9988 -4.064) (xy 91.9988 -4.318) (xy 92.2528 -4.318)
			)
		)
		(polygon
			(pts
				(xy 91.6432 -4.064) (xy 91.1098 -4.064) (xy 91.1098 -4.318) (xy 91.6432 -4.318)
			)
		)
		(polygon
			(pts
				(xy 90.7542 -4.064) (xy 90.5002 -4.064) (xy 90.5002 -4.318) (xy 90.7542 -4.318)
			)
		)
		(polygon
			(pts
				(xy 89.0778 -4.064) (xy 88.8238 -4.064) (xy 88.8238 -4.318) (xy 89.0778 -4.318)
			)
		)
		(polygon
			(pts
				(xy 88.4682 -4.064) (xy 88.2142 -4.064) (xy 88.2142 -4.318) (xy 88.4682 -4.318)
			)
		)
		(polygon
			(pts
				(xy 90.1954 -4.0132) (xy 89.9414 -4.0132) (xy 89.9414 -4.2672) (xy 90.1954 -4.2672)
			)
		)
		(polygon
			(pts
				(xy 89.6366 -4.0132) (xy 89.3826 -4.0132) (xy 89.3826 -4.2672) (xy 89.6366 -4.2672)
			)
		)
	)
	(zone
		(layers "B.Cu" "In2.Cu")
		(hatch none 0.5)
		(connect_pads
			(clearance 0)
		)
		(min_thickness 0.25)
		(keepout
			(tracks not_allowed)
			(vias allowed)
			(pads allowed)
			(copperpour not_allowed)
			(footprints allowed)
		)
		(placement
			(enabled no)
			(sheetname "")
		)
		(fill yes
			(thermal_gap 0.5)
			(thermal_bridge_width 0.5)
			(island_removal_mode 0)
		)
		(polygon
			(pts
				(arc
					(start 132.930392 -80.733646)
					(mid 132.546852 -81.117186)
					(end 132.930392 -81.500726)
				)
				(arc
					(start 133.858254 -81.500726)
					(mid 134.128722 -81.389376)
					(end 134.242048 -81.119726)
				)
				(arc
					(start 134.150608 -81.119726)
					(mid 133.858508 -81.409297)
					(end 133.566408 -81.119726)
				)
				(arc
					(start 133.222492 -81.119726)
					(mid 132.930392 -81.409297)
					(end 132.638292 -81.119726)
				)
				(arc
					(start 132.638292 -81.117186)
					(mid 132.930392 -80.825086)
					(end 133.222492 -81.117186)
				)
				(arc
					(start 133.566408 -81.117186)
					(mid 133.858508 -80.825086)
					(end 134.150608 -81.117186)
				)
				(arc
					(start 134.242048 -81.117186)
					(mid 134.129712 -80.845982)
					(end 133.858508 -80.733646)
				)
			)
		)
	)
	(zone
		(layers "B.Cu" "In2.Cu")
		(hatch none 0.5)
		(connect_pads
			(clearance 0)
		)
		(min_thickness 0.25)
		(keepout
			(tracks not_allowed)
			(vias allowed)
			(pads allowed)
			(copperpour not_allowed)
			(footprints allowed)
		)
		(placement
			(enabled no)
			(sheetname "")
		)
		(fill yes
			(thermal_gap 0.5)
			(thermal_bridge_width 0.5)
			(island_removal_mode 0)
		)
		(polygon
			(pts
				(arc
					(start 131.02844 -79.37246)
					(mid 130.6449 -79.756)
					(end 131.02844 -80.13954)
				)
				(arc
					(start 132.00507 -80.13954)
					(mid 132.275538 -80.02819)
					(end 132.388864 -79.75854)
				)
				(arc
					(start 132.297424 -79.75854)
					(mid 132.005324 -80.048111)
					(end 131.713224 -79.75854)
				)
				(arc
					(start 131.32054 -79.75854)
					(mid 131.02844 -80.048111)
					(end 130.73634 -79.75854)
				)
				(arc
					(start 130.73634 -79.756)
					(mid 131.02844 -79.4639)
					(end 131.32054 -79.756)
				)
				(arc
					(start 131.713224 -79.756)
					(mid 132.005324 -79.4639)
					(end 132.297424 -79.756)
				)
				(arc
					(start 132.388864 -79.756)
					(mid 132.276528 -79.484796)
					(end 132.005324 -79.37246)
				)
			)
		)
	)
	(zone
		(layers "B.Cu" "In2.Cu")
		(hatch none 0.5)
		(connect_pads
			(clearance 0)
		)
		(min_thickness 0.25)
		(keepout
			(tracks not_allowed)
			(vias allowed)
			(pads allowed)
			(copperpour not_allowed)
			(footprints allowed)
		)
		(placement
			(enabled no)
			(sheetname "")
		)
		(fill yes
			(thermal_gap 0.5)
			(thermal_bridge_width 0.5)
			(island_removal_mode 0)
		)
		(polygon
			(pts
				(arc
					(start 41.693592 -83.106006)
					(mid 41.309798 -83.489419)
					(end 41.693338 -83.873086)
				)
				(arc
					(start 42.670222 -83.873086)
					(mid 42.940526 -83.761646)
					(end 43.053762 -83.492086)
				)
				(arc
					(start 42.962322 -83.492086)
					(mid 42.670222 -83.781657)
					(end 42.378122 -83.492086)
				)
				(arc
					(start 41.985438 -83.492086)
					(mid 41.693338 -83.781657)
					(end 41.401238 -83.492086)
				)
				(arc
					(start 41.401238 -83.489546)
					(mid 41.693338 -83.197446)
					(end 41.985438 -83.489546)
				)
				(arc
					(start 42.378122 -83.489546)
					(mid 42.670222 -83.197446)
					(end 42.962322 -83.489546)
				)
				(arc
					(start 43.053762 -83.489546)
					(mid 42.941426 -83.218342)
					(end 42.670222 -83.106006)
				)
			)
		)
	)
	(zone
		(layers "B.Cu" "In2.Cu")
		(hatch none 0.5)
		(connect_pads
			(clearance 0)
		)
		(min_thickness 0.25)
		(keepout
			(tracks not_allowed)
			(vias allowed)
			(pads allowed)
			(copperpour not_allowed)
			(footprints allowed)
		)
		(placement
			(enabled no)
			(sheetname "")
		)
		(fill yes
			(thermal_gap 0.5)
			(thermal_bridge_width 0.5)
			(island_removal_mode 0)
		)
		(polygon
			(pts
				(arc
					(start 318.715898 -81.407)
					(mid 318.306958 -80.99806)
					(end 317.898018 -81.407)
				)
				(arc
					(start 317.898018 -82.422746)
					(mid 318.305561 -82.831938)
					(end 318.715898 -82.42554)
				)
				(arc
					(start 318.599058 -82.42554)
					(mid 318.306958 -82.715111)
					(end 318.014858 -82.42554)
				)
				(arc
					(start 318.014858 -82.423)
					(mid 318.306958 -82.1309)
					(end 318.599058 -82.423)
				)
				(xy 318.715898 -82.423) (xy 318.715898 -81.40954)
				(arc
					(start 318.599058 -81.40954)
					(mid 318.306958 -81.699111)
					(end 318.014858 -81.40954)
				)
				(arc
					(start 318.014858 -81.407)
					(mid 318.306958 -81.1149)
					(end 318.599058 -81.407)
				)
			)
		)
	)
	(zone
		(layers "B.Cu" "In2.Cu")
		(hatch none 0.5)
		(connect_pads
			(clearance 0)
		)
		(min_thickness 0.25)
		(keepout
			(tracks not_allowed)
			(vias allowed)
			(pads allowed)
			(copperpour not_allowed)
			(footprints allowed)
		)
		(placement
			(enabled no)
			(sheetname "")
		)
		(fill yes
			(thermal_gap 0.5)
			(thermal_bridge_width 0.5)
			(island_removal_mode 0)
		)
		(polygon
			(pts
				(arc
					(start 134.11454 -87.114126)
					(mid 133.731 -86.730586)
					(end 133.34746 -87.114126)
				)
				(arc
					(start 133.34746 -88.019128)
					(mid 133.72973 -88.402666)
					(end 134.11454 -88.021668)
				)
				(arc
					(start 134.0231 -88.021668)
					(mid 133.731 -88.311239)
					(end 133.4389 -88.021668)
				)
				(arc
					(start 133.4389 -88.019128)
					(mid 133.731 -87.727028)
					(end 134.0231 -88.019128)
				)
				(xy 134.11454 -88.019128) (xy 134.11454 -87.116666)
				(arc
					(start 134.0231 -87.116666)
					(mid 133.731 -87.406237)
					(end 133.4389 -87.116666)
				)
				(arc
					(start 133.4389 -87.114126)
					(mid 133.731 -86.822026)
					(end 134.0231 -87.114126)
				)
			)
		)
	)
	(zone
		(layers "B.Cu" "In2.Cu")
		(hatch none 0.5)
		(connect_pads
			(clearance 0)
		)
		(min_thickness 0.25)
		(keepout
			(tracks not_allowed)
			(vias allowed)
			(pads allowed)
			(copperpour not_allowed)
			(footprints allowed)
		)
		(placement
			(enabled no)
			(sheetname "")
		)
		(fill yes
			(thermal_gap 0.5)
			(thermal_bridge_width 0.5)
			(island_removal_mode 0)
		)
		(polygon
			(pts
				(arc
					(start 350.369124 -154.275028)
					(mid 350.010984 -153.916888)
					(end 349.652844 -154.275028)
				)
				(arc
					(start 349.652844 -155.154884)
					(mid 350.009587 -155.513275)
					(end 350.369124 -155.157678)
				)
				(arc
					(start 350.277684 -155.157678)
					(mid 350.010984 -155.42185)
					(end 349.744284 -155.157678)
				)
				(arc
					(start 349.744284 -155.155138)
					(mid 350.010984 -154.888438)
					(end 350.277684 -155.155138)
				)
				(xy 350.369124 -155.155138) (xy 350.369124 -154.277568)
				(arc
					(start 350.277684 -154.277568)
					(mid 350.010984 -154.54174)
					(end 349.744284 -154.277568)
				)
				(arc
					(start 349.744284 -154.275028)
					(mid 350.010984 -154.008328)
					(end 350.277684 -154.275028)
				)
			)
		)
	)
	(zone
		(layers "B.Cu" "In2.Cu")
		(hatch none 0.5)
		(connect_pads
			(clearance 0)
		)
		(min_thickness 0.25)
		(keepout
			(tracks not_allowed)
			(vias allowed)
			(pads allowed)
			(copperpour not_allowed)
			(footprints allowed)
		)
		(placement
			(enabled no)
			(sheetname "")
		)
		(fill yes
			(thermal_gap 0.5)
			(thermal_bridge_width 0.5)
			(island_removal_mode 0)
		)
		(polygon
			(pts
				(arc
					(start 38.430454 -89.712546)
					(mid 38.046914 -90.096086)
					(end 38.430454 -90.479626)
				)
				(arc
					(start 39.407084 -90.479626)
					(mid 39.677552 -90.368276)
					(end 39.790878 -90.098626)
				)
				(arc
					(start 39.699438 -90.098626)
					(mid 39.407338 -90.388197)
					(end 39.115238 -90.098626)
				)
				(arc
					(start 38.722554 -90.098626)
					(mid 38.430454 -90.388197)
					(end 38.138354 -90.098626)
				)
				(arc
					(start 38.138354 -90.096086)
					(mid 38.430454 -89.803986)
					(end 38.722554 -90.096086)
				)
				(arc
					(start 39.115238 -90.096086)
					(mid 39.407338 -89.803986)
					(end 39.699438 -90.096086)
				)
				(arc
					(start 39.790878 -90.096086)
					(mid 39.678542 -89.824882)
					(end 39.407338 -89.712546)
				)
			)
		)
	)
	(zone
		(layers "B.Cu" "In2.Cu")
		(hatch none 0.5)
		(connect_pads
			(clearance 0)
		)
		(min_thickness 0.25)
		(keepout
			(tracks not_allowed)
			(vias allowed)
			(pads allowed)
			(copperpour not_allowed)
			(footprints allowed)
		)
		(placement
			(enabled no)
			(sheetname "")
		)
		(fill yes
			(thermal_gap 0.5)
			(thermal_bridge_width 0.5)
			(island_removal_mode 0)
		)
		(polygon
			(pts
				(arc
					(start 303.80305 -87.141812)
					(mid 303.41951 -87.525352)
					(end 303.80305 -87.908892)
				)
				(arc
					(start 304.719736 -87.908892)
					(mid 304.990204 -87.797542)
					(end 305.10353 -87.527892)
				)
				(arc
					(start 305.01209 -87.527892)
					(mid 304.71999 -87.817463)
					(end 304.42789 -87.527892)
				)
				(arc
					(start 304.09515 -87.527892)
					(mid 303.80305 -87.817463)
					(end 303.51095 -87.527892)
				)
				(arc
					(start 303.51095 -87.525352)
					(mid 303.80305 -87.233252)
					(end 304.09515 -87.525352)
				)
				(arc
					(start 304.42789 -87.525352)
					(mid 304.71999 -87.233252)
					(end 305.01209 -87.525352)
				)
				(arc
					(start 305.10353 -87.525352)
					(mid 304.991194 -87.254148)
					(end 304.71999 -87.141812)
				)
			)
		)
	)
	(zone
		(layers "B.Cu" "In2.Cu")
		(hatch none 0.5)
		(connect_pads
			(clearance 0)
		)
		(min_thickness 0.25)
		(keepout
			(tracks not_allowed)
			(vias allowed)
			(pads allowed)
			(copperpour not_allowed)
			(footprints allowed)
		)
		(placement
			(enabled no)
			(sheetname "")
		)
		(fill yes
			(thermal_gap 0.5)
			(thermal_bridge_width 0.5)
			(island_removal_mode 0)
		)
		(polygon
			(pts
				(arc
					(start 44.647104 -83.118706)
					(mid 44.263564 -83.502246)
					(end 44.647104 -83.885786)
				)
				(arc
					(start 45.623734 -83.885786)
					(mid 45.894202 -83.774436)
					(end 46.007528 -83.504786)
				)
				(arc
					(start 45.916088 -83.504786)
					(mid 45.623988 -83.794357)
					(end 45.331888 -83.504786)
				)
				(arc
					(start 44.939204 -83.504786)
					(mid 44.647104 -83.794357)
					(end 44.355004 -83.504786)
				)
				(arc
					(start 44.355004 -83.502246)
					(mid 44.647104 -83.210146)
					(end 44.939204 -83.502246)
				)
				(arc
					(start 45.331888 -83.502246)
					(mid 45.623988 -83.210146)
					(end 45.916088 -83.502246)
				)
				(arc
					(start 46.007528 -83.502246)
					(mid 45.895192 -83.231042)
					(end 45.623988 -83.118706)
				)
			)
		)
	)
	(zone
		(layers "B.Cu" "In2.Cu")
		(hatch none 0.5)
		(connect_pads
			(clearance 0)
		)
		(min_thickness 0.25)
		(keepout
			(tracks not_allowed)
			(vias allowed)
			(pads allowed)
			(copperpour not_allowed)
			(footprints allowed)
		)
		(placement
			(enabled no)
			(sheetname "")
		)
		(fill yes
			(thermal_gap 0.5)
			(thermal_bridge_width 0.5)
			(island_removal_mode 0)
		)
		(polygon
			(pts
				(arc
					(start 301.975012 -73.22566)
					(mid 301.591218 -73.609073)
					(end 301.974758 -73.99274)
				)
				(arc
					(start 302.956722 -73.99274)
					(mid 303.227026 -73.8813)
					(end 303.340262 -73.61174)
				)
				(arc
					(start 303.248822 -73.61174)
					(mid 302.956722 -73.901311)
					(end 302.664622 -73.61174)
				)
				(arc
					(start 302.266858 -73.61174)
					(mid 301.974758 -73.901311)
					(end 301.682658 -73.61174)
				)
				(arc
					(start 301.682658 -73.6092)
					(mid 301.974758 -73.3171)
					(end 302.266858 -73.6092)
				)
				(arc
					(start 302.664622 -73.6092)
					(mid 302.956722 -73.3171)
					(end 303.248822 -73.6092)
				)
				(arc
					(start 303.340262 -73.6092)
					(mid 303.227926 -73.337996)
					(end 302.956722 -73.22566)
				)
			)
		)
	)
	(zone
		(layers "B.Cu" "In2.Cu")
		(hatch none 0.5)
		(connect_pads
			(clearance 0)
		)
		(min_thickness 0.25)
		(keepout
			(tracks not_allowed)
			(vias allowed)
			(pads allowed)
			(copperpour not_allowed)
			(footprints allowed)
		)
		(placement
			(enabled no)
			(sheetname "")
		)
		(fill yes
			(thermal_gap 0.5)
			(thermal_bridge_width 0.5)
			(island_removal_mode 0)
		)
		(polygon
			(pts
				(arc
					(start 351.11309 -151.97201)
					(mid 350.75495 -151.61387)
					(end 350.39681 -151.97201)
				)
				(arc
					(start 350.39681 -152.916636)
					(mid 350.753553 -153.275027)
					(end 351.11309 -152.91943)
				)
				(arc
					(start 351.02165 -152.91943)
					(mid 350.75495 -153.183602)
					(end 350.48825 -152.91943)
				)
				(arc
					(start 350.48825 -152.91689)
					(mid 350.75495 -152.65019)
					(end 351.02165 -152.91689)
				)
				(xy 351.11309 -152.91689) (xy 351.11309 -151.97455)
				(arc
					(start 351.02165 -151.97455)
					(mid 350.75495 -152.238722)
					(end 350.48825 -151.97455)
				)
				(arc
					(start 350.48825 -151.97201)
					(mid 350.75495 -151.70531)
					(end 351.02165 -151.97201)
				)
			)
		)
	)
	(zone
		(layers "B.Cu" "In2.Cu")
		(hatch none 0.5)
		(connect_pads
			(clearance 0)
		)
		(min_thickness 0.25)
		(keepout
			(tracks not_allowed)
			(vias allowed)
			(pads allowed)
			(copperpour not_allowed)
			(footprints allowed)
		)
		(placement
			(enabled no)
			(sheetname "")
		)
		(fill yes
			(thermal_gap 0.5)
			(thermal_bridge_width 0.5)
			(island_removal_mode 0)
		)
		(polygon
			(pts
				(arc
					(start 294.03294 -79.44993)
					(mid 293.6494 -79.06639)
					(end 293.26586 -79.44993)
				)
				(arc
					(start 293.26586 -80.366616)
					(mid 293.648003 -80.750408)
					(end 294.03294 -80.36941)
				)
				(arc
					(start 293.9415 -80.36941)
					(mid 293.6494 -80.658981)
					(end 293.3573 -80.36941)
				)
				(arc
					(start 293.3573 -80.36687)
					(mid 293.6494 -80.07477)
					(end 293.9415 -80.36687)
				)
				(xy 294.03294 -80.36687) (xy 294.03294 -79.45247)
				(arc
					(start 293.9415 -79.45247)
					(mid 293.6494 -79.742041)
					(end 293.3573 -79.45247)
				)
				(arc
					(start 293.3573 -79.44993)
					(mid 293.6494 -79.15783)
					(end 293.9415 -79.44993)
				)
			)
		)
	)
	(zone
		(layers "B.Cu" "In2.Cu")
		(hatch none 0.5)
		(connect_pads
			(clearance 0)
		)
		(min_thickness 0.25)
		(keepout
			(tracks not_allowed)
			(vias allowed)
			(pads allowed)
			(copperpour not_allowed)
			(footprints allowed)
		)
		(placement
			(enabled no)
			(sheetname "")
		)
		(fill yes
			(thermal_gap 0.5)
			(thermal_bridge_width 0.5)
			(island_removal_mode 0)
		)
		(polygon
			(pts
				(arc
					(start 135.880094 -81.15046)
					(mid 135.4963 -81.533873)
					(end 135.87984 -81.91754)
				)
				(arc
					(start 136.807956 -81.91754)
					(mid 137.07826 -81.8061)
					(end 137.191496 -81.53654)
				)
				(arc
					(start 137.100056 -81.53654)
					(mid 136.807956 -81.826111)
					(end 136.515856 -81.53654)
				)
				(arc
					(start 136.17194 -81.53654)
					(mid 135.87984 -81.826111)
					(end 135.58774 -81.53654)
				)
				(arc
					(start 135.58774 -81.534)
					(mid 135.87984 -81.2419)
					(end 136.17194 -81.534)
				)
				(arc
					(start 136.515856 -81.534)
					(mid 136.807956 -81.2419)
					(end 137.100056 -81.534)
				)
				(arc
					(start 137.191496 -81.534)
					(mid 137.07916 -81.262796)
					(end 136.807956 -81.15046)
				)
			)
		)
	)
	(zone
		(layers "B.Cu" "In2.Cu")
		(hatch none 0.5)
		(connect_pads
			(clearance 0)
		)
		(min_thickness 0.25)
		(keepout
			(tracks not_allowed)
			(vias allowed)
			(pads allowed)
			(copperpour not_allowed)
			(footprints allowed)
		)
		(placement
			(enabled no)
			(sheetname "")
		)
		(fill yes
			(thermal_gap 0.5)
			(thermal_bridge_width 0.5)
			(island_removal_mode 0)
		)
		(polygon
			(pts
				(arc
					(start 132.59054 -91.169998)
					(mid 132.207 -90.786458)
					(end 131.82346 -91.169998)
				)
				(arc
					(start 131.82346 -92.075)
					(mid 132.20573 -92.458538)
					(end 132.59054 -92.07754)
				)
				(arc
					(start 132.4991 -92.07754)
					(mid 132.207 -92.367111)
					(end 131.9149 -92.07754)
				)
				(arc
					(start 131.9149 -92.075)
					(mid 132.207 -91.7829)
					(end 132.4991 -92.075)
				)
				(xy 132.59054 -92.075) (xy 132.59054 -91.172538)
				(arc
					(start 132.4991 -91.172538)
					(mid 132.207 -91.462109)
					(end 131.9149 -91.172538)
				)
				(arc
					(start 131.9149 -91.169998)
					(mid 132.207 -90.877898)
					(end 132.4991 -91.169998)
				)
			)
		)
	)
	(zone
		(layers "B.Cu" "In2.Cu")
		(hatch none 0.5)
		(connect_pads
			(clearance 0)
		)
		(min_thickness 0.25)
		(keepout
			(tracks not_allowed)
			(vias allowed)
			(pads allowed)
			(copperpour not_allowed)
			(footprints allowed)
		)
		(placement
			(enabled no)
			(sheetname "")
		)
		(fill yes
			(thermal_gap 0.5)
			(thermal_bridge_width 0.5)
			(island_removal_mode 0)
		)
		(polygon
			(pts
				(arc
					(start 35.382454 -89.712546)
					(mid 34.998914 -90.096086)
					(end 35.382454 -90.479626)
				)
				(arc
					(start 36.359084 -90.479626)
					(mid 36.629552 -90.368276)
					(end 36.742878 -90.098626)
				)
				(arc
					(start 36.651438 -90.098626)
					(mid 36.359338 -90.388197)
					(end 36.067238 -90.098626)
				)
				(arc
					(start 35.674554 -90.098626)
					(mid 35.382454 -90.388197)
					(end 35.090354 -90.098626)
				)
				(arc
					(start 35.090354 -90.096086)
					(mid 35.382454 -89.803986)
					(end 35.674554 -90.096086)
				)
				(arc
					(start 36.067238 -90.096086)
					(mid 36.359338 -89.803986)
					(end 36.651438 -90.096086)
				)
				(arc
					(start 36.742878 -90.096086)
					(mid 36.630542 -89.824882)
					(end 36.359338 -89.712546)
				)
			)
		)
	)
	(zone
		(layers "B.Cu" "In2.Cu")
		(hatch none 0.5)
		(connect_pads
			(clearance 0)
		)
		(min_thickness 0.25)
		(keepout
			(tracks not_allowed)
			(vias allowed)
			(pads allowed)
			(copperpour not_allowed)
			(footprints allowed)
		)
		(placement
			(enabled no)
			(sheetname "")
		)
		(fill yes
			(thermal_gap 0.5)
			(thermal_bridge_width 0.5)
			(island_removal_mode 0)
		)
		(polygon
			(pts
				(arc
					(start 318.080898 -72.009)
					(mid 317.671958 -71.60006)
					(end 317.263018 -72.009)
				)
				(arc
					(start 317.263018 -73.024746)
					(mid 317.670561 -73.433938)
					(end 318.080898 -73.02754)
				)
				(arc
					(start 317.964058 -73.02754)
					(mid 317.671958 -73.317111)
					(end 317.379858 -73.02754)
				)
				(arc
					(start 317.379858 -73.025)
					(mid 317.671958 -72.7329)
					(end 317.964058 -73.025)
				)
				(xy 318.080898 -73.025) (xy 318.080898 -72.01154)
				(arc
					(start 317.964058 -72.01154)
					(mid 317.671958 -72.301111)
					(end 317.379858 -72.01154)
				)
				(arc
					(start 317.379858 -72.009)
					(mid 317.671958 -71.7169)
					(end 317.964058 -72.009)
				)
			)
		)
	)
	(zone
		(layers "B.Cu" "In2.Cu")
		(hatch none 0.5)
		(connect_pads
			(clearance 0)
		)
		(min_thickness 0.25)
		(keepout
			(tracks not_allowed)
			(vias allowed)
			(pads allowed)
			(copperpour not_allowed)
			(footprints allowed)
		)
		(placement
			(enabled no)
			(sheetname "")
		)
		(fill yes
			(thermal_gap 0.5)
			(thermal_bridge_width 0.5)
			(island_removal_mode 0)
		)
		(polygon
			(pts
				(arc
					(start 320.595498 -75.209908)
					(mid 320.186558 -74.800968)
					(end 319.777618 -75.209908)
				)
				(arc
					(start 319.777618 -76.191618)
					(mid 320.185161 -76.60081)
					(end 320.595498 -76.194412)
				)
				(arc
					(start 320.478658 -76.194412)
					(mid 320.186558 -76.483983)
					(end 319.894458 -76.194412)
				)
				(arc
					(start 319.894458 -76.191872)
					(mid 320.186558 -75.899772)
					(end 320.478658 -76.191872)
				)
				(xy 320.595498 -76.191872) (xy 320.595498 -75.212448)
				(arc
					(start 320.478658 -75.212448)
					(mid 320.186558 -75.502019)
					(end 319.894458 -75.212448)
				)
				(arc
					(start 319.894458 -75.209908)
					(mid 320.186558 -74.917808)
					(end 320.478658 -75.209908)
				)
			)
		)
	)
	(zone
		(layers "B.Cu" "In2.Cu")
		(hatch none 0.5)
		(connect_pads
			(clearance 0)
		)
		(min_thickness 0.25)
		(keepout
			(tracks not_allowed)
			(vias allowed)
			(pads allowed)
			(copperpour not_allowed)
			(footprints allowed)
		)
		(placement
			(enabled no)
			(sheetname "")
		)
		(fill yes
			(thermal_gap 0.5)
			(thermal_bridge_width 0.5)
			(island_removal_mode 0)
		)
		(polygon
			(pts
				(arc
					(start 132.59054 -88.375998)
					(mid 132.207 -87.992458)
					(end 131.82346 -88.375998)
				)
				(arc
					(start 131.82346 -89.281)
					(mid 132.20573 -89.664538)
					(end 132.59054 -89.28354)
				)
				(arc
					(start 132.4991 -89.28354)
					(mid 132.207 -89.573111)
					(end 131.9149 -89.28354)
				)
				(arc
					(start 131.9149 -89.281)
					(mid 132.207 -88.9889)
					(end 132.4991 -89.281)
				)
				(xy 132.59054 -89.281) (xy 132.59054 -88.378538)
				(arc
					(start 132.4991 -88.378538)
					(mid 132.207 -88.668109)
					(end 131.9149 -88.378538)
				)
				(arc
					(start 131.9149 -88.375998)
					(mid 132.207 -88.083898)
					(end 132.4991 -88.375998)
				)
			)
		)
	)
	(zone
		(layers "B.Cu" "In2.Cu")
		(hatch none 0.5)
		(connect_pads
			(clearance 0)
		)
		(min_thickness 0.25)
		(keepout
			(tracks not_allowed)
			(vias allowed)
			(pads allowed)
			(copperpour not_allowed)
			(footprints allowed)
		)
		(placement
			(enabled no)
			(sheetname "")
		)
		(fill yes
			(thermal_gap 0.5)
			(thermal_bridge_width 0.5)
			(island_removal_mode 0)
		)
		(polygon
			(pts
				(arc
					(start 32.334708 -89.712546)
					(mid 31.950914 -90.095959)
					(end 32.334454 -90.479626)
				)
				(arc
					(start 33.311338 -90.479626)
					(mid 33.581642 -90.368186)
					(end 33.694878 -90.098626)
				)
				(arc
					(start 33.603438 -90.098626)
					(mid 33.311338 -90.388197)
					(end 33.019238 -90.098626)
				)
				(arc
					(start 32.626554 -90.098626)
					(mid 32.334454 -90.388197)
					(end 32.042354 -90.098626)
				)
				(arc
					(start 32.042354 -90.096086)
					(mid 32.334454 -89.803986)
					(end 32.626554 -90.096086)
				)
				(arc
					(start 33.019238 -90.096086)
					(mid 33.311338 -89.803986)
					(end 33.603438 -90.096086)
				)
				(arc
					(start 33.694878 -90.096086)
					(mid 33.582542 -89.824882)
					(end 33.311338 -89.712546)
				)
			)
		)
	)
	(zone
		(layers "B.Cu" "In2.Cu")
		(hatch none 0.5)
		(connect_pads
			(clearance 0)
		)
		(min_thickness 0.25)
		(keepout
			(tracks not_allowed)
			(vias allowed)
			(pads allowed)
			(copperpour not_allowed)
			(footprints allowed)
		)
		(placement
			(enabled no)
			(sheetname "")
		)
		(fill yes
			(thermal_gap 0.5)
			(thermal_bridge_width 0.5)
			(island_removal_mode 0)
		)
		(polygon
			(pts
				(arc
					(start 297.123358 -73.30821)
					(mid 296.739818 -73.69175)
					(end 297.123358 -74.07529)
				)
				(arc
					(start 298.139104 -74.07529)
					(mid 298.409572 -73.96394)
					(end 298.522898 -73.69429)
				)
				(arc
					(start 298.431458 -73.69429)
					(mid 298.139358 -73.983861)
					(end 297.847258 -73.69429)
				)
				(arc
					(start 297.415458 -73.69429)
					(mid 297.123358 -73.983861)
					(end 296.831258 -73.69429)
				)
				(arc
					(start 296.831258 -73.69175)
					(mid 297.123358 -73.39965)
					(end 297.415458 -73.69175)
				)
				(arc
					(start 297.847258 -73.69175)
					(mid 298.139358 -73.39965)
					(end 298.431458 -73.69175)
				)
				(arc
					(start 298.522898 -73.69175)
					(mid 298.410562 -73.420546)
					(end 298.139358 -73.30821)
				)
			)
		)
	)
	(zone
		(layers "B.Cu" "In2.Cu")
		(hatch none 0.5)
		(connect_pads
			(clearance 0)
		)
		(min_thickness 0.25)
		(keepout
			(tracks not_allowed)
			(vias allowed)
			(pads allowed)
			(copperpour not_allowed)
			(footprints allowed)
		)
		(placement
			(enabled no)
			(sheetname "")
		)
		(fill yes
			(thermal_gap 0.5)
			(thermal_bridge_width 0.5)
			(island_removal_mode 0)
		)
		(polygon
			(pts
				(arc
					(start 134.581646 -82.29346)
					(mid 134.197852 -82.676873)
					(end 134.581392 -83.06054)
				)
				(arc
					(start 135.509508 -83.06054)
					(mid 135.779812 -82.9491)
					(end 135.893048 -82.67954)
				)
				(arc
					(start 135.801608 -82.67954)
					(mid 135.509508 -82.969111)
					(end 135.217408 -82.67954)
				)
				(arc
					(start 134.873492 -82.67954)
					(mid 134.581392 -82.969111)
					(end 134.289292 -82.67954)
				)
				(arc
					(start 134.289292 -82.677)
					(mid 134.581392 -82.3849)
					(end 134.873492 -82.677)
				)
				(arc
					(start 135.217408 -82.677)
					(mid 135.509508 -82.3849)
					(end 135.801608 -82.677)
				)
				(arc
					(start 135.893048 -82.677)
					(mid 135.780712 -82.405796)
					(end 135.509508 -82.29346)
				)
			)
		)
	)
	(zone
		(layers "B.Cu" "In2.Cu")
		(hatch none 0.5)
		(connect_pads
			(clearance 0)
		)
		(min_thickness 0.25)
		(keepout
			(tracks not_allowed)
			(vias allowed)
			(pads allowed)
			(copperpour not_allowed)
			(footprints allowed)
		)
		(placement
			(enabled no)
			(sheetname "")
		)
		(fill yes
			(thermal_gap 0.5)
			(thermal_bridge_width 0.5)
			(island_removal_mode 0)
		)
		(polygon
			(pts
				(arc
					(start 134.11454 -89.654126)
					(mid 133.731 -89.270586)
					(end 133.34746 -89.654126)
				)
				(arc
					(start 133.34746 -90.558874)
					(mid 133.729603 -90.942666)
					(end 134.11454 -90.561668)
				)
				(arc
					(start 134.0231 -90.561668)
					(mid 133.731 -90.851239)
					(end 133.4389 -90.561668)
				)
				(arc
					(start 133.4389 -90.559128)
					(mid 133.731 -90.267028)
					(end 134.0231 -90.559128)
				)
				(xy 134.11454 -90.559128) (xy 134.11454 -89.656666)
				(arc
					(start 134.0231 -89.656666)
					(mid 133.731 -89.946237)
					(end 133.4389 -89.656666)
				)
				(arc
					(start 133.4389 -89.654126)
					(mid 133.731 -89.362026)
					(end 134.0231 -89.654126)
				)
			)
		)
	)
	(zone
		(layers "B.Cu" "In2.Cu")
		(hatch none 0.5)
		(connect_pads
			(clearance 0)
		)
		(min_thickness 0.25)
		(keepout
			(tracks not_allowed)
			(vias allowed)
			(pads allowed)
			(copperpour not_allowed)
			(footprints allowed)
		)
		(placement
			(enabled no)
			(sheetname "")
		)
		(fill yes
			(thermal_gap 0.5)
			(thermal_bridge_width 0.5)
			(island_removal_mode 0)
		)
		(polygon
			(pts
				(arc
					(start 297.05681 -81.840324)
					(mid 296.67327 -82.223864)
					(end 297.05681 -82.607404)
				)
				(arc
					(start 297.973496 -82.607404)
					(mid 298.243964 -82.496054)
					(end 298.35729 -82.226404)
				)
				(arc
					(start 298.26585 -82.226404)
					(mid 297.97375 -82.515975)
					(end 297.68165 -82.226404)
				)
				(arc
					(start 297.34891 -82.226404)
					(mid 297.05681 -82.515975)
					(end 296.76471 -82.226404)
				)
				(arc
					(start 296.76471 -82.223864)
					(mid 297.05681 -81.931764)
					(end 297.34891 -82.223864)
				)
				(arc
					(start 297.68165 -82.223864)
					(mid 297.97375 -81.931764)
					(end 298.26585 -82.223864)
				)
				(arc
					(start 298.35729 -82.223864)
					(mid 298.244954 -81.95266)
					(end 297.97375 -81.840324)
				)
			)
		)
	)
	(zone
		(layers "B.Cu" "In2.Cu")
		(hatch none 0.5)
		(connect_pads
			(clearance 0)
		)
		(min_thickness 0.25)
		(keepout
			(tracks not_allowed)
			(vias allowed)
			(pads allowed)
			(copperpour not_allowed)
			(footprints allowed)
		)
		(placement
			(enabled no)
			(sheetname "")
		)
		(fill yes
			(thermal_gap 0.5)
			(thermal_bridge_width 0.5)
			(island_removal_mode 0)
		)
		(polygon
			(pts
				(arc
					(start 318.817498 -78.4352)
					(mid 318.413637 -78.026292)
					(end 317.999618 -78.42504)
				)
				(xy 317.997332 -78.42504) (xy 317.971932 -79.440786) (xy 317.972186 -79.44104)
				(arc
					(start 317.974218 -79.44104)
					(mid 318.372998 -79.86014)
					(end 318.792098 -79.46136)
				)
				(xy 318.794384 -79.46136) (xy 318.794638 -79.45374)
				(arc
					(start 318.675258 -79.45374)
					(mid 318.383158 -79.743311)
					(end 318.091058 -79.45374)
				)
				(arc
					(start 318.091058 -79.4512)
					(mid 318.383158 -79.1591)
					(end 318.675258 -79.4512)
				)
				(xy 318.794638 -79.4512) (xy 318.819784 -78.44536) (xy 318.817498 -78.44536) (xy 318.817498 -78.43774)
				(arc
					(start 318.700658 -78.43774)
					(mid 318.408558 -78.727311)
					(end 318.116458 -78.43774)
				)
				(arc
					(start 318.116458 -78.4352)
					(mid 318.408558 -78.1431)
					(end 318.700658 -78.4352)
				)
			)
		)
	)
	(zone
		(layers "B.Cu" "In2.Cu")
		(hatch none 0.5)
		(connect_pads
			(clearance 0)
		)
		(min_thickness 0.25)
		(keepout
			(tracks not_allowed)
			(vias allowed)
			(pads allowed)
			(copperpour not_allowed)
			(footprints allowed)
		)
		(placement
			(enabled no)
			(sheetname "")
		)
		(fill yes
			(thermal_gap 0.5)
			(thermal_bridge_width 0.5)
			(island_removal_mode 0)
		)
		(polygon
			(pts
				(arc
					(start 350.87941 -147.26539)
					(mid 350.52127 -147.62353)
					(end 350.87941 -147.98167)
				)
				(arc
					(start 351.824036 -147.98167)
					(mid 352.076544 -147.877759)
					(end 352.18243 -147.62607)
				)
				(arc
					(start 352.09099 -147.62607)
					(mid 351.82429 -147.890242)
					(end 351.55759 -147.62607)
				)
				(arc
					(start 351.14611 -147.62607)
					(mid 350.87941 -147.890242)
					(end 350.61271 -147.62607)
				)
				(arc
					(start 350.61271 -147.62353)
					(mid 350.87941 -147.35683)
					(end 351.14611 -147.62353)
				)
				(arc
					(start 351.55759 -147.62353)
					(mid 351.82429 -147.35683)
					(end 352.09099 -147.62353)
				)
				(arc
					(start 352.18243 -147.62353)
					(mid 352.077533 -147.370287)
					(end 351.82429 -147.26539)
				)
			)
		)
	)
	(zone
		(layers "B.Cu" "In2.Cu")
		(hatch none 0.5)
		(connect_pads
			(clearance 0)
		)
		(min_thickness 0.25)
		(keepout
			(tracks not_allowed)
			(vias allowed)
			(pads allowed)
			(copperpour not_allowed)
			(footprints allowed)
		)
		(placement
			(enabled no)
			(sheetname "")
		)
		(fill yes
			(thermal_gap 0.5)
			(thermal_bridge_width 0.5)
			(island_removal_mode 0)
		)
		(polygon
			(pts
				(arc
					(start 41.351708 -89.712546)
					(mid 40.967914 -90.095959)
					(end 41.351454 -90.479626)
				)
				(arc
					(start 42.328338 -90.479626)
					(mid 42.598642 -90.368186)
					(end 42.711878 -90.098626)
				)
				(arc
					(start 42.620438 -90.098626)
					(mid 42.328338 -90.388197)
					(end 42.036238 -90.098626)
				)
				(arc
					(start 41.643554 -90.098626)
					(mid 41.351454 -90.388197)
					(end 41.059354 -90.098626)
				)
				(arc
					(start 41.059354 -90.096086)
					(mid 41.351454 -89.803986)
					(end 41.643554 -90.096086)
				)
				(arc
					(start 42.036238 -90.096086)
					(mid 42.328338 -89.803986)
					(end 42.620438 -90.096086)
				)
				(arc
					(start 42.711878 -90.096086)
					(mid 42.599542 -89.824882)
					(end 42.328338 -89.712546)
				)
			)
		)
	)
	(zone
		(layers "B.Cu" "In2.Cu" "In5.Cu")
		(hatch none 0.5)
		(connect_pads
			(clearance 0)
		)
		(min_thickness 0.25)
		(keepout
			(tracks not_allowed)
			(vias allowed)
			(pads allowed)
			(copperpour not_allowed)
			(footprints allowed)
		)
		(placement
			(enabled no)
			(sheetname "")
		)
		(fill yes
			(thermal_gap 0.5)
			(thermal_bridge_width 0.5)
			(island_removal_mode 0)
		)
		(polygon
			(pts
				(arc
					(start 270.999966 -10.199878)
					(mid 270.210026 -10.989818)
					(end 270.999966 -11.779758)
				)
				(arc
					(start 272.999962 -11.779758)
					(mid 273.557635 -11.549287)
					(end 273.789902 -10.992358)
				)
				(arc
					(start 273.698462 -10.992358)
					(mid 272.999962 -11.688323)
					(end 272.301462 -10.992358)
				)
				(arc
					(start 271.698466 -10.992358)
					(mid 270.999966 -11.688323)
					(end 270.301466 -10.992358)
				)
				(arc
					(start 270.301466 -10.989818)
					(mid 270.999966 -10.291318)
					(end 271.698466 -10.989818)
				)
				(arc
					(start 272.301462 -10.989818)
					(mid 272.999962 -10.291318)
					(end 273.698462 -10.989818)
				)
				(arc
					(start 273.789902 -10.989818)
					(mid 273.558534 -10.431246)
					(end 272.999962 -10.199878)
				)
			)
		)
	)
	(zone
		(layers "B.Cu" "In5.Cu")
		(hatch none 0.5)
		(connect_pads
			(clearance 0)
		)
		(min_thickness 0.25)
		(keepout
			(tracks not_allowed)
			(vias allowed)
			(pads allowed)
			(copperpour not_allowed)
			(footprints allowed)
		)
		(placement
			(enabled no)
			(sheetname "")
		)
		(fill yes
			(thermal_gap 0.5)
			(thermal_bridge_width 0.5)
			(island_removal_mode 0)
		)
		(polygon
			(pts
				(arc
					(start 276.867112 -31.74746)
					(mid 276.483572 -32.131)
					(end 276.867112 -32.51454)
				)
				(arc
					(start 277.848822 -32.51454)
					(mid 278.11929 -32.40319)
					(end 278.232616 -32.13354)
				)
				(arc
					(start 278.141176 -32.13354)
					(mid 277.849076 -32.423111)
					(end 277.556976 -32.13354)
				)
				(arc
					(start 277.159212 -32.13354)
					(mid 276.867112 -32.423111)
					(end 276.575012 -32.13354)
				)
				(arc
					(start 276.575012 -32.131)
					(mid 276.867112 -31.8389)
					(end 277.159212 -32.131)
				)
				(arc
					(start 277.556976 -32.131)
					(mid 277.849076 -31.8389)
					(end 278.141176 -32.131)
				)
				(arc
					(start 278.232616 -32.131)
					(mid 278.12028 -31.859796)
					(end 277.849076 -31.74746)
				)
			)
		)
	)
	(zone
		(layer "In1.Cu")
		(hatch none 0.5)
		(connect_pads
			(clearance 0)
		)
		(min_thickness 0.25)
		(keepout
			(tracks not_allowed)
			(vias allowed)
			(pads allowed)
			(copperpour not_allowed)
			(footprints allowed)
		)
		(placement
			(enabled no)
			(sheetname "")
		)
		(fill
			(thermal_gap 0.5)
			(thermal_bridge_width 0.5)
			(island_removal_mode 0)
		)
		(polygon
			(pts
				(arc
					(start 131.4704 -86.99246)
					(mid 131.360841 -87.037841)
					(end 131.31546 -87.1474)
				)
				(arc
					(start 131.31546 -87.3506)
					(mid 131.360841 -87.460159)
					(end 131.4704 -87.50554)
				)
				(arc
					(start 131.7244 -87.50554)
					(mid 131.833959 -87.460159)
					(end 131.87934 -87.3506)
				)
				(arc
					(start 131.87934 -87.1474)
					(mid 131.833959 -87.037841)
					(end 131.7244 -86.99246)
				)
			)
		)
	)
	(zone
		(layer "In1.Cu")
		(hatch none 0.5)
		(connect_pads
			(clearance 0)
		)
		(min_thickness 0.25)
		(keepout
			(tracks not_allowed)
			(vias allowed)
			(pads allowed)
			(copperpour not_allowed)
			(footprints allowed)
		)
		(placement
			(enabled no)
			(sheetname "")
		)
		(fill
			(thermal_gap 0.5)
			(thermal_bridge_width 0.5)
			(island_removal_mode 0)
		)
		(polygon
			(pts
				(arc
					(start 131.4704 -91.05646)
					(mid 131.360841 -91.101841)
					(end 131.31546 -91.2114)
				)
				(arc
					(start 131.31546 -91.4146)
					(mid 131.360841 -91.524159)
					(end 131.4704 -91.56954)
				)
				(arc
					(start 131.7244 -91.56954)
					(mid 131.833959 -91.524159)
					(end 131.87934 -91.4146)
				)
				(arc
					(start 131.87934 -91.2114)
					(mid 131.833959 -91.101841)
					(end 131.7244 -91.05646)
				)
			)
		)
	)
	(zone
		(layer "In1.Cu")
		(hatch none 0.5)
		(connect_pads
			(clearance 0)
		)
		(min_thickness 0.25)
		(keepout
			(tracks not_allowed)
			(vias allowed)
			(pads allowed)
			(copperpour not_allowed)
			(footprints allowed)
		)
		(placement
			(enabled no)
			(sheetname "")
		)
		(fill
			(thermal_gap 0.5)
			(thermal_bridge_width 0.5)
			(island_removal_mode 0)
		)
		(polygon
			(pts
				(xy 276.441154 -24.392128) (xy 277.309834 -24.392128) (xy 277.309834 -25.514808) (xy 276.441154 -25.514808)
			)
		)
	)
	(zone
		(layer "In1.Cu")
		(hatch none 0.5)
		(connect_pads
			(clearance 0)
		)
		(min_thickness 0.25)
		(keepout
			(tracks not_allowed)
			(vias allowed)
			(pads allowed)
			(copperpour not_allowed)
			(footprints allowed)
		)
		(placement
			(enabled no)
			(sheetname "")
		)
		(fill
			(thermal_gap 0.5)
			(thermal_bridge_width 0.5)
			(island_removal_mode 0)
		)
		(polygon
			(pts
				(arc
					(start 137.16254 -98.3996)
					(mid 137.117159 -98.290041)
					(end 137.0076 -98.24466)
				)
				(arc
					(start 136.8044 -98.24466)
					(mid 136.694841 -98.290041)
					(end 136.64946 -98.3996)
				)
				(arc
					(start 136.64946 -98.6536)
					(mid 136.694841 -98.763159)
					(end 136.8044 -98.80854)
				)
				(arc
					(start 137.0076 -98.80854)
					(mid 137.117159 -98.763159)
					(end 137.16254 -98.6536)
				)
			)
		)
	)
	(zone
		(layer "In1.Cu")
		(hatch none 0.5)
		(connect_pads
			(clearance 0)
		)
		(min_thickness 0.25)
		(keepout
			(tracks not_allowed)
			(vias allowed)
			(pads allowed)
			(copperpour not_allowed)
			(footprints allowed)
		)
		(placement
			(enabled no)
			(sheetname "")
		)
		(fill
			(thermal_gap 0.5)
			(thermal_bridge_width 0.5)
			(island_removal_mode 0)
		)
		(polygon
			(pts
				(arc
					(start 130.9116 -88.26246)
					(mid 130.802041 -88.307841)
					(end 130.75666 -88.4174)
				)
				(arc
					(start 130.75666 -88.6206)
					(mid 130.802041 -88.730159)
					(end 130.9116 -88.77554)
				)
				(arc
					(start 131.1656 -88.77554)
					(mid 131.275159 -88.730159)
					(end 131.32054 -88.6206)
				)
				(arc
					(start 131.32054 -88.4174)
					(mid 131.275159 -88.307841)
					(end 131.1656 -88.26246)
				)
			)
		)
	)
	(zone
		(layer "In1.Cu")
		(hatch none 0.5)
		(connect_pads
			(clearance 0)
		)
		(min_thickness 0.25)
		(keepout
			(tracks not_allowed)
			(vias allowed)
			(pads allowed)
			(copperpour not_allowed)
			(footprints allowed)
		)
		(placement
			(enabled no)
			(sheetname "")
		)
		(fill
			(thermal_gap 0.5)
			(thermal_bridge_width 0.5)
			(island_removal_mode 0)
		)
		(polygon
			(pts
				(xy 106.548428 -1.303528) (xy 107.798108 -1.303528) (xy 107.798108 -2.756408) (xy 106.548428 -2.756408)
			)
		)
	)
	(zone
		(layer "In1.Cu")
		(hatch none 0.5)
		(connect_pads
			(clearance 0)
		)
		(min_thickness 0.25)
		(keepout
			(tracks not_allowed)
			(vias allowed)
			(pads allowed)
			(copperpour not_allowed)
			(footprints allowed)
		)
		(placement
			(enabled no)
			(sheetname "")
		)
		(fill
			(thermal_gap 0.5)
			(thermal_bridge_width 0.5)
			(island_removal_mode 0)
		)
		(polygon
			(pts
				(arc
					(start 114.675412 -221.94774)
					(mid 114.820892 -221.88748)
					(end 114.881152 -221.742)
				)
				(arc
					(start 114.881152 -221.3864)
					(mid 114.820892 -221.24092)
					(end 114.675412 -221.18066)
				)
				(arc
					(start 114.319812 -221.18066)
					(mid 114.174332 -221.24092)
					(end 114.114072 -221.3864)
				)
				(arc
					(start 114.114072 -221.742)
					(mid 114.174332 -221.88748)
					(end 114.319812 -221.94774)
				)
			)
		)
	)
	(zone
		(layer "In1.Cu")
		(hatch none 0.5)
		(connect_pads
			(clearance 0)
		)
		(min_thickness 0.25)
		(keepout
			(tracks not_allowed)
			(vias allowed)
			(pads allowed)
			(copperpour not_allowed)
			(footprints allowed)
		)
		(placement
			(enabled no)
			(sheetname "")
		)
		(fill
			(thermal_gap 0.5)
			(thermal_bridge_width 0.5)
			(island_removal_mode 0)
		)
		(polygon
			(pts
				(arc
					(start 42.317924 -80.314038)
					(mid 42.599864 -80.595978)
					(end 42.881804 -80.314038)
				)
				(arc
					(start 42.881804 -78.866238)
					(mid 42.599864 -78.584298)
					(end 42.317924 -78.866238)
				)
			)
		)
	)
	(zone
		(layer "In1.Cu")
		(hatch none 0.5)
		(connect_pads
			(clearance 0)
		)
		(min_thickness 0.25)
		(keepout
			(tracks not_allowed)
			(vias allowed)
			(pads allowed)
			(copperpour not_allowed)
			(footprints allowed)
		)
		(placement
			(enabled no)
			(sheetname "")
		)
		(fill
			(thermal_gap 0.5)
			(thermal_bridge_width 0.5)
			(island_removal_mode 0)
		)
		(polygon
			(pts
				(arc
					(start 110.88751 -113.8936)
					(mid 110.842129 -113.784041)
					(end 110.73257 -113.73866)
				)
				(arc
					(start 110.52937 -113.73866)
					(mid 110.419811 -113.784041)
					(end 110.37443 -113.8936)
				)
				(arc
					(start 110.37443 -114.1476)
					(mid 110.419811 -114.257159)
					(end 110.52937 -114.30254)
				)
				(arc
					(start 110.73257 -114.30254)
					(mid 110.842129 -114.257159)
					(end 110.88751 -114.1476)
				)
			)
		)
	)
	(zone
		(layer "In1.Cu")
		(hatch none 0.5)
		(connect_pads
			(clearance 0)
		)
		(min_thickness 0.25)
		(keepout
			(tracks not_allowed)
			(vias allowed)
			(pads allowed)
			(copperpour not_allowed)
			(footprints allowed)
		)
		(placement
			(enabled no)
			(sheetname "")
		)
		(fill
			(thermal_gap 0.5)
			(thermal_bridge_width 0.5)
			(island_removal_mode 0)
		)
		(polygon
			(pts
				(arc
					(start 116.22151 -113.8936)
					(mid 116.176129 -113.784041)
					(end 116.06657 -113.73866)
				)
				(arc
					(start 115.86337 -113.73866)
					(mid 115.753811 -113.784041)
					(end 115.70843 -113.8936)
				)
				(arc
					(start 115.70843 -114.1476)
					(mid 115.753811 -114.257159)
					(end 115.86337 -114.30254)
				)
				(arc
					(start 116.06657 -114.30254)
					(mid 116.176129 -114.257159)
					(end 116.22151 -114.1476)
				)
			)
		)
	)
	(zone
		(layer "In1.Cu")
		(hatch none 0.5)
		(connect_pads
			(clearance 0)
		)
		(min_thickness 0.25)
		(keepout
			(tracks not_allowed)
			(vias allowed)
			(pads allowed)
			(copperpour not_allowed)
			(footprints allowed)
		)
		(placement
			(enabled no)
			(sheetname "")
		)
		(fill
			(thermal_gap 0.5)
			(thermal_bridge_width 0.5)
			(island_removal_mode 0)
		)
		(polygon
			(pts
				(arc
					(start 107.96651 -113.8936)
					(mid 107.921129 -113.784041)
					(end 107.81157 -113.73866)
				)
				(arc
					(start 107.60837 -113.73866)
					(mid 107.498811 -113.784041)
					(end 107.45343 -113.8936)
				)
				(arc
					(start 107.45343 -114.1476)
					(mid 107.498811 -114.257159)
					(end 107.60837 -114.30254)
				)
				(arc
					(start 107.81157 -114.30254)
					(mid 107.921129 -114.257159)
					(end 107.96651 -114.1476)
				)
			)
		)
	)
	(zone
		(layer "In1.Cu")
		(hatch none 0.5)
		(connect_pads
			(clearance 0)
		)
		(min_thickness 0.25)
		(keepout
			(tracks not_allowed)
			(vias allowed)
			(pads allowed)
			(copperpour not_allowed)
			(footprints allowed)
		)
		(placement
			(enabled no)
			(sheetname "")
		)
		(fill
			(thermal_gap 0.5)
			(thermal_bridge_width 0.5)
			(island_removal_mode 0)
		)
		(polygon
			(pts
				(arc
					(start 86.90356 -39.88054)
					(mid 87.013119 -39.835159)
					(end 87.0585 -39.7256)
				)
				(arc
					(start 87.0585 -39.5224)
					(mid 87.013119 -39.412841)
					(end 86.90356 -39.36746)
				)
				(arc
					(start 86.64956 -39.36746)
					(mid 86.540001 -39.412841)
					(end 86.49462 -39.5224)
				)
				(arc
					(start 86.49462 -39.7256)
					(mid 86.540001 -39.835159)
					(end 86.64956 -39.88054)
				)
			)
		)
	)
	(zone
		(layer "In1.Cu")
		(hatch none 0.5)
		(connect_pads
			(clearance 0)
		)
		(min_thickness 0.25)
		(keepout
			(tracks not_allowed)
			(vias allowed)
			(pads allowed)
			(copperpour not_allowed)
			(footprints allowed)
		)
		(placement
			(enabled no)
			(sheetname "")
		)
		(fill
			(thermal_gap 0.5)
			(thermal_bridge_width 0.5)
			(island_removal_mode 0)
		)
		(polygon
			(pts
				(arc
					(start 106.18851 -114.4524)
					(mid 106.143129 -114.342841)
					(end 106.03357 -114.29746)
				)
				(arc
					(start 105.83037 -114.29746)
					(mid 105.720811 -114.342841)
					(end 105.67543 -114.4524)
				)
				(arc
					(start 105.67543 -114.7064)
					(mid 105.720811 -114.815959)
					(end 105.83037 -114.86134)
				)
				(arc
					(start 106.03357 -114.86134)
					(mid 106.143129 -114.815959)
					(end 106.18851 -114.7064)
				)
			)
		)
	)
	(zone
		(layer "In1.Cu")
		(hatch none 0.5)
		(connect_pads
			(clearance 0)
		)
		(min_thickness 0.25)
		(keepout
			(tracks not_allowed)
			(vias allowed)
			(pads allowed)
			(copperpour not_allowed)
			(footprints allowed)
		)
		(placement
			(enabled no)
			(sheetname "")
		)
		(fill
			(thermal_gap 0.5)
			(thermal_bridge_width 0.5)
			(island_removal_mode 0)
		)
		(polygon
			(pts
				(arc
					(start 107.33151 -113.8936)
					(mid 107.286129 -113.784041)
					(end 107.17657 -113.73866)
				)
				(arc
					(start 106.97337 -113.73866)
					(mid 106.863811 -113.784041)
					(end 106.81843 -113.8936)
				)
				(arc
					(start 106.81843 -114.1476)
					(mid 106.863811 -114.257159)
					(end 106.97337 -114.30254)
				)
				(arc
					(start 107.17657 -114.30254)
					(mid 107.286129 -114.257159)
					(end 107.33151 -114.1476)
				)
			)
		)
	)
	(zone
		(layer "In1.Cu")
		(hatch none 0.5)
		(connect_pads
			(clearance 0)
		)
		(min_thickness 0.25)
		(keepout
			(tracks not_allowed)
			(vias allowed)
			(pads allowed)
			(copperpour not_allowed)
			(footprints allowed)
		)
		(placement
			(enabled no)
			(sheetname "")
		)
		(fill
			(thermal_gap 0.5)
			(thermal_bridge_width 0.5)
			(island_removal_mode 0)
		)
		(polygon
			(pts
				(arc
					(start 107.33151 -114.4524)
					(mid 107.286129 -114.342841)
					(end 107.17657 -114.29746)
				)
				(arc
					(start 106.97337 -114.29746)
					(mid 106.863811 -114.342841)
					(end 106.81843 -114.4524)
				)
				(arc
					(start 106.81843 -114.7064)
					(mid 106.863811 -114.815959)
					(end 106.97337 -114.86134)
				)
				(arc
					(start 107.17657 -114.86134)
					(mid 107.286129 -114.815959)
					(end 107.33151 -114.7064)
				)
			)
		)
	)
	(zone
		(layer "In1.Cu")
		(hatch none 0.5)
		(connect_pads
			(clearance 0)
		)
		(min_thickness 0.25)
		(keepout
			(tracks not_allowed)
			(vias allowed)
			(pads allowed)
			(copperpour not_allowed)
			(footprints allowed)
		)
		(placement
			(enabled no)
			(sheetname "")
		)
		(fill
			(thermal_gap 0.5)
			(thermal_bridge_width 0.5)
			(island_removal_mode 0)
		)
		(polygon
			(pts
				(arc
					(start 44.31792 -77.80401)
					(mid 44.59986 -78.08595)
					(end 44.8818 -77.80401)
				)
				(arc
					(start 44.8818 -76.35621)
					(mid 44.59986 -76.07427)
					(end 44.31792 -76.35621)
				)
			)
		)
	)
	(zone
		(layer "In1.Cu")
		(hatch none 0.5)
		(connect_pads
			(clearance 0)
		)
		(min_thickness 0.25)
		(keepout
			(tracks not_allowed)
			(vias allowed)
			(pads allowed)
			(copperpour not_allowed)
			(footprints allowed)
		)
		(placement
			(enabled no)
			(sheetname "")
		)
		(fill
			(thermal_gap 0.5)
			(thermal_bridge_width 0.5)
			(island_removal_mode 0)
		)
		(polygon
			(pts
				(arc
					(start 121.812812 -222.93326)
					(mid 121.667332 -222.99352)
					(end 121.607072 -223.139)
				)
				(arc
					(start 121.607072 -223.4946)
					(mid 121.667332 -223.64008)
					(end 121.812812 -223.70034)
				)
				(arc
					(start 122.168412 -223.70034)
					(mid 122.313892 -223.64008)
					(end 122.374152 -223.4946)
				)
				(arc
					(start 122.374152 -223.139)
					(mid 122.313892 -222.99352)
					(end 122.168412 -222.93326)
				)
			)
		)
	)
	(zone
		(layer "In1.Cu")
		(hatch none 0.5)
		(connect_pads
			(clearance 0)
		)
		(min_thickness 0.25)
		(keepout
			(tracks not_allowed)
			(vias allowed)
			(pads allowed)
			(copperpour not_allowed)
			(footprints allowed)
		)
		(placement
			(enabled no)
			(sheetname "")
		)
		(fill
			(thermal_gap 0.5)
			(thermal_bridge_width 0.5)
			(island_removal_mode 0)
		)
		(polygon
			(pts
				(arc
					(start 114.44351 -114.4524)
					(mid 114.398129 -114.342841)
					(end 114.28857 -114.29746)
				)
				(arc
					(start 114.08537 -114.29746)
					(mid 113.975811 -114.342841)
					(end 113.93043 -114.4524)
				)
				(arc
					(start 113.93043 -114.7064)
					(mid 113.975811 -114.815959)
					(end 114.08537 -114.86134)
				)
				(arc
					(start 114.28857 -114.86134)
					(mid 114.398129 -114.815959)
					(end 114.44351 -114.7064)
				)
			)
		)
	)
	(zone
		(layer "In1.Cu")
		(hatch none 0.5)
		(connect_pads
			(clearance 0)
		)
		(min_thickness 0.25)
		(keepout
			(tracks not_allowed)
			(vias allowed)
			(pads allowed)
			(copperpour not_allowed)
			(footprints allowed)
		)
		(placement
			(enabled no)
			(sheetname "")
		)
		(fill
			(thermal_gap 0.5)
			(thermal_bridge_width 0.5)
			(island_removal_mode 0)
		)
		(polygon
			(pts
				(arc
					(start 119.77751 -113.8936)
					(mid 119.732129 -113.784041)
					(end 119.62257 -113.73866)
				)
				(arc
					(start 119.41937 -113.73866)
					(mid 119.309811 -113.784041)
					(end 119.26443 -113.8936)
				)
				(arc
					(start 119.26443 -114.1476)
					(mid 119.309811 -114.257159)
					(end 119.41937 -114.30254)
				)
				(arc
					(start 119.62257 -114.30254)
					(mid 119.732129 -114.257159)
					(end 119.77751 -114.1476)
				)
			)
		)
	)
	(zone
		(layer "In1.Cu")
		(hatch none 0.5)
		(connect_pads
			(clearance 0)
		)
		(min_thickness 0.25)
		(keepout
			(tracks not_allowed)
			(vias allowed)
			(pads allowed)
			(copperpour not_allowed)
			(footprints allowed)
		)
		(placement
			(enabled no)
			(sheetname "")
		)
		(fill
			(thermal_gap 0.5)
			(thermal_bridge_width 0.5)
			(island_removal_mode 0)
		)
		(polygon
			(pts
				(arc
					(start 316.53226 -68.3768)
					(mid 316.59252 -68.52228)
					(end 316.738 -68.58254)
				)
				(arc
					(start 317.0936 -68.58254)
					(mid 317.23908 -68.52228)
					(end 317.29934 -68.3768)
				)
				(arc
					(start 317.29934 -68.0212)
					(mid 317.23908 -67.87572)
					(end 317.0936 -67.81546)
				)
				(arc
					(start 316.738 -67.81546)
					(mid 316.59252 -67.87572)
					(end 316.53226 -68.0212)
				)
			)
		)
	)
	(zone
		(layer "In1.Cu")
		(hatch none 0.5)
		(connect_pads
			(clearance 0)
		)
		(min_thickness 0.25)
		(keepout
			(tracks not_allowed)
			(vias allowed)
			(pads allowed)
			(copperpour not_allowed)
			(footprints allowed)
		)
		(placement
			(enabled no)
			(sheetname "")
		)
		(fill
			(thermal_gap 0.5)
			(thermal_bridge_width 0.5)
			(island_removal_mode 0)
		)
		(polygon
			(pts
				(arc
					(start 102.63251 -114.4524)
					(mid 102.587129 -114.342841)
					(end 102.47757 -114.29746)
				)
				(arc
					(start 102.27437 -114.29746)
					(mid 102.164811 -114.342841)
					(end 102.11943 -114.4524)
				)
				(arc
					(start 102.11943 -114.7064)
					(mid 102.164811 -114.815959)
					(end 102.27437 -114.86134)
				)
				(arc
					(start 102.47757 -114.86134)
					(mid 102.587129 -114.815959)
					(end 102.63251 -114.7064)
				)
			)
		)
	)
	(zone
		(layer "In1.Cu")
		(hatch none 0.5)
		(connect_pads
			(clearance 0)
		)
		(min_thickness 0.25)
		(keepout
			(tracks not_allowed)
			(vias allowed)
			(pads allowed)
			(copperpour not_allowed)
			(footprints allowed)
		)
		(placement
			(enabled no)
			(sheetname "")
		)
		(fill
			(thermal_gap 0.5)
			(thermal_bridge_width 0.5)
			(island_removal_mode 0)
		)
		(polygon
			(pts
				(arc
					(start 132.365242 -82.238342)
					(mid 132.255683 -82.283723)
					(end 132.210302 -82.393282)
				)
				(arc
					(start 132.210302 -82.596482)
					(mid 132.255683 -82.706041)
					(end 132.365242 -82.751422)
				)
				(arc
					(start 132.619242 -82.751422)
					(mid 132.728801 -82.706041)
					(end 132.774182 -82.596482)
				)
				(arc
					(start 132.774182 -82.393282)
					(mid 132.728801 -82.283723)
					(end 132.619242 -82.238342)
				)
			)
		)
	)
	(zone
		(layer "In1.Cu")
		(hatch none 0.5)
		(connect_pads
			(clearance 0)
		)
		(min_thickness 0.25)
		(keepout
			(tracks not_allowed)
			(vias allowed)
			(pads allowed)
			(copperpour not_allowed)
			(footprints allowed)
		)
		(placement
			(enabled no)
			(sheetname "")
		)
		(fill
			(thermal_gap 0.5)
			(thermal_bridge_width 0.5)
			(island_removal_mode 0)
		)
		(polygon
			(pts
				(arc
					(start 315.66866 -69.3928)
					(mid 315.72892 -69.53828)
					(end 315.8744 -69.59854)
				)
				(arc
					(start 316.23 -69.59854)
					(mid 316.37548 -69.53828)
					(end 316.43574 -69.3928)
				)
				(arc
					(start 316.43574 -69.0372)
					(mid 316.37548 -68.89172)
					(end 316.23 -68.83146)
				)
				(arc
					(start 315.8744 -68.83146)
					(mid 315.72892 -68.89172)
					(end 315.66866 -69.0372)
				)
			)
		)
	)
	(zone
		(layer "In1.Cu")
		(hatch none 0.5)
		(connect_pads
			(clearance 0)
		)
		(min_thickness 0.25)
		(keepout
			(tracks not_allowed)
			(vias allowed)
			(pads allowed)
			(copperpour not_allowed)
			(footprints allowed)
		)
		(placement
			(enabled no)
			(sheetname "")
		)
		(fill
			(thermal_gap 0.5)
			(thermal_bridge_width 0.5)
			(island_removal_mode 0)
		)
		(polygon
			(pts
				(arc
					(start 136.52754 -98.3996)
					(mid 136.482159 -98.290041)
					(end 136.3726 -98.24466)
				)
				(arc
					(start 136.1694 -98.24466)
					(mid 136.059841 -98.290041)
					(end 136.01446 -98.3996)
				)
				(arc
					(start 136.01446 -98.6536)
					(mid 136.059841 -98.763159)
					(end 136.1694 -98.80854)
				)
				(arc
					(start 136.3726 -98.80854)
					(mid 136.482159 -98.763159)
					(end 136.52754 -98.6536)
				)
			)
		)
	)
	(zone
		(layer "In1.Cu")
		(hatch none 0.5)
		(connect_pads
			(clearance 0)
		)
		(min_thickness 0.25)
		(keepout
			(tracks not_allowed)
			(vias allowed)
			(pads allowed)
			(copperpour not_allowed)
			(footprints allowed)
		)
		(placement
			(enabled no)
			(sheetname "")
		)
		(fill
			(thermal_gap 0.5)
			(thermal_bridge_width 0.5)
			(island_removal_mode 0)
		)
		(polygon
			(pts
				(arc
					(start 111.52251 -114.4524)
					(mid 111.477129 -114.342841)
					(end 111.36757 -114.29746)
				)
				(arc
					(start 111.16437 -114.29746)
					(mid 111.054811 -114.342841)
					(end 111.00943 -114.4524)
				)
				(arc
					(start 111.00943 -114.7064)
					(mid 111.054811 -114.815959)
					(end 111.16437 -114.86134)
				)
				(arc
					(start 111.36757 -114.86134)
					(mid 111.477129 -114.815959)
					(end 111.52251 -114.7064)
				)
			)
		)
	)
	(zone
		(layer "In1.Cu")
		(hatch none 0.5)
		(connect_pads
			(clearance 0)
		)
		(min_thickness 0.25)
		(keepout
			(tracks not_allowed)
			(vias allowed)
			(pads allowed)
			(copperpour not_allowed)
			(footprints allowed)
		)
		(placement
			(enabled no)
			(sheetname "")
		)
		(fill
			(thermal_gap 0.5)
			(thermal_bridge_width 0.5)
			(island_removal_mode 0)
		)
		(polygon
			(pts
				(arc
					(start 134.76351 -98.3996)
					(mid 134.718129 -98.290041)
					(end 134.60857 -98.24466)
				)
				(arc
					(start 134.40537 -98.24466)
					(mid 134.295811 -98.290041)
					(end 134.25043 -98.3996)
				)
				(arc
					(start 134.25043 -98.6536)
					(mid 134.295811 -98.763159)
					(end 134.40537 -98.80854)
				)
				(arc
					(start 134.60857 -98.80854)
					(mid 134.718129 -98.763159)
					(end 134.76351 -98.6536)
				)
			)
		)
	)
	(zone
		(layer "In1.Cu")
		(hatch none 0.5)
		(connect_pads
			(clearance 0)
		)
		(min_thickness 0.25)
		(keepout
			(tracks not_allowed)
			(vias allowed)
			(pads allowed)
			(copperpour not_allowed)
			(footprints allowed)
		)
		(placement
			(enabled no)
			(sheetname "")
		)
		(fill
			(thermal_gap 0.5)
			(thermal_bridge_width 0.5)
			(island_removal_mode 0)
		)
		(polygon
			(pts
				(arc
					(start 113.30051 -113.8936)
					(mid 113.255129 -113.784041)
					(end 113.14557 -113.73866)
				)
				(arc
					(start 112.94237 -113.73866)
					(mid 112.832811 -113.784041)
					(end 112.78743 -113.8936)
				)
				(arc
					(start 112.78743 -114.1476)
					(mid 112.832811 -114.257159)
					(end 112.94237 -114.30254)
				)
				(arc
					(start 113.14557 -114.30254)
					(mid 113.255129 -114.257159)
					(end 113.30051 -114.1476)
				)
			)
		)
	)
	(zone
		(layer "In1.Cu")
		(hatch none 0.5)
		(connect_pads
			(clearance 0)
		)
		(min_thickness 0.25)
		(keepout
			(tracks not_allowed)
			(vias allowed)
			(pads allowed)
			(copperpour not_allowed)
			(footprints allowed)
		)
		(placement
			(enabled no)
			(sheetname "")
		)
		(fill
			(thermal_gap 0.5)
			(thermal_bridge_width 0.5)
			(island_removal_mode 0)
		)
		(polygon
			(pts
				(arc
					(start 111.144812 -205.02626)
					(mid 110.999332 -205.08652)
					(end 110.939072 -205.232)
				)
				(arc
					(start 110.939072 -205.5876)
					(mid 110.999332 -205.73308)
					(end 111.144812 -205.79334)
				)
				(arc
					(start 111.500412 -205.79334)
					(mid 111.645892 -205.73308)
					(end 111.706152 -205.5876)
				)
				(arc
					(start 111.706152 -205.232)
					(mid 111.645892 -205.08652)
					(end 111.500412 -205.02626)
				)
			)
		)
	)
	(zone
		(layer "In1.Cu")
		(hatch none 0.5)
		(connect_pads
			(clearance 0)
		)
		(min_thickness 0.25)
		(keepout
			(tracks not_allowed)
			(vias allowed)
			(pads allowed)
			(copperpour not_allowed)
			(footprints allowed)
		)
		(placement
			(enabled no)
			(sheetname "")
		)
		(fill
			(thermal_gap 0.5)
			(thermal_bridge_width 0.5)
			(island_removal_mode 0)
		)
		(polygon
			(pts
				(arc
					(start 131.222242 -84.778342)
					(mid 131.112683 -84.823723)
					(end 131.067302 -84.933282)
				)
				(arc
					(start 131.067302 -85.136482)
					(mid 131.112683 -85.246041)
					(end 131.222242 -85.291422)
				)
				(arc
					(start 131.476242 -85.291422)
					(mid 131.585801 -85.246041)
					(end 131.631182 -85.136482)
				)
				(arc
					(start 131.631182 -84.933282)
					(mid 131.585801 -84.823723)
					(end 131.476242 -84.778342)
				)
			)
		)
	)
	(zone
		(layer "In1.Cu")
		(hatch none 0.5)
		(connect_pads
			(clearance 0)
		)
		(min_thickness 0.25)
		(keepout
			(tracks not_allowed)
			(vias allowed)
			(pads allowed)
			(copperpour not_allowed)
			(footprints allowed)
		)
		(placement
			(enabled no)
			(sheetname "")
		)
		(fill
			(thermal_gap 0.5)
			(thermal_bridge_width 0.5)
			(island_removal_mode 0)
		)
		(polygon
			(pts
				(arc
					(start 347.575378 -154.333448)
					(mid 347.635638 -154.478928)
					(end 347.781118 -154.539188)
				)
				(arc
					(start 348.136718 -154.539188)
					(mid 348.282198 -154.478928)
					(end 348.342458 -154.333448)
				)
				(arc
					(start 348.342458 -153.977848)
					(mid 348.282198 -153.832368)
					(end 348.136718 -153.772108)
				)
				(arc
					(start 347.781118 -153.772108)
					(mid 347.635638 -153.832368)
					(end 347.575378 -153.977848)
				)
			)
		)
	)
	(zone
		(layer "In1.Cu")
		(hatch none 0.5)
		(connect_pads
			(clearance 0)
		)
		(min_thickness 0.25)
		(keepout
			(tracks not_allowed)
			(vias allowed)
			(pads allowed)
			(copperpour not_allowed)
			(footprints allowed)
		)
		(placement
			(enabled no)
			(sheetname "")
		)
		(fill
			(thermal_gap 0.5)
			(thermal_bridge_width 0.5)
			(island_removal_mode 0)
		)
		(polygon
			(pts
				(arc
					(start 315.66866 -68.3768)
					(mid 315.72892 -68.52228)
					(end 315.8744 -68.58254)
				)
				(arc
					(start 316.23 -68.58254)
					(mid 316.37548 -68.52228)
					(end 316.43574 -68.3768)
				)
				(arc
					(start 316.43574 -68.0212)
					(mid 316.37548 -67.87572)
					(end 316.23 -67.81546)
				)
				(arc
					(start 315.8744 -67.81546)
					(mid 315.72892 -67.87572)
					(end 315.66866 -68.0212)
				)
			)
		)
	)
	(zone
		(layer "In1.Cu")
		(hatch none 0.5)
		(connect_pads
			(clearance 0)
		)
		(min_thickness 0.25)
		(keepout
			(tracks not_allowed)
			(vias allowed)
			(pads allowed)
			(copperpour not_allowed)
			(footprints allowed)
		)
		(placement
			(enabled no)
			(sheetname "")
		)
		(fill
			(thermal_gap 0.5)
			(thermal_bridge_width 0.5)
			(island_removal_mode 0)
		)
		(polygon
			(pts
				(arc
					(start 86.34476 -43.18254)
					(mid 86.454319 -43.137159)
					(end 86.4997 -43.0276)
				)
				(arc
					(start 86.4997 -42.8244)
					(mid 86.454319 -42.714841)
					(end 86.34476 -42.66946)
				)
				(arc
					(start 86.09076 -42.66946)
					(mid 85.981201 -42.714841)
					(end 85.93582 -42.8244)
				)
				(arc
					(start 85.93582 -43.0276)
					(mid 85.981201 -43.137159)
					(end 86.09076 -43.18254)
				)
			)
		)
	)
	(zone
		(layer "In1.Cu")
		(hatch none 0.5)
		(connect_pads
			(clearance 0)
		)
		(min_thickness 0.25)
		(keepout
			(tracks not_allowed)
			(vias allowed)
			(pads allowed)
			(copperpour not_allowed)
			(footprints allowed)
		)
		(placement
			(enabled no)
			(sheetname "")
		)
		(fill
			(thermal_gap 0.5)
			(thermal_bridge_width 0.5)
			(island_removal_mode 0)
		)
		(polygon
			(pts
				(arc
					(start 122.19051 -113.8936)
					(mid 122.145129 -113.784041)
					(end 122.03557 -113.73866)
				)
				(arc
					(start 121.83237 -113.73866)
					(mid 121.722811 -113.784041)
					(end 121.67743 -113.8936)
				)
				(arc
					(start 121.67743 -114.1476)
					(mid 121.722811 -114.257159)
					(end 121.83237 -114.30254)
				)
				(arc
					(start 122.03557 -114.30254)
					(mid 122.145129 -114.257159)
					(end 122.19051 -114.1476)
				)
			)
		)
	)
	(zone
		(layer "In1.Cu")
		(hatch none 0.5)
		(connect_pads
			(clearance 0)
		)
		(min_thickness 0.25)
		(keepout
			(tracks not_allowed)
			(vias allowed)
			(pads allowed)
			(copperpour not_allowed)
			(footprints allowed)
		)
		(placement
			(enabled no)
			(sheetname "")
		)
		(fill
			(thermal_gap 0.5)
			(thermal_bridge_width 0.5)
			(island_removal_mode 0)
		)
		(polygon
			(pts
				(arc
					(start 86.90356 -38.86454)
					(mid 87.013119 -38.819159)
					(end 87.0585 -38.7096)
				)
				(arc
					(start 87.0585 -38.5064)
					(mid 87.013119 -38.396841)
					(end 86.90356 -38.35146)
				)
				(arc
					(start 86.64956 -38.35146)
					(mid 86.540001 -38.396841)
					(end 86.49462 -38.5064)
				)
				(arc
					(start 86.49462 -38.7096)
					(mid 86.540001 -38.819159)
					(end 86.64956 -38.86454)
				)
			)
		)
	)
	(zone
		(layer "In1.Cu")
		(hatch none 0.5)
		(connect_pads
			(clearance 0)
		)
		(min_thickness 0.25)
		(keepout
			(tracks not_allowed)
			(vias allowed)
			(pads allowed)
			(copperpour not_allowed)
			(footprints allowed)
		)
		(placement
			(enabled no)
			(sheetname "")
		)
		(fill
			(thermal_gap 0.5)
			(thermal_bridge_width 0.5)
			(island_removal_mode 0)
		)
		(polygon
			(pts
				(arc
					(start 86.34476 -42.16654)
					(mid 86.454319 -42.121159)
					(end 86.4997 -42.0116)
				)
				(arc
					(start 86.4997 -41.8084)
					(mid 86.454319 -41.698841)
					(end 86.34476 -41.65346)
				)
				(arc
					(start 86.09076 -41.65346)
					(mid 85.981201 -41.698841)
					(end 85.93582 -41.8084)
				)
				(arc
					(start 85.93582 -42.0116)
					(mid 85.981201 -42.121159)
					(end 86.09076 -42.16654)
				)
			)
		)
	)
	(zone
		(layer "In1.Cu")
		(hatch none 0.5)
		(connect_pads
			(clearance 0)
		)
		(min_thickness 0.25)
		(keepout
			(tracks not_allowed)
			(vias allowed)
			(pads allowed)
			(copperpour not_allowed)
			(footprints allowed)
		)
		(placement
			(enabled no)
			(sheetname "")
		)
		(fill
			(thermal_gap 0.5)
			(thermal_bridge_width 0.5)
			(island_removal_mode 0)
		)
		(polygon
			(pts
				(arc
					(start 130.9116 -87.62746)
					(mid 130.802041 -87.672841)
					(end 130.75666 -87.7824)
				)
				(arc
					(start 130.75666 -87.9856)
					(mid 130.802041 -88.095159)
					(end 130.9116 -88.14054)
				)
				(arc
					(start 131.1656 -88.14054)
					(mid 131.275159 -88.095159)
					(end 131.32054 -87.9856)
				)
				(arc
					(start 131.32054 -87.7824)
					(mid 131.275159 -87.672841)
					(end 131.1656 -87.62746)
				)
			)
		)
	)
	(zone
		(layer "In1.Cu")
		(hatch none 0.5)
		(connect_pads
			(clearance 0)
		)
		(min_thickness 0.25)
		(keepout
			(tracks not_allowed)
			(vias allowed)
			(pads allowed)
			(copperpour not_allowed)
			(footprints allowed)
		)
		(placement
			(enabled no)
			(sheetname "")
		)
		(fill
			(thermal_gap 0.5)
			(thermal_bridge_width 0.5)
			(island_removal_mode 0)
		)
		(polygon
			(pts
				(arc
					(start 51.118008 -80.314038)
					(mid 51.399948 -80.595978)
					(end 51.681888 -80.314038)
				)
				(arc
					(start 51.681888 -78.866238)
					(mid 51.399948 -78.584298)
					(end 51.118008 -78.866238)
				)
			)
		)
	)
	(zone
		(layer "In1.Cu")
		(hatch none 0.5)
		(connect_pads
			(clearance 0)
		)
		(min_thickness 0.25)
		(keepout
			(tracks not_allowed)
			(vias allowed)
			(pads allowed)
			(copperpour not_allowed)
			(footprints allowed)
		)
		(placement
			(enabled no)
			(sheetname "")
		)
		(fill
			(thermal_gap 0.5)
			(thermal_bridge_width 0.5)
			(island_removal_mode 0)
		)
		(polygon
			(pts
				(arc
					(start 302.503332 -67.24904)
					(mid 302.563592 -67.39452)
					(end 302.709072 -67.45478)
				)
				(arc
					(start 303.064672 -67.45478)
					(mid 303.210152 -67.39452)
					(end 303.270412 -67.24904)
				)
				(arc
					(start 303.270412 -66.89344)
					(mid 303.210152 -66.74796)
					(end 303.064672 -66.6877)
				)
				(arc
					(start 302.709072 -66.6877)
					(mid 302.563592 -66.74796)
					(end 302.503332 -66.89344)
				)
			)
		)
	)
	(zone
		(layer "In1.Cu")
		(hatch none 0.5)
		(connect_pads
			(clearance 0)
		)
		(min_thickness 0.25)
		(keepout
			(tracks not_allowed)
			(vias allowed)
			(pads allowed)
			(copperpour not_allowed)
			(footprints allowed)
		)
		(placement
			(enabled no)
			(sheetname "")
		)
		(fill
			(thermal_gap 0.5)
			(thermal_bridge_width 0.5)
			(island_removal_mode 0)
		)
		(polygon
			(pts
				(arc
					(start 111.52251 -113.8936)
					(mid 111.477129 -113.784041)
					(end 111.36757 -113.73866)
				)
				(arc
					(start 111.16437 -113.73866)
					(mid 111.054811 -113.784041)
					(end 111.00943 -113.8936)
				)
				(arc
					(start 111.00943 -114.1476)
					(mid 111.054811 -114.257159)
					(end 111.16437 -114.30254)
				)
				(arc
					(start 111.36757 -114.30254)
					(mid 111.477129 -114.257159)
					(end 111.52251 -114.1476)
				)
			)
		)
	)
	(zone
		(layer "In1.Cu")
		(hatch none 0.5)
		(connect_pads
			(clearance 0)
		)
		(min_thickness 0.25)
		(keepout
			(tracks not_allowed)
			(vias allowed)
			(pads allowed)
			(copperpour not_allowed)
			(footprints allowed)
		)
		(placement
			(enabled no)
			(sheetname "")
		)
		(fill
			(thermal_gap 0.5)
			(thermal_bridge_width 0.5)
			(island_removal_mode 0)
		)
		(polygon
			(pts
				(arc
					(start 86.34476 -40.51554)
					(mid 86.454319 -40.470159)
					(end 86.4997 -40.3606)
				)
				(arc
					(start 86.4997 -40.1574)
					(mid 86.454319 -40.047841)
					(end 86.34476 -40.00246)
				)
				(arc
					(start 86.09076 -40.00246)
					(mid 85.981201 -40.047841)
					(end 85.93582 -40.1574)
				)
				(arc
					(start 85.93582 -40.3606)
					(mid 85.981201 -40.470159)
					(end 86.09076 -40.51554)
				)
			)
		)
	)
	(zone
		(layer "In1.Cu")
		(hatch none 0.5)
		(connect_pads
			(clearance 0)
		)
		(min_thickness 0.25)
		(keepout
			(tracks not_allowed)
			(vias allowed)
			(pads allowed)
			(copperpour not_allowed)
			(footprints allowed)
		)
		(placement
			(enabled no)
			(sheetname "")
		)
		(fill
			(thermal_gap 0.5)
			(thermal_bridge_width 0.5)
			(island_removal_mode 0)
		)
		(polygon
			(pts
				(arc
					(start 119.77751 -114.4524)
					(mid 119.732129 -114.342841)
					(end 119.62257 -114.29746)
				)
				(arc
					(start 119.41937 -114.29746)
					(mid 119.309811 -114.342841)
					(end 119.26443 -114.4524)
				)
				(arc
					(start 119.26443 -114.7064)
					(mid 119.309811 -114.815959)
					(end 119.41937 -114.86134)
				)
				(arc
					(start 119.62257 -114.86134)
					(mid 119.732129 -114.815959)
					(end 119.77751 -114.7064)
				)
			)
		)
	)
	(zone
		(layer "In1.Cu")
		(hatch none 0.5)
		(connect_pads
			(clearance 0)
		)
		(min_thickness 0.25)
		(keepout
			(tracks not_allowed)
			(vias allowed)
			(pads allowed)
			(copperpour not_allowed)
			(footprints allowed)
		)
		(placement
			(enabled no)
			(sheetname "")
		)
		(fill
			(thermal_gap 0.5)
			(thermal_bridge_width 0.5)
			(island_removal_mode 0)
		)
		(polygon
			(pts
				(arc
					(start 53.118004 -77.80401)
					(mid 53.399944 -78.08595)
					(end 53.681884 -77.80401)
				)
				(arc
					(start 53.681884 -76.35621)
					(mid 53.399944 -76.07427)
					(end 53.118004 -76.35621)
				)
			)
		)
	)
	(zone
		(layer "In1.Cu")
		(hatch none 0.5)
		(connect_pads
			(clearance 0)
		)
		(min_thickness 0.25)
		(keepout
			(tracks not_allowed)
			(vias allowed)
			(pads allowed)
			(copperpour not_allowed)
			(footprints allowed)
		)
		(placement
			(enabled no)
			(sheetname "")
		)
		(fill
			(thermal_gap 0.5)
			(thermal_bridge_width 0.5)
			(island_removal_mode 0)
		)
		(polygon
			(pts
				(arc
					(start 52.717954 -80.314038)
					(mid 52.999894 -80.595978)
					(end 53.281834 -80.314038)
				)
				(arc
					(start 53.281834 -78.866238)
					(mid 52.999894 -78.584298)
					(end 52.717954 -78.866238)
				)
			)
		)
	)
	(zone
		(layer "In1.Cu")
		(hatch none 0.5)
		(connect_pads
			(clearance 0)
		)
		(min_thickness 0.25)
		(keepout
			(tracks not_allowed)
			(vias allowed)
			(pads allowed)
			(copperpour not_allowed)
			(footprints allowed)
		)
		(placement
			(enabled no)
			(sheetname "")
		)
		(fill
			(thermal_gap 0.5)
			(thermal_bridge_width 0.5)
			(island_removal_mode 0)
		)
		(polygon
			(pts
				(arc
					(start 348.438978 -154.333448)
					(mid 348.499238 -154.478928)
					(end 348.644718 -154.539188)
				)
				(arc
					(start 349.000318 -154.539188)
					(mid 349.145798 -154.478928)
					(end 349.206058 -154.333448)
				)
				(arc
					(start 349.206058 -153.977848)
					(mid 349.145798 -153.832368)
					(end 349.000318 -153.772108)
				)
				(arc
					(start 348.644718 -153.772108)
					(mid 348.499238 -153.832368)
					(end 348.438978 -153.977848)
				)
			)
		)
	)
	(zone
		(layer "In1.Cu")
		(hatch none 0.5)
		(connect_pads
			(clearance 0)
		)
		(min_thickness 0.25)
		(keepout
			(tracks not_allowed)
			(vias allowed)
			(pads allowed)
			(copperpour not_allowed)
			(footprints allowed)
		)
		(placement
			(enabled no)
			(sheetname "")
		)
		(fill
			(thermal_gap 0.5)
			(thermal_bridge_width 0.5)
			(island_removal_mode 0)
		)
		(polygon
			(pts
				(arc
					(start 276.672294 -24.976328)
					(mid 276.526814 -25.036588)
					(end 276.466554 -25.182068)
				)
				(arc
					(start 276.466554 -25.537668)
					(mid 276.526814 -25.683148)
					(end 276.672294 -25.743408)
				)
				(arc
					(start 277.027894 -25.743408)
					(mid 277.173374 -25.683148)
					(end 277.233634 -25.537668)
				)
				(arc
					(start 277.233634 -25.182068)
					(mid 277.173374 -25.036588)
					(end 277.027894 -24.976328)
				)
			)
		)
	)
	(zone
		(layer "In1.Cu")
		(hatch none 0.5)
		(connect_pads
			(clearance 0)
		)
		(min_thickness 0.25)
		(keepout
			(tracks not_allowed)
			(vias allowed)
			(pads allowed)
			(copperpour not_allowed)
			(footprints allowed)
		)
		(placement
			(enabled no)
			(sheetname "")
		)
		(fill
			(thermal_gap 0.5)
			(thermal_bridge_width 0.5)
			(island_removal_mode 0)
		)
		(polygon
			(pts
				(arc
					(start 112.66551 -114.4524)
					(mid 112.620129 -114.342841)
					(end 112.51057 -114.29746)
				)
				(arc
					(start 112.30737 -114.29746)
					(mid 112.197811 -114.342841)
					(end 112.15243 -114.4524)
				)
				(arc
					(start 112.15243 -114.7064)
					(mid 112.197811 -114.815959)
					(end 112.30737 -114.86134)
				)
				(arc
					(start 112.51057 -114.86134)
					(mid 112.620129 -114.815959)
					(end 112.66551 -114.7064)
				)
			)
		)
	)
	(zone
		(layer "In1.Cu")
		(hatch none 0.5)
		(connect_pads
			(clearance 0)
		)
		(min_thickness 0.25)
		(keepout
			(tracks not_allowed)
			(vias allowed)
			(pads allowed)
			(copperpour not_allowed)
			(footprints allowed)
		)
		(placement
			(enabled no)
			(sheetname "")
		)
		(fill
			(thermal_gap 0.5)
			(thermal_bridge_width 0.5)
			(island_removal_mode 0)
		)
		(polygon
			(pts
				(arc
					(start 86.34476 -33.27654)
					(mid 86.454319 -33.231159)
					(end 86.4997 -33.1216)
				)
				(arc
					(start 86.4997 -32.9184)
					(mid 86.454319 -32.808841)
					(end 86.34476 -32.76346)
				)
				(arc
					(start 86.09076 -32.76346)
					(mid 85.981201 -32.808841)
					(end 85.93582 -32.9184)
				)
				(arc
					(start 85.93582 -33.1216)
					(mid 85.981201 -33.231159)
					(end 86.09076 -33.27654)
				)
			)
		)
	)
	(zone
		(layer "In1.Cu")
		(hatch none 0.5)
		(connect_pads
			(clearance 0)
		)
		(min_thickness 0.25)
		(keepout
			(tracks not_allowed)
			(vias allowed)
			(pads allowed)
			(copperpour not_allowed)
			(footprints allowed)
		)
		(placement
			(enabled no)
			(sheetname "")
		)
		(fill
			(thermal_gap 0.5)
			(thermal_bridge_width 0.5)
			(island_removal_mode 0)
		)
		(polygon
			(pts
				(arc
					(start 131.92125 -99.07524)
					(mid 131.875869 -98.965681)
					(end 131.76631 -98.9203)
				)
				(arc
					(start 131.56311 -98.9203)
					(mid 131.453551 -98.965681)
					(end 131.40817 -99.07524)
				)
				(arc
					(start 131.40817 -99.32924)
					(mid 131.453551 -99.438799)
					(end 131.56311 -99.48418)
				)
				(arc
					(start 131.76631 -99.48418)
					(mid 131.875869 -99.438799)
					(end 131.92125 -99.32924)
				)
			)
		)
	)
	(zone
		(layer "In1.Cu")
		(hatch none 0.5)
		(connect_pads
			(clearance 0)
		)
		(min_thickness 0.25)
		(keepout
			(tracks not_allowed)
			(vias allowed)
			(pads allowed)
			(copperpour not_allowed)
			(footprints allowed)
		)
		(placement
			(enabled no)
			(sheetname "")
		)
		(fill
			(thermal_gap 0.5)
			(thermal_bridge_width 0.5)
			(island_removal_mode 0)
		)
		(polygon
			(pts
				(arc
					(start 114.319812 -222.93326)
					(mid 114.174332 -222.99352)
					(end 114.114072 -223.139)
				)
				(arc
					(start 114.114072 -223.4946)
					(mid 114.174332 -223.64008)
					(end 114.319812 -223.70034)
				)
				(arc
					(start 114.675412 -223.70034)
					(mid 114.820892 -223.64008)
					(end 114.881152 -223.4946)
				)
				(arc
					(start 114.881152 -223.139)
					(mid 114.820892 -222.99352)
					(end 114.675412 -222.93326)
				)
			)
		)
	)
	(zone
		(layer "In1.Cu")
		(hatch none 0.5)
		(connect_pads
			(clearance 0)
		)
		(min_thickness 0.25)
		(keepout
			(tracks not_allowed)
			(vias allowed)
			(pads allowed)
			(copperpour not_allowed)
			(footprints allowed)
		)
		(placement
			(enabled no)
			(sheetname "")
		)
		(fill
			(thermal_gap 0.5)
			(thermal_bridge_width 0.5)
			(island_removal_mode 0)
		)
		(polygon
			(pts
				(arc
					(start 133.330442 -84.270342)
					(mid 133.220883 -84.315723)
					(end 133.175502 -84.425282)
				)
				(arc
					(start 133.175502 -84.628482)
					(mid 133.220883 -84.738041)
					(end 133.330442 -84.783422)
				)
				(arc
					(start 133.584442 -84.783422)
					(mid 133.694001 -84.738041)
					(end 133.739382 -84.628482)
				)
				(arc
					(start 133.739382 -84.425282)
					(mid 133.694001 -84.315723)
					(end 133.584442 -84.270342)
				)
			)
		)
	)
	(zone
		(layer "In1.Cu")
		(hatch none 0.5)
		(connect_pads
			(clearance 0)
		)
		(min_thickness 0.25)
		(keepout
			(tracks not_allowed)
			(vias allowed)
			(pads allowed)
			(copperpour not_allowed)
			(footprints allowed)
		)
		(placement
			(enabled no)
			(sheetname "")
		)
		(fill
			(thermal_gap 0.5)
			(thermal_bridge_width 0.5)
			(island_removal_mode 0)
		)
		(polygon
			(pts
				(arc
					(start 119.374412 -206.68234)
					(mid 119.519892 -206.62208)
					(end 119.580152 -206.4766)
				)
				(arc
					(start 119.580152 -206.121)
					(mid 119.519892 -205.97552)
					(end 119.374412 -205.91526)
				)
				(arc
					(start 119.018812 -205.91526)
					(mid 118.873332 -205.97552)
					(end 118.813072 -206.121)
				)
				(arc
					(start 118.813072 -206.4766)
					(mid 118.873332 -206.62208)
					(end 119.018812 -206.68234)
				)
			)
		)
	)
	(zone
		(layer "In1.Cu")
		(hatch none 0.5)
		(connect_pads
			(clearance 0)
		)
		(min_thickness 0.25)
		(keepout
			(tracks not_allowed)
			(vias allowed)
			(pads allowed)
			(copperpour not_allowed)
			(footprints allowed)
		)
		(placement
			(enabled no)
			(sheetname "")
		)
		(fill
			(thermal_gap 0.5)
			(thermal_bridge_width 0.5)
			(island_removal_mode 0)
		)
		(polygon
			(pts
				(arc
					(start 348.438978 -148.872448)
					(mid 348.499238 -149.017928)
					(end 348.644718 -149.078188)
				)
				(arc
					(start 349.000318 -149.078188)
					(mid 349.145798 -149.017928)
					(end 349.206058 -148.872448)
				)
				(arc
					(start 349.206058 -148.516848)
					(mid 349.145798 -148.371368)
					(end 349.000318 -148.311108)
				)
				(arc
					(start 348.644718 -148.311108)
					(mid 348.499238 -148.371368)
					(end 348.438978 -148.516848)
				)
			)
		)
	)
	(zone
		(layer "In1.Cu")
		(hatch none 0.5)
		(connect_pads
			(clearance 0)
		)
		(min_thickness 0.25)
		(keepout
			(tracks not_allowed)
			(vias allowed)
			(pads allowed)
			(copperpour not_allowed)
			(footprints allowed)
		)
		(placement
			(enabled no)
			(sheetname "")
		)
		(fill
			(thermal_gap 0.5)
			(thermal_bridge_width 0.5)
			(island_removal_mode 0)
		)
		(polygon
			(pts
				(arc
					(start 101.99751 -114.4524)
					(mid 101.952129 -114.342841)
					(end 101.84257 -114.29746)
				)
				(arc
					(start 101.63937 -114.29746)
					(mid 101.529811 -114.342841)
					(end 101.48443 -114.4524)
				)
				(arc
					(start 101.48443 -114.7064)
					(mid 101.529811 -114.815959)
					(end 101.63937 -114.86134)
				)
				(arc
					(start 101.84257 -114.86134)
					(mid 101.952129 -114.815959)
					(end 101.99751 -114.7064)
				)
			)
		)
	)
	(zone
		(layer "In1.Cu")
		(hatch none 0.5)
		(connect_pads
			(clearance 0)
		)
		(min_thickness 0.25)
		(keepout
			(tracks not_allowed)
			(vias allowed)
			(pads allowed)
			(copperpour not_allowed)
			(footprints allowed)
		)
		(placement
			(enabled no)
			(sheetname "")
		)
		(fill
			(thermal_gap 0.5)
			(thermal_bridge_width 0.5)
			(island_removal_mode 0)
		)
		(polygon
			(pts
				(xy 109.281976 -1.303528) (xy 110.531656 -1.303528) (xy 110.531656 -2.756408) (xy 109.281976 -2.756408)
			)
		)
	)
	(zone
		(layer "In1.Cu")
		(hatch none 0.5)
		(connect_pads
			(clearance 0)
		)
		(min_thickness 0.25)
		(keepout
			(tracks not_allowed)
			(vias allowed)
			(pads allowed)
			(copperpour not_allowed)
			(footprints allowed)
		)
		(placement
			(enabled no)
			(sheetname "")
		)
		(fill
			(thermal_gap 0.5)
			(thermal_bridge_width 0.5)
			(island_removal_mode 0)
		)
		(polygon
			(pts
				(arc
					(start 50.317908 -80.314038)
					(mid 50.599848 -80.595978)
					(end 50.881788 -80.314038)
				)
				(arc
					(start 50.881788 -78.866238)
					(mid 50.599848 -78.584298)
					(end 50.317908 -78.866238)
				)
			)
		)
	)
	(zone
		(layer "In1.Cu")
		(hatch none 0.5)
		(connect_pads
			(clearance 0)
		)
		(min_thickness 0.25)
		(keepout
			(tracks not_allowed)
			(vias allowed)
			(pads allowed)
			(copperpour not_allowed)
			(footprints allowed)
		)
		(placement
			(enabled no)
			(sheetname "")
		)
		(fill
			(thermal_gap 0.5)
			(thermal_bridge_width 0.5)
			(island_removal_mode 0)
		)
		(polygon
			(pts
				(arc
					(start 118.63451 -113.8936)
					(mid 118.589129 -113.784041)
					(end 118.47957 -113.73866)
				)
				(arc
					(start 118.27637 -113.73866)
					(mid 118.166811 -113.784041)
					(end 118.12143 -113.8936)
				)
				(arc
					(start 118.12143 -114.1476)
					(mid 118.166811 -114.257159)
					(end 118.27637 -114.30254)
				)
				(arc
					(start 118.47957 -114.30254)
					(mid 118.589129 -114.257159)
					(end 118.63451 -114.1476)
				)
			)
		)
	)
	(zone
		(layer "In1.Cu")
		(hatch none 0.5)
		(connect_pads
			(clearance 0)
		)
		(min_thickness 0.25)
		(keepout
			(tracks not_allowed)
			(vias allowed)
			(pads allowed)
			(copperpour not_allowed)
			(footprints allowed)
		)
		(placement
			(enabled no)
			(sheetname "")
		)
		(fill
			(thermal_gap 0.5)
			(thermal_bridge_width 0.5)
			(island_removal_mode 0)
		)
		(polygon
			(pts
				(arc
					(start 86.34476 -35.56254)
					(mid 86.454319 -35.517159)
					(end 86.4997 -35.4076)
				)
				(arc
					(start 86.4997 -35.2044)
					(mid 86.454319 -35.094841)
					(end 86.34476 -35.04946)
				)
				(arc
					(start 86.09076 -35.04946)
					(mid 85.981201 -35.094841)
					(end 85.93582 -35.2044)
				)
				(arc
					(start 85.93582 -35.4076)
					(mid 85.981201 -35.517159)
					(end 86.09076 -35.56254)
				)
			)
		)
	)
	(zone
		(layer "In1.Cu")
		(hatch none 0.5)
		(connect_pads
			(clearance 0)
		)
		(min_thickness 0.25)
		(keepout
			(tracks not_allowed)
			(vias allowed)
			(pads allowed)
			(copperpour not_allowed)
			(footprints allowed)
		)
		(placement
			(enabled no)
			(sheetname "")
		)
		(fill
			(thermal_gap 0.5)
			(thermal_bridge_width 0.5)
			(island_removal_mode 0)
		)
		(polygon
			(pts
				(arc
					(start 133.62051 -98.3996)
					(mid 133.575129 -98.290041)
					(end 133.46557 -98.24466)
				)
				(arc
					(start 133.26237 -98.24466)
					(mid 133.152811 -98.290041)
					(end 133.10743 -98.3996)
				)
				(arc
					(start 133.10743 -98.6536)
					(mid 133.152811 -98.763159)
					(end 133.26237 -98.80854)
				)
				(arc
					(start 133.46557 -98.80854)
					(mid 133.575129 -98.763159)
					(end 133.62051 -98.6536)
				)
			)
		)
	)
	(zone
		(layer "In1.Cu")
		(hatch none 0.5)
		(connect_pads
			(clearance 0)
		)
		(min_thickness 0.25)
		(keepout
			(tracks not_allowed)
			(vias allowed)
			(pads allowed)
			(copperpour not_allowed)
			(footprints allowed)
		)
		(placement
			(enabled no)
			(sheetname "")
		)
		(fill
			(thermal_gap 0.5)
			(thermal_bridge_width 0.5)
			(island_removal_mode 0)
		)
		(polygon
			(pts
				(arc
					(start 131.4704 -87.62746)
					(mid 131.360841 -87.672841)
					(end 131.31546 -87.7824)
				)
				(arc
					(start 131.31546 -87.9856)
					(mid 131.360841 -88.095159)
					(end 131.4704 -88.14054)
				)
				(arc
					(start 131.7244 -88.14054)
					(mid 131.833959 -88.095159)
					(end 131.87934 -87.9856)
				)
				(arc
					(start 131.87934 -87.7824)
					(mid 131.833959 -87.672841)
					(end 131.7244 -87.62746)
				)
			)
		)
	)
	(zone
		(layer "In1.Cu")
		(hatch none 0.5)
		(connect_pads
			(clearance 0)
		)
		(min_thickness 0.25)
		(keepout
			(tracks not_allowed)
			(vias allowed)
			(pads allowed)
			(copperpour not_allowed)
			(footprints allowed)
		)
		(placement
			(enabled no)
			(sheetname "")
		)
		(fill
			(thermal_gap 0.5)
			(thermal_bridge_width 0.5)
			(island_removal_mode 0)
		)
		(polygon
			(pts
				(arc
					(start 131.4704 -90.16746)
					(mid 131.360841 -90.212841)
					(end 131.31546 -90.3224)
				)
				(arc
					(start 131.31546 -90.5256)
					(mid 131.360841 -90.635159)
					(end 131.4704 -90.68054)
				)
				(arc
					(start 131.7244 -90.68054)
					(mid 131.833959 -90.635159)
					(end 131.87934 -90.5256)
				)
				(arc
					(start 131.87934 -90.3224)
					(mid 131.833959 -90.212841)
					(end 131.7244 -90.16746)
				)
			)
		)
	)
	(zone
		(layer "In1.Cu")
		(hatch none 0.5)
		(connect_pads
			(clearance 0)
		)
		(min_thickness 0.25)
		(keepout
			(tracks not_allowed)
			(vias allowed)
			(pads allowed)
			(copperpour not_allowed)
			(footprints allowed)
		)
		(placement
			(enabled no)
			(sheetname "")
		)
		(fill
			(thermal_gap 0.5)
			(thermal_bridge_width 0.5)
			(island_removal_mode 0)
		)
		(polygon
			(pts
				(arc
					(start 86.90356 -43.81754)
					(mid 87.013119 -43.772159)
					(end 87.0585 -43.6626)
				)
				(arc
					(start 87.0585 -43.4594)
					(mid 87.013119 -43.349841)
					(end 86.90356 -43.30446)
				)
				(arc
					(start 86.64956 -43.30446)
					(mid 86.540001 -43.349841)
					(end 86.49462 -43.4594)
				)
				(arc
					(start 86.49462 -43.6626)
					(mid 86.540001 -43.772159)
					(end 86.64956 -43.81754)
				)
			)
		)
	)
	(zone
		(layer "In1.Cu")
		(hatch none 0.5)
		(connect_pads
			(clearance 0)
		)
		(min_thickness 0.25)
		(keepout
			(tracks not_allowed)
			(vias allowed)
			(pads allowed)
			(copperpour not_allowed)
			(footprints allowed)
		)
		(placement
			(enabled no)
			(sheetname "")
		)
		(fill
			(thermal_gap 0.5)
			(thermal_bridge_width 0.5)
			(island_removal_mode 0)
		)
		(polygon
			(pts
				(arc
					(start 106.18851 -113.8936)
					(mid 106.143129 -113.784041)
					(end 106.03357 -113.73866)
				)
				(arc
					(start 105.83037 -113.73866)
					(mid 105.720811 -113.784041)
					(end 105.67543 -113.8936)
				)
				(arc
					(start 105.67543 -114.1476)
					(mid 105.720811 -114.257159)
					(end 105.83037 -114.30254)
				)
				(arc
					(start 106.03357 -114.30254)
					(mid 106.143129 -114.257159)
					(end 106.18851 -114.1476)
				)
			)
		)
	)
	(zone
		(layer "In1.Cu")
		(hatch none 0.5)
		(connect_pads
			(clearance 0)
		)
		(min_thickness 0.25)
		(keepout
			(tracks not_allowed)
			(vias allowed)
			(pads allowed)
			(copperpour not_allowed)
			(footprints allowed)
		)
		(placement
			(enabled no)
			(sheetname "")
		)
		(fill
			(thermal_gap 0.5)
			(thermal_bridge_width 0.5)
			(island_removal_mode 0)
		)
		(polygon
			(pts
				(arc
					(start 347.575378 -150.015448)
					(mid 347.635638 -150.160928)
					(end 347.781118 -150.221188)
				)
				(arc
					(start 348.136718 -150.221188)
					(mid 348.282198 -150.160928)
					(end 348.342458 -150.015448)
				)
				(arc
					(start 348.342458 -149.659848)
					(mid 348.282198 -149.514368)
					(end 348.136718 -149.454108)
				)
				(arc
					(start 347.781118 -149.454108)
					(mid 347.635638 -149.514368)
					(end 347.575378 -149.659848)
				)
			)
		)
	)
	(zone
		(layer "In1.Cu")
		(hatch none 0.5)
		(connect_pads
			(clearance 0)
		)
		(min_thickness 0.25)
		(keepout
			(tracks not_allowed)
			(vias allowed)
			(pads allowed)
			(copperpour not_allowed)
			(footprints allowed)
		)
		(placement
			(enabled no)
			(sheetname "")
		)
		(fill
			(thermal_gap 0.5)
			(thermal_bridge_width 0.5)
			(island_removal_mode 0)
		)
		(polygon
			(pts
				(arc
					(start 132.98551 -98.3996)
					(mid 132.940129 -98.290041)
					(end 132.83057 -98.24466)
				)
				(arc
					(start 132.62737 -98.24466)
					(mid 132.517811 -98.290041)
					(end 132.47243 -98.3996)
				)
				(arc
					(start 132.47243 -98.6536)
					(mid 132.517811 -98.763159)
					(end 132.62737 -98.80854)
				)
				(arc
					(start 132.83057 -98.80854)
					(mid 132.940129 -98.763159)
					(end 132.98551 -98.6536)
				)
			)
		)
	)
	(zone
		(layer "In1.Cu")
		(hatch none 0.5)
		(connect_pads
			(clearance 0)
		)
		(min_thickness 0.25)
		(keepout
			(tracks not_allowed)
			(vias allowed)
			(pads allowed)
			(copperpour not_allowed)
			(footprints allowed)
		)
		(placement
			(enabled no)
			(sheetname "")
		)
		(fill
			(thermal_gap 0.5)
			(thermal_bridge_width 0.5)
			(island_removal_mode 0)
		)
		(polygon
			(pts
				(arc
					(start 16.51762 -100.704142)
					(mid 16.79956 -100.986082)
					(end 17.0815 -100.704142)
				)
				(arc
					(start 17.0815 -99.256342)
					(mid 16.79956 -98.974402)
					(end 16.51762 -99.256342)
				)
			)
		)
	)
	(zone
		(layer "In1.Cu")
		(hatch none 0.5)
		(connect_pads
			(clearance 0)
		)
		(min_thickness 0.25)
		(keepout
			(tracks not_allowed)
			(vias allowed)
			(pads allowed)
			(copperpour not_allowed)
			(footprints allowed)
		)
		(placement
			(enabled no)
			(sheetname "")
		)
		(fill
			(thermal_gap 0.5)
			(thermal_bridge_width 0.5)
			(island_removal_mode 0)
		)
		(polygon
			(pts
				(arc
					(start 112.66551 -113.8936)
					(mid 112.620129 -113.784041)
					(end 112.51057 -113.73866)
				)
				(arc
					(start 112.30737 -113.73866)
					(mid 112.197811 -113.784041)
					(end 112.15243 -113.8936)
				)
				(arc
					(start 112.15243 -114.1476)
					(mid 112.197811 -114.257159)
					(end 112.30737 -114.30254)
				)
				(arc
					(start 112.51057 -114.30254)
					(mid 112.620129 -114.257159)
					(end 112.66551 -114.1476)
				)
			)
		)
	)
	(zone
		(layer "In1.Cu")
		(hatch none 0.5)
		(connect_pads
			(clearance 0)
		)
		(min_thickness 0.25)
		(keepout
			(tracks not_allowed)
			(vias allowed)
			(pads allowed)
			(copperpour not_allowed)
			(footprints allowed)
		)
		(placement
			(enabled no)
			(sheetname "")
		)
		(fill
			(thermal_gap 0.5)
			(thermal_bridge_width 0.5)
			(island_removal_mode 0)
		)
		(polygon
			(pts
				(arc
					(start 112.668812 -222.06966)
					(mid 112.523332 -222.12992)
					(end 112.463072 -222.2754)
				)
				(arc
					(start 112.463072 -222.631)
					(mid 112.523332 -222.77648)
					(end 112.668812 -222.83674)
				)
				(arc
					(start 113.024412 -222.83674)
					(mid 113.169892 -222.77648)
					(end 113.230152 -222.631)
				)
				(arc
					(start 113.230152 -222.2754)
					(mid 113.169892 -222.12992)
					(end 113.024412 -222.06966)
				)
			)
		)
	)
	(zone
		(layer "In1.Cu")
		(hatch none 0.5)
		(connect_pads
			(clearance 0)
		)
		(min_thickness 0.25)
		(keepout
			(tracks not_allowed)
			(vias allowed)
			(pads allowed)
			(copperpour not_allowed)
			(footprints allowed)
		)
		(placement
			(enabled no)
			(sheetname "")
		)
		(fill
			(thermal_gap 0.5)
			(thermal_bridge_width 0.5)
			(island_removal_mode 0)
		)
		(polygon
			(pts
				(arc
					(start 104.41051 -113.8936)
					(mid 104.365129 -113.784041)
					(end 104.25557 -113.73866)
				)
				(arc
					(start 104.05237 -113.73866)
					(mid 103.942811 -113.784041)
					(end 103.89743 -113.8936)
				)
				(arc
					(start 103.89743 -114.1476)
					(mid 103.942811 -114.257159)
					(end 104.05237 -114.30254)
				)
				(arc
					(start 104.25557 -114.30254)
					(mid 104.365129 -114.257159)
					(end 104.41051 -114.1476)
				)
			)
		)
	)
	(zone
		(layer "In1.Cu")
		(hatch none 0.5)
		(connect_pads
			(clearance 0)
		)
		(min_thickness 0.25)
		(keepout
			(tracks not_allowed)
			(vias allowed)
			(pads allowed)
			(copperpour not_allowed)
			(footprints allowed)
		)
		(placement
			(enabled no)
			(sheetname "")
		)
		(fill
			(thermal_gap 0.5)
			(thermal_bridge_width 0.5)
			(island_removal_mode 0)
		)
		(polygon
			(pts
				(arc
					(start 86.34476 -36.57854)
					(mid 86.454319 -36.533159)
					(end 86.4997 -36.4236)
				)
				(arc
					(start 86.4997 -36.2204)
					(mid 86.454319 -36.110841)
					(end 86.34476 -36.06546)
				)
				(arc
					(start 86.09076 -36.06546)
					(mid 85.981201 -36.110841)
					(end 85.93582 -36.2204)
				)
				(arc
					(start 85.93582 -36.4236)
					(mid 85.981201 -36.533159)
					(end 86.09076 -36.57854)
				)
			)
		)
	)
	(zone
		(layer "In1.Cu")
		(hatch none 0.5)
		(connect_pads
			(clearance 0)
		)
		(min_thickness 0.25)
		(keepout
			(tracks not_allowed)
			(vias allowed)
			(pads allowed)
			(copperpour not_allowed)
			(footprints allowed)
		)
		(placement
			(enabled no)
			(sheetname "")
		)
		(fill
			(thermal_gap 0.5)
			(thermal_bridge_width 0.5)
			(island_removal_mode 0)
		)
		(polygon
			(pts
				(arc
					(start 105.55351 -113.8936)
					(mid 105.508129 -113.784041)
					(end 105.39857 -113.73866)
				)
				(arc
					(start 105.19537 -113.73866)
					(mid 105.085811 -113.784041)
					(end 105.04043 -113.8936)
				)
				(arc
					(start 105.04043 -114.1476)
					(mid 105.085811 -114.257159)
					(end 105.19537 -114.30254)
				)
				(arc
					(start 105.39857 -114.30254)
					(mid 105.508129 -114.257159)
					(end 105.55351 -114.1476)
				)
			)
		)
	)
	(zone
		(layer "In1.Cu")
		(hatch none 0.5)
		(connect_pads
			(clearance 0)
		)
		(min_thickness 0.25)
		(keepout
			(tracks not_allowed)
			(vias allowed)
			(pads allowed)
			(copperpour not_allowed)
			(footprints allowed)
		)
		(placement
			(enabled no)
			(sheetname "")
		)
		(fill
			(thermal_gap 0.5)
			(thermal_bridge_width 0.5)
			(island_removal_mode 0)
		)
		(polygon
			(pts
				(arc
					(start 115.07851 -114.4524)
					(mid 115.033129 -114.342841)
					(end 114.92357 -114.29746)
				)
				(arc
					(start 114.72037 -114.29746)
					(mid 114.610811 -114.342841)
					(end 114.56543 -114.4524)
				)
				(arc
					(start 114.56543 -114.7064)
					(mid 114.610811 -114.815959)
					(end 114.72037 -114.86134)
				)
				(arc
					(start 114.92357 -114.86134)
					(mid 115.033129 -114.815959)
					(end 115.07851 -114.7064)
				)
			)
		)
	)
	(zone
		(layer "In1.Cu")
		(hatch none 0.5)
		(connect_pads
			(clearance 0)
		)
		(min_thickness 0.25)
		(keepout
			(tracks not_allowed)
			(vias allowed)
			(pads allowed)
			(copperpour not_allowed)
			(footprints allowed)
		)
		(placement
			(enabled no)
			(sheetname "")
		)
		(fill
			(thermal_gap 0.5)
			(thermal_bridge_width 0.5)
			(island_removal_mode 0)
		)
		(polygon
			(pts
				(arc
					(start 347.575378 -152.047448)
					(mid 347.635638 -152.192928)
					(end 347.781118 -152.253188)
				)
				(arc
					(start 348.136718 -152.253188)
					(mid 348.282198 -152.192928)
					(end 348.342458 -152.047448)
				)
				(arc
					(start 348.342458 -151.691848)
					(mid 348.282198 -151.546368)
					(end 348.136718 -151.486108)
				)
				(arc
					(start 347.781118 -151.486108)
					(mid 347.635638 -151.546368)
					(end 347.575378 -151.691848)
				)
			)
		)
	)
	(zone
		(layer "In1.Cu")
		(hatch none 0.5)
		(connect_pads
			(clearance 0)
		)
		(min_thickness 0.25)
		(keepout
			(tracks not_allowed)
			(vias allowed)
			(pads allowed)
			(copperpour not_allowed)
			(footprints allowed)
		)
		(placement
			(enabled no)
			(sheetname "")
		)
		(fill
			(thermal_gap 0.5)
			(thermal_bridge_width 0.5)
			(island_removal_mode 0)
		)
		(polygon
			(pts
				(arc
					(start 130.663442 -84.143342)
					(mid 130.553883 -84.188723)
					(end 130.508502 -84.298282)
				)
				(arc
					(start 130.508502 -84.501482)
					(mid 130.553883 -84.611041)
					(end 130.663442 -84.656422)
				)
				(arc
					(start 130.917442 -84.656422)
					(mid 131.027001 -84.611041)
					(end 131.072382 -84.501482)
				)
				(arc
					(start 131.072382 -84.298282)
					(mid 131.027001 -84.188723)
					(end 130.917442 -84.143342)
				)
			)
		)
	)
	(zone
		(layer "In1.Cu")
		(hatch none 0.5)
		(connect_pads
			(clearance 0)
		)
		(min_thickness 0.25)
		(keepout
			(tracks not_allowed)
			(vias allowed)
			(pads allowed)
			(copperpour not_allowed)
			(footprints allowed)
		)
		(placement
			(enabled no)
			(sheetname "")
		)
		(fill
			(thermal_gap 0.5)
			(thermal_bridge_width 0.5)
			(island_removal_mode 0)
		)
		(polygon
			(pts
				(xy 307.594 -80.6958) (xy 307.594 -79.2988) (xy 309.753 -79.2988) (xy 309.753 -80.6958)
			)
		)
	)
	(zone
		(layer "In1.Cu")
		(hatch none 0.5)
		(connect_pads
			(clearance 0)
		)
		(min_thickness 0.25)
		(keepout
			(tracks not_allowed)
			(vias allowed)
			(pads allowed)
			(copperpour not_allowed)
			(footprints allowed)
		)
		(placement
			(enabled no)
			(sheetname "")
		)
		(fill
			(thermal_gap 0.5)
			(thermal_bridge_width 0.5)
			(island_removal_mode 0)
		)
		(polygon
			(pts
				(arc
					(start 135.39851 -98.3996)
					(mid 135.353129 -98.290041)
					(end 135.24357 -98.24466)
				)
				(arc
					(start 135.04037 -98.24466)
					(mid 134.930811 -98.290041)
					(end 134.88543 -98.3996)
				)
				(arc
					(start 134.88543 -98.6536)
					(mid 134.930811 -98.763159)
					(end 135.04037 -98.80854)
				)
				(arc
					(start 135.24357 -98.80854)
					(mid 135.353129 -98.763159)
					(end 135.39851 -98.6536)
				)
			)
		)
	)
	(zone
		(layer "In1.Cu")
		(hatch none 0.5)
		(connect_pads
			(clearance 0)
		)
		(min_thickness 0.25)
		(keepout
			(tracks not_allowed)
			(vias allowed)
			(pads allowed)
			(copperpour not_allowed)
			(footprints allowed)
		)
		(placement
			(enabled no)
			(sheetname "")
		)
		(fill
			(thermal_gap 0.5)
			(thermal_bridge_width 0.5)
			(island_removal_mode 0)
		)
		(polygon
			(pts
				(arc
					(start 112.668812 -222.93326)
					(mid 112.523332 -222.99352)
					(end 112.463072 -223.139)
				)
				(arc
					(start 112.463072 -223.4946)
					(mid 112.523332 -223.64008)
					(end 112.668812 -223.70034)
				)
				(arc
					(start 113.024412 -223.70034)
					(mid 113.169892 -223.64008)
					(end 113.230152 -223.4946)
				)
				(arc
					(start 113.230152 -223.139)
					(mid 113.169892 -222.99352)
					(end 113.024412 -222.93326)
				)
			)
		)
	)
	(zone
		(layer "In1.Cu")
		(hatch none 0.5)
		(connect_pads
			(clearance 0)
		)
		(min_thickness 0.25)
		(keepout
			(tracks not_allowed)
			(vias allowed)
			(pads allowed)
			(copperpour not_allowed)
			(footprints allowed)
		)
		(placement
			(enabled no)
			(sheetname "")
		)
		(fill
			(thermal_gap 0.5)
			(thermal_bridge_width 0.5)
			(island_removal_mode 0)
		)
		(polygon
			(pts
				(arc
					(start 120.669812 -204.16266)
					(mid 120.524332 -204.22292)
					(end 120.464072 -204.3684)
				)
				(arc
					(start 120.464072 -204.724)
					(mid 120.524332 -204.86948)
					(end 120.669812 -204.92974)
				)
				(arc
					(start 121.025412 -204.92974)
					(mid 121.170892 -204.86948)
					(end 121.231152 -204.724)
				)
				(arc
					(start 121.231152 -204.3684)
					(mid 121.170892 -204.22292)
					(end 121.025412 -204.16266)
				)
			)
		)
	)
	(zone
		(layer "In1.Cu")
		(hatch none 0.5)
		(connect_pads
			(clearance 0)
		)
		(min_thickness 0.25)
		(keepout
			(tracks not_allowed)
			(vias allowed)
			(pads allowed)
			(copperpour not_allowed)
			(footprints allowed)
		)
		(placement
			(enabled no)
			(sheetname "")
		)
		(fill
			(thermal_gap 0.5)
			(thermal_bridge_width 0.5)
			(island_removal_mode 0)
		)
		(polygon
			(pts
				(arc
					(start 277.688294 -25.839928)
					(mid 277.542814 -25.900188)
					(end 277.482554 -26.045668)
				)
				(arc
					(start 277.482554 -26.401268)
					(mid 277.542814 -26.546748)
					(end 277.688294 -26.607008)
				)
				(arc
					(start 278.043894 -26.607008)
					(mid 278.189374 -26.546748)
					(end 278.249634 -26.401268)
				)
				(arc
					(start 278.249634 -26.045668)
					(mid 278.189374 -25.900188)
					(end 278.043894 -25.839928)
				)
			)
		)
	)
	(zone
		(layer "In1.Cu")
		(hatch none 0.5)
		(connect_pads
			(clearance 0)
		)
		(min_thickness 0.25)
		(keepout
			(tracks not_allowed)
			(vias allowed)
			(pads allowed)
			(copperpour not_allowed)
			(footprints allowed)
		)
		(placement
			(enabled no)
			(sheetname "")
		)
		(fill
			(thermal_gap 0.5)
			(thermal_bridge_width 0.5)
			(island_removal_mode 0)
		)
		(polygon
			(pts
				(arc
					(start 13.71854 -103.213662)
					(mid 14.00048 -103.495602)
					(end 14.28242 -103.213662)
				)
				(arc
					(start 14.28242 -101.765862)
					(mid 14.00048 -101.483922)
					(end 13.71854 -101.765862)
				)
			)
		)
	)
	(zone
		(layer "In1.Cu")
		(hatch none 0.5)
		(connect_pads
			(clearance 0)
		)
		(min_thickness 0.25)
		(keepout
			(tracks not_allowed)
			(vias allowed)
			(pads allowed)
			(copperpour not_allowed)
			(footprints allowed)
		)
		(placement
			(enabled no)
			(sheetname "")
		)
		(fill
			(thermal_gap 0.5)
			(thermal_bridge_width 0.5)
			(island_removal_mode 0)
		)
		(polygon
			(pts
				(arc
					(start 131.222242 -84.143342)
					(mid 131.112683 -84.188723)
					(end 131.067302 -84.298282)
				)
				(arc
					(start 131.067302 -84.501482)
					(mid 131.112683 -84.611041)
					(end 131.222242 -84.656422)
				)
				(arc
					(start 131.476242 -84.656422)
					(mid 131.585801 -84.611041)
					(end 131.631182 -84.501482)
				)
				(arc
					(start 131.631182 -84.298282)
					(mid 131.585801 -84.188723)
					(end 131.476242 -84.143342)
				)
			)
		)
	)
	(zone
		(layer "In1.Cu")
		(hatch none 0.5)
		(connect_pads
			(clearance 0)
		)
		(min_thickness 0.25)
		(keepout
			(tracks not_allowed)
			(vias allowed)
			(pads allowed)
			(copperpour not_allowed)
			(footprints allowed)
		)
		(placement
			(enabled no)
			(sheetname "")
		)
		(fill
			(thermal_gap 0.5)
			(thermal_bridge_width 0.5)
			(island_removal_mode 0)
		)
		(polygon
			(pts
				(arc
					(start 109.74451 -114.4524)
					(mid 109.699129 -114.342841)
					(end 109.58957 -114.29746)
				)
				(arc
					(start 109.38637 -114.29746)
					(mid 109.276811 -114.342841)
					(end 109.23143 -114.4524)
				)
				(arc
					(start 109.23143 -114.7064)
					(mid 109.276811 -114.815959)
					(end 109.38637 -114.86134)
				)
				(arc
					(start 109.58957 -114.86134)
					(mid 109.699129 -114.815959)
					(end 109.74451 -114.7064)
				)
			)
		)
	)
	(zone
		(layer "In1.Cu")
		(hatch none 0.5)
		(connect_pads
			(clearance 0)
		)
		(min_thickness 0.25)
		(keepout
			(tracks not_allowed)
			(vias allowed)
			(pads allowed)
			(copperpour not_allowed)
			(footprints allowed)
		)
		(placement
			(enabled no)
			(sheetname "")
		)
		(fill
			(thermal_gap 0.5)
			(thermal_bridge_width 0.5)
			(island_removal_mode 0)
		)
		(polygon
			(pts
				(arc
					(start 131.641342 -80.994758)
					(mid 131.686723 -81.104317)
					(end 131.796282 -81.149698)
				)
				(arc
					(start 131.999482 -81.149698)
					(mid 132.109041 -81.104317)
					(end 132.154422 -80.994758)
				)
				(arc
					(start 132.154422 -80.740758)
					(mid 132.109041 -80.631199)
					(end 131.999482 -80.585818)
				)
				(arc
					(start 131.796282 -80.585818)
					(mid 131.686723 -80.631199)
					(end 131.641342 -80.740758)
				)
			)
		)
	)
	(zone
		(layer "In1.Cu")
		(hatch none 0.5)
		(connect_pads
			(clearance 0)
		)
		(min_thickness 0.25)
		(keepout
			(tracks not_allowed)
			(vias allowed)
			(pads allowed)
			(copperpour not_allowed)
			(footprints allowed)
		)
		(placement
			(enabled no)
			(sheetname "")
		)
		(fill
			(thermal_gap 0.5)
			(thermal_bridge_width 0.5)
			(island_removal_mode 0)
		)
		(polygon
			(pts
				(arc
					(start 114.44351 -113.8936)
					(mid 114.398129 -113.784041)
					(end 114.28857 -113.73866)
				)
				(arc
					(start 114.08537 -113.73866)
					(mid 113.975811 -113.784041)
					(end 113.93043 -113.8936)
				)
				(arc
					(start 113.93043 -114.1476)
					(mid 113.975811 -114.257159)
					(end 114.08537 -114.30254)
				)
				(arc
					(start 114.28857 -114.30254)
					(mid 114.398129 -114.257159)
					(end 114.44351 -114.1476)
				)
			)
		)
	)
	(zone
		(layer "In1.Cu")
		(hatch none 0.5)
		(connect_pads
			(clearance 0)
		)
		(min_thickness 0.25)
		(keepout
			(tracks not_allowed)
			(vias allowed)
			(pads allowed)
			(copperpour not_allowed)
			(footprints allowed)
		)
		(placement
			(enabled no)
			(sheetname "")
		)
		(fill
			(thermal_gap 0.5)
			(thermal_bridge_width 0.5)
			(island_removal_mode 0)
		)
		(polygon
			(pts
				(xy 276.441154 -26.068528) (xy 277.309834 -26.068528) (xy 277.309834 -27.191208) (xy 276.441154 -27.191208)
			)
		)
	)
	(zone
		(layer "In1.Cu")
		(hatch none 0.5)
		(connect_pads
			(clearance 0)
		)
		(min_thickness 0.25)
		(keepout
			(tracks not_allowed)
			(vias allowed)
			(pads allowed)
			(copperpour not_allowed)
			(footprints allowed)
		)
		(placement
			(enabled no)
			(sheetname "")
		)
		(fill
			(thermal_gap 0.5)
			(thermal_bridge_width 0.5)
			(island_removal_mode 0)
		)
		(polygon
			(pts
				(arc
					(start 112.795812 -205.02626)
					(mid 112.650332 -205.08652)
					(end 112.590072 -205.232)
				)
				(arc
					(start 112.590072 -205.5876)
					(mid 112.650332 -205.73308)
					(end 112.795812 -205.79334)
				)
				(arc
					(start 113.151412 -205.79334)
					(mid 113.296892 -205.73308)
					(end 113.357152 -205.5876)
				)
				(arc
					(start 113.357152 -205.232)
					(mid 113.296892 -205.08652)
					(end 113.151412 -205.02626)
				)
			)
		)
	)
	(zone
		(layer "In1.Cu")
		(hatch none 0.5)
		(connect_pads
			(clearance 0)
		)
		(min_thickness 0.25)
		(keepout
			(tracks not_allowed)
			(vias allowed)
			(pads allowed)
			(copperpour not_allowed)
			(footprints allowed)
		)
		(placement
			(enabled no)
			(sheetname "")
		)
		(fill
			(thermal_gap 0.5)
			(thermal_bridge_width 0.5)
			(island_removal_mode 0)
		)
		(polygon
			(pts
				(arc
					(start 43.91787 -80.314038)
					(mid 44.19981 -80.595978)
					(end 44.48175 -80.314038)
				)
				(arc
					(start 44.48175 -78.866238)
					(mid 44.19981 -78.584298)
					(end 43.91787 -78.866238)
				)
			)
		)
	)
	(zone
		(layer "In1.Cu")
		(hatch none 0.5)
		(connect_pads
			(clearance 0)
		)
		(min_thickness 0.25)
		(keepout
			(tracks not_allowed)
			(vias allowed)
			(pads allowed)
			(copperpour not_allowed)
			(footprints allowed)
		)
		(placement
			(enabled no)
			(sheetname "")
		)
		(fill
			(thermal_gap 0.5)
			(thermal_bridge_width 0.5)
			(island_removal_mode 0)
		)
		(polygon
			(pts
				(arc
					(start 120.41251 -114.4524)
					(mid 120.367129 -114.342841)
					(end 120.25757 -114.29746)
				)
				(arc
					(start 120.05437 -114.29746)
					(mid 119.944811 -114.342841)
					(end 119.89943 -114.4524)
				)
				(arc
					(start 119.89943 -114.7064)
					(mid 119.944811 -114.815959)
					(end 120.05437 -114.86134)
				)
				(arc
					(start 120.25757 -114.86134)
					(mid 120.367129 -114.815959)
					(end 120.41251 -114.7064)
				)
			)
		)
	)
	(zone
		(layer "In1.Cu")
		(hatch none 0.5)
		(connect_pads
			(clearance 0)
		)
		(min_thickness 0.25)
		(keepout
			(tracks not_allowed)
			(vias allowed)
			(pads allowed)
			(copperpour not_allowed)
			(footprints allowed)
		)
		(placement
			(enabled no)
			(sheetname "")
		)
		(fill
			(thermal_gap 0.5)
			(thermal_bridge_width 0.5)
			(island_removal_mode 0)
		)
		(polygon
			(pts
				(arc
					(start 120.517412 -221.94774)
					(mid 120.662892 -221.88748)
					(end 120.723152 -221.742)
				)
				(arc
					(start 120.723152 -221.3864)
					(mid 120.662892 -221.24092)
					(end 120.517412 -221.18066)
				)
				(arc
					(start 120.161812 -221.18066)
					(mid 120.016332 -221.24092)
					(end 119.956072 -221.3864)
				)
				(arc
					(start 119.956072 -221.742)
					(mid 120.016332 -221.88748)
					(end 120.161812 -221.94774)
				)
			)
		)
	)
	(zone
		(layer "In1.Cu")
		(hatch none 0.5)
		(connect_pads
			(clearance 0)
		)
		(min_thickness 0.25)
		(keepout
			(tracks not_allowed)
			(vias allowed)
			(pads allowed)
			(copperpour not_allowed)
			(footprints allowed)
		)
		(placement
			(enabled no)
			(sheetname "")
		)
		(fill
			(thermal_gap 0.5)
			(thermal_bridge_width 0.5)
			(island_removal_mode 0)
		)
		(polygon
			(pts
				(arc
					(start 11.31824 -103.213662)
					(mid 11.60018 -103.495602)
					(end 11.88212 -103.213662)
				)
				(arc
					(start 11.88212 -101.765862)
					(mid 11.60018 -101.483922)
					(end 11.31824 -101.765862)
				)
			)
		)
	)
	(zone
		(layer "In1.Cu")
		(hatch none 0.5)
		(connect_pads
			(clearance 0)
		)
		(min_thickness 0.25)
		(keepout
			(tracks not_allowed)
			(vias allowed)
			(pads allowed)
			(copperpour not_allowed)
			(footprints allowed)
		)
		(placement
			(enabled no)
			(sheetname "")
		)
		(fill
			(thermal_gap 0.5)
			(thermal_bridge_width 0.5)
			(island_removal_mode 0)
		)
		(polygon
			(pts
				(arc
					(start 103.77551 -113.8936)
					(mid 103.730129 -113.784041)
					(end 103.62057 -113.73866)
				)
				(arc
					(start 103.41737 -113.73866)
					(mid 103.307811 -113.784041)
					(end 103.26243 -113.8936)
				)
				(arc
					(start 103.26243 -114.1476)
					(mid 103.307811 -114.257159)
					(end 103.41737 -114.30254)
				)
				(arc
					(start 103.62057 -114.30254)
					(mid 103.730129 -114.257159)
					(end 103.77551 -114.1476)
				)
			)
		)
	)
	(zone
		(layer "In1.Cu")
		(hatch none 0.5)
		(connect_pads
			(clearance 0)
		)
		(min_thickness 0.25)
		(keepout
			(tracks not_allowed)
			(vias allowed)
			(pads allowed)
			(copperpour not_allowed)
			(footprints allowed)
		)
		(placement
			(enabled no)
			(sheetname "")
		)
		(fill
			(thermal_gap 0.5)
			(thermal_bridge_width 0.5)
			(island_removal_mode 0)
		)
		(polygon
			(pts
				(arc
					(start 131.4704 -88.26246)
					(mid 131.360841 -88.307841)
					(end 131.31546 -88.4174)
				)
				(arc
					(start 131.31546 -88.6206)
					(mid 131.360841 -88.730159)
					(end 131.4704 -88.77554)
				)
				(arc
					(start 131.7244 -88.77554)
					(mid 131.833959 -88.730159)
					(end 131.87934 -88.6206)
				)
				(arc
					(start 131.87934 -88.4174)
					(mid 131.833959 -88.307841)
					(end 131.7244 -88.26246)
				)
			)
		)
	)
	(zone
		(layer "In1.Cu")
		(hatch none 0.5)
		(connect_pads
			(clearance 0)
		)
		(min_thickness 0.25)
		(keepout
			(tracks not_allowed)
			(vias allowed)
			(pads allowed)
			(copperpour not_allowed)
			(footprints allowed)
		)
		(placement
			(enabled no)
			(sheetname "")
		)
		(fill
			(thermal_gap 0.5)
			(thermal_bridge_width 0.5)
			(island_removal_mode 0)
		)
		(polygon
			(pts
				(arc
					(start 132.365242 -82.873342)
					(mid 132.255683 -82.918723)
					(end 132.210302 -83.028282)
				)
				(arc
					(start 132.210302 -83.231482)
					(mid 132.255683 -83.341041)
					(end 132.365242 -83.386422)
				)
				(arc
					(start 132.619242 -83.386422)
					(mid 132.728801 -83.341041)
					(end 132.774182 -83.231482)
				)
				(arc
					(start 132.774182 -83.028282)
					(mid 132.728801 -82.918723)
					(end 132.619242 -82.873342)
				)
			)
		)
	)
	(zone
		(layer "In1.Cu")
		(hatch none 0.5)
		(connect_pads
			(clearance 0)
		)
		(min_thickness 0.25)
		(keepout
			(tracks not_allowed)
			(vias allowed)
			(pads allowed)
			(copperpour not_allowed)
			(footprints allowed)
		)
		(placement
			(enabled no)
			(sheetname "")
		)
		(fill
			(thermal_gap 0.5)
			(thermal_bridge_width 0.5)
			(island_removal_mode 0)
		)
		(polygon
			(pts
				(arc
					(start 131.28625 -99.07524)
					(mid 131.240869 -98.965681)
					(end 131.13131 -98.9203)
				)
				(arc
					(start 130.92811 -98.9203)
					(mid 130.818551 -98.965681)
					(end 130.77317 -99.07524)
				)
				(arc
					(start 130.77317 -99.32924)
					(mid 130.818551 -99.438799)
					(end 130.92811 -99.48418)
				)
				(arc
					(start 131.13131 -99.48418)
					(mid 131.240869 -99.438799)
					(end 131.28625 -99.32924)
				)
			)
		)
	)
	(zone
		(layer "In1.Cu")
		(hatch none 0.5)
		(connect_pads
			(clearance 0)
		)
		(min_thickness 0.25)
		(keepout
			(tracks not_allowed)
			(vias allowed)
			(pads allowed)
			(copperpour not_allowed)
			(footprints allowed)
		)
		(placement
			(enabled no)
			(sheetname "")
		)
		(fill
			(thermal_gap 0.5)
			(thermal_bridge_width 0.5)
			(island_removal_mode 0)
		)
		(polygon
			(pts
				(arc
					(start 86.90356 -33.27654)
					(mid 87.013119 -33.231159)
					(end 87.0585 -33.1216)
				)
				(arc
					(start 87.0585 -32.9184)
					(mid 87.013119 -32.808841)
					(end 86.90356 -32.76346)
				)
				(arc
					(start 86.64956 -32.76346)
					(mid 86.540001 -32.808841)
					(end 86.49462 -32.9184)
				)
				(arc
					(start 86.49462 -33.1216)
					(mid 86.540001 -33.231159)
					(end 86.64956 -33.27654)
				)
			)
		)
	)
	(zone
		(layer "In1.Cu")
		(hatch none 0.5)
		(connect_pads
			(clearance 0)
		)
		(min_thickness 0.25)
		(keepout
			(tracks not_allowed)
			(vias allowed)
			(pads allowed)
			(copperpour not_allowed)
			(footprints allowed)
		)
		(placement
			(enabled no)
			(sheetname "")
		)
		(fill
			(thermal_gap 0.5)
			(thermal_bridge_width 0.5)
			(island_removal_mode 0)
		)
		(polygon
			(pts
				(xy 277.406354 -24.392128) (xy 278.275034 -24.392128) (xy 278.275034 -25.514808) (xy 277.406354 -25.514808)
			)
		)
	)
	(zone
		(layer "In1.Cu")
		(hatch none 0.5)
		(connect_pads
			(clearance 0)
		)
		(min_thickness 0.25)
		(keepout
			(tracks not_allowed)
			(vias allowed)
			(pads allowed)
			(copperpour not_allowed)
			(footprints allowed)
		)
		(placement
			(enabled no)
			(sheetname "")
		)
		(fill
			(thermal_gap 0.5)
			(thermal_bridge_width 0.5)
			(island_removal_mode 0)
		)
		(polygon
			(pts
				(arc
					(start 130.9116 -91.69146)
					(mid 130.802041 -91.736841)
					(end 130.75666 -91.8464)
				)
				(arc
					(start 130.75666 -92.0496)
					(mid 130.802041 -92.159159)
					(end 130.9116 -92.20454)
				)
				(arc
					(start 131.1656 -92.20454)
					(mid 131.275159 -92.159159)
					(end 131.32054 -92.0496)
				)
				(arc
					(start 131.32054 -91.8464)
					(mid 131.275159 -91.736841)
					(end 131.1656 -91.69146)
				)
			)
		)
	)
	(zone
		(layer "In1.Cu")
		(hatch none 0.5)
		(connect_pads
			(clearance 0)
		)
		(min_thickness 0.25)
		(keepout
			(tracks not_allowed)
			(vias allowed)
			(pads allowed)
			(copperpour not_allowed)
			(footprints allowed)
		)
		(placement
			(enabled no)
			(sheetname "")
		)
		(fill
			(thermal_gap 0.5)
			(thermal_bridge_width 0.5)
			(island_removal_mode 0)
		)
		(polygon
			(pts
				(arc
					(start 132.98551 -98.9584)
					(mid 132.940129 -98.848841)
					(end 132.83057 -98.80346)
				)
				(arc
					(start 132.62737 -98.80346)
					(mid 132.517811 -98.848841)
					(end 132.47243 -98.9584)
				)
				(arc
					(start 132.47243 -99.2124)
					(mid 132.517811 -99.321959)
					(end 132.62737 -99.36734)
				)
				(arc
					(start 132.83057 -99.36734)
					(mid 132.940129 -99.321959)
					(end 132.98551 -99.2124)
				)
			)
		)
	)
	(zone
		(layer "In1.Cu")
		(hatch none 0.5)
		(connect_pads
			(clearance 0)
		)
		(min_thickness 0.25)
		(keepout
			(tracks not_allowed)
			(vias allowed)
			(pads allowed)
			(copperpour not_allowed)
			(footprints allowed)
		)
		(placement
			(enabled no)
			(sheetname "")
		)
		(fill
			(thermal_gap 0.5)
			(thermal_bridge_width 0.5)
			(island_removal_mode 0)
		)
		(polygon
			(pts
				(xy 97.435416 -1.354328) (xy 98.786696 -1.354328) (xy 98.786696 -2.705608) (xy 97.435416 -2.705608)
			)
		)
	)
	(zone
		(layer "In1.Cu")
		(hatch none 0.5)
		(connect_pads
			(clearance 0)
		)
		(min_thickness 0.25)
		(keepout
			(tracks not_allowed)
			(vias allowed)
			(pads allowed)
			(copperpour not_allowed)
			(footprints allowed)
		)
		(placement
			(enabled no)
			(sheetname "")
		)
		(fill
			(thermal_gap 0.5)
			(thermal_bridge_width 0.5)
			(island_removal_mode 0)
		)
		(polygon
			(pts
				(arc
					(start 130.663442 -84.778342)
					(mid 130.553883 -84.823723)
					(end 130.508502 -84.933282)
				)
				(arc
					(start 130.508502 -85.136482)
					(mid 130.553883 -85.246041)
					(end 130.663442 -85.291422)
				)
				(arc
					(start 130.917442 -85.291422)
					(mid 131.027001 -85.246041)
					(end 131.072382 -85.136482)
				)
				(arc
					(start 131.072382 -84.933282)
					(mid 131.027001 -84.823723)
					(end 130.917442 -84.778342)
				)
			)
		)
	)
	(zone
		(layer "In1.Cu")
		(hatch none 0.5)
		(connect_pads
			(clearance 0)
		)
		(min_thickness 0.25)
		(keepout
			(tracks not_allowed)
			(vias allowed)
			(pads allowed)
			(copperpour not_allowed)
			(footprints allowed)
		)
		(placement
			(enabled no)
			(sheetname "")
		)
		(fill
			(thermal_gap 0.5)
			(thermal_bridge_width 0.5)
			(island_removal_mode 0)
		)
		(polygon
			(pts
				(xy 312.039 -75.8952) (xy 312.039 -74.4982) (xy 314.198 -74.4982) (xy 314.198 -75.8952)
			)
		)
	)
	(zone
		(layer "In1.Cu")
		(hatch none 0.5)
		(connect_pads
			(clearance 0)
		)
		(min_thickness 0.25)
		(keepout
			(tracks not_allowed)
			(vias allowed)
			(pads allowed)
			(copperpour not_allowed)
			(footprints allowed)
		)
		(placement
			(enabled no)
			(sheetname "")
		)
		(fill
			(thermal_gap 0.5)
			(thermal_bridge_width 0.5)
			(island_removal_mode 0)
		)
		(polygon
			(pts
				(xy 94.293436 -1.354328) (xy 95.644716 -1.354328) (xy 95.644716 -2.705608) (xy 94.293436 -2.705608)
			)
		)
	)
	(zone
		(layer "In1.Cu")
		(hatch none 0.5)
		(connect_pads
			(clearance 0)
		)
		(min_thickness 0.25)
		(keepout
			(tracks not_allowed)
			(vias allowed)
			(pads allowed)
			(copperpour not_allowed)
			(footprints allowed)
		)
		(placement
			(enabled no)
			(sheetname "")
		)
		(fill
			(thermal_gap 0.5)
			(thermal_bridge_width 0.5)
			(island_removal_mode 0)
		)
		(polygon
			(pts
				(arc
					(start 122.168412 -221.94774)
					(mid 122.313892 -221.88748)
					(end 122.374152 -221.742)
				)
				(arc
					(start 122.374152 -221.3864)
					(mid 122.313892 -221.24092)
					(end 122.168412 -221.18066)
				)
				(arc
					(start 121.812812 -221.18066)
					(mid 121.667332 -221.24092)
					(end 121.607072 -221.3864)
				)
				(arc
					(start 121.607072 -221.742)
					(mid 121.667332 -221.88748)
					(end 121.812812 -221.94774)
				)
			)
		)
	)
	(zone
		(layer "In1.Cu")
		(hatch none 0.5)
		(connect_pads
			(clearance 0)
		)
		(min_thickness 0.25)
		(keepout
			(tracks not_allowed)
			(vias allowed)
			(pads allowed)
			(copperpour not_allowed)
			(footprints allowed)
		)
		(placement
			(enabled no)
			(sheetname "")
		)
		(fill
			(thermal_gap 0.5)
			(thermal_bridge_width 0.5)
			(island_removal_mode 0)
		)
		(polygon
			(pts
				(arc
					(start 10.91819 -100.704142)
					(mid 11.20013 -100.986082)
					(end 11.48207 -100.704142)
				)
				(arc
					(start 11.48207 -99.256342)
					(mid 11.20013 -98.974402)
					(end 10.91819 -99.256342)
				)
			)
		)
	)
	(zone
		(layer "In1.Cu")
		(hatch none 0.5)
		(connect_pads
			(clearance 0)
		)
		(min_thickness 0.25)
		(keepout
			(tracks not_allowed)
			(vias allowed)
			(pads allowed)
			(copperpour not_allowed)
			(footprints allowed)
		)
		(placement
			(enabled no)
			(sheetname "")
		)
		(fill
			(thermal_gap 0.5)
			(thermal_bridge_width 0.5)
			(island_removal_mode 0)
		)
		(polygon
			(pts
				(arc
					(start 136.52754 -98.9584)
					(mid 136.482159 -98.848841)
					(end 136.3726 -98.80346)
				)
				(arc
					(start 136.1694 -98.80346)
					(mid 136.059841 -98.848841)
					(end 136.01446 -98.9584)
				)
				(arc
					(start 136.01446 -99.2124)
					(mid 136.059841 -99.321959)
					(end 136.1694 -99.36734)
				)
				(arc
					(start 136.3726 -99.36734)
					(mid 136.482159 -99.321959)
					(end 136.52754 -99.2124)
				)
			)
		)
	)
	(zone
		(layer "In1.Cu")
		(hatch none 0.5)
		(connect_pads
			(clearance 0)
		)
		(min_thickness 0.25)
		(keepout
			(tracks not_allowed)
			(vias allowed)
			(pads allowed)
			(copperpour not_allowed)
			(footprints allowed)
		)
		(placement
			(enabled no)
			(sheetname "")
		)
		(fill
			(thermal_gap 0.5)
			(thermal_bridge_width 0.5)
			(island_removal_mode 0)
		)
		(polygon
			(pts
				(arc
					(start 104.41051 -114.4524)
					(mid 104.365129 -114.342841)
					(end 104.25557 -114.29746)
				)
				(arc
					(start 104.05237 -114.29746)
					(mid 103.942811 -114.342841)
					(end 103.89743 -114.4524)
				)
				(arc
					(start 103.89743 -114.7064)
					(mid 103.942811 -114.815959)
					(end 104.05237 -114.86134)
				)
				(arc
					(start 104.25557 -114.86134)
					(mid 104.365129 -114.815959)
					(end 104.41051 -114.7064)
				)
			)
		)
	)
	(zone
		(layer "In1.Cu")
		(hatch none 0.5)
		(connect_pads
			(clearance 0)
		)
		(min_thickness 0.25)
		(keepout
			(tracks not_allowed)
			(vias allowed)
			(pads allowed)
			(copperpour not_allowed)
			(footprints allowed)
		)
		(placement
			(enabled no)
			(sheetname "")
		)
		(fill
			(thermal_gap 0.5)
			(thermal_bridge_width 0.5)
			(island_removal_mode 0)
		)
		(polygon
			(pts
				(arc
					(start 86.90356 -33.91154)
					(mid 87.013119 -33.866159)
					(end 87.0585 -33.7566)
				)
				(arc
					(start 87.0585 -33.5534)
					(mid 87.013119 -33.443841)
					(end 86.90356 -33.39846)
				)
				(arc
					(start 86.64956 -33.39846)
					(mid 86.540001 -33.443841)
					(end 86.49462 -33.5534)
				)
				(arc
					(start 86.49462 -33.7566)
					(mid 86.540001 -33.866159)
					(end 86.64956 -33.91154)
				)
			)
		)
	)
	(zone
		(layer "In1.Cu")
		(hatch none 0.5)
		(connect_pads
			(clearance 0)
		)
		(min_thickness 0.25)
		(keepout
			(tracks not_allowed)
			(vias allowed)
			(pads allowed)
			(copperpour not_allowed)
			(footprints allowed)
		)
		(placement
			(enabled no)
			(sheetname "")
		)
		(fill
			(thermal_gap 0.5)
			(thermal_bridge_width 0.5)
			(island_removal_mode 0)
		)
		(polygon
			(pts
				(arc
					(start 303.366932 -68.39204)
					(mid 303.427192 -68.53752)
					(end 303.572672 -68.59778)
				)
				(arc
					(start 303.928272 -68.59778)
					(mid 304.073752 -68.53752)
					(end 304.134012 -68.39204)
				)
				(arc
					(start 304.134012 -68.03644)
					(mid 304.073752 -67.89096)
					(end 303.928272 -67.8307)
				)
				(arc
					(start 303.572672 -67.8307)
					(mid 303.427192 -67.89096)
					(end 303.366932 -68.03644)
				)
			)
		)
	)
	(zone
		(layer "In1.Cu")
		(hatch none 0.5)
		(connect_pads
			(clearance 0)
		)
		(min_thickness 0.25)
		(keepout
			(tracks not_allowed)
			(vias allowed)
			(pads allowed)
			(copperpour not_allowed)
			(footprints allowed)
		)
		(placement
			(enabled no)
			(sheetname "")
		)
		(fill
			(thermal_gap 0.5)
			(thermal_bridge_width 0.5)
			(island_removal_mode 0)
		)
		(polygon
			(pts
				(arc
					(start 50.717958 -77.80401)
					(mid 50.999898 -78.08595)
					(end 51.281838 -77.80401)
				)
				(arc
					(start 51.281838 -76.35621)
					(mid 50.999898 -76.07427)
					(end 50.717958 -76.35621)
				)
			)
		)
	)
	(zone
		(layer "In1.Cu")
		(hatch none 0.5)
		(connect_pads
			(clearance 0)
		)
		(min_thickness 0.25)
		(keepout
			(tracks not_allowed)
			(vias allowed)
			(pads allowed)
			(copperpour not_allowed)
			(footprints allowed)
		)
		(placement
			(enabled no)
			(sheetname "")
		)
		(fill
			(thermal_gap 0.5)
			(thermal_bridge_width 0.5)
			(island_removal_mode 0)
		)
		(polygon
			(pts
				(arc
					(start 130.9116 -86.99246)
					(mid 130.802041 -87.037841)
					(end 130.75666 -87.1474)
				)
				(arc
					(start 130.75666 -87.3506)
					(mid 130.802041 -87.460159)
					(end 130.9116 -87.50554)
				)
				(arc
					(start 131.1656 -87.50554)
					(mid 131.275159 -87.460159)
					(end 131.32054 -87.3506)
				)
				(arc
					(start 131.32054 -87.1474)
					(mid 131.275159 -87.037841)
					(end 131.1656 -86.99246)
				)
			)
		)
	)
	(zone
		(layer "In1.Cu")
		(hatch none 0.5)
		(connect_pads
			(clearance 0)
		)
		(min_thickness 0.25)
		(keepout
			(tracks not_allowed)
			(vias allowed)
			(pads allowed)
			(copperpour not_allowed)
			(footprints allowed)
		)
		(placement
			(enabled no)
			(sheetname "")
		)
		(fill
			(thermal_gap 0.5)
			(thermal_bridge_width 0.5)
			(island_removal_mode 0)
		)
		(polygon
			(pts
				(arc
					(start 137.16254 -98.9584)
					(mid 137.117159 -98.848841)
					(end 137.0076 -98.80346)
				)
				(arc
					(start 136.8044 -98.80346)
					(mid 136.694841 -98.848841)
					(end 136.64946 -98.9584)
				)
				(arc
					(start 136.64946 -99.2124)
					(mid 136.694841 -99.321959)
					(end 136.8044 -99.36734)
				)
				(arc
					(start 137.0076 -99.36734)
					(mid 137.117159 -99.321959)
					(end 137.16254 -99.2124)
				)
			)
		)
	)
	(zone
		(layer "In1.Cu")
		(hatch none 0.5)
		(connect_pads
			(clearance 0)
		)
		(min_thickness 0.25)
		(keepout
			(tracks not_allowed)
			(vias allowed)
			(pads allowed)
			(copperpour not_allowed)
			(footprints allowed)
		)
		(placement
			(enabled no)
			(sheetname "")
		)
		(fill
			(thermal_gap 0.5)
			(thermal_bridge_width 0.5)
			(island_removal_mode 0)
		)
		(polygon
			(pts
				(arc
					(start 16.11757 -103.213662)
					(mid 16.39951 -103.495602)
					(end 16.68145 -103.213662)
				)
				(arc
					(start 16.68145 -101.765862)
					(mid 16.39951 -101.483922)
					(end 16.11757 -101.765862)
				)
			)
		)
	)
	(zone
		(layer "In1.Cu")
		(hatch none 0.5)
		(connect_pads
			(clearance 0)
		)
		(min_thickness 0.25)
		(keepout
			(tracks not_allowed)
			(vias allowed)
			(pads allowed)
			(copperpour not_allowed)
			(footprints allowed)
		)
		(placement
			(enabled no)
			(sheetname "")
		)
		(fill
			(thermal_gap 0.5)
			(thermal_bridge_width 0.5)
			(island_removal_mode 0)
		)
		(polygon
			(pts
				(arc
					(start 105.55351 -114.4524)
					(mid 105.508129 -114.342841)
					(end 105.39857 -114.29746)
				)
				(arc
					(start 105.19537 -114.29746)
					(mid 105.085811 -114.342841)
					(end 105.04043 -114.4524)
				)
				(arc
					(start 105.04043 -114.7064)
					(mid 105.085811 -114.815959)
					(end 105.19537 -114.86134)
				)
				(arc
					(start 105.39857 -114.86134)
					(mid 105.508129 -114.815959)
					(end 105.55351 -114.7064)
				)
			)
		)
	)
	(zone
		(layer "In1.Cu")
		(hatch none 0.5)
		(connect_pads
			(clearance 0)
		)
		(min_thickness 0.25)
		(keepout
			(tracks not_allowed)
			(vias allowed)
			(pads allowed)
			(copperpour not_allowed)
			(footprints allowed)
		)
		(placement
			(enabled no)
			(sheetname "")
		)
		(fill
			(thermal_gap 0.5)
			(thermal_bridge_width 0.5)
			(island_removal_mode 0)
		)
		(polygon
			(pts
				(arc
					(start 348.438978 -152.047448)
					(mid 348.499238 -152.192928)
					(end 348.644718 -152.253188)
				)
				(arc
					(start 349.000318 -152.253188)
					(mid 349.145798 -152.192928)
					(end 349.206058 -152.047448)
				)
				(arc
					(start 349.206058 -151.691848)
					(mid 349.145798 -151.546368)
					(end 349.000318 -151.486108)
				)
				(arc
					(start 348.644718 -151.486108)
					(mid 348.499238 -151.546368)
					(end 348.438978 -151.691848)
				)
			)
		)
	)
	(zone
		(layer "In1.Cu")
		(hatch none 0.5)
		(connect_pads
			(clearance 0)
		)
		(min_thickness 0.25)
		(keepout
			(tracks not_allowed)
			(vias allowed)
			(pads allowed)
			(copperpour not_allowed)
			(footprints allowed)
		)
		(placement
			(enabled no)
			(sheetname "")
		)
		(fill
			(thermal_gap 0.5)
			(thermal_bridge_width 0.5)
			(island_removal_mode 0)
		)
		(polygon
			(pts
				(arc
					(start 131.92125 -98.51644)
					(mid 131.875869 -98.406881)
					(end 131.76631 -98.3615)
				)
				(arc
					(start 131.56311 -98.3615)
					(mid 131.453551 -98.406881)
					(end 131.40817 -98.51644)
				)
				(arc
					(start 131.40817 -98.77044)
					(mid 131.453551 -98.879999)
					(end 131.56311 -98.92538)
				)
				(arc
					(start 131.76631 -98.92538)
					(mid 131.875869 -98.879999)
					(end 131.92125 -98.77044)
				)
			)
		)
	)
	(zone
		(layer "In1.Cu")
		(hatch none 0.5)
		(connect_pads
			(clearance 0)
		)
		(min_thickness 0.25)
		(keepout
			(tracks not_allowed)
			(vias allowed)
			(pads allowed)
			(copperpour not_allowed)
			(footprints allowed)
		)
		(placement
			(enabled no)
			(sheetname "")
		)
		(fill
			(thermal_gap 0.5)
			(thermal_bridge_width 0.5)
			(island_removal_mode 0)
		)
		(polygon
			(pts
				(arc
					(start 101.99751 -113.8936)
					(mid 101.952129 -113.784041)
					(end 101.84257 -113.73866)
				)
				(arc
					(start 101.63937 -113.73866)
					(mid 101.529811 -113.784041)
					(end 101.48443 -113.8936)
				)
				(arc
					(start 101.48443 -114.1476)
					(mid 101.529811 -114.257159)
					(end 101.63937 -114.30254)
				)
				(arc
					(start 101.84257 -114.30254)
					(mid 101.952129 -114.257159)
					(end 101.99751 -114.1476)
				)
			)
		)
	)
	(zone
		(layer "In1.Cu")
		(hatch none 0.5)
		(connect_pads
			(clearance 0)
		)
		(min_thickness 0.25)
		(keepout
			(tracks not_allowed)
			(vias allowed)
			(pads allowed)
			(copperpour not_allowed)
			(footprints allowed)
		)
		(placement
			(enabled no)
			(sheetname "")
		)
		(fill
			(thermal_gap 0.5)
			(thermal_bridge_width 0.5)
			(island_removal_mode 0)
		)
		(polygon
			(pts
				(xy 307.594 -77.4954) (xy 307.594 -76.0984) (xy 309.753 -76.0984) (xy 309.753 -77.4954)
			)
		)
	)
	(zone
		(layer "In1.Cu")
		(hatch none 0.5)
		(connect_pads
			(clearance 0)
		)
		(min_thickness 0.25)
		(keepout
			(tracks not_allowed)
			(vias allowed)
			(pads allowed)
			(copperpour not_allowed)
			(footprints allowed)
		)
		(placement
			(enabled no)
			(sheetname "")
		)
		(fill
			(thermal_gap 0.5)
			(thermal_bridge_width 0.5)
			(island_removal_mode 0)
		)
		(polygon
			(pts
				(arc
					(start 130.9116 -89.53246)
					(mid 130.802041 -89.577841)
					(end 130.75666 -89.6874)
				)
				(arc
					(start 130.75666 -89.8906)
					(mid 130.802041 -90.000159)
					(end 130.9116 -90.04554)
				)
				(arc
					(start 131.1656 -90.04554)
					(mid 131.275159 -90.000159)
					(end 131.32054 -89.8906)
				)
				(arc
					(start 131.32054 -89.6874)
					(mid 131.275159 -89.577841)
					(end 131.1656 -89.53246)
				)
			)
		)
	)
	(zone
		(layer "In1.Cu")
		(hatch none 0.5)
		(connect_pads
			(clearance 0)
		)
		(min_thickness 0.25)
		(keepout
			(tracks not_allowed)
			(vias allowed)
			(pads allowed)
			(copperpour not_allowed)
			(footprints allowed)
		)
		(placement
			(enabled no)
			(sheetname "")
		)
		(fill
			(thermal_gap 0.5)
			(thermal_bridge_width 0.5)
			(island_removal_mode 0)
		)
		(polygon
			(pts
				(arc
					(start 121.55551 -113.8936)
					(mid 121.510129 -113.784041)
					(end 121.40057 -113.73866)
				)
				(arc
					(start 121.19737 -113.73866)
					(mid 121.087811 -113.784041)
					(end 121.04243 -113.8936)
				)
				(arc
					(start 121.04243 -114.1476)
					(mid 121.087811 -114.257159)
					(end 121.19737 -114.30254)
				)
				(arc
					(start 121.40057 -114.30254)
					(mid 121.510129 -114.257159)
					(end 121.55551 -114.1476)
				)
			)
		)
	)
	(zone
		(layer "In1.Cu")
		(hatch none 0.5)
		(connect_pads
			(clearance 0)
		)
		(min_thickness 0.25)
		(keepout
			(tracks not_allowed)
			(vias allowed)
			(pads allowed)
			(copperpour not_allowed)
			(footprints allowed)
		)
		(placement
			(enabled no)
			(sheetname "")
		)
		(fill
			(thermal_gap 0.5)
			(thermal_bridge_width 0.5)
			(island_removal_mode 0)
		)
		(polygon
			(pts
				(arc
					(start 120.41251 -113.8936)
					(mid 120.367129 -113.784041)
					(end 120.25757 -113.73866)
				)
				(arc
					(start 120.05437 -113.73866)
					(mid 119.944811 -113.784041)
					(end 119.89943 -113.8936)
				)
				(arc
					(start 119.89943 -114.1476)
					(mid 119.944811 -114.257159)
					(end 120.05437 -114.30254)
				)
				(arc
					(start 120.25757 -114.30254)
					(mid 120.367129 -114.257159)
					(end 120.41251 -114.1476)
				)
			)
		)
	)
	(zone
		(layer "In1.Cu")
		(hatch none 0.5)
		(connect_pads
			(clearance 0)
		)
		(min_thickness 0.25)
		(keepout
			(tracks not_allowed)
			(vias allowed)
			(pads allowed)
			(copperpour not_allowed)
			(footprints allowed)
		)
		(placement
			(enabled no)
			(sheetname "")
		)
		(fill
			(thermal_gap 0.5)
			(thermal_bridge_width 0.5)
			(island_removal_mode 0)
		)
		(polygon
			(pts
				(arc
					(start 348.438978 -150.015448)
					(mid 348.499238 -150.160928)
					(end 348.644718 -150.221188)
				)
				(arc
					(start 349.000318 -150.221188)
					(mid 349.145798 -150.160928)
					(end 349.206058 -150.015448)
				)
				(arc
					(start 349.206058 -149.659848)
					(mid 349.145798 -149.514368)
					(end 349.000318 -149.454108)
				)
				(arc
					(start 348.644718 -149.454108)
					(mid 348.499238 -149.514368)
					(end 348.438978 -149.659848)
				)
			)
		)
	)
	(zone
		(net "GND")
		(layer "In1.Cu")
		(hatch none 0.5)
		(connect_pads
			(clearance 0.5)
		)
		(min_thickness 0.25)
		(fill yes
			(thermal_gap 0.5)
			(thermal_bridge_width 0.5)
			(island_removal_mode 0)
		)
		(polygon
			(pts
				(xy 250.465844 -195.238116)
				(arc
					(start 250.49988 -195.272152)
					(mid 251.396754 -195.753482)
					(end 251.878084 -196.650356)
				)
				(xy 251.91212 -196.684392) (xy 251.91212 -196.94017) (xy 251.913136 -197.000114)
				(arc
					(start 251.913136 -246.000016)
					(mid 253.154117 -248.996009)
					(end 256.15011 -250.23699)
				)
				(arc
					(start 350.60001 -250.23699)
					(mid 353.596003 -248.996009)
					(end 354.836984 -246.000016)
				)
				(arc
					(start 354.836984 -0.999998)
					(mid 354.767574 -0.832426)
					(end 354.600002 -0.763016)
				)
				(arc
					(start 307.485034 -0.763016)
					(mid 307.317462 -0.832426)
					(end 307.248052 -0.999998)
				)
				(xy 307.248052 -43.50004) (xy 307.247036 -43.559984) (xy 307.247036 -43.815762)
				(arc
					(start 307.213 -43.849798)
					(mid 306.601183 -44.864739)
					(end 305.485038 -45.263054)
				)
				(arc
					(start 305.485038 -45.263054)
					(mid 305.317466 -45.332464)
					(end 305.248056 -45.500036)
				)
				(xy 305.248056 -53.50002) (xy 305.24704 -53.559964) (xy 305.24704 -53.815742)
				(arc
					(start 305.213004 -53.849778)
					(mid 304.731674 -54.746652)
					(end 303.8348 -55.227982)
				)
				(xy 303.800764 -55.262018) (xy 303.544986 -55.262018) (xy 303.485042 -55.263034) (xy 283.485082 -55.263034)
				(xy 283.425138 -55.262018) (xy 283.16936 -55.262018)
				(arc
					(start 283.135578 -55.227982)
					(mid 282.238485 -54.746617)
					(end 281.75712 -53.849524)
				)
				(xy 281.723084 -53.815742) (xy 281.723084 -53.559964) (xy 281.722068 -53.50002)
				(arc
					(start 281.722068 -0.999998)
					(mid 281.652658 -0.832426)
					(end 281.485086 -0.763016)
				)
				(arc
					(start 75.449938 -0.763016)
					(mid 75.282366 -0.832426)
					(end 75.212956 -0.999998)
				)
				(xy 75.212956 -15.999968) (xy 75.21194 -16.059912) (xy 75.21194 -16.31569)
				(arc
					(start 75.177904 -16.349472)
					(mid 74.696539 -17.246565)
					(end 73.799446 -17.72793)
				)
				(xy 73.765664 -17.761966) (xy 73.509886 -17.761966) (xy 73.449942 -17.762982)
				(arc
					(start 62.95009 -17.762982)
					(mid 62.782518 -17.832392)
					(end 62.713108 -17.999964)
				)
				(xy 62.713108 -57.010046) (xy 62.712092 -57.069736) (xy 62.712092 -57.325768)
				(arc
					(start 62.678056 -57.359804)
					(mid 62.196726 -58.256678)
					(end 61.299852 -58.738008)
				)
				(xy 61.265816 -58.772044) (xy 61.009784 -58.772044) (xy 60.950094 -58.77306)
				(arc
					(start 29.500068 -58.77306)
					(mid 28.625391 -59.135363)
					(end 28.263088 -60.01004)
				)
				(xy 28.263088 -76.010008) (xy 28.262072 -76.084938) (xy 28.262072 -76.32573)
				(arc
					(start 28.242768 -76.345034)
					(mid 27.453867 -77.963799)
					(end 25.835102 -78.7527)
				)
				(xy 25.815798 -78.772004) (xy 25.575006 -78.772004) (xy 25.500076 -78.77302)
				(arc
					(start 2.999994 -78.77302)
					(mid 1.418212 -79.428216)
					(end 0.763016 -81.009998)
				)
				(arc
					(start 0.763016 -246.000016)
					(mid 2.003997 -248.996009)
					(end 4.99999 -250.23699)
				)
				(xy 26.34996 -250.23699) (xy 26.409904 -250.238006) (xy 26.665682 -250.238006)
				(arc
					(start 26.699464 -250.272042)
					(mid 27.596557 -250.753407)
					(end 28.077922 -251.6505)
				)
				(xy 28.111958 -251.684282) (xy 28.111958 -251.94006) (xy 28.112974 -252.000004) (xy 28.112974 -257.836924)
				(xy 33.78708 -257.836924) (xy 33.78708 -252.549914) (xy 33.788096 -252.490986) (xy 33.788096 -252.234192)
				(arc
					(start 33.823402 -252.198886)
					(mid 35.500056 -250.836908)
					(end 37.17671 -252.198886)
				)
				(xy 37.212016 -252.234192) (xy 37.212016 -252.490986) (xy 37.213032 -252.549914) (xy 37.213032 -257.836924)
				(xy 46.886876 -257.836924) (xy 46.886876 -252.000004) (xy 46.887892 -251.940314) (xy 46.887892 -251.684282)
				(arc
					(start 46.921928 -251.650246)
					(mid 47.403258 -250.753372)
					(end 48.300132 -250.272042)
				)
				(xy 48.334168 -250.238006) (xy 48.5902 -250.238006) (xy 48.64989 -250.23699) (xy 66.34988 -250.23699)
				(xy 66.409824 -250.238006) (xy 66.665602 -250.238006)
				(arc
					(start 66.699384 -250.272042)
					(mid 67.596477 -250.753407)
					(end 68.077842 -251.6505)
				)
				(xy 68.111878 -251.684282) (xy 68.111878 -251.94006) (xy 68.112894 -252.000004) (xy 68.112894 -254.4064)
				(xy 137.786872 -254.4064) (xy 137.786872 -252.549914) (xy 137.787888 -252.490986) (xy 137.787888 -252.234192)
				(arc
					(start 137.823194 -252.198886)
					(mid 139.500076 -250.836659)
					(end 141.176756 -252.198886)
				)
				(xy 141.212062 -252.234192) (xy 141.212062 -252.490986) (xy 141.213078 -252.549914) (xy 141.213078 -254.4064)
				(xy 150.886922 -254.4064) (xy 150.886922 -252.000004) (xy 150.887938 -251.94006) (xy 150.887938 -251.684282)
				(arc
					(start 150.921974 -251.650246)
					(mid 151.403304 -250.753372)
					(end 152.300178 -250.272042)
				)
				(xy 152.334214 -250.238006) (xy 152.589992 -250.238006) (xy 152.649936 -250.23699) (xy 181.150006 -250.23699)
				(xy 181.20995 -250.238006) (xy 181.465728 -250.238006)
				(arc
					(start 181.499764 -250.272042)
					(mid 182.396638 -250.753372)
					(end 182.877968 -251.650246)
				)
				(xy 182.912004 -251.684282) (xy 182.912004 -251.94006) (xy 182.91302 -252.000004) (xy 182.91302 -257.836924)
				(xy 188.586872 -257.836924) (xy 188.586872 -252.549914) (xy 188.587888 -252.490986) (xy 188.587888 -252.234192)
				(arc
					(start 188.623194 -252.198886)
					(mid 190.300076 -250.836659)
					(end 191.976756 -252.198886)
				)
				(xy 192.012062 -252.234192) (xy 192.012062 -252.490986) (xy 192.013078 -252.549914) (xy 192.013078 -257.836924)
				(xy 201.686922 -257.836924) (xy 201.686922 -252.000004) (xy 201.687938 -251.94006) (xy 201.687938 -251.684282)
				(arc
					(start 201.721974 -251.650246)
					(mid 202.203304 -250.753372)
					(end 203.100178 -250.272042)
				)
				(xy 203.134214 -250.238006) (xy 203.389992 -250.238006) (xy 203.449936 -250.23699)
				(arc
					(start 229.14991 -250.23699)
					(mid 232.145903 -248.996009)
					(end 233.386884 -246.000016)
				)
				(xy 233.386884 -197.000114) (xy 233.3879 -196.94017) (xy 233.3879 -196.684392)
				(arc
					(start 233.421936 -196.65061)
					(mid 233.903301 -195.753517)
					(end 234.800394 -195.272152)
				)
				(xy 234.834176 -195.238116) (xy 235.089954 -195.238116) (xy 235.149898 -195.2371) (xy 250.150122 -195.2371)
				(xy 250.210066 -195.238116)
			)
		)
		(polygon
			(pts
				(arc
					(start 122.374152 -223.139)
					(mid 122.313892 -222.99352)
					(end 122.168412 -222.93326)
				)
				(arc
					(start 121.812812 -222.93326)
					(mid 121.667332 -222.99352)
					(end 121.607072 -223.139)
				)
				(arc
					(start 121.607072 -223.4946)
					(mid 121.667332 -223.64008)
					(end 121.812812 -223.70034)
				)
				(arc
					(start 122.168412 -223.70034)
					(mid 122.313892 -223.64008)
					(end 122.374152 -223.4946)
				)
			)
		)
		(polygon
			(pts
				(arc
					(start 120.723152 -223.139)
					(mid 120.662892 -222.99352)
					(end 120.517412 -222.93326)
				)
				(arc
					(start 120.161812 -222.93326)
					(mid 120.016332 -222.99352)
					(end 119.956072 -223.139)
				)
				(arc
					(start 119.956072 -223.4946)
					(mid 120.016332 -223.64008)
					(end 120.161812 -223.70034)
				)
				(arc
					(start 120.517412 -223.70034)
					(mid 120.662892 -223.64008)
					(end 120.723152 -223.4946)
				)
			)
		)
		(polygon
			(pts
				(arc
					(start 114.881152 -223.139)
					(mid 114.820892 -222.99352)
					(end 114.675412 -222.93326)
				)
				(arc
					(start 114.319812 -222.93326)
					(mid 114.174332 -222.99352)
					(end 114.114072 -223.139)
				)
				(arc
					(start 114.114072 -223.4946)
					(mid 114.174332 -223.64008)
					(end 114.319812 -223.70034)
				)
				(arc
					(start 114.675412 -223.70034)
					(mid 114.820892 -223.64008)
					(end 114.881152 -223.4946)
				)
			)
		)
		(polygon
			(pts
				(arc
					(start 113.230152 -223.139)
					(mid 113.169892 -222.99352)
					(end 113.024412 -222.93326)
				)
				(arc
					(start 112.668812 -222.93326)
					(mid 112.523332 -222.99352)
					(end 112.463072 -223.139)
				)
				(arc
					(start 112.463072 -223.4946)
					(mid 112.523332 -223.64008)
					(end 112.668812 -223.70034)
				)
				(arc
					(start 113.024412 -223.70034)
					(mid 113.169892 -223.64008)
					(end 113.230152 -223.4946)
				)
			)
		)
		(polygon
			(pts
				(arc
					(start 122.374152 -222.2754)
					(mid 122.313892 -222.12992)
					(end 122.168412 -222.06966)
				)
				(arc
					(start 121.812812 -222.06966)
					(mid 121.667332 -222.12992)
					(end 121.607072 -222.2754)
				)
				(arc
					(start 121.607072 -222.631)
					(mid 121.667332 -222.77648)
					(end 121.812812 -222.83674)
				)
				(arc
					(start 122.168412 -222.83674)
					(mid 122.313892 -222.77648)
					(end 122.374152 -222.631)
				)
			)
		)
		(polygon
			(pts
				(arc
					(start 120.723152 -222.2754)
					(mid 120.662892 -222.12992)
					(end 120.517412 -222.06966)
				)
				(arc
					(start 120.161812 -222.06966)
					(mid 120.016332 -222.12992)
					(end 119.956072 -222.2754)
				)
				(arc
					(start 119.956072 -222.631)
					(mid 120.016332 -222.77648)
					(end 120.161812 -222.83674)
				)
				(arc
					(start 120.517412 -222.83674)
					(mid 120.662892 -222.77648)
					(end 120.723152 -222.631)
				)
			)
		)
		(polygon
			(pts
				(arc
					(start 114.881152 -222.2754)
					(mid 114.820892 -222.12992)
					(end 114.675412 -222.06966)
				)
				(arc
					(start 114.319812 -222.06966)
					(mid 114.174332 -222.12992)
					(end 114.114072 -222.2754)
				)
				(arc
					(start 114.114072 -222.631)
					(mid 114.174332 -222.77648)
					(end 114.319812 -222.83674)
				)
				(arc
					(start 114.675412 -222.83674)
					(mid 114.820892 -222.77648)
					(end 114.881152 -222.631)
				)
			)
		)
		(polygon
			(pts
				(arc
					(start 113.230152 -222.2754)
					(mid 113.169892 -222.12992)
					(end 113.024412 -222.06966)
				)
				(arc
					(start 112.668812 -222.06966)
					(mid 112.523332 -222.12992)
					(end 112.463072 -222.2754)
				)
				(arc
					(start 112.463072 -222.631)
					(mid 112.523332 -222.77648)
					(end 112.668812 -222.83674)
				)
				(arc
					(start 113.024412 -222.83674)
					(mid 113.169892 -222.77648)
					(end 113.230152 -222.631)
				)
			)
		)
		(polygon
			(pts
				(arc
					(start 122.374152 -221.3864)
					(mid 122.313892 -221.24092)
					(end 122.168412 -221.18066)
				)
				(arc
					(start 121.812812 -221.18066)
					(mid 121.667332 -221.24092)
					(end 121.607072 -221.3864)
				)
				(arc
					(start 121.607072 -221.742)
					(mid 121.667332 -221.88748)
					(end 121.812812 -221.94774)
				)
				(arc
					(start 122.168412 -221.94774)
					(mid 122.313892 -221.88748)
					(end 122.374152 -221.742)
				)
			)
		)
		(polygon
			(pts
				(arc
					(start 120.723152 -221.3864)
					(mid 120.662892 -221.24092)
					(end 120.517412 -221.18066)
				)
				(arc
					(start 120.161812 -221.18066)
					(mid 120.016332 -221.24092)
					(end 119.956072 -221.3864)
				)
				(arc
					(start 119.956072 -221.742)
					(mid 120.016332 -221.88748)
					(end 120.161812 -221.94774)
				)
				(arc
					(start 120.517412 -221.94774)
					(mid 120.662892 -221.88748)
					(end 120.723152 -221.742)
				)
			)
		)
		(polygon
			(pts
				(arc
					(start 114.881152 -221.3864)
					(mid 114.820892 -221.24092)
					(end 114.675412 -221.18066)
				)
				(arc
					(start 114.319812 -221.18066)
					(mid 114.174332 -221.24092)
					(end 114.114072 -221.3864)
				)
				(arc
					(start 114.114072 -221.742)
					(mid 114.174332 -221.88748)
					(end 114.319812 -221.94774)
				)
				(arc
					(start 114.675412 -221.94774)
					(mid 114.820892 -221.88748)
					(end 114.881152 -221.742)
				)
			)
		)
		(polygon
			(pts
				(arc
					(start 113.230152 -221.3864)
					(mid 113.169892 -221.24092)
					(end 113.024412 -221.18066)
				)
				(arc
					(start 112.668812 -221.18066)
					(mid 112.523332 -221.24092)
					(end 112.463072 -221.3864)
				)
				(arc
					(start 112.463072 -221.742)
					(mid 112.523332 -221.88748)
					(end 112.668812 -221.94774)
				)
				(arc
					(start 113.024412 -221.94774)
					(mid 113.169892 -221.88748)
					(end 113.230152 -221.742)
				)
			)
		)
		(polygon
			(pts
				(arc
					(start 121.231152 -206.121)
					(mid 121.170892 -205.97552)
					(end 121.025412 -205.91526)
				)
				(arc
					(start 120.669812 -205.91526)
					(mid 120.524332 -205.97552)
					(end 120.464072 -206.121)
				)
				(arc
					(start 120.464072 -206.4766)
					(mid 120.524332 -206.62208)
					(end 120.669812 -206.68234)
				)
				(arc
					(start 121.025412 -206.68234)
					(mid 121.170892 -206.62208)
					(end 121.231152 -206.4766)
				)
			)
		)
		(polygon
			(pts
				(arc
					(start 119.580152 -206.121)
					(mid 119.519892 -205.97552)
					(end 119.374412 -205.91526)
				)
				(arc
					(start 119.018812 -205.91526)
					(mid 118.873332 -205.97552)
					(end 118.813072 -206.121)
				)
				(arc
					(start 118.813072 -206.4766)
					(mid 118.873332 -206.62208)
					(end 119.018812 -206.68234)
				)
				(arc
					(start 119.374412 -206.68234)
					(mid 119.519892 -206.62208)
					(end 119.580152 -206.4766)
				)
			)
		)
		(polygon
			(pts
				(arc
					(start 113.357152 -206.121)
					(mid 113.296892 -205.97552)
					(end 113.151412 -205.91526)
				)
				(arc
					(start 112.795812 -205.91526)
					(mid 112.650332 -205.97552)
					(end 112.590072 -206.121)
				)
				(arc
					(start 112.590072 -206.4766)
					(mid 112.650332 -206.62208)
					(end 112.795812 -206.68234)
				)
				(arc
					(start 113.151412 -206.68234)
					(mid 113.296892 -206.62208)
					(end 113.357152 -206.4766)
				)
			)
		)
		(polygon
			(pts
				(arc
					(start 111.706152 -206.121)
					(mid 111.645892 -205.97552)
					(end 111.500412 -205.91526)
				)
				(arc
					(start 111.144812 -205.91526)
					(mid 110.999332 -205.97552)
					(end 110.939072 -206.121)
				)
				(arc
					(start 110.939072 -206.4766)
					(mid 110.999332 -206.62208)
					(end 111.144812 -206.68234)
				)
				(arc
					(start 111.500412 -206.68234)
					(mid 111.645892 -206.62208)
					(end 111.706152 -206.4766)
				)
			)
		)
		(polygon
			(pts
				(arc
					(start 121.231152 -205.232)
					(mid 121.170892 -205.08652)
					(end 121.025412 -205.02626)
				)
				(arc
					(start 120.669812 -205.02626)
					(mid 120.524332 -205.08652)
					(end 120.464072 -205.232)
				)
				(arc
					(start 120.464072 -205.5876)
					(mid 120.524332 -205.73308)
					(end 120.669812 -205.79334)
				)
				(arc
					(start 121.025412 -205.79334)
					(mid 121.170892 -205.73308)
					(end 121.231152 -205.5876)
				)
			)
		)
		(polygon
			(pts
				(arc
					(start 119.580152 -205.232)
					(mid 119.519892 -205.08652)
					(end 119.374412 -205.02626)
				)
				(arc
					(start 119.018812 -205.02626)
					(mid 118.873332 -205.08652)
					(end 118.813072 -205.232)
				)
				(arc
					(start 118.813072 -205.5876)
					(mid 118.873332 -205.73308)
					(end 119.018812 -205.79334)
				)
				(arc
					(start 119.374412 -205.79334)
					(mid 119.519892 -205.73308)
					(end 119.580152 -205.5876)
				)
			)
		)
		(polygon
			(pts
				(arc
					(start 113.357152 -205.232)
					(mid 113.296892 -205.08652)
					(end 113.151412 -205.02626)
				)
				(arc
					(start 112.795812 -205.02626)
					(mid 112.650332 -205.08652)
					(end 112.590072 -205.232)
				)
				(arc
					(start 112.590072 -205.5876)
					(mid 112.650332 -205.73308)
					(end 112.795812 -205.79334)
				)
				(arc
					(start 113.151412 -205.79334)
					(mid 113.296892 -205.73308)
					(end 113.357152 -205.5876)
				)
			)
		)
		(polygon
			(pts
				(arc
					(start 111.706152 -205.232)
					(mid 111.645892 -205.08652)
					(end 111.500412 -205.02626)
				)
				(arc
					(start 111.144812 -205.02626)
					(mid 110.999332 -205.08652)
					(end 110.939072 -205.232)
				)
				(arc
					(start 110.939072 -205.5876)
					(mid 110.999332 -205.73308)
					(end 111.144812 -205.79334)
				)
				(arc
					(start 111.500412 -205.79334)
					(mid 111.645892 -205.73308)
					(end 111.706152 -205.5876)
				)
			)
		)
		(polygon
			(pts
				(arc
					(start 121.231152 -204.3684)
					(mid 121.170892 -204.22292)
					(end 121.025412 -204.16266)
				)
				(arc
					(start 120.669812 -204.16266)
					(mid 120.524332 -204.22292)
					(end 120.464072 -204.3684)
				)
				(arc
					(start 120.464072 -204.724)
					(mid 120.524332 -204.86948)
					(end 120.669812 -204.92974)
				)
				(arc
					(start 121.025412 -204.92974)
					(mid 121.170892 -204.86948)
					(end 121.231152 -204.724)
				)
			)
		)
		(polygon
			(pts
				(arc
					(start 119.580152 -204.3684)
					(mid 119.519892 -204.22292)
					(end 119.374412 -204.16266)
				)
				(arc
					(start 119.018812 -204.16266)
					(mid 118.873332 -204.22292)
					(end 118.813072 -204.3684)
				)
				(arc
					(start 118.813072 -204.724)
					(mid 118.873332 -204.86948)
					(end 119.018812 -204.92974)
				)
				(arc
					(start 119.374412 -204.92974)
					(mid 119.519892 -204.86948)
					(end 119.580152 -204.724)
				)
			)
		)
		(polygon
			(pts
				(arc
					(start 113.357152 -204.3684)
					(mid 113.296892 -204.22292)
					(end 113.151412 -204.16266)
				)
				(arc
					(start 112.795812 -204.16266)
					(mid 112.650332 -204.22292)
					(end 112.590072 -204.3684)
				)
				(arc
					(start 112.590072 -204.724)
					(mid 112.650332 -204.86948)
					(end 112.795812 -204.92974)
				)
				(arc
					(start 113.151412 -204.92974)
					(mid 113.296892 -204.86948)
					(end 113.357152 -204.724)
				)
			)
		)
		(polygon
			(pts
				(arc
					(start 111.706152 -204.3684)
					(mid 111.645892 -204.22292)
					(end 111.500412 -204.16266)
				)
				(arc
					(start 111.144812 -204.16266)
					(mid 110.999332 -204.22292)
					(end 110.939072 -204.3684)
				)
				(arc
					(start 110.939072 -204.724)
					(mid 110.999332 -204.86948)
					(end 111.144812 -204.92974)
				)
				(arc
					(start 111.500412 -204.92974)
					(mid 111.645892 -204.86948)
					(end 111.706152 -204.724)
				)
			)
		)
		(polygon
			(pts
				(arc
					(start 285.550356 -185.54573)
					(mid 285.87573 -185.111644)
					(end 285.441644 -184.78627)
				)
				(arc
					(start 284.552898 -184.91327)
					(mid 284.227506 -185.347232)
					(end 284.661356 -185.67273)
				)
			)
		)
		(polygon
			(pts
				(arc
					(start 299.643546 -174.676054)
					(mid 299.280328 -175.028987)
					(end 299.633132 -175.392334)
				)
				(arc
					(start 300.430438 -175.40351)
					(mid 300.793658 -175.05045)
					(end 300.440598 -174.68723)
				)
			)
		)
		(polygon
			(pts
				(arc
					(start 303.024032 -174.096426)
					(mid 303.38903 -173.69536)
					(end 302.987964 -173.330362)
				)
				(xy 302.987964 -173.327822) (xy 302.21428 -173.36389) (xy 302.214026 -173.364144)
				(arc
					(start 302.214026 -173.36643)
					(mid 301.849028 -173.767496)
					(end 302.250094 -174.132494)
				)
				(xy 302.250094 -174.135034) (xy 303.024032 -174.098966)
			)
		)
		(polygon
			(pts
				(arc
					(start 349.206058 -155.120848)
					(mid 349.145798 -154.975368)
					(end 349.000318 -154.915108)
				)
				(arc
					(start 348.644718 -154.915108)
					(mid 348.499238 -154.975368)
					(end 348.438978 -155.120848)
				)
				(arc
					(start 348.438978 -155.476448)
					(mid 348.499238 -155.621928)
					(end 348.644718 -155.682188)
				)
				(arc
					(start 349.000318 -155.682188)
					(mid 349.145798 -155.621928)
					(end 349.206058 -155.476448)
				)
			)
		)
		(polygon
			(pts
				(arc
					(start 348.342458 -155.120848)
					(mid 348.282198 -154.975368)
					(end 348.136718 -154.915108)
				)
				(arc
					(start 347.781118 -154.915108)
					(mid 347.635638 -154.975368)
					(end 347.575378 -155.120848)
				)
				(arc
					(start 347.575378 -155.476448)
					(mid 347.635638 -155.621928)
					(end 347.781118 -155.682188)
				)
				(arc
					(start 348.136718 -155.682188)
					(mid 348.282198 -155.621928)
					(end 348.342458 -155.476448)
				)
			)
		)
		(polygon
			(pts
				(arc
					(start 350.369124 -154.275028)
					(mid 350.010984 -153.916888)
					(end 349.652844 -154.275028)
				)
				(arc
					(start 349.652844 -155.155392)
					(mid 350.011111 -155.513278)
					(end 350.369124 -155.155138)
				)
			)
		)
		(polygon
			(pts
				(arc
					(start 349.206058 -153.977848)
					(mid 349.145798 -153.832368)
					(end 349.000318 -153.772108)
				)
				(arc
					(start 348.644718 -153.772108)
					(mid 348.499238 -153.832368)
					(end 348.438978 -153.977848)
				)
				(arc
					(start 348.438978 -154.333448)
					(mid 348.499238 -154.478928)
					(end 348.644718 -154.539188)
				)
				(arc
					(start 349.000318 -154.539188)
					(mid 349.145798 -154.478928)
					(end 349.206058 -154.333448)
				)
			)
		)
		(polygon
			(pts
				(arc
					(start 348.342458 -153.977848)
					(mid 348.282198 -153.832368)
					(end 348.136718 -153.772108)
				)
				(arc
					(start 347.781118 -153.772108)
					(mid 347.635638 -153.832368)
					(end 347.575378 -153.977848)
				)
				(arc
					(start 347.575378 -154.333448)
					(mid 347.635638 -154.478928)
					(end 347.781118 -154.539188)
				)
				(arc
					(start 348.136718 -154.539188)
					(mid 348.282198 -154.478928)
					(end 348.342458 -154.333448)
				)
			)
		)
		(polygon
			(pts
				(arc
					(start 349.206058 -152.834848)
					(mid 349.145798 -152.689368)
					(end 349.000318 -152.629108)
				)
				(arc
					(start 348.644718 -152.629108)
					(mid 348.499238 -152.689368)
					(end 348.438978 -152.834848)
				)
				(arc
					(start 348.438978 -153.190448)
					(mid 348.499238 -153.335928)
					(end 348.644718 -153.396188)
				)
				(arc
					(start 349.000318 -153.396188)
					(mid 349.145798 -153.335928)
					(end 349.206058 -153.190448)
				)
			)
		)
		(polygon
			(pts
				(arc
					(start 348.342458 -152.834848)
					(mid 348.282198 -152.689368)
					(end 348.136718 -152.629108)
				)
				(arc
					(start 347.781118 -152.629108)
					(mid 347.635638 -152.689368)
					(end 347.575378 -152.834848)
				)
				(arc
					(start 347.575378 -153.190448)
					(mid 347.635638 -153.335928)
					(end 347.781118 -153.396188)
				)
				(arc
					(start 348.136718 -153.396188)
					(mid 348.282198 -153.335928)
					(end 348.342458 -153.190448)
				)
			)
		)
		(polygon
			(pts
				(arc
					(start 351.11309 -151.97201)
					(mid 350.75495 -151.61387)
					(end 350.39681 -151.97201)
				)
				(arc
					(start 350.39681 -152.917144)
					(mid 350.755077 -153.27503)
					(end 351.11309 -152.91689)
				)
			)
		)
		(polygon
			(pts
				(arc
					(start 349.206058 -151.691848)
					(mid 349.145798 -151.546368)
					(end 349.000318 -151.486108)
				)
				(arc
					(start 348.644718 -151.486108)
					(mid 348.499238 -151.546368)
					(end 348.438978 -151.691848)
				)
				(arc
					(start 348.438978 -152.047448)
					(mid 348.499238 -152.192928)
					(end 348.644718 -152.253188)
				)
				(arc
					(start 349.000318 -152.253188)
					(mid 349.145798 -152.192928)
					(end 349.206058 -152.047448)
				)
			)
		)
		(polygon
			(pts
				(arc
					(start 348.342458 -151.691848)
					(mid 348.282198 -151.546368)
					(end 348.136718 -151.486108)
				)
				(arc
					(start 347.781118 -151.486108)
					(mid 347.635638 -151.546368)
					(end 347.575378 -151.691848)
				)
				(arc
					(start 347.575378 -152.047448)
					(mid 347.635638 -152.192928)
					(end 347.781118 -152.253188)
				)
				(arc
					(start 348.136718 -152.253188)
					(mid 348.282198 -152.192928)
					(end 348.342458 -152.047448)
				)
			)
		)
		(polygon
			(pts
				(arc
					(start 349.206058 -149.659848)
					(mid 349.145798 -149.514368)
					(end 349.000318 -149.454108)
				)
				(arc
					(start 348.644718 -149.454108)
					(mid 348.499238 -149.514368)
					(end 348.438978 -149.659848)
				)
				(arc
					(start 348.438978 -150.015448)
					(mid 348.499238 -150.160928)
					(end 348.644718 -150.221188)
				)
				(arc
					(start 349.000318 -150.221188)
					(mid 349.145798 -150.160928)
					(end 349.206058 -150.015448)
				)
			)
		)
		(polygon
			(pts
				(arc
					(start 348.342458 -149.659848)
					(mid 348.282198 -149.514368)
					(end 348.136718 -149.454108)
				)
				(arc
					(start 347.781118 -149.454108)
					(mid 347.635638 -149.514368)
					(end 347.575378 -149.659848)
				)
				(arc
					(start 347.575378 -150.015448)
					(mid 347.635638 -150.160928)
					(end 347.781118 -150.221188)
				)
				(arc
					(start 348.136718 -150.221188)
					(mid 348.282198 -150.160928)
					(end 348.342458 -150.015448)
				)
			)
		)
		(polygon
			(pts
				(arc
					(start 349.206058 -148.516848)
					(mid 349.145798 -148.371368)
					(end 349.000318 -148.311108)
				)
				(arc
					(start 348.644718 -148.311108)
					(mid 348.499238 -148.371368)
					(end 348.438978 -148.516848)
				)
				(arc
					(start 348.438978 -148.872448)
					(mid 348.499238 -149.017928)
					(end 348.644718 -149.078188)
				)
				(arc
					(start 349.000318 -149.078188)
					(mid 349.145798 -149.017928)
					(end 349.206058 -148.872448)
				)
			)
		)
		(polygon
			(pts
				(arc
					(start 348.342458 -148.516848)
					(mid 348.282198 -148.371368)
					(end 348.136718 -148.311108)
				)
				(arc
					(start 347.781118 -148.311108)
					(mid 347.635638 -148.371368)
					(end 347.575378 -148.516848)
				)
				(arc
					(start 347.575378 -148.872448)
					(mid 347.635638 -149.017928)
					(end 347.781118 -149.078188)
				)
				(arc
					(start 348.136718 -149.078188)
					(mid 348.282198 -149.017928)
					(end 348.342458 -148.872448)
				)
			)
		)
		(polygon
			(pts
				(arc
					(start 351.824544 -147.98167)
					(mid 352.18243 -147.623403)
					(end 351.82429 -147.26539)
				)
				(arc
					(start 350.87941 -147.26539)
					(mid 350.52127 -147.62353)
					(end 350.87941 -147.98167)
				)
			)
		)
		(polygon
			(pts
				(arc
					(start 122.19051 -113.8936)
					(mid 122.145129 -113.784041)
					(end 122.03557 -113.73866)
				)
				(arc
					(start 121.83237 -113.73866)
					(mid 121.722811 -113.784041)
					(end 121.67743 -113.8936)
				)
				(arc
					(start 121.67743 -114.1476)
					(mid 121.713342 -114.24679)
					(end 121.80443 -114.3)
				)
				(arc
					(start 121.80443 -114.3)
					(mid 121.713342 -114.35321)
					(end 121.67743 -114.4524)
				)
				(arc
					(start 121.67743 -114.7064)
					(mid 121.722811 -114.815959)
					(end 121.83237 -114.86134)
				)
				(arc
					(start 122.03557 -114.86134)
					(mid 122.145129 -114.815959)
					(end 122.19051 -114.7064)
				)
				(arc
					(start 122.19051 -114.4524)
					(mid 122.154598 -114.35321)
					(end 122.06351 -114.3)
				)
				(arc
					(start 122.06351 -114.3)
					(mid 122.154598 -114.24679)
					(end 122.19051 -114.1476)
				)
			)
		)
		(polygon
			(pts
				(arc
					(start 121.55551 -113.8936)
					(mid 121.510129 -113.784041)
					(end 121.40057 -113.73866)
				)
				(arc
					(start 121.19737 -113.73866)
					(mid 121.087811 -113.784041)
					(end 121.04243 -113.8936)
				)
				(arc
					(start 121.04243 -114.1476)
					(mid 121.078342 -114.24679)
					(end 121.16943 -114.3)
				)
				(arc
					(start 121.16943 -114.3)
					(mid 121.078342 -114.35321)
					(end 121.04243 -114.4524)
				)
				(arc
					(start 121.04243 -114.7064)
					(mid 121.087811 -114.815959)
					(end 121.19737 -114.86134)
				)
				(arc
					(start 121.40057 -114.86134)
					(mid 121.510129 -114.815959)
					(end 121.55551 -114.7064)
				)
				(arc
					(start 121.55551 -114.4524)
					(mid 121.519598 -114.35321)
					(end 121.42851 -114.3)
				)
				(arc
					(start 121.42851 -114.3)
					(mid 121.519598 -114.24679)
					(end 121.55551 -114.1476)
				)
			)
		)
		(polygon
			(pts
				(arc
					(start 120.41251 -113.8936)
					(mid 120.367129 -113.784041)
					(end 120.25757 -113.73866)
				)
				(arc
					(start 120.05437 -113.73866)
					(mid 119.944811 -113.784041)
					(end 119.89943 -113.8936)
				)
				(arc
					(start 119.89943 -114.1476)
					(mid 119.935342 -114.24679)
					(end 120.02643 -114.3)
				)
				(arc
					(start 120.02643 -114.3)
					(mid 119.935342 -114.35321)
					(end 119.89943 -114.4524)
				)
				(arc
					(start 119.89943 -114.7064)
					(mid 119.944811 -114.815959)
					(end 120.05437 -114.86134)
				)
				(arc
					(start 120.25757 -114.86134)
					(mid 120.367129 -114.815959)
					(end 120.41251 -114.7064)
				)
				(arc
					(start 120.41251 -114.4524)
					(mid 120.376598 -114.35321)
					(end 120.28551 -114.3)
				)
				(arc
					(start 120.28551 -114.3)
					(mid 120.376598 -114.24679)
					(end 120.41251 -114.1476)
				)
			)
		)
		(polygon
			(pts
				(arc
					(start 119.77751 -113.8936)
					(mid 119.732129 -113.784041)
					(end 119.62257 -113.73866)
				)
				(arc
					(start 119.41937 -113.73866)
					(mid 119.309811 -113.784041)
					(end 119.26443 -113.8936)
				)
				(arc
					(start 119.26443 -114.1476)
					(mid 119.300342 -114.24679)
					(end 119.39143 -114.3)
				)
				(arc
					(start 119.39143 -114.3)
					(mid 119.300342 -114.35321)
					(end 119.26443 -114.4524)
				)
				(arc
					(start 119.26443 -114.7064)
					(mid 119.309811 -114.815959)
					(end 119.41937 -114.86134)
				)
				(arc
					(start 119.62257 -114.86134)
					(mid 119.732129 -114.815959)
					(end 119.77751 -114.7064)
				)
				(arc
					(start 119.77751 -114.4524)
					(mid 119.741598 -114.35321)
					(end 119.65051 -114.3)
				)
				(arc
					(start 119.65051 -114.3)
					(mid 119.741598 -114.24679)
					(end 119.77751 -114.1476)
				)
			)
		)
		(polygon
			(pts
				(arc
					(start 118.63451 -113.8936)
					(mid 118.589129 -113.784041)
					(end 118.47957 -113.73866)
				)
				(arc
					(start 118.27637 -113.73866)
					(mid 118.166811 -113.784041)
					(end 118.12143 -113.8936)
				)
				(arc
					(start 118.12143 -114.1476)
					(mid 118.157342 -114.24679)
					(end 118.24843 -114.3)
				)
				(arc
					(start 118.24843 -114.3)
					(mid 118.157342 -114.35321)
					(end 118.12143 -114.4524)
				)
				(arc
					(start 118.12143 -114.7064)
					(mid 118.166811 -114.815959)
					(end 118.27637 -114.86134)
				)
				(arc
					(start 118.47957 -114.86134)
					(mid 118.589129 -114.815959)
					(end 118.63451 -114.7064)
				)
				(arc
					(start 118.63451 -114.4524)
					(mid 118.598598 -114.35321)
					(end 118.50751 -114.3)
				)
				(arc
					(start 118.50751 -114.3)
					(mid 118.598598 -114.24679)
					(end 118.63451 -114.1476)
				)
			)
		)
		(polygon
			(pts
				(arc
					(start 117.99951 -113.8936)
					(mid 117.954129 -113.784041)
					(end 117.84457 -113.73866)
				)
				(arc
					(start 117.64137 -113.73866)
					(mid 117.531811 -113.784041)
					(end 117.48643 -113.8936)
				)
				(arc
					(start 117.48643 -114.1476)
					(mid 117.522342 -114.24679)
					(end 117.61343 -114.3)
				)
				(arc
					(start 117.61343 -114.3)
					(mid 117.522342 -114.35321)
					(end 117.48643 -114.4524)
				)
				(arc
					(start 117.48643 -114.7064)
					(mid 117.531811 -114.815959)
					(end 117.64137 -114.86134)
				)
				(arc
					(start 117.84457 -114.86134)
					(mid 117.954129 -114.815959)
					(end 117.99951 -114.7064)
				)
				(arc
					(start 117.99951 -114.4524)
					(mid 117.963598 -114.35321)
					(end 117.87251 -114.3)
				)
				(arc
					(start 117.87251 -114.3)
					(mid 117.963598 -114.24679)
					(end 117.99951 -114.1476)
				)
			)
		)
		(polygon
			(pts
				(arc
					(start 116.85651 -113.8936)
					(mid 116.811129 -113.784041)
					(end 116.70157 -113.73866)
				)
				(arc
					(start 116.49837 -113.73866)
					(mid 116.388811 -113.784041)
					(end 116.34343 -113.8936)
				)
				(arc
					(start 116.34343 -114.1476)
					(mid 116.379342 -114.24679)
					(end 116.47043 -114.3)
				)
				(arc
					(start 116.47043 -114.3)
					(mid 116.379342 -114.35321)
					(end 116.34343 -114.4524)
				)
				(arc
					(start 116.34343 -114.7064)
					(mid 116.388811 -114.815959)
					(end 116.49837 -114.86134)
				)
				(arc
					(start 116.70157 -114.86134)
					(mid 116.811129 -114.815959)
					(end 116.85651 -114.7064)
				)
				(arc
					(start 116.85651 -114.4524)
					(mid 116.820598 -114.35321)
					(end 116.72951 -114.3)
				)
				(arc
					(start 116.72951 -114.3)
					(mid 116.820598 -114.24679)
					(end 116.85651 -114.1476)
				)
			)
		)
		(polygon
			(pts
				(arc
					(start 116.22151 -113.8936)
					(mid 116.176129 -113.784041)
					(end 116.06657 -113.73866)
				)
				(arc
					(start 115.86337 -113.73866)
					(mid 115.753811 -113.784041)
					(end 115.70843 -113.8936)
				)
				(arc
					(start 115.70843 -114.1476)
					(mid 115.744342 -114.24679)
					(end 115.83543 -114.3)
				)
				(arc
					(start 115.83543 -114.3)
					(mid 115.744342 -114.35321)
					(end 115.70843 -114.4524)
				)
				(arc
					(start 115.70843 -114.7064)
					(mid 115.753811 -114.815959)
					(end 115.86337 -114.86134)
				)
				(arc
					(start 116.06657 -114.86134)
					(mid 116.176129 -114.815959)
					(end 116.22151 -114.7064)
				)
				(arc
					(start 116.22151 -114.4524)
					(mid 116.185598 -114.35321)
					(end 116.09451 -114.3)
				)
				(arc
					(start 116.09451 -114.3)
					(mid 116.185598 -114.24679)
					(end 116.22151 -114.1476)
				)
			)
		)
		(polygon
			(pts
				(arc
					(start 115.07851 -113.8936)
					(mid 115.033129 -113.784041)
					(end 114.92357 -113.73866)
				)
				(arc
					(start 114.72037 -113.73866)
					(mid 114.610811 -113.784041)
					(end 114.56543 -113.8936)
				)
				(arc
					(start 114.56543 -114.1476)
					(mid 114.601342 -114.24679)
					(end 114.69243 -114.3)
				)
				(arc
					(start 114.69243 -114.3)
					(mid 114.601342 -114.35321)
					(end 114.56543 -114.4524)
				)
				(arc
					(start 114.56543 -114.7064)
					(mid 114.610811 -114.815959)
					(end 114.72037 -114.86134)
				)
				(arc
					(start 114.92357 -114.86134)
					(mid 115.033129 -114.815959)
					(end 115.07851 -114.7064)
				)
				(arc
					(start 115.07851 -114.4524)
					(mid 115.042598 -114.35321)
					(end 114.95151 -114.3)
				)
				(arc
					(start 114.95151 -114.3)
					(mid 115.042598 -114.24679)
					(end 115.07851 -114.1476)
				)
			)
		)
		(polygon
			(pts
				(arc
					(start 114.44351 -113.8936)
					(mid 114.398129 -113.784041)
					(end 114.28857 -113.73866)
				)
				(arc
					(start 114.08537 -113.73866)
					(mid 113.975811 -113.784041)
					(end 113.93043 -113.8936)
				)
				(arc
					(start 113.93043 -114.1476)
					(mid 113.966342 -114.24679)
					(end 114.05743 -114.3)
				)
				(arc
					(start 114.05743 -114.3)
					(mid 113.966342 -114.35321)
					(end 113.93043 -114.4524)
				)
				(arc
					(start 113.93043 -114.7064)
					(mid 113.975811 -114.815959)
					(end 114.08537 -114.86134)
				)
				(arc
					(start 114.28857 -114.86134)
					(mid 114.398129 -114.815959)
					(end 114.44351 -114.7064)
				)
				(arc
					(start 114.44351 -114.4524)
					(mid 114.407598 -114.35321)
					(end 114.31651 -114.3)
				)
				(arc
					(start 114.31651 -114.3)
					(mid 114.407598 -114.24679)
					(end 114.44351 -114.1476)
				)
			)
		)
		(polygon
			(pts
				(arc
					(start 113.30051 -113.8936)
					(mid 113.255129 -113.784041)
					(end 113.14557 -113.73866)
				)
				(arc
					(start 112.94237 -113.73866)
					(mid 112.832811 -113.784041)
					(end 112.78743 -113.8936)
				)
				(arc
					(start 112.78743 -114.1476)
					(mid 112.823342 -114.24679)
					(end 112.91443 -114.3)
				)
				(arc
					(start 112.91443 -114.3)
					(mid 112.823342 -114.35321)
					(end 112.78743 -114.4524)
				)
				(arc
					(start 112.78743 -114.7064)
					(mid 112.832811 -114.815959)
					(end 112.94237 -114.86134)
				)
				(arc
					(start 113.14557 -114.86134)
					(mid 113.255129 -114.815959)
					(end 113.30051 -114.7064)
				)
				(arc
					(start 113.30051 -114.4524)
					(mid 113.264598 -114.35321)
					(end 113.17351 -114.3)
				)
				(arc
					(start 113.17351 -114.3)
					(mid 113.264598 -114.24679)
					(end 113.30051 -114.1476)
				)
			)
		)
		(polygon
			(pts
				(arc
					(start 112.66551 -113.8936)
					(mid 112.620129 -113.784041)
					(end 112.51057 -113.73866)
				)
				(arc
					(start 112.30737 -113.73866)
					(mid 112.197811 -113.784041)
					(end 112.15243 -113.8936)
				)
				(arc
					(start 112.15243 -114.1476)
					(mid 112.188342 -114.24679)
					(end 112.27943 -114.3)
				)
				(arc
					(start 112.27943 -114.3)
					(mid 112.188342 -114.35321)
					(end 112.15243 -114.4524)
				)
				(arc
					(start 112.15243 -114.7064)
					(mid 112.197811 -114.815959)
					(end 112.30737 -114.86134)
				)
				(arc
					(start 112.51057 -114.86134)
					(mid 112.620129 -114.815959)
					(end 112.66551 -114.7064)
				)
				(arc
					(start 112.66551 -114.4524)
					(mid 112.629598 -114.35321)
					(end 112.53851 -114.3)
				)
				(arc
					(start 112.53851 -114.3)
					(mid 112.629598 -114.24679)
					(end 112.66551 -114.1476)
				)
			)
		)
		(polygon
			(pts
				(arc
					(start 111.52251 -113.8936)
					(mid 111.477129 -113.784041)
					(end 111.36757 -113.73866)
				)
				(arc
					(start 111.16437 -113.73866)
					(mid 111.054811 -113.784041)
					(end 111.00943 -113.8936)
				)
				(arc
					(start 111.00943 -114.1476)
					(mid 111.045342 -114.24679)
					(end 111.13643 -114.3)
				)
				(arc
					(start 111.13643 -114.3)
					(mid 111.045342 -114.35321)
					(end 111.00943 -114.4524)
				)
				(arc
					(start 111.00943 -114.7064)
					(mid 111.054811 -114.815959)
					(end 111.16437 -114.86134)
				)
				(arc
					(start 111.36757 -114.86134)
					(mid 111.477129 -114.815959)
					(end 111.52251 -114.7064)
				)
				(arc
					(start 111.52251 -114.4524)
					(mid 111.486598 -114.35321)
					(end 111.39551 -114.3)
				)
				(arc
					(start 111.39551 -114.3)
					(mid 111.486598 -114.24679)
					(end 111.52251 -114.1476)
				)
			)
		)
		(polygon
			(pts
				(arc
					(start 110.88751 -113.8936)
					(mid 110.842129 -113.784041)
					(end 110.73257 -113.73866)
				)
				(arc
					(start 110.52937 -113.73866)
					(mid 110.419811 -113.784041)
					(end 110.37443 -113.8936)
				)
				(arc
					(start 110.37443 -114.1476)
					(mid 110.410342 -114.24679)
					(end 110.50143 -114.3)
				)
				(arc
					(start 110.50143 -114.3)
					(mid 110.410342 -114.35321)
					(end 110.37443 -114.4524)
				)
				(arc
					(start 110.37443 -114.7064)
					(mid 110.419811 -114.815959)
					(end 110.52937 -114.86134)
				)
				(arc
					(start 110.73257 -114.86134)
					(mid 110.842129 -114.815959)
					(end 110.88751 -114.7064)
				)
				(arc
					(start 110.88751 -114.4524)
					(mid 110.851598 -114.35321)
					(end 110.76051 -114.3)
				)
				(arc
					(start 110.76051 -114.3)
					(mid 110.851598 -114.24679)
					(end 110.88751 -114.1476)
				)
			)
		)
		(polygon
			(pts
				(arc
					(start 109.74451 -113.8936)
					(mid 109.699129 -113.784041)
					(end 109.58957 -113.73866)
				)
				(arc
					(start 109.38637 -113.73866)
					(mid 109.276811 -113.784041)
					(end 109.23143 -113.8936)
				)
				(arc
					(start 109.23143 -114.1476)
					(mid 109.267342 -114.24679)
					(end 109.35843 -114.3)
				)
				(arc
					(start 109.35843 -114.3)
					(mid 109.267342 -114.35321)
					(end 109.23143 -114.4524)
				)
				(arc
					(start 109.23143 -114.7064)
					(mid 109.276811 -114.815959)
					(end 109.38637 -114.86134)
				)
				(arc
					(start 109.58957 -114.86134)
					(mid 109.699129 -114.815959)
					(end 109.74451 -114.7064)
				)
				(arc
					(start 109.74451 -114.4524)
					(mid 109.708598 -114.35321)
					(end 109.61751 -114.3)
				)
				(arc
					(start 109.61751 -114.3)
					(mid 109.708598 -114.24679)
					(end 109.74451 -114.1476)
				)
			)
		)
		(polygon
			(pts
				(arc
					(start 109.10951 -113.8936)
					(mid 109.064129 -113.784041)
					(end 108.95457 -113.73866)
				)
				(arc
					(start 108.75137 -113.73866)
					(mid 108.641811 -113.784041)
					(end 108.59643 -113.8936)
				)
				(arc
					(start 108.59643 -114.1476)
					(mid 108.632342 -114.24679)
					(end 108.72343 -114.3)
				)
				(arc
					(start 108.72343 -114.3)
					(mid 108.632342 -114.35321)
					(end 108.59643 -114.4524)
				)
				(arc
					(start 108.59643 -114.7064)
					(mid 108.641811 -114.815959)
					(end 108.75137 -114.86134)
				)
				(arc
					(start 108.95457 -114.86134)
					(mid 109.064129 -114.815959)
					(end 109.10951 -114.7064)
				)
				(arc
					(start 109.10951 -114.4524)
					(mid 109.073598 -114.35321)
					(end 108.98251 -114.3)
				)
				(arc
					(start 108.98251 -114.3)
					(mid 109.073598 -114.24679)
					(end 109.10951 -114.1476)
				)
			)
		)
		(polygon
			(pts
				(arc
					(start 107.96651 -113.8936)
					(mid 107.921129 -113.784041)
					(end 107.81157 -113.73866)
				)
				(arc
					(start 107.60837 -113.73866)
					(mid 107.498811 -113.784041)
					(end 107.45343 -113.8936)
				)
				(arc
					(start 107.45343 -114.1476)
					(mid 107.489342 -114.24679)
					(end 107.58043 -114.3)
				)
				(arc
					(start 107.58043 -114.3)
					(mid 107.489342 -114.35321)
					(end 107.45343 -114.4524)
				)
				(arc
					(start 107.45343 -114.7064)
					(mid 107.498811 -114.815959)
					(end 107.60837 -114.86134)
				)
				(arc
					(start 107.81157 -114.86134)
					(mid 107.921129 -114.815959)
					(end 107.96651 -114.7064)
				)
				(arc
					(start 107.96651 -114.4524)
					(mid 107.930598 -114.35321)
					(end 107.83951 -114.3)
				)
				(arc
					(start 107.83951 -114.3)
					(mid 107.930598 -114.24679)
					(end 107.96651 -114.1476)
				)
			)
		)
		(polygon
			(pts
				(arc
					(start 107.33151 -113.8936)
					(mid 107.286129 -113.784041)
					(end 107.17657 -113.73866)
				)
				(arc
					(start 106.97337 -113.73866)
					(mid 106.863811 -113.784041)
					(end 106.81843 -113.8936)
				)
				(arc
					(start 106.81843 -114.1476)
					(mid 106.854342 -114.24679)
					(end 106.94543 -114.3)
				)
				(arc
					(start 106.94543 -114.3)
					(mid 106.854342 -114.35321)
					(end 106.81843 -114.4524)
				)
				(arc
					(start 106.81843 -114.7064)
					(mid 106.863811 -114.815959)
					(end 106.97337 -114.86134)
				)
				(arc
					(start 107.17657 -114.86134)
					(mid 107.286129 -114.815959)
					(end 107.33151 -114.7064)
				)
				(arc
					(start 107.33151 -114.4524)
					(mid 107.295598 -114.35321)
					(end 107.20451 -114.3)
				)
				(arc
					(start 107.20451 -114.3)
					(mid 107.295598 -114.24679)
					(end 107.33151 -114.1476)
				)
			)
		)
		(polygon
			(pts
				(arc
					(start 106.18851 -113.8936)
					(mid 106.143129 -113.784041)
					(end 106.03357 -113.73866)
				)
				(arc
					(start 105.83037 -113.73866)
					(mid 105.720811 -113.784041)
					(end 105.67543 -113.8936)
				)
				(arc
					(start 105.67543 -114.1476)
					(mid 105.711342 -114.24679)
					(end 105.80243 -114.3)
				)
				(arc
					(start 105.80243 -114.3)
					(mid 105.711342 -114.35321)
					(end 105.67543 -114.4524)
				)
				(arc
					(start 105.67543 -114.7064)
					(mid 105.720811 -114.815959)
					(end 105.83037 -114.86134)
				)
				(arc
					(start 106.03357 -114.86134)
					(mid 106.143129 -114.815959)
					(end 106.18851 -114.7064)
				)
				(arc
					(start 106.18851 -114.4524)
					(mid 106.152598 -114.35321)
					(end 106.06151 -114.3)
				)
				(arc
					(start 106.06151 -114.3)
					(mid 106.152598 -114.24679)
					(end 106.18851 -114.1476)
				)
			)
		)
		(polygon
			(pts
				(arc
					(start 105.55351 -113.8936)
					(mid 105.508129 -113.784041)
					(end 105.39857 -113.73866)
				)
				(arc
					(start 105.19537 -113.73866)
					(mid 105.085811 -113.784041)
					(end 105.04043 -113.8936)
				)
				(arc
					(start 105.04043 -114.1476)
					(mid 105.076342 -114.24679)
					(end 105.16743 -114.3)
				)
				(arc
					(start 105.16743 -114.3)
					(mid 105.076342 -114.35321)
					(end 105.04043 -114.4524)
				)
				(arc
					(start 105.04043 -114.7064)
					(mid 105.085811 -114.815959)
					(end 105.19537 -114.86134)
				)
				(arc
					(start 105.39857 -114.86134)
					(mid 105.508129 -114.815959)
					(end 105.55351 -114.7064)
				)
				(arc
					(start 105.55351 -114.4524)
					(mid 105.517598 -114.35321)
					(end 105.42651 -114.3)
				)
				(arc
					(start 105.42651 -114.3)
					(mid 105.517598 -114.24679)
					(end 105.55351 -114.1476)
				)
			)
		)
		(polygon
			(pts
				(arc
					(start 104.41051 -113.8936)
					(mid 104.365129 -113.784041)
					(end 104.25557 -113.73866)
				)
				(arc
					(start 104.05237 -113.73866)
					(mid 103.942811 -113.784041)
					(end 103.89743 -113.8936)
				)
				(arc
					(start 103.89743 -114.1476)
					(mid 103.933342 -114.24679)
					(end 104.02443 -114.3)
				)
				(arc
					(start 104.02443 -114.3)
					(mid 103.933342 -114.35321)
					(end 103.89743 -114.4524)
				)
				(arc
					(start 103.89743 -114.7064)
					(mid 103.942811 -114.815959)
					(end 104.05237 -114.86134)
				)
				(arc
					(start 104.25557 -114.86134)
					(mid 104.365129 -114.815959)
					(end 104.41051 -114.7064)
				)
				(arc
					(start 104.41051 -114.4524)
					(mid 104.374598 -114.35321)
					(end 104.28351 -114.3)
				)
				(arc
					(start 104.28351 -114.3)
					(mid 104.374598 -114.24679)
					(end 104.41051 -114.1476)
				)
			)
		)
		(polygon
			(pts
				(arc
					(start 103.77551 -113.8936)
					(mid 103.730129 -113.784041)
					(end 103.62057 -113.73866)
				)
				(arc
					(start 103.41737 -113.73866)
					(mid 103.307811 -113.784041)
					(end 103.26243 -113.8936)
				)
				(arc
					(start 103.26243 -114.1476)
					(mid 103.298342 -114.24679)
					(end 103.38943 -114.3)
				)
				(arc
					(start 103.38943 -114.3)
					(mid 103.298342 -114.35321)
					(end 103.26243 -114.4524)
				)
				(arc
					(start 103.26243 -114.7064)
					(mid 103.307811 -114.815959)
					(end 103.41737 -114.86134)
				)
				(arc
					(start 103.62057 -114.86134)
					(mid 103.730129 -114.815959)
					(end 103.77551 -114.7064)
				)
				(arc
					(start 103.77551 -114.4524)
					(mid 103.739598 -114.35321)
					(end 103.64851 -114.3)
				)
				(arc
					(start 103.64851 -114.3)
					(mid 103.739598 -114.24679)
					(end 103.77551 -114.1476)
				)
			)
		)
		(polygon
			(pts
				(arc
					(start 102.63251 -113.8936)
					(mid 102.587129 -113.784041)
					(end 102.47757 -113.73866)
				)
				(arc
					(start 102.27437 -113.73866)
					(mid 102.164811 -113.784041)
					(end 102.11943 -113.8936)
				)
				(arc
					(start 102.11943 -114.1476)
					(mid 102.155342 -114.24679)
					(end 102.24643 -114.3)
				)
				(arc
					(start 102.24643 -114.3)
					(mid 102.155342 -114.35321)
					(end 102.11943 -114.4524)
				)
				(arc
					(start 102.11943 -114.7064)
					(mid 102.164811 -114.815959)
					(end 102.27437 -114.86134)
				)
				(arc
					(start 102.47757 -114.86134)
					(mid 102.587129 -114.815959)
					(end 102.63251 -114.7064)
				)
				(arc
					(start 102.63251 -114.4524)
					(mid 102.596598 -114.35321)
					(end 102.50551 -114.3)
				)
				(arc
					(start 102.50551 -114.3)
					(mid 102.596598 -114.24679)
					(end 102.63251 -114.1476)
				)
			)
		)
		(polygon
			(pts
				(arc
					(start 101.99751 -113.8936)
					(mid 101.952129 -113.784041)
					(end 101.84257 -113.73866)
				)
				(arc
					(start 101.63937 -113.73866)
					(mid 101.529811 -113.784041)
					(end 101.48443 -113.8936)
				)
				(arc
					(start 101.48443 -114.1476)
					(mid 101.520342 -114.24679)
					(end 101.61143 -114.3)
				)
				(arc
					(start 101.61143 -114.3)
					(mid 101.520342 -114.35321)
					(end 101.48443 -114.4524)
				)
				(arc
					(start 101.48443 -114.7064)
					(mid 101.529811 -114.815959)
					(end 101.63937 -114.86134)
				)
				(arc
					(start 101.84257 -114.86134)
					(mid 101.952129 -114.815959)
					(end 101.99751 -114.7064)
				)
				(arc
					(start 101.99751 -114.4524)
					(mid 101.961598 -114.35321)
					(end 101.87051 -114.3)
				)
				(arc
					(start 101.87051 -114.3)
					(mid 101.961598 -114.24679)
					(end 101.99751 -114.1476)
				)
			)
		)
		(polygon
			(pts
				(arc
					(start 119.208296 -102.850188)
					(mid 118.850156 -102.492048)
					(end 118.492016 -102.850188)
				)
				(arc
					(start 118.492016 -103.85044)
					(mid 118.850283 -104.208326)
					(end 119.208296 -103.850186)
				)
			)
		)
		(polygon
			(pts
				(arc
					(start 118.208298 -102.850188)
					(mid 117.850158 -102.492048)
					(end 117.492018 -102.850188)
				)
				(arc
					(start 117.492018 -103.85044)
					(mid 117.850285 -104.208326)
					(end 118.208298 -103.850186)
				)
			)
		)
		(polygon
			(pts
				(arc
					(start 114.207798 -102.850188)
					(mid 113.849658 -102.492048)
					(end 113.491518 -102.850188)
				)
				(arc
					(start 113.491518 -103.85044)
					(mid 113.849785 -104.208326)
					(end 114.207798 -103.850186)
				)
			)
		)
		(polygon
			(pts
				(arc
					(start 112.207802 -102.850188)
					(mid 111.849662 -102.492048)
					(end 111.491522 -102.850188)
				)
				(arc
					(start 111.491522 -103.85044)
					(mid 111.849789 -104.208326)
					(end 112.207802 -103.850186)
				)
			)
		)
		(polygon
			(pts
				(arc
					(start 110.207806 -102.850188)
					(mid 109.849666 -102.492048)
					(end 109.491526 -102.850188)
				)
				(arc
					(start 109.491526 -103.85044)
					(mid 109.849793 -104.208326)
					(end 110.207806 -103.850186)
				)
			)
		)
		(polygon
			(pts
				(arc
					(start 109.207808 -102.850188)
					(mid 108.849668 -102.492048)
					(end 108.491528 -102.850188)
				)
				(arc
					(start 108.491528 -103.85044)
					(mid 108.849795 -104.208326)
					(end 109.207808 -103.850186)
				)
			)
		)
		(polygon
			(pts
				(arc
					(start 113.2078 -102.849934)
					(mid 112.849533 -102.492048)
					(end 112.49152 -102.850188)
				)
				(arc
					(start 112.49152 -103.850186)
					(mid 112.84966 -104.208326)
					(end 113.2078 -103.850186)
				)
			)
		)
		(polygon
			(pts
				(arc
					(start 111.207804 -102.849934)
					(mid 110.849537 -102.492048)
					(end 110.491524 -102.850188)
				)
				(arc
					(start 110.491524 -103.850186)
					(mid 110.849664 -104.208326)
					(end 111.207804 -103.850186)
				)
			)
		)
		(polygon
			(pts
				(arc
					(start 108.20781 -102.849934)
					(mid 107.849543 -102.492048)
					(end 107.49153 -102.850188)
				)
				(arc
					(start 107.49153 -103.850186)
					(mid 107.84967 -104.208326)
					(end 108.20781 -103.850186)
				)
			)
		)
		(polygon
			(pts
				(arc
					(start 107.207812 -102.849934)
					(mid 106.849545 -102.492048)
					(end 106.491532 -102.850188)
				)
				(arc
					(start 106.491532 -103.850186)
					(mid 106.849672 -104.208326)
					(end 107.207812 -103.850186)
				)
			)
		)
		(polygon
			(pts
				(arc
					(start 116.238782 -102.840028)
					(mid 115.880515 -102.482142)
					(end 115.522502 -102.840282)
				)
				(arc
					(start 115.522502 -103.830882)
					(mid 115.880642 -104.189022)
					(end 116.238782 -103.830882)
				)
			)
		)
		(polygon
			(pts
				(arc
					(start 115.222782 -102.840028)
					(mid 114.864515 -102.482142)
					(end 114.506502 -102.840282)
				)
				(arc
					(start 114.506502 -103.830882)
					(mid 114.864642 -104.189022)
					(end 115.222782 -103.830882)
				)
			)
		)
		(polygon
			(pts
				(arc
					(start 19.08175 -101.765862)
					(mid 18.79981 -101.483922)
					(end 18.51787 -101.765862)
				)
				(arc
					(start 18.51787 -103.213662)
					(mid 18.79981 -103.495602)
					(end 19.08175 -103.213662)
				)
			)
		)
		(polygon
			(pts
				(arc
					(start 18.28165 -101.765862)
					(mid 17.99971 -101.483922)
					(end 17.71777 -101.765862)
				)
				(arc
					(start 17.71777 -103.213662)
					(mid 17.99971 -103.495602)
					(end 18.28165 -103.213662)
				)
			)
		)
		(polygon
			(pts
				(arc
					(start 16.68145 -101.765862)
					(mid 16.39951 -101.483922)
					(end 16.11757 -101.765862)
				)
				(arc
					(start 16.11757 -103.213662)
					(mid 16.39951 -103.495602)
					(end 16.68145 -103.213662)
				)
			)
		)
		(polygon
			(pts
				(arc
					(start 15.88135 -101.765862)
					(mid 15.59941 -101.483922)
					(end 15.31747 -101.765862)
				)
				(arc
					(start 15.31747 -103.213662)
					(mid 15.59941 -103.495602)
					(end 15.88135 -103.213662)
				)
			)
		)
		(polygon
			(pts
				(arc
					(start 14.28242 -101.765862)
					(mid 14.00048 -101.483922)
					(end 13.71854 -101.765862)
				)
				(arc
					(start 13.71854 -103.213662)
					(mid 14.00048 -103.495602)
					(end 14.28242 -103.213662)
				)
			)
		)
		(polygon
			(pts
				(arc
					(start 13.48232 -101.765862)
					(mid 13.20038 -101.483922)
					(end 12.91844 -101.765862)
				)
				(arc
					(start 12.91844 -103.213662)
					(mid 13.20038 -103.495602)
					(end 13.48232 -103.213662)
				)
			)
		)
		(polygon
			(pts
				(arc
					(start 11.88212 -101.765862)
					(mid 11.60018 -101.483922)
					(end 11.31824 -101.765862)
				)
				(arc
					(start 11.31824 -103.213662)
					(mid 11.60018 -103.495602)
					(end 11.88212 -103.213662)
				)
			)
		)
		(polygon
			(pts
				(arc
					(start 11.08202 -101.765862)
					(mid 10.80008 -101.483922)
					(end 10.51814 -101.765862)
				)
				(arc
					(start 10.51814 -103.213662)
					(mid 10.80008 -103.495602)
					(end 11.08202 -103.213662)
				)
			)
		)
		(polygon
			(pts
				(arc
					(start 19.4818 -99.256342)
					(mid 19.19986 -98.974402)
					(end 18.91792 -99.256342)
				)
				(arc
					(start 18.91792 -100.704142)
					(mid 19.19986 -100.986082)
					(end 19.4818 -100.704142)
				)
			)
		)
		(polygon
			(pts
				(arc
					(start 18.6817 -99.256342)
					(mid 18.39976 -98.974402)
					(end 18.11782 -99.256342)
				)
				(arc
					(start 18.11782 -100.704142)
					(mid 18.39976 -100.986082)
					(end 18.6817 -100.704142)
				)
			)
		)
		(polygon
			(pts
				(arc
					(start 17.0815 -99.256342)
					(mid 16.79956 -98.974402)
					(end 16.51762 -99.256342)
				)
				(arc
					(start 16.51762 -100.704142)
					(mid 16.79956 -100.986082)
					(end 17.0815 -100.704142)
				)
			)
		)
		(polygon
			(pts
				(arc
					(start 16.2814 -99.256342)
					(mid 15.99946 -98.974402)
					(end 15.71752 -99.256342)
				)
				(arc
					(start 15.71752 -100.704142)
					(mid 15.99946 -100.986082)
					(end 16.2814 -100.704142)
				)
			)
		)
		(polygon
			(pts
				(arc
					(start 14.68247 -99.256342)
					(mid 14.40053 -98.974402)
					(end 14.11859 -99.256342)
				)
				(arc
					(start 14.11859 -100.704142)
					(mid 14.40053 -100.986082)
					(end 14.68247 -100.704142)
				)
			)
		)
		(polygon
			(pts
				(arc
					(start 13.88237 -99.256342)
					(mid 13.60043 -98.974402)
					(end 13.31849 -99.256342)
				)
				(arc
					(start 13.31849 -100.704142)
					(mid 13.60043 -100.986082)
					(end 13.88237 -100.704142)
				)
			)
		)
		(polygon
			(pts
				(arc
					(start 12.28217 -99.256342)
					(mid 12.00023 -98.974402)
					(end 11.71829 -99.256342)
				)
				(arc
					(start 11.71829 -100.704142)
					(mid 12.00023 -100.986082)
					(end 12.28217 -100.704142)
				)
			)
		)
		(polygon
			(pts
				(arc
					(start 11.48207 -99.256342)
					(mid 11.20013 -98.974402)
					(end 10.91819 -99.256342)
				)
				(arc
					(start 10.91819 -100.704142)
					(mid 11.20013 -100.986082)
					(end 11.48207 -100.704142)
				)
			)
		)
		(polygon
			(pts
				(arc
					(start 131.92125 -98.51644)
					(mid 131.875869 -98.406881)
					(end 131.76631 -98.3615)
				)
				(arc
					(start 131.56311 -98.3615)
					(mid 131.453551 -98.406881)
					(end 131.40817 -98.51644)
				)
				(arc
					(start 131.40817 -98.77044)
					(mid 131.444082 -98.86963)
					(end 131.53517 -98.92284)
				)
				(arc
					(start 131.53517 -98.92284)
					(mid 131.444082 -98.97605)
					(end 131.40817 -99.07524)
				)
				(arc
					(start 131.40817 -99.32924)
					(mid 131.453551 -99.438799)
					(end 131.56311 -99.48418)
				)
				(arc
					(start 131.76631 -99.48418)
					(mid 131.875869 -99.438799)
					(end 131.92125 -99.32924)
				)
				(arc
					(start 131.92125 -99.07524)
					(mid 131.885338 -98.97605)
					(end 131.79425 -98.92284)
				)
				(arc
					(start 131.79425 -98.92284)
					(mid 131.885338 -98.86963)
					(end 131.92125 -98.77044)
				)
			)
		)
		(polygon
			(pts
				(arc
					(start 131.28625 -98.51644)
					(mid 131.240869 -98.406881)
					(end 131.13131 -98.3615)
				)
				(arc
					(start 130.92811 -98.3615)
					(mid 130.818551 -98.406881)
					(end 130.77317 -98.51644)
				)
				(arc
					(start 130.77317 -98.77044)
					(mid 130.809082 -98.86963)
					(end 130.90017 -98.92284)
				)
				(arc
					(start 130.90017 -98.92284)
					(mid 130.809082 -98.97605)
					(end 130.77317 -99.07524)
				)
				(arc
					(start 130.77317 -99.32924)
					(mid 130.818551 -99.438799)
					(end 130.92811 -99.48418)
				)
				(arc
					(start 131.13131 -99.48418)
					(mid 131.240869 -99.438799)
					(end 131.28625 -99.32924)
				)
				(arc
					(start 131.28625 -99.07524)
					(mid 131.250338 -98.97605)
					(end 131.15925 -98.92284)
				)
				(arc
					(start 131.15925 -98.92284)
					(mid 131.250338 -98.86963)
					(end 131.28625 -98.77044)
				)
			)
		)
		(polygon
			(pts
				(arc
					(start 137.16254 -98.3996)
					(mid 137.117159 -98.290041)
					(end 137.0076 -98.24466)
				)
				(arc
					(start 136.8044 -98.24466)
					(mid 136.694841 -98.290041)
					(end 136.64946 -98.3996)
				)
				(arc
					(start 136.64946 -98.6536)
					(mid 136.685372 -98.75279)
					(end 136.77646 -98.806)
				)
				(arc
					(start 136.77646 -98.806)
					(mid 136.685372 -98.85921)
					(end 136.64946 -98.9584)
				)
				(arc
					(start 136.64946 -99.2124)
					(mid 136.694841 -99.321959)
					(end 136.8044 -99.36734)
				)
				(arc
					(start 137.0076 -99.36734)
					(mid 137.117159 -99.321959)
					(end 137.16254 -99.2124)
				)
				(arc
					(start 137.16254 -98.9584)
					(mid 137.126628 -98.85921)
					(end 137.03554 -98.806)
				)
				(arc
					(start 137.03554 -98.806)
					(mid 137.126628 -98.75279)
					(end 137.16254 -98.6536)
				)
			)
		)
		(polygon
			(pts
				(arc
					(start 136.52754 -98.3996)
					(mid 136.482159 -98.290041)
					(end 136.3726 -98.24466)
				)
				(arc
					(start 136.1694 -98.24466)
					(mid 136.059841 -98.290041)
					(end 136.01446 -98.3996)
				)
				(arc
					(start 136.01446 -98.6536)
					(mid 136.050372 -98.75279)
					(end 136.14146 -98.806)
				)
				(arc
					(start 136.14146 -98.806)
					(mid 136.050372 -98.85921)
					(end 136.01446 -98.9584)
				)
				(arc
					(start 136.01446 -99.2124)
					(mid 136.059841 -99.321959)
					(end 136.1694 -99.36734)
				)
				(arc
					(start 136.3726 -99.36734)
					(mid 136.482159 -99.321959)
					(end 136.52754 -99.2124)
				)
				(arc
					(start 136.52754 -98.9584)
					(mid 136.491628 -98.85921)
					(end 136.40054 -98.806)
				)
				(arc
					(start 136.40054 -98.806)
					(mid 136.491628 -98.75279)
					(end 136.52754 -98.6536)
				)
			)
		)
		(polygon
			(pts
				(arc
					(start 135.39851 -98.3996)
					(mid 135.353129 -98.290041)
					(end 135.24357 -98.24466)
				)
				(arc
					(start 135.04037 -98.24466)
					(mid 134.930811 -98.290041)
					(end 134.88543 -98.3996)
				)
				(arc
					(start 134.88543 -98.6536)
					(mid 134.921342 -98.75279)
					(end 135.01243 -98.806)
				)
				(arc
					(start 135.01243 -98.806)
					(mid 134.921342 -98.85921)
					(end 134.88543 -98.9584)
				)
				(arc
					(start 134.88543 -99.2124)
					(mid 134.930811 -99.321959)
					(end 135.04037 -99.36734)
				)
				(arc
					(start 135.24357 -99.36734)
					(mid 135.353129 -99.321959)
					(end 135.39851 -99.2124)
				)
				(arc
					(start 135.39851 -98.9584)
					(mid 135.362598 -98.85921)
					(end 135.27151 -98.806)
				)
				(arc
					(start 135.27151 -98.806)
					(mid 135.362598 -98.75279)
					(end 135.39851 -98.6536)
				)
			)
		)
		(polygon
			(pts
				(arc
					(start 134.76351 -98.3996)
					(mid 134.718129 -98.290041)
					(end 134.60857 -98.24466)
				)
				(arc
					(start 134.40537 -98.24466)
					(mid 134.295811 -98.290041)
					(end 134.25043 -98.3996)
				)
				(arc
					(start 134.25043 -98.6536)
					(mid 134.286342 -98.75279)
					(end 134.37743 -98.806)
				)
				(arc
					(start 134.37743 -98.806)
					(mid 134.286342 -98.85921)
					(end 134.25043 -98.9584)
				)
				(arc
					(start 134.25043 -99.2124)
					(mid 134.295811 -99.321959)
					(end 134.40537 -99.36734)
				)
				(arc
					(start 134.60857 -99.36734)
					(mid 134.718129 -99.321959)
					(end 134.76351 -99.2124)
				)
				(arc
					(start 134.76351 -98.9584)
					(mid 134.727598 -98.85921)
					(end 134.63651 -98.806)
				)
				(arc
					(start 134.63651 -98.806)
					(mid 134.727598 -98.75279)
					(end 134.76351 -98.6536)
				)
			)
		)
		(polygon
			(pts
				(arc
					(start 133.62051 -98.3996)
					(mid 133.575129 -98.290041)
					(end 133.46557 -98.24466)
				)
				(arc
					(start 133.26237 -98.24466)
					(mid 133.152811 -98.290041)
					(end 133.10743 -98.3996)
				)
				(arc
					(start 133.10743 -98.6536)
					(mid 133.143342 -98.75279)
					(end 133.23443 -98.806)
				)
				(arc
					(start 133.23443 -98.806)
					(mid 133.143342 -98.85921)
					(end 133.10743 -98.9584)
				)
				(arc
					(start 133.10743 -99.2124)
					(mid 133.152811 -99.321959)
					(end 133.26237 -99.36734)
				)
				(arc
					(start 133.46557 -99.36734)
					(mid 133.575129 -99.321959)
					(end 133.62051 -99.2124)
				)
				(arc
					(start 133.62051 -98.9584)
					(mid 133.584598 -98.85921)
					(end 133.49351 -98.806)
				)
				(arc
					(start 133.49351 -98.806)
					(mid 133.584598 -98.75279)
					(end 133.62051 -98.6536)
				)
			)
		)
		(polygon
			(pts
				(arc
					(start 132.98551 -98.3996)
					(mid 132.940129 -98.290041)
					(end 132.83057 -98.24466)
				)
				(arc
					(start 132.62737 -98.24466)
					(mid 132.517811 -98.290041)
					(end 132.47243 -98.3996)
				)
				(arc
					(start 132.47243 -98.6536)
					(mid 132.508342 -98.75279)
					(end 132.59943 -98.806)
				)
				(arc
					(start 132.59943 -98.806)
					(mid 132.508342 -98.85921)
					(end 132.47243 -98.9584)
				)
				(arc
					(start 132.47243 -99.2124)
					(mid 132.517811 -99.321959)
					(end 132.62737 -99.36734)
				)
				(arc
					(start 132.83057 -99.36734)
					(mid 132.940129 -99.321959)
					(end 132.98551 -99.2124)
				)
				(arc
					(start 132.98551 -98.9584)
					(mid 132.949598 -98.85921)
					(end 132.85851 -98.806)
				)
				(arc
					(start 132.85851 -98.806)
					(mid 132.949598 -98.75279)
					(end 132.98551 -98.6536)
				)
			)
		)
		(polygon
			(pts
				(arc
					(start 19.325082 -98.929444)
					(mid 19.708622 -98.545904)
					(end 19.325082 -98.162364)
				)
				(arc
					(start 18.258028 -98.162364)
					(mid 17.874742 -98.546031)
					(end 18.258282 -98.929444)
				)
			)
		)
		(polygon
			(pts
				(arc
					(start 11.147044 -98.109786)
					(mid 10.762742 -98.492564)
					(end 11.14552 -98.876866)
				)
				(arc
					(start 12.059666 -98.878644)
					(mid 12.444222 -98.495993)
					(end 12.061444 -98.111564)
				)
			)
		)
		(polygon
			(pts
				(xy 15.95755 -98.109278) (xy 15.957296 -98.109532)
				(arc
					(start 15.957296 -98.111818)
					(mid 15.563596 -98.48469)
					(end 15.936468 -98.87839)
				)
				(xy 15.936468 -98.88093) (xy 16.876268 -98.90633)
				(arc
					(start 16.876268 -98.90379)
					(mid 17.269968 -98.530918)
					(end 16.897096 -98.137218)
				)
				(xy 16.897096 -98.134678)
			)
		)
		(polygon
			(pts
				(arc
					(start 13.52931 -98.086672)
					(mid 13.12545 -98.448876)
					(end 13.487654 -98.852736)
				)
				(xy 14.4272 -98.903536)
				(arc
					(start 14.427454 -98.903536)
					(mid 14.831314 -98.541332)
					(end 14.46911 -98.137472)
				)
			)
		)
		(polygon
			(pts
				(arc
					(start 122.862848 -93.470222)
					(mid 122.497342 -93.820996)
					(end 122.848116 -94.186502)
				)
				(arc
					(start 123.843542 -94.206822)
					(mid 124.209305 -93.856175)
					(end 123.858528 -93.490542)
				)
			)
		)
		(polygon
			(pts
				(arc
					(start 123.208288 -91.849702)
					(mid 122.850021 -91.491562)
					(end 122.492008 -91.849956)
				)
				(arc
					(start 122.492262 -92.827348)
					(mid 122.850402 -93.185742)
					(end 123.208542 -92.827348)
				)
				(xy 123.208288 -91.849956)
			)
		)
		(polygon
			(pts
				(arc
					(start 132.59054 -91.169744)
					(mid 132.242981 -90.788149)
					(end 131.830318 -91.098116)
				)
				(arc
					(start 131.830318 -91.098116)
					(mid 131.78132 -91.067223)
					(end 131.7244 -91.05646)
				)
				(arc
					(start 131.4704 -91.05646)
					(mid 131.37121 -91.092372)
					(end 131.318 -91.18346)
				)
				(arc
					(start 131.318 -91.18346)
					(mid 131.26479 -91.092372)
					(end 131.1656 -91.05646)
				)
				(arc
					(start 130.9116 -91.05646)
					(mid 130.802041 -91.101841)
					(end 130.75666 -91.2114)
				)
				(arc
					(start 130.75666 -91.4146)
					(mid 130.802041 -91.524159)
					(end 130.9116 -91.56954)
				)
				(arc
					(start 131.1656 -91.56954)
					(mid 131.26479 -91.533628)
					(end 131.318 -91.44254)
				)
				(arc
					(start 131.318 -91.44254)
					(mid 131.37121 -91.533628)
					(end 131.4704 -91.56954)
				)
				(arc
					(start 131.7244 -91.56954)
					(mid 131.777069 -91.560313)
					(end 131.82346 -91.533726)
				)
				(arc
					(start 131.82346 -91.727274)
					(mid 131.777066 -91.700694)
					(end 131.7244 -91.69146)
				)
				(arc
					(start 131.4704 -91.69146)
					(mid 131.37121 -91.727372)
					(end 131.318 -91.81846)
				)
				(arc
					(start 131.318 -91.81846)
					(mid 131.26479 -91.727372)
					(end 131.1656 -91.69146)
				)
				(arc
					(start 130.9116 -91.69146)
					(mid 130.802041 -91.736841)
					(end 130.75666 -91.8464)
				)
				(arc
					(start 130.75666 -92.0496)
					(mid 130.802041 -92.159159)
					(end 130.9116 -92.20454)
				)
				(arc
					(start 131.1656 -92.20454)
					(mid 131.26479 -92.168628)
					(end 131.318 -92.07754)
				)
				(arc
					(start 131.318 -92.07754)
					(mid 131.37121 -92.168628)
					(end 131.4704 -92.20454)
				)
				(arc
					(start 131.7244 -92.20454)
					(mid 131.783126 -92.193)
					(end 131.833112 -92.16009)
				)
				(arc
					(start 131.833112 -92.16009)
					(mid 132.249813 -92.456051)
					(end 132.59054 -92.075)
				)
			)
		)
		(polygon
			(pts
				(arc
					(start 123.850146 -91.207844)
					(mid 124.208286 -90.849704)
					(end 123.850146 -90.491564)
				)
				(arc
					(start 122.849894 -90.491564)
					(mid 122.492008 -90.849831)
					(end 122.850148 -91.207844)
				)
			)
		)
		(polygon
			(pts
				(arc
					(start 131.318 -90.29446)
					(mid 131.26479 -90.203372)
					(end 131.1656 -90.16746)
				)
				(arc
					(start 130.9116 -90.16746)
					(mid 130.802041 -90.212841)
					(end 130.75666 -90.3224)
				)
				(arc
					(start 130.75666 -90.5256)
					(mid 130.802041 -90.635159)
					(end 130.9116 -90.68054)
				)
				(arc
					(start 131.1656 -90.68054)
					(mid 131.26479 -90.644628)
					(end 131.318 -90.55354)
				)
				(arc
					(start 131.318 -90.55354)
					(mid 131.37121 -90.644628)
					(end 131.4704 -90.68054)
				)
				(arc
					(start 131.7244 -90.68054)
					(mid 131.833959 -90.635159)
					(end 131.87934 -90.5256)
				)
				(arc
					(start 131.87934 -90.3224)
					(mid 131.833959 -90.212841)
					(end 131.7244 -90.16746)
				)
				(arc
					(start 131.4704 -90.16746)
					(mid 131.37121 -90.203372)
					(end 131.318 -90.29446)
				)
			)
		)
		(polygon
			(pts
				(arc
					(start 42.328338 -90.479626)
					(mid 42.711878 -90.096086)
					(end 42.328338 -89.712546)
				)
				(arc
					(start 41.3512 -89.712546)
					(mid 40.967914 -90.096213)
					(end 41.351454 -90.479626)
				)
			)
		)
		(polygon
			(pts
				(arc
					(start 39.407592 -90.479626)
					(mid 39.790878 -90.095959)
					(end 39.407338 -89.712546)
				)
				(arc
					(start 38.430454 -89.712546)
					(mid 38.046914 -90.096086)
					(end 38.430454 -90.479626)
				)
			)
		)
		(polygon
			(pts
				(arc
					(start 36.359592 -90.479626)
					(mid 36.742878 -90.095959)
					(end 36.359338 -89.712546)
				)
				(arc
					(start 35.382454 -89.712546)
					(mid 34.998914 -90.096086)
					(end 35.382454 -90.479626)
				)
			)
		)
		(polygon
			(pts
				(arc
					(start 33.311338 -90.479626)
					(mid 33.694878 -90.096086)
					(end 33.311338 -89.712546)
				)
				(arc
					(start 32.3342 -89.712546)
					(mid 31.950914 -90.096213)
					(end 32.334454 -90.479626)
				)
			)
		)
		(polygon
			(pts
				(arc
					(start 131.318 -89.65946)
					(mid 131.26479 -89.568372)
					(end 131.1656 -89.53246)
				)
				(arc
					(start 130.9116 -89.53246)
					(mid 130.802041 -89.577841)
					(end 130.75666 -89.6874)
				)
				(arc
					(start 130.75666 -89.8906)
					(mid 130.802041 -90.000159)
					(end 130.9116 -90.04554)
				)
				(arc
					(start 131.1656 -90.04554)
					(mid 131.26479 -90.009628)
					(end 131.318 -89.91854)
				)
				(arc
					(start 131.318 -89.91854)
					(mid 131.37121 -90.009628)
					(end 131.4704 -90.04554)
				)
				(arc
					(start 131.7244 -90.04554)
					(mid 131.833959 -90.000159)
					(end 131.87934 -89.8906)
				)
				(arc
					(start 131.87934 -89.6874)
					(mid 131.833959 -89.577841)
					(end 131.7244 -89.53246)
				)
				(arc
					(start 131.4704 -89.53246)
					(mid 131.37121 -89.568372)
					(end 131.318 -89.65946)
				)
			)
		)
		(polygon
			(pts
				(arc
					(start 123.850146 -90.207846)
					(mid 124.208286 -89.849706)
					(end 123.850146 -89.491566)
				)
				(arc
					(start 122.849894 -89.491566)
					(mid 122.492008 -89.849833)
					(end 122.850148 -90.207846)
				)
			)
		)
		(polygon
			(pts
				(arc
					(start 134.11454 -89.654126)
					(mid 133.731 -89.270586)
					(end 133.34746 -89.654126)
				)
				(arc
					(start 133.34746 -90.559382)
					(mid 133.731127 -90.942668)
					(end 134.11454 -90.559128)
				)
			)
		)
		(polygon
			(pts
				(arc
					(start 132.59054 -88.375744)
					(mid 132.242981 -87.994149)
					(end 131.830318 -88.304116)
				)
				(arc
					(start 131.830318 -88.304116)
					(mid 131.78132 -88.273223)
					(end 131.7244 -88.26246)
				)
				(arc
					(start 131.4704 -88.26246)
					(mid 131.37121 -88.298372)
					(end 131.318 -88.38946)
				)
				(arc
					(start 131.318 -88.38946)
					(mid 131.26479 -88.298372)
					(end 131.1656 -88.26246)
				)
				(arc
					(start 130.9116 -88.26246)
					(mid 130.802041 -88.307841)
					(end 130.75666 -88.4174)
				)
				(arc
					(start 130.75666 -88.6206)
					(mid 130.802041 -88.730159)
					(end 130.9116 -88.77554)
				)
				(arc
					(start 131.1656 -88.77554)
					(mid 131.26479 -88.739628)
					(end 131.318 -88.64854)
				)
				(arc
					(start 131.318 -88.64854)
					(mid 131.37121 -88.739628)
					(end 131.4704 -88.77554)
				)
				(arc
					(start 131.7244 -88.77554)
					(mid 131.777069 -88.766313)
					(end 131.82346 -88.739726)
				)
				(arc
					(start 131.82346 -88.933274)
					(mid 131.777066 -88.906694)
					(end 131.7244 -88.89746)
				)
				(arc
					(start 131.4704 -88.89746)
					(mid 131.37121 -88.933372)
					(end 131.318 -89.02446)
				)
				(arc
					(start 131.318 -89.02446)
					(mid 131.26479 -88.933372)
					(end 131.1656 -88.89746)
				)
				(arc
					(start 130.9116 -88.89746)
					(mid 130.802041 -88.942841)
					(end 130.75666 -89.0524)
				)
				(arc
					(start 130.75666 -89.2556)
					(mid 130.802041 -89.365159)
					(end 130.9116 -89.41054)
				)
				(arc
					(start 131.1656 -89.41054)
					(mid 131.26479 -89.374628)
					(end 131.318 -89.28354)
				)
				(arc
					(start 131.318 -89.28354)
					(mid 131.37121 -89.374628)
					(end 131.4704 -89.41054)
				)
				(arc
					(start 131.7244 -89.41054)
					(mid 131.783126 -89.399)
					(end 131.833112 -89.36609)
				)
				(arc
					(start 131.833112 -89.36609)
					(mid 132.249813 -89.662051)
					(end 132.59054 -89.281)
				)
			)
		)
		(polygon
			(pts
				(arc
					(start 131.318 -87.75446)
					(mid 131.26479 -87.663372)
					(end 131.1656 -87.62746)
				)
				(arc
					(start 130.9116 -87.62746)
					(mid 130.802041 -87.672841)
					(end 130.75666 -87.7824)
				)
				(arc
					(start 130.75666 -87.9856)
					(mid 130.802041 -88.095159)
					(end 130.9116 -88.14054)
				)
				(arc
					(start 131.1656 -88.14054)
					(mid 131.26479 -88.104628)
					(end 131.318 -88.01354)
				)
				(arc
					(start 131.318 -88.01354)
					(mid 131.37121 -88.104628)
					(end 131.4704 -88.14054)
				)
				(arc
					(start 131.7244 -88.14054)
					(mid 131.833959 -88.095159)
					(end 131.87934 -87.9856)
				)
				(arc
					(start 131.87934 -87.7824)
					(mid 131.833959 -87.672841)
					(end 131.7244 -87.62746)
				)
				(arc
					(start 131.4704 -87.62746)
					(mid 131.37121 -87.663372)
					(end 131.318 -87.75446)
				)
			)
		)
		(polygon
			(pts
				(arc
					(start 304.720244 -87.908892)
					(mid 305.10353 -87.525225)
					(end 304.71999 -87.141812)
				)
				(arc
					(start 303.80305 -87.141812)
					(mid 303.41951 -87.525352)
					(end 303.80305 -87.908892)
				)
			)
		)
		(polygon
			(pts
				(arc
					(start 131.318 -87.11946)
					(mid 131.26479 -87.028372)
					(end 131.1656 -86.99246)
				)
				(arc
					(start 130.9116 -86.99246)
					(mid 130.802041 -87.037841)
					(end 130.75666 -87.1474)
				)
				(arc
					(start 130.75666 -87.3506)
					(mid 130.802041 -87.460159)
					(end 130.9116 -87.50554)
				)
				(arc
					(start 131.1656 -87.50554)
					(mid 131.26479 -87.469628)
					(end 131.318 -87.37854)
				)
				(arc
					(start 131.318 -87.37854)
					(mid 131.37121 -87.469628)
					(end 131.4704 -87.50554)
				)
				(arc
					(start 131.7244 -87.50554)
					(mid 131.833959 -87.460159)
					(end 131.87934 -87.3506)
				)
				(arc
					(start 131.87934 -87.1474)
					(mid 131.833959 -87.037841)
					(end 131.7244 -86.99246)
				)
				(arc
					(start 131.4704 -86.99246)
					(mid 131.37121 -87.028372)
					(end 131.318 -87.11946)
				)
			)
		)
		(polygon
			(pts
				(arc
					(start 134.11454 -87.113872)
					(mid 133.730873 -86.730586)
					(end 133.34746 -87.114126)
				)
				(arc
					(start 133.34746 -88.019128)
					(mid 133.731 -88.402668)
					(end 134.11454 -88.019128)
				)
			)
		)
		(polygon
			(pts
				(arc
					(start 49.373536 -86.76894)
					(mid 48.989869 -86.385654)
					(end 48.606456 -86.769194)
				)
				(arc
					(start 48.606456 -87.746078)
					(mid 48.989996 -88.129618)
					(end 49.373536 -87.746078)
				)
			)
		)
		(polygon
			(pts
				(arc
					(start 131.069842 -84.905342)
					(mid 131.016632 -84.814254)
					(end 130.917442 -84.778342)
				)
				(arc
					(start 130.663442 -84.778342)
					(mid 130.553883 -84.823723)
					(end 130.508502 -84.933282)
				)
				(arc
					(start 130.508502 -85.136482)
					(mid 130.553883 -85.246041)
					(end 130.663442 -85.291422)
				)
				(arc
					(start 130.917442 -85.291422)
					(mid 131.016632 -85.25551)
					(end 131.069842 -85.164422)
				)
				(arc
					(start 131.069842 -85.164422)
					(mid 131.123052 -85.25551)
					(end 131.222242 -85.291422)
				)
				(arc
					(start 131.476242 -85.291422)
					(mid 131.585801 -85.246041)
					(end 131.631182 -85.136482)
				)
				(arc
					(start 131.631182 -84.933282)
					(mid 131.585801 -84.823723)
					(end 131.476242 -84.778342)
				)
				(arc
					(start 131.222242 -84.778342)
					(mid 131.123052 -84.814254)
					(end 131.069842 -84.905342)
				)
			)
		)
		(polygon
			(pts
				(arc
					(start 123.84532 -85.151214)
					(mid 124.182625 -84.773135)
					(end 123.804426 -84.43595)
				)
				(arc
					(start 122.829574 -84.492084)
					(mid 122.492516 -84.87029)
					(end 122.870722 -85.207348)
				)
			)
		)
		(polygon
			(pts
				(arc
					(start 133.736842 -84.397342)
					(mid 133.683632 -84.306254)
					(end 133.584442 -84.270342)
				)
				(arc
					(start 133.330442 -84.270342)
					(mid 133.220883 -84.315723)
					(end 133.175502 -84.425282)
				)
				(arc
					(start 133.175502 -84.628482)
					(mid 133.220883 -84.738041)
					(end 133.330442 -84.783422)
				)
				(arc
					(start 133.584442 -84.783422)
					(mid 133.683632 -84.74751)
					(end 133.736842 -84.656422)
				)
				(arc
					(start 133.736842 -84.656422)
					(mid 133.790052 -84.74751)
					(end 133.889242 -84.783422)
				)
				(arc
					(start 134.143242 -84.783422)
					(mid 134.252801 -84.738041)
					(end 134.298182 -84.628482)
				)
				(arc
					(start 134.298182 -84.425282)
					(mid 134.252801 -84.315723)
					(end 134.143242 -84.270342)
				)
				(arc
					(start 133.889242 -84.270342)
					(mid 133.790052 -84.306254)
					(end 133.736842 -84.397342)
				)
			)
		)
		(polygon
			(pts
				(arc
					(start 131.069842 -84.270342)
					(mid 131.016632 -84.179254)
					(end 130.917442 -84.143342)
				)
				(arc
					(start 130.663442 -84.143342)
					(mid 130.553883 -84.188723)
					(end 130.508502 -84.298282)
				)
				(arc
					(start 130.508502 -84.501482)
					(mid 130.553883 -84.611041)
					(end 130.663442 -84.656422)
				)
				(arc
					(start 130.917442 -84.656422)
					(mid 131.016632 -84.62051)
					(end 131.069842 -84.529422)
				)
				(arc
					(start 131.069842 -84.529422)
					(mid 131.123052 -84.62051)
					(end 131.222242 -84.656422)
				)
				(arc
					(start 131.476242 -84.656422)
					(mid 131.585801 -84.611041)
					(end 131.631182 -84.501482)
				)
				(arc
					(start 131.631182 -84.298282)
					(mid 131.585801 -84.188723)
					(end 131.476242 -84.143342)
				)
				(arc
					(start 131.222242 -84.143342)
					(mid 131.123052 -84.179254)
					(end 131.069842 -84.270342)
				)
			)
		)
		(polygon
			(pts
				(arc
					(start 133.736842 -83.762342)
					(mid 133.683632 -83.671254)
					(end 133.584442 -83.635342)
				)
				(arc
					(start 133.330442 -83.635342)
					(mid 133.220883 -83.680723)
					(end 133.175502 -83.790282)
				)
				(arc
					(start 133.175502 -83.993482)
					(mid 133.220883 -84.103041)
					(end 133.330442 -84.148422)
				)
				(arc
					(start 133.584442 -84.148422)
					(mid 133.683632 -84.11251)
					(end 133.736842 -84.021422)
				)
				(arc
					(start 133.736842 -84.021422)
					(mid 133.790052 -84.11251)
					(end 133.889242 -84.148422)
				)
				(arc
					(start 134.143242 -84.148422)
					(mid 134.252801 -84.103041)
					(end 134.298182 -83.993482)
				)
				(arc
					(start 134.298182 -83.790282)
					(mid 134.252801 -83.680723)
					(end 134.143242 -83.635342)
				)
				(arc
					(start 133.889242 -83.635342)
					(mid 133.790052 -83.671254)
					(end 133.736842 -83.762342)
				)
			)
		)
		(polygon
			(pts
				(arc
					(start 49.373536 -83.937094)
					(mid 48.989996 -83.553554)
					(end 48.606456 -83.937094)
				)
				(arc
					(start 48.606456 -84.914232)
					(mid 48.990123 -85.297518)
					(end 49.373536 -84.913978)
				)
			)
		)
		(polygon
			(pts
				(arc
					(start 123.8504 -84.207858)
					(mid 124.208286 -83.849591)
					(end 123.850146 -83.491578)
				)
				(arc
					(start 122.850148 -83.491578)
					(mid 122.492008 -83.849718)
					(end 122.850148 -84.207858)
				)
			)
		)
		(polygon
			(pts
				(arc
					(start 45.624242 -83.885786)
					(mid 46.007528 -83.502119)
					(end 45.623988 -83.118706)
				)
				(arc
					(start 44.647104 -83.118706)
					(mid 44.263564 -83.502246)
					(end 44.647104 -83.885786)
				)
			)
		)
		(polygon
			(pts
				(arc
					(start 42.670222 -83.873086)
					(mid 43.053762 -83.489546)
					(end 42.670222 -83.106006)
				)
				(arc
					(start 41.693084 -83.106006)
					(mid 41.309798 -83.489673)
					(end 41.693338 -83.873086)
				)
			)
		)
		(polygon
			(pts
				(arc
					(start 132.212842 -83.000342)
					(mid 132.159632 -82.909254)
					(end 132.060442 -82.873342)
				)
				(arc
					(start 131.806442 -82.873342)
					(mid 131.696883 -82.918723)
					(end 131.651502 -83.028282)
				)
				(arc
					(start 131.651502 -83.231482)
					(mid 131.696883 -83.341041)
					(end 131.806442 -83.386422)
				)
				(arc
					(start 132.060442 -83.386422)
					(mid 132.159632 -83.35051)
					(end 132.212842 -83.259422)
				)
				(arc
					(start 132.212842 -83.259422)
					(mid 132.266052 -83.35051)
					(end 132.365242 -83.386422)
				)
				(arc
					(start 132.619242 -83.386422)
					(mid 132.728801 -83.341041)
					(end 132.774182 -83.231482)
				)
				(arc
					(start 132.774182 -83.028282)
					(mid 132.728801 -82.918723)
					(end 132.619242 -82.873342)
				)
				(arc
					(start 132.365242 -82.873342)
					(mid 132.266052 -82.909254)
					(end 132.212842 -83.000342)
				)
			)
		)
		(polygon
			(pts
				(arc
					(start 123.850146 -83.20786)
					(mid 124.208286 -82.84972)
					(end 123.850146 -82.49158)
				)
				(arc
					(start 122.849894 -82.49158)
					(mid 122.492008 -82.849847)
					(end 122.850148 -83.20786)
				)
			)
		)
		(polygon
			(pts
				(arc
					(start 135.509508 -83.06054)
					(mid 135.893048 -82.677)
					(end 135.509508 -82.29346)
				)
				(arc
					(start 134.581138 -82.29346)
					(mid 134.197852 -82.677127)
					(end 134.581392 -83.06054)
				)
			)
		)
		(polygon
			(pts
				(arc
					(start 132.212842 -82.365342)
					(mid 132.159632 -82.274254)
					(end 132.060442 -82.238342)
				)
				(arc
					(start 131.806442 -82.238342)
					(mid 131.696883 -82.283723)
					(end 131.651502 -82.393282)
				)
				(arc
					(start 131.651502 -82.596482)
					(mid 131.696883 -82.706041)
					(end 131.806442 -82.751422)
				)
				(arc
					(start 132.060442 -82.751422)
					(mid 132.159632 -82.71551)
					(end 132.212842 -82.624422)
				)
				(arc
					(start 132.212842 -82.624422)
					(mid 132.266052 -82.71551)
					(end 132.365242 -82.751422)
				)
				(arc
					(start 132.619242 -82.751422)
					(mid 132.728801 -82.706041)
					(end 132.774182 -82.596482)
				)
				(arc
					(start 132.774182 -82.393282)
					(mid 132.728801 -82.283723)
					(end 132.619242 -82.238342)
				)
				(arc
					(start 132.365242 -82.238342)
					(mid 132.266052 -82.274254)
					(end 132.212842 -82.365342)
				)
			)
		)
		(polygon
			(pts
				(arc
					(start 317.037212 -82.17408)
					(mid 316.976952 -82.0286)
					(end 316.831472 -81.96834)
				)
				(arc
					(start 316.425072 -81.96834)
					(mid 316.279592 -82.0286)
					(end 316.219332 -82.17408)
				)
				(arc
					(start 316.219332 -82.58048)
					(mid 316.279592 -82.72596)
					(end 316.425072 -82.78622)
				)
				(arc
					(start 316.831472 -82.78622)
					(mid 316.976952 -82.72596)
					(end 317.037212 -82.58048)
				)
			)
		)
		(polygon
			(pts
				(arc
					(start 316.122812 -82.17408)
					(mid 316.062552 -82.0286)
					(end 315.917072 -81.96834)
				)
				(arc
					(start 315.510672 -81.96834)
					(mid 315.365192 -82.0286)
					(end 315.304932 -82.17408)
				)
				(arc
					(start 315.304932 -82.58048)
					(mid 315.365192 -82.72596)
					(end 315.510672 -82.78622)
				)
				(arc
					(start 315.917072 -82.78622)
					(mid 316.062552 -82.72596)
					(end 316.122812 -82.58048)
				)
			)
		)
		(polygon
			(pts
				(arc
					(start 297.974004 -82.607404)
					(mid 298.35729 -82.223737)
					(end 297.97375 -81.840324)
				)
				(arc
					(start 297.05681 -81.840324)
					(mid 296.67327 -82.223864)
					(end 297.05681 -82.607404)
				)
			)
		)
		(polygon
			(pts
				(arc
					(start 39.975536 -82.070194)
					(mid 39.591996 -81.686654)
					(end 39.208456 -82.070194)
				)
				(arc
					(start 39.208456 -83.047332)
					(mid 39.592123 -83.430618)
					(end 39.975536 -83.047078)
				)
			)
		)
		(polygon
			(pts
				(arc
					(start 123.7488 -82.120486)
					(mid 124.095256 -81.75117)
					(end 123.72594 -81.404714)
				)
				(xy 123.72594 -81.402174) (xy 122.924824 -81.427574) (xy 122.92457 -81.427828)
				(arc
					(start 122.92457 -81.430114)
					(mid 122.578114 -81.79943)
					(end 122.94743 -82.145886)
				)
				(xy 122.94743 -82.148426) (xy 123.7488 -82.123026)
			)
		)
		(polygon
			(pts
				(arc
					(start 136.807956 -81.91754)
					(mid 137.191496 -81.534)
					(end 136.807956 -81.15046)
				)
				(arc
					(start 135.879586 -81.15046)
					(mid 135.4963 -81.534127)
					(end 135.87984 -81.91754)
				)
			)
		)
		(polygon
			(pts
				(arc
					(start 317.037212 -81.28508)
					(mid 316.976952 -81.1396)
					(end 316.831472 -81.07934)
				)
				(arc
					(start 316.425072 -81.07934)
					(mid 316.279592 -81.1396)
					(end 316.219332 -81.28508)
				)
				(arc
					(start 316.219332 -81.69148)
					(mid 316.279592 -81.83696)
					(end 316.425072 -81.89722)
				)
				(arc
					(start 316.831472 -81.89722)
					(mid 316.976952 -81.83696)
					(end 317.037212 -81.69148)
				)
			)
		)
		(polygon
			(pts
				(arc
					(start 316.122812 -81.28508)
					(mid 316.062552 -81.1396)
					(end 315.917072 -81.07934)
				)
				(arc
					(start 315.510672 -81.07934)
					(mid 315.365192 -81.1396)
					(end 315.304932 -81.28508)
				)
				(arc
					(start 315.304932 -81.69148)
					(mid 315.365192 -81.83696)
					(end 315.510672 -81.89722)
				)
				(arc
					(start 315.917072 -81.89722)
					(mid 316.062552 -81.83696)
					(end 316.122812 -81.69148)
				)
			)
		)
		(polygon
			(pts
				(arc
					(start 318.690498 -81.407)
					(mid 318.306958 -81.02346)
					(end 317.923418 -81.407)
				)
				(arc
					(start 317.923418 -82.423254)
					(mid 318.307085 -82.80654)
					(end 318.690498 -82.423)
				)
			)
		)
		(polygon
			(pts
				(xy 314.198 -80.899) (xy 312.039 -80.899) (xy 312.039 -82.296) (xy 314.198 -82.296)
			)
		)
		(polygon
			(pts
				(arc
					(start 130.048254 -81.66354)
					(mid 130.43154 -81.279873)
					(end 130.048 -80.89646)
				)
				(arc
					(start 129.159 -80.89646)
					(mid 128.77546 -81.28)
					(end 129.159 -81.66354)
				)
			)
		)
		(polygon
			(pts
				(arc
					(start 133.858762 -81.500726)
					(mid 134.242048 -81.117059)
					(end 133.858508 -80.733646)
				)
				(arc
					(start 132.930392 -80.733646)
					(mid 132.546852 -81.117186)
					(end 132.930392 -81.500726)
				)
			)
		)
		(polygon
			(pts
				(arc
					(start 132.154422 -80.740758)
					(mid 132.109041 -80.631199)
					(end 131.999482 -80.585818)
				)
				(arc
					(start 131.796282 -80.585818)
					(mid 131.686723 -80.631199)
					(end 131.641342 -80.740758)
				)
				(arc
					(start 131.641342 -80.994758)
					(mid 131.677254 -81.093948)
					(end 131.768342 -81.147158)
				)
				(arc
					(start 131.768342 -81.147158)
					(mid 131.677254 -81.200368)
					(end 131.641342 -81.299558)
				)
				(arc
					(start 131.641342 -81.553558)
					(mid 131.686723 -81.663117)
					(end 131.796282 -81.708498)
				)
				(arc
					(start 131.999482 -81.708498)
					(mid 132.109041 -81.663117)
					(end 132.154422 -81.553558)
				)
				(arc
					(start 132.154422 -81.299558)
					(mid 132.11851 -81.200368)
					(end 132.027422 -81.147158)
				)
				(arc
					(start 132.027422 -81.147158)
					(mid 132.11851 -81.093948)
					(end 132.154422 -80.994758)
				)
			)
		)
		(polygon
			(pts
				(arc
					(start 131.392422 -80.740758)
					(mid 131.347041 -80.631199)
					(end 131.237482 -80.585818)
				)
				(arc
					(start 131.034282 -80.585818)
					(mid 130.924723 -80.631199)
					(end 130.879342 -80.740758)
				)
				(arc
					(start 130.879342 -80.994758)
					(mid 130.915254 -81.093948)
					(end 131.006342 -81.147158)
				)
				(arc
					(start 131.006342 -81.147158)
					(mid 130.915254 -81.200368)
					(end 130.879342 -81.299558)
				)
				(arc
					(start 130.879342 -81.553558)
					(mid 130.924723 -81.663117)
					(end 131.034282 -81.708498)
				)
				(arc
					(start 131.237482 -81.708498)
					(mid 131.347041 -81.663117)
					(end 131.392422 -81.553558)
				)
				(arc
					(start 131.392422 -81.299558)
					(mid 131.35651 -81.200368)
					(end 131.265422 -81.147158)
				)
				(arc
					(start 131.265422 -81.147158)
					(mid 131.35651 -81.093948)
					(end 131.392422 -80.994758)
				)
			)
		)
		(polygon
			(pts
				(arc
					(start 123.85294 -81.309464)
					(mid 124.236988 -80.926432)
					(end 123.853956 -80.542384)
				)
				(xy 123.833128 -80.542892)
				(arc
					(start 122.925332 -80.56626)
					(mid 122.566684 -80.923765)
					(end 122.924062 -81.28254)
				)
				(xy 123.831858 -81.308956)
			)
		)
		(polygon
			(pts
				(arc
					(start 125.756162 -80.635348)
					(mid 126.139702 -80.251808)
					(end 125.756162 -79.868268)
				)
				(arc
					(start 124.779024 -79.868268)
					(mid 124.395738 -80.251935)
					(end 124.779278 -80.635348)
				)
			)
		)
		(polygon
			(pts
				(arc
					(start 128.131316 -80.19034)
					(mid 128.514602 -79.806673)
					(end 128.131062 -79.42326)
				)
				(arc
					(start 127.154178 -79.42326)
					(mid 126.770638 -79.8068)
					(end 127.154178 -80.19034)
				)
			)
		)
		(polygon
			(pts
				(arc
					(start 132.005578 -80.13954)
					(mid 132.388864 -79.755873)
					(end 132.005324 -79.37246)
				)
				(arc
					(start 131.02844 -79.37246)
					(mid 130.6449 -79.756)
					(end 131.02844 -80.13954)
				)
			)
		)
		(polygon
			(pts
				(arc
					(start 39.975536 -79.74584)
					(mid 39.591869 -79.362554)
					(end 39.208456 -79.746094)
				)
				(arc
					(start 39.208456 -80.722978)
					(mid 39.591996 -81.106518)
					(end 39.975536 -80.722978)
				)
			)
		)
		(polygon
			(pts
				(xy 309.753 -79.2988) (xy 307.594 -79.2988) (xy 307.594 -80.6958) (xy 309.753 -80.6958)
			)
		)
		(polygon
			(pts
				(arc
					(start 294.03294 -79.44993)
					(mid 293.6494 -79.06639)
					(end 293.26586 -79.44993)
				)
				(arc
					(start 293.26586 -80.367124)
					(mid 293.649527 -80.75041)
					(end 294.03294 -80.36687)
				)
			)
		)
		(polygon
			(pts
				(arc
					(start 317.070232 -79.14132)
					(mid 317.009972 -78.99584)
					(end 316.864492 -78.93558)
				)
				(arc
					(start 316.458092 -78.93558)
					(mid 316.312612 -78.99584)
					(end 316.252352 -79.14132)
				)
				(arc
					(start 316.252352 -79.54772)
					(mid 316.312612 -79.6932)
					(end 316.458092 -79.75346)
				)
				(arc
					(start 316.864492 -79.75346)
					(mid 317.009972 -79.6932)
					(end 317.070232 -79.54772)
				)
			)
		)
		(polygon
			(pts
				(arc
					(start 316.155832 -79.14132)
					(mid 316.095572 -78.99584)
					(end 315.950092 -78.93558)
				)
				(arc
					(start 315.543692 -78.93558)
					(mid 315.398212 -78.99584)
					(end 315.337952 -79.14132)
				)
				(arc
					(start 315.337952 -79.54772)
					(mid 315.398212 -79.6932)
					(end 315.543692 -79.75346)
				)
				(arc
					(start 315.950092 -79.75346)
					(mid 316.095572 -79.6932)
					(end 316.155832 -79.54772)
				)
			)
		)
		(polygon
			(pts
				(arc
					(start 54.081934 -78.866238)
					(mid 53.799994 -78.584298)
					(end 53.518054 -78.866238)
				)
				(arc
					(start 53.518054 -80.314038)
					(mid 53.799994 -80.595978)
					(end 54.081934 -80.314038)
				)
			)
		)
		(polygon
			(pts
				(arc
					(start 53.281834 -78.866238)
					(mid 52.999894 -78.584298)
					(end 52.717954 -78.866238)
				)
				(arc
					(start 52.717954 -80.314038)
					(mid 52.999894 -80.595978)
					(end 53.281834 -80.314038)
				)
			)
		)
		(polygon
			(pts
				(arc
					(start 51.681888 -78.866238)
					(mid 51.399948 -78.584298)
					(end 51.118008 -78.866238)
				)
				(arc
					(start 51.118008 -80.314038)
					(mid 51.399948 -80.595978)
					(end 51.681888 -80.314038)
				)
			)
		)
		(polygon
			(pts
				(arc
					(start 50.881788 -78.866238)
					(mid 50.599848 -78.584298)
					(end 50.317908 -78.866238)
				)
				(arc
					(start 50.317908 -80.314038)
					(mid 50.599848 -80.595978)
					(end 50.881788 -80.314038)
				)
			)
		)
		(polygon
			(pts
				(arc
					(start 45.28185 -78.866238)
					(mid 44.99991 -78.584298)
					(end 44.71797 -78.866238)
				)
				(arc
					(start 44.71797 -80.314038)
					(mid 44.99991 -80.595978)
					(end 45.28185 -80.314038)
				)
			)
		)
		(polygon
			(pts
				(arc
					(start 44.48175 -78.866238)
					(mid 44.19981 -78.584298)
					(end 43.91787 -78.866238)
				)
				(arc
					(start 43.91787 -80.314038)
					(mid 44.19981 -80.595978)
					(end 44.48175 -80.314038)
				)
			)
		)
		(polygon
			(pts
				(arc
					(start 42.881804 -78.866238)
					(mid 42.599864 -78.584298)
					(end 42.317924 -78.866238)
				)
				(arc
					(start 42.317924 -80.314038)
					(mid 42.599864 -80.595978)
					(end 42.881804 -80.314038)
				)
			)
		)
		(polygon
			(pts
				(arc
					(start 42.081958 -78.866238)
					(mid 41.800018 -78.584298)
					(end 41.518078 -78.866238)
				)
				(arc
					(start 41.518078 -80.314038)
					(mid 41.800018 -80.595978)
					(end 42.081958 -80.314038)
				)
			)
		)
		(polygon
			(pts
				(arc
					(start 318.792098 -78.445106)
					(mid 318.418337 -78.051917)
					(end 318.025018 -78.425548)
				)
				(arc
					(start 317.999618 -79.441548)
					(mid 318.373506 -79.83474)
					(end 318.766698 -79.460852)
				)
			)
		)
		(polygon
			(pts
				(arc
					(start 317.070232 -78.25232)
					(mid 317.009972 -78.10684)
					(end 316.864492 -78.04658)
				)
				(arc
					(start 316.458092 -78.04658)
					(mid 316.312612 -78.10684)
					(end 316.252352 -78.25232)
				)
				(arc
					(start 316.252352 -78.65872)
					(mid 316.312612 -78.8042)
					(end 316.458092 -78.86446)
				)
				(arc
					(start 316.864492 -78.86446)
					(mid 317.009972 -78.8042)
					(end 317.070232 -78.65872)
				)
			)
		)
		(polygon
			(pts
				(arc
					(start 316.155832 -78.25232)
					(mid 316.095572 -78.10684)
					(end 315.950092 -78.04658)
				)
				(arc
					(start 315.543692 -78.04658)
					(mid 315.398212 -78.10684)
					(end 315.337952 -78.25232)
				)
				(arc
					(start 315.337952 -78.65872)
					(mid 315.398212 -78.8042)
					(end 315.543692 -78.86446)
				)
				(arc
					(start 315.950092 -78.86446)
					(mid 316.095572 -78.8042)
					(end 316.155832 -78.65872)
				)
			)
		)
		(polygon
			(pts
				(xy 314.198 -77.6986) (xy 312.039 -77.6986) (xy 312.039 -79.0956) (xy 314.198 -79.0956)
			)
		)
		(polygon
			(pts
				(arc
					(start 296.29354 -77.35951)
					(mid 295.91 -76.97597)
					(end 295.52646 -77.35951)
				)
				(arc
					(start 295.52646 -78.276704)
					(mid 295.910127 -78.65999)
					(end 296.29354 -78.27645)
				)
			)
		)
		(polygon
			(pts
				(arc
					(start 204.929232 -77.40904)
					(mid 205.312772 -77.0255)
					(end 204.929232 -76.64196)
				)
				(arc
					(start 203.947014 -76.64196)
					(mid 203.563728 -77.025627)
					(end 203.947268 -77.40904)
				)
			)
		)
		(polygon
			(pts
				(arc
					(start 200.928986 -77.40904)
					(mid 201.312272 -77.025373)
					(end 200.928732 -76.64196)
				)
				(arc
					(start 199.946768 -76.64196)
					(mid 199.563228 -77.0255)
					(end 199.946768 -77.40904)
				)
			)
		)
		(polygon
			(pts
				(arc
					(start 196.929502 -77.40904)
					(mid 197.313042 -77.0255)
					(end 196.929502 -76.64196)
				)
				(arc
					(start 195.947284 -76.64196)
					(mid 195.563998 -77.025627)
					(end 195.947538 -77.40904)
				)
			)
		)
		(polygon
			(pts
				(arc
					(start 192.929256 -77.40904)
					(mid 193.312542 -77.025373)
					(end 192.929002 -76.64196)
				)
				(arc
					(start 191.947038 -76.64196)
					(mid 191.563498 -77.0255)
					(end 191.947038 -77.40904)
				)
			)
		)
		(polygon
			(pts
				(arc
					(start 168.928542 -77.40904)
					(mid 169.312082 -77.0255)
					(end 168.928542 -76.64196)
				)
				(arc
					(start 167.946324 -76.64196)
					(mid 167.563038 -77.025627)
					(end 167.946578 -77.40904)
				)
			)
		)
		(polygon
			(pts
				(arc
					(start 164.928042 -77.40904)
					(mid 165.311582 -77.0255)
					(end 164.928042 -76.64196)
				)
				(arc
					(start 163.945824 -76.64196)
					(mid 163.562538 -77.025627)
					(end 163.946078 -77.40904)
				)
			)
		)
		(polygon
			(pts
				(arc
					(start 160.928812 -77.40904)
					(mid 161.312352 -77.0255)
					(end 160.928812 -76.64196)
				)
				(arc
					(start 159.946594 -76.64196)
					(mid 159.563308 -77.025627)
					(end 159.946848 -77.40904)
				)
			)
		)
		(polygon
			(pts
				(arc
					(start 156.928312 -77.40904)
					(mid 157.311852 -77.0255)
					(end 156.928312 -76.64196)
				)
				(arc
					(start 155.946094 -76.64196)
					(mid 155.562808 -77.025627)
					(end 155.946348 -77.40904)
				)
			)
		)
		(polygon
			(pts
				(xy 309.753 -76.0984) (xy 307.594 -76.0984) (xy 307.594 -77.4954) (xy 309.753 -77.4954)
			)
		)
		(polygon
			(pts
				(arc
					(start 54.48173 -76.35621)
					(mid 54.19979 -76.07427)
					(end 53.91785 -76.35621)
				)
				(arc
					(start 53.91785 -77.80401)
					(mid 54.19979 -78.08595)
					(end 54.48173 -77.80401)
				)
			)
		)
		(polygon
			(pts
				(arc
					(start 53.681884 -76.35621)
					(mid 53.399944 -76.07427)
					(end 53.118004 -76.35621)
				)
				(arc
					(start 53.118004 -77.80401)
					(mid 53.399944 -78.08595)
					(end 53.681884 -77.80401)
				)
			)
		)
		(polygon
			(pts
				(arc
					(start 52.081938 -76.35621)
					(mid 51.799998 -76.07427)
					(end 51.518058 -76.35621)
				)
				(arc
					(start 51.518058 -77.80401)
					(mid 51.799998 -78.08595)
					(end 52.081938 -77.80401)
				)
			)
		)
		(polygon
			(pts
				(arc
					(start 51.281838 -76.35621)
					(mid 50.999898 -76.07427)
					(end 50.717958 -76.35621)
				)
				(arc
					(start 50.717958 -77.80401)
					(mid 50.999898 -78.08595)
					(end 51.281838 -77.80401)
				)
			)
		)
		(polygon
			(pts
				(arc
					(start 45.6819 -76.35621)
					(mid 45.39996 -76.07427)
					(end 45.11802 -76.35621)
				)
				(arc
					(start 45.11802 -77.80401)
					(mid 45.39996 -78.08595)
					(end 45.6819 -77.80401)
				)
			)
		)
		(polygon
			(pts
				(arc
					(start 44.8818 -76.35621)
					(mid 44.59986 -76.07427)
					(end 44.31792 -76.35621)
				)
				(arc
					(start 44.31792 -77.80401)
					(mid 44.59986 -78.08595)
					(end 44.8818 -77.80401)
				)
			)
		)
		(polygon
			(pts
				(arc
					(start 43.281854 -76.35621)
					(mid 42.999914 -76.07427)
					(end 42.717974 -76.35621)
				)
				(arc
					(start 42.717974 -77.80401)
					(mid 42.999914 -78.08595)
					(end 43.281854 -77.80401)
				)
			)
		)
		(polygon
			(pts
				(arc
					(start 42.481754 -76.35621)
					(mid 42.199814 -76.07427)
					(end 41.917874 -76.35621)
				)
				(arc
					(start 41.917874 -77.80401)
					(mid 42.199814 -78.08595)
					(end 42.481754 -77.80401)
				)
			)
		)
		(polygon
			(pts
				(arc
					(start 317.108332 -75.94092)
					(mid 317.048072 -75.79544)
					(end 316.902592 -75.73518)
				)
				(arc
					(start 316.496192 -75.73518)
					(mid 316.350712 -75.79544)
					(end 316.290452 -75.94092)
				)
				(arc
					(start 316.290452 -76.34732)
					(mid 316.350712 -76.4928)
					(end 316.496192 -76.55306)
				)
				(arc
					(start 316.902592 -76.55306)
					(mid 317.048072 -76.4928)
					(end 317.108332 -76.34732)
				)
			)
		)
		(polygon
			(pts
				(arc
					(start 316.193932 -75.94092)
					(mid 316.133672 -75.79544)
					(end 315.988192 -75.73518)
				)
				(arc
					(start 315.581792 -75.73518)
					(mid 315.436312 -75.79544)
					(end 315.376052 -75.94092)
				)
				(arc
					(start 315.376052 -76.34732)
					(mid 315.436312 -76.4928)
					(end 315.581792 -76.55306)
				)
				(arc
					(start 315.988192 -76.55306)
					(mid 316.133672 -76.4928)
					(end 316.193932 -76.34732)
				)
			)
		)
		(polygon
			(pts
				(arc
					(start 317.108332 -75.05192)
					(mid 317.048072 -74.90644)
					(end 316.902592 -74.84618)
				)
				(arc
					(start 316.496192 -74.84618)
					(mid 316.350712 -74.90644)
					(end 316.290452 -75.05192)
				)
				(arc
					(start 316.290452 -75.45832)
					(mid 316.350712 -75.6038)
					(end 316.496192 -75.66406)
				)
				(arc
					(start 316.902592 -75.66406)
					(mid 317.048072 -75.6038)
					(end 317.108332 -75.45832)
				)
			)
		)
		(polygon
			(pts
				(arc
					(start 316.193932 -75.05192)
					(mid 316.133672 -74.90644)
					(end 315.988192 -74.84618)
				)
				(arc
					(start 315.581792 -74.84618)
					(mid 315.436312 -74.90644)
					(end 315.376052 -75.05192)
				)
				(arc
					(start 315.376052 -75.45832)
					(mid 315.436312 -75.6038)
					(end 315.581792 -75.66406)
				)
				(arc
					(start 315.988192 -75.66406)
					(mid 316.133672 -75.6038)
					(end 316.193932 -75.45832)
				)
			)
		)
		(polygon
			(pts
				(arc
					(start 320.570098 -75.209908)
					(mid 320.186558 -74.826368)
					(end 319.803018 -75.209908)
				)
				(arc
					(start 319.803018 -76.192126)
					(mid 320.186685 -76.575412)
					(end 320.570098 -76.191872)
				)
			)
		)
		(polygon
			(pts
				(arc
					(start 54.288436 -75.290426)
					(mid 54.671722 -74.906759)
					(end 54.288182 -74.523346)
				)
				(arc
					(start 53.311298 -74.523346)
					(mid 52.927758 -74.906886)
					(end 53.311298 -75.290426)
				)
			)
		)
		(polygon
			(pts
				(arc
					(start 51.888644 -75.290426)
					(mid 52.27193 -74.906759)
					(end 51.88839 -74.523346)
				)
				(arc
					(start 50.911506 -74.523346)
					(mid 50.527966 -74.906886)
					(end 50.911506 -75.290426)
				)
			)
		)
		(polygon
			(pts
				(arc
					(start 45.488606 -75.290426)
					(mid 45.871892 -74.906759)
					(end 45.488352 -74.523346)
				)
				(arc
					(start 44.511468 -74.523346)
					(mid 44.127928 -74.906886)
					(end 44.511468 -75.290426)
				)
			)
		)
		(polygon
			(pts
				(xy 314.198 -74.4982) (xy 312.039 -74.4982) (xy 312.039 -75.8952) (xy 314.198 -75.8952)
			)
		)
		(polygon
			(pts
				(arc
					(start 43.088306 -75.138026)
					(mid 43.471846 -74.754486)
					(end 43.088306 -74.370946)
				)
				(arc
					(start 42.111168 -74.370946)
					(mid 41.727882 -74.754613)
					(end 42.111422 -75.138026)
				)
			)
		)
		(polygon
			(pts
				(arc
					(start 298.139612 -74.07529)
					(mid 298.522898 -73.691623)
					(end 298.139358 -73.30821)
				)
				(arc
					(start 297.123358 -73.30821)
					(mid 296.739818 -73.69175)
					(end 297.123358 -74.07529)
				)
			)
		)
		(polygon
			(pts
				(arc
					(start 302.956722 -73.99274)
					(mid 303.340262 -73.6092)
					(end 302.956722 -73.22566)
				)
				(arc
					(start 301.974504 -73.22566)
					(mid 301.591218 -73.609327)
					(end 301.974758 -73.99274)
				)
			)
		)
		(polygon
			(pts
				(xy 309.753 -72.898) (xy 307.594 -72.898) (xy 307.594 -74.295) (xy 309.753 -74.295)
			)
		)
		(polygon
			(pts
				(arc
					(start 317.141098 -72.6948)
					(mid 317.080838 -72.54932)
					(end 316.935358 -72.48906)
				)
				(arc
					(start 316.528958 -72.48906)
					(mid 316.383478 -72.54932)
					(end 316.323218 -72.6948)
				)
				(arc
					(start 316.323218 -73.1012)
					(mid 316.383478 -73.24668)
					(end 316.528958 -73.30694)
				)
				(arc
					(start 316.935358 -73.30694)
					(mid 317.080838 -73.24668)
					(end 317.141098 -73.1012)
				)
			)
		)
		(polygon
			(pts
				(arc
					(start 316.226698 -72.6948)
					(mid 316.166438 -72.54932)
					(end 316.020958 -72.48906)
				)
				(arc
					(start 315.614558 -72.48906)
					(mid 315.469078 -72.54932)
					(end 315.408818 -72.6948)
				)
				(arc
					(start 315.408818 -73.1012)
					(mid 315.469078 -73.24668)
					(end 315.614558 -73.30694)
				)
				(arc
					(start 316.020958 -73.30694)
					(mid 316.166438 -73.24668)
					(end 316.226698 -73.1012)
				)
			)
		)
		(polygon
			(pts
				(arc
					(start 318.055498 -72.009)
					(mid 317.671958 -71.62546)
					(end 317.288418 -72.009)
				)
				(arc
					(start 317.288418 -73.025254)
					(mid 317.672085 -73.40854)
					(end 318.055498 -73.025)
				)
			)
		)
		(polygon
			(pts
				(arc
					(start 317.141098 -71.8058)
					(mid 317.080838 -71.66032)
					(end 316.935358 -71.60006)
				)
				(arc
					(start 316.528958 -71.60006)
					(mid 316.383478 -71.66032)
					(end 316.323218 -71.8058)
				)
				(arc
					(start 316.323218 -72.2122)
					(mid 316.383478 -72.35768)
					(end 316.528958 -72.41794)
				)
				(arc
					(start 316.935358 -72.41794)
					(mid 317.080838 -72.35768)
					(end 317.141098 -72.2122)
				)
			)
		)
		(polygon
			(pts
				(arc
					(start 316.226698 -71.8058)
					(mid 316.166438 -71.66032)
					(end 316.020958 -71.60006)
				)
				(arc
					(start 315.614558 -71.60006)
					(mid 315.469078 -71.66032)
					(end 315.408818 -71.8058)
				)
				(arc
					(start 315.408818 -72.2122)
					(mid 315.469078 -72.35768)
					(end 315.614558 -72.41794)
				)
				(arc
					(start 316.020958 -72.41794)
					(mid 316.166438 -72.35768)
					(end 316.226698 -72.2122)
				)
			)
		)
		(polygon
			(pts
				(xy 314.198 -71.2978) (xy 312.039 -71.2978) (xy 312.039 -72.6948) (xy 314.198 -72.6948)
			)
		)
		(polygon
			(pts
				(xy 309.753 -69.723) (xy 307.594 -69.723) (xy 307.594 -71.12) (xy 309.753 -71.12)
			)
		)
		(polygon
			(pts
				(arc
					(start 317.29934 -69.0372)
					(mid 317.23908 -68.89172)
					(end 317.0936 -68.83146)
				)
				(arc
					(start 316.738 -68.83146)
					(mid 316.59252 -68.89172)
					(end 316.53226 -69.0372)
				)
				(arc
					(start 316.53226 -69.3928)
					(mid 316.59252 -69.53828)
					(end 316.738 -69.59854)
				)
				(arc
					(start 317.0936 -69.59854)
					(mid 317.23908 -69.53828)
					(end 317.29934 -69.3928)
				)
			)
		)
		(polygon
			(pts
				(arc
					(start 316.43574 -69.0372)
					(mid 316.37548 -68.89172)
					(end 316.23 -68.83146)
				)
				(arc
					(start 315.8744 -68.83146)
					(mid 315.72892 -68.89172)
					(end 315.66866 -69.0372)
				)
				(arc
					(start 315.66866 -69.3928)
					(mid 315.72892 -69.53828)
					(end 315.8744 -69.59854)
				)
				(arc
					(start 316.23 -69.59854)
					(mid 316.37548 -69.53828)
					(end 316.43574 -69.3928)
				)
			)
		)
		(polygon
			(pts
				(xy 314.198 -68.0974) (xy 312.039 -68.0974) (xy 312.039 -69.4944) (xy 314.198 -69.4944)
			)
		)
		(polygon
			(pts
				(arc
					(start 319.139316 -68.215764)
					(mid 318.755649 -67.832478)
					(end 318.372236 -68.216018)
				)
				(arc
					(start 318.372236 -69.197982)
					(mid 318.755776 -69.581522)
					(end 319.139316 -69.197982)
				)
			)
		)
		(polygon
			(pts
				(arc
					(start 304.134012 -68.03644)
					(mid 304.073752 -67.89096)
					(end 303.928272 -67.8307)
				)
				(arc
					(start 303.572672 -67.8307)
					(mid 303.427192 -67.89096)
					(end 303.366932 -68.03644)
				)
				(arc
					(start 303.366932 -68.39204)
					(mid 303.427192 -68.53752)
					(end 303.572672 -68.59778)
				)
				(arc
					(start 303.928272 -68.59778)
					(mid 304.073752 -68.53752)
					(end 304.134012 -68.39204)
				)
			)
		)
		(polygon
			(pts
				(arc
					(start 303.270412 -68.03644)
					(mid 303.210152 -67.89096)
					(end 303.064672 -67.8307)
				)
				(arc
					(start 302.709072 -67.8307)
					(mid 302.563592 -67.89096)
					(end 302.503332 -68.03644)
				)
				(arc
					(start 302.503332 -68.39204)
					(mid 302.563592 -68.53752)
					(end 302.709072 -68.59778)
				)
				(arc
					(start 303.064672 -68.59778)
					(mid 303.210152 -68.53752)
					(end 303.270412 -68.39204)
				)
			)
		)
		(polygon
			(pts
				(arc
					(start 317.29934 -68.0212)
					(mid 317.23908 -67.87572)
					(end 317.0936 -67.81546)
				)
				(arc
					(start 316.738 -67.81546)
					(mid 316.59252 -67.87572)
					(end 316.53226 -68.0212)
				)
				(arc
					(start 316.53226 -68.3768)
					(mid 316.59252 -68.52228)
					(end 316.738 -68.58254)
				)
				(arc
					(start 317.0936 -68.58254)
					(mid 317.23908 -68.52228)
					(end 317.29934 -68.3768)
				)
			)
		)
		(polygon
			(pts
				(arc
					(start 316.43574 -68.0212)
					(mid 316.37548 -67.87572)
					(end 316.23 -67.81546)
				)
				(arc
					(start 315.8744 -67.81546)
					(mid 315.72892 -67.87572)
					(end 315.66866 -68.0212)
				)
				(arc
					(start 315.66866 -68.3768)
					(mid 315.72892 -68.52228)
					(end 315.8744 -68.58254)
				)
				(arc
					(start 316.23 -68.58254)
					(mid 316.37548 -68.52228)
					(end 316.43574 -68.3768)
				)
			)
		)
		(polygon
			(pts
				(arc
					(start 304.134012 -66.89344)
					(mid 304.073752 -66.74796)
					(end 303.928272 -66.6877)
				)
				(arc
					(start 303.572672 -66.6877)
					(mid 303.427192 -66.74796)
					(end 303.366932 -66.89344)
				)
				(arc
					(start 303.366932 -67.24904)
					(mid 303.427192 -67.39452)
					(end 303.572672 -67.45478)
				)
				(arc
					(start 303.928272 -67.45478)
					(mid 304.073752 -67.39452)
					(end 304.134012 -67.24904)
				)
			)
		)
		(polygon
			(pts
				(arc
					(start 303.270412 -66.89344)
					(mid 303.210152 -66.74796)
					(end 303.064672 -66.6877)
				)
				(arc
					(start 302.709072 -66.6877)
					(mid 302.563592 -66.74796)
					(end 302.503332 -66.89344)
				)
				(arc
					(start 302.503332 -67.24904)
					(mid 302.563592 -67.39452)
					(end 302.709072 -67.45478)
				)
				(arc
					(start 303.064672 -67.45478)
					(mid 303.210152 -67.39452)
					(end 303.270412 -67.24904)
				)
			)
		)
		(polygon
			(pts
				(xy 309.753 -66.4972) (xy 307.594 -66.4972) (xy 307.594 -67.8942) (xy 309.753 -67.8942)
			)
		)
		(polygon
			(pts
				(arc
					(start 86.49716 -45.08246)
					(mid 86.44395 -44.991372)
					(end 86.34476 -44.95546)
				)
				(arc
					(start 86.09076 -44.95546)
					(mid 85.981201 -45.000841)
					(end 85.93582 -45.1104)
				)
				(arc
					(start 85.93582 -45.3136)
					(mid 85.981201 -45.423159)
					(end 86.09076 -45.46854)
				)
				(arc
					(start 86.34476 -45.46854)
					(mid 86.44395 -45.432628)
					(end 86.49716 -45.34154)
				)
				(arc
					(start 86.49716 -45.34154)
					(mid 86.55037 -45.432628)
					(end 86.64956 -45.46854)
				)
				(arc
					(start 86.90356 -45.46854)
					(mid 87.013119 -45.423159)
					(end 87.0585 -45.3136)
				)
				(arc
					(start 87.0585 -45.1104)
					(mid 87.013119 -45.000841)
					(end 86.90356 -44.95546)
				)
				(arc
					(start 86.64956 -44.95546)
					(mid 86.55037 -44.991372)
					(end 86.49716 -45.08246)
				)
			)
		)
		(polygon
			(pts
				(arc
					(start 86.49716 -44.44746)
					(mid 86.44395 -44.356372)
					(end 86.34476 -44.32046)
				)
				(arc
					(start 86.09076 -44.32046)
					(mid 85.981201 -44.365841)
					(end 85.93582 -44.4754)
				)
				(arc
					(start 85.93582 -44.6786)
					(mid 85.981201 -44.788159)
					(end 86.09076 -44.83354)
				)
				(arc
					(start 86.34476 -44.83354)
					(mid 86.44395 -44.797628)
					(end 86.49716 -44.70654)
				)
				(arc
					(start 86.49716 -44.70654)
					(mid 86.55037 -44.797628)
					(end 86.64956 -44.83354)
				)
				(arc
					(start 86.90356 -44.83354)
					(mid 87.013119 -44.788159)
					(end 87.0585 -44.6786)
				)
				(arc
					(start 87.0585 -44.4754)
					(mid 87.013119 -44.365841)
					(end 86.90356 -44.32046)
				)
				(arc
					(start 86.64956 -44.32046)
					(mid 86.55037 -44.356372)
					(end 86.49716 -44.44746)
				)
			)
		)
		(polygon
			(pts
				(arc
					(start 86.49716 -43.43146)
					(mid 86.44395 -43.340372)
					(end 86.34476 -43.30446)
				)
				(arc
					(start 86.09076 -43.30446)
					(mid 85.981201 -43.349841)
					(end 85.93582 -43.4594)
				)
				(arc
					(start 85.93582 -43.6626)
					(mid 85.981201 -43.772159)
					(end 86.09076 -43.81754)
				)
				(arc
					(start 86.34476 -43.81754)
					(mid 86.44395 -43.781628)
					(end 86.49716 -43.69054)
				)
				(arc
					(start 86.49716 -43.69054)
					(mid 86.55037 -43.781628)
					(end 86.64956 -43.81754)
				)
				(arc
					(start 86.90356 -43.81754)
					(mid 87.013119 -43.772159)
					(end 87.0585 -43.6626)
				)
				(arc
					(start 87.0585 -43.4594)
					(mid 87.013119 -43.349841)
					(end 86.90356 -43.30446)
				)
				(arc
					(start 86.64956 -43.30446)
					(mid 86.55037 -43.340372)
					(end 86.49716 -43.43146)
				)
			)
		)
		(polygon
			(pts
				(arc
					(start 86.49716 -42.79646)
					(mid 86.44395 -42.705372)
					(end 86.34476 -42.66946)
				)
				(arc
					(start 86.09076 -42.66946)
					(mid 85.981201 -42.714841)
					(end 85.93582 -42.8244)
				)
				(arc
					(start 85.93582 -43.0276)
					(mid 85.981201 -43.137159)
					(end 86.09076 -43.18254)
				)
				(arc
					(start 86.34476 -43.18254)
					(mid 86.44395 -43.146628)
					(end 86.49716 -43.05554)
				)
				(arc
					(start 86.49716 -43.05554)
					(mid 86.55037 -43.146628)
					(end 86.64956 -43.18254)
				)
				(arc
					(start 86.90356 -43.18254)
					(mid 87.013119 -43.137159)
					(end 87.0585 -43.0276)
				)
				(arc
					(start 87.0585 -42.8244)
					(mid 87.013119 -42.714841)
					(end 86.90356 -42.66946)
				)
				(arc
					(start 86.64956 -42.66946)
					(mid 86.55037 -42.705372)
					(end 86.49716 -42.79646)
				)
			)
		)
		(polygon
			(pts
				(arc
					(start 93.914976 -42.600118)
					(mid 93.55963 -42.239184)
					(end 93.198696 -42.59453)
				)
				(arc
					(start 93.192346 -43.387772)
					(mid 93.547565 -43.748961)
					(end 93.908626 -43.393614)
				)
			)
		)
		(polygon
			(pts
				(arc
					(start 86.49716 -41.78046)
					(mid 86.44395 -41.689372)
					(end 86.34476 -41.65346)
				)
				(arc
					(start 86.09076 -41.65346)
					(mid 85.981201 -41.698841)
					(end 85.93582 -41.8084)
				)
				(arc
					(start 85.93582 -42.0116)
					(mid 85.981201 -42.121159)
					(end 86.09076 -42.16654)
				)
				(arc
					(start 86.34476 -42.16654)
					(mid 86.44395 -42.130628)
					(end 86.49716 -42.03954)
				)
				(arc
					(start 86.49716 -42.03954)
					(mid 86.55037 -42.130628)
					(end 86.64956 -42.16654)
				)
				(arc
					(start 86.90356 -42.16654)
					(mid 87.013119 -42.121159)
					(end 87.0585 -42.0116)
				)
				(arc
					(start 87.0585 -41.8084)
					(mid 87.013119 -41.698841)
					(end 86.90356 -41.65346)
				)
				(arc
					(start 86.64956 -41.65346)
					(mid 86.55037 -41.689372)
					(end 86.49716 -41.78046)
				)
			)
		)
		(polygon
			(pts
				(arc
					(start 92.753942 -41.438576)
					(mid 92.392247 -41.793033)
					(end 92.746576 -42.154856)
				)
				(arc
					(start 93.550994 -42.16273)
					(mid 93.91269 -41.808146)
					(end 93.558106 -41.44645)
				)
			)
		)
		(polygon
			(pts
				(arc
					(start 78.663546 -41.98874)
					(mid 79.046832 -41.605073)
					(end 78.663292 -41.22166)
				)
				(arc
					(start 77.686408 -41.22166)
					(mid 77.302868 -41.6052)
					(end 77.686408 -41.98874)
				)
			)
		)
		(polygon
			(pts
				(arc
					(start 86.49716 -41.14546)
					(mid 86.44395 -41.054372)
					(end 86.34476 -41.01846)
				)
				(arc
					(start 86.09076 -41.01846)
					(mid 85.981201 -41.063841)
					(end 85.93582 -41.1734)
				)
				(arc
					(start 85.93582 -41.3766)
					(mid 85.981201 -41.486159)
					(end 86.09076 -41.53154)
				)
				(arc
					(start 86.34476 -41.53154)
					(mid 86.44395 -41.495628)
					(end 86.49716 -41.40454)
				)
				(arc
					(start 86.49716 -41.40454)
					(mid 86.55037 -41.495628)
					(end 86.64956 -41.53154)
				)
				(arc
					(start 86.90356 -41.53154)
					(mid 87.013119 -41.486159)
					(end 87.0585 -41.3766)
				)
				(arc
					(start 87.0585 -41.1734)
					(mid 87.013119 -41.063841)
					(end 86.90356 -41.01846)
				)
				(arc
					(start 86.64956 -41.01846)
					(mid 86.55037 -41.054372)
					(end 86.49716 -41.14546)
				)
			)
		)
		(polygon
			(pts
				(arc
					(start 86.49716 -40.12946)
					(mid 86.44395 -40.038372)
					(end 86.34476 -40.00246)
				)
				(arc
					(start 86.09076 -40.00246)
					(mid 85.981201 -40.047841)
					(end 85.93582 -40.1574)
				)
				(arc
					(start 85.93582 -40.3606)
					(mid 85.981201 -40.470159)
					(end 86.09076 -40.51554)
				)
				(arc
					(start 86.34476 -40.51554)
					(mid 86.44395 -40.479628)
					(end 86.49716 -40.38854)
				)
				(arc
					(start 86.49716 -40.38854)
					(mid 86.55037 -40.479628)
					(end 86.64956 -40.51554)
				)
				(arc
					(start 86.90356 -40.51554)
					(mid 87.013119 -40.470159)
					(end 87.0585 -40.3606)
				)
				(arc
					(start 87.0585 -40.1574)
					(mid 87.013119 -40.047841)
					(end 86.90356 -40.00246)
				)
				(arc
					(start 86.64956 -40.00246)
					(mid 86.55037 -40.038372)
					(end 86.49716 -40.12946)
				)
			)
		)
		(polygon
			(pts
				(arc
					(start 93.898974 -40.193722)
					(mid 93.534484 -39.841932)
					(end 93.182694 -40.206422)
				)
				(arc
					(start 93.196664 -41.001696)
					(mid 93.561027 -41.353738)
					(end 93.912944 -40.98925)
				)
			)
		)
		(polygon
			(pts
				(arc
					(start 86.49716 -39.49446)
					(mid 86.44395 -39.403372)
					(end 86.34476 -39.36746)
				)
				(arc
					(start 86.09076 -39.36746)
					(mid 85.981201 -39.412841)
					(end 85.93582 -39.5224)
				)
				(arc
					(start 85.93582 -39.7256)
					(mid 85.981201 -39.835159)
					(end 86.09076 -39.88054)
				)
				(arc
					(start 86.34476 -39.88054)
					(mid 86.44395 -39.844628)
					(end 86.49716 -39.75354)
				)
				(arc
					(start 86.49716 -39.75354)
					(mid 86.55037 -39.844628)
					(end 86.64956 -39.88054)
				)
				(arc
					(start 86.90356 -39.88054)
					(mid 87.013119 -39.835159)
					(end 87.0585 -39.7256)
				)
				(arc
					(start 87.0585 -39.5224)
					(mid 87.013119 -39.412841)
					(end 86.90356 -39.36746)
				)
				(arc
					(start 86.64956 -39.36746)
					(mid 86.55037 -39.403372)
					(end 86.49716 -39.49446)
				)
			)
		)
		(polygon
			(pts
				(arc
					(start 80.581246 -40.00754)
					(mid 80.964532 -39.623873)
					(end 80.580992 -39.24046)
				)
				(arc
					(start 79.604108 -39.24046)
					(mid 79.220568 -39.624)
					(end 79.604108 -40.00754)
				)
			)
		)
		(polygon
			(pts
				(arc
					(start 92.746576 -39.03726)
					(mid 92.387674 -39.394511)
					(end 92.744798 -39.75354)
				)
				(arc
					(start 93.55582 -39.755318)
					(mid 93.914722 -39.39794)
					(end 93.557344 -39.039038)
				)
			)
		)
		(polygon
			(pts
				(arc
					(start 86.49716 -38.47846)
					(mid 86.44395 -38.387372)
					(end 86.34476 -38.35146)
				)
				(arc
					(start 86.09076 -38.35146)
					(mid 85.981201 -38.396841)
					(end 85.93582 -38.5064)
				)
				(arc
					(start 85.93582 -38.7096)
					(mid 85.981201 -38.819159)
					(end 86.09076 -38.86454)
				)
				(arc
					(start 86.34476 -38.86454)
					(mid 86.44395 -38.828628)
					(end 86.49716 -38.73754)
				)
				(arc
					(start 86.49716 -38.73754)
					(mid 86.55037 -38.828628)
					(end 86.64956 -38.86454)
				)
				(arc
					(start 86.90356 -38.86454)
					(mid 87.013119 -38.819159)
					(end 87.0585 -38.7096)
				)
				(arc
					(start 87.0585 -38.5064)
					(mid 87.013119 -38.396841)
					(end 86.90356 -38.35146)
				)
				(arc
					(start 86.64956 -38.35146)
					(mid 86.55037 -38.387372)
					(end 86.49716 -38.47846)
				)
			)
		)
		(polygon
			(pts
				(arc
					(start 86.49716 -37.84346)
					(mid 86.44395 -37.752372)
					(end 86.34476 -37.71646)
				)
				(arc
					(start 86.09076 -37.71646)
					(mid 85.981201 -37.761841)
					(end 85.93582 -37.8714)
				)
				(arc
					(start 85.93582 -38.0746)
					(mid 85.981201 -38.184159)
					(end 86.09076 -38.22954)
				)
				(arc
					(start 86.34476 -38.22954)
					(mid 86.44395 -38.193628)
					(end 86.49716 -38.10254)
				)
				(arc
					(start 86.49716 -38.10254)
					(mid 86.55037 -38.193628)
					(end 86.64956 -38.22954)
				)
				(arc
					(start 86.90356 -38.22954)
					(mid 87.013119 -38.184159)
					(end 87.0585 -38.0746)
				)
				(arc
					(start 87.0585 -37.8714)
					(mid 87.013119 -37.761841)
					(end 86.90356 -37.71646)
				)
				(arc
					(start 86.64956 -37.71646)
					(mid 86.55037 -37.752372)
					(end 86.49716 -37.84346)
				)
			)
		)
		(polygon
			(pts
				(arc
					(start 83.294728 -37.831776)
					(mid 82.911188 -37.448236)
					(end 82.527648 -37.831776)
				)
				(arc
					(start 82.527648 -38.737032)
					(mid 82.911315 -39.120318)
					(end 83.294728 -38.736778)
				)
			)
		)
		(polygon
			(pts
				(arc
					(start 93.914722 -37.80282)
					(mid 93.557217 -37.444172)
					(end 93.198442 -37.80155)
				)
				(arc
					(start 93.197426 -38.596316)
					(mid 93.555058 -38.954964)
					(end 93.913706 -38.597332)
				)
				(xy 93.913706 -38.596824) (xy 93.913706 -38.596316)
			)
		)
		(polygon
			(pts
				(arc
					(start 84.413852 -37.734494)
					(mid 84.04606 -37.386514)
					(end 83.69808 -37.754306)
				)
				(xy 83.69554 -37.754306) (xy 83.723734 -38.770306) (xy 83.723988 -38.77056)
				(arc
					(start 83.726274 -38.77056)
					(mid 84.094066 -39.11854)
					(end 84.442046 -38.750748)
				)
				(xy 84.444586 -38.750748) (xy 84.416392 -37.734494)
			)
		)
		(polygon
			(pts
				(arc
					(start 86.49716 -36.82746)
					(mid 86.44395 -36.736372)
					(end 86.34476 -36.70046)
				)
				(arc
					(start 86.09076 -36.70046)
					(mid 85.981201 -36.745841)
					(end 85.93582 -36.8554)
				)
				(arc
					(start 85.93582 -37.0586)
					(mid 85.981201 -37.168159)
					(end 86.09076 -37.21354)
				)
				(arc
					(start 86.34476 -37.21354)
					(mid 86.44395 -37.177628)
					(end 86.49716 -37.08654)
				)
				(arc
					(start 86.49716 -37.08654)
					(mid 86.55037 -37.177628)
					(end 86.64956 -37.21354)
				)
				(arc
					(start 86.90356 -37.21354)
					(mid 87.013119 -37.168159)
					(end 87.0585 -37.0586)
				)
				(arc
					(start 87.0585 -36.8554)
					(mid 87.013119 -36.745841)
					(end 86.90356 -36.70046)
				)
				(arc
					(start 86.64956 -36.70046)
					(mid 86.55037 -36.736372)
					(end 86.49716 -36.82746)
				)
			)
		)
		(polygon
			(pts
				(arc
					(start 94.360492 -37.357558)
					(mid 94.717362 -36.998021)
					(end 94.357698 -36.641278)
				)
				(arc
					(start 93.550232 -36.64458)
					(mid 93.193616 -37.004244)
					(end 93.55328 -37.36086)
				)
			)
		)
		(polygon
			(pts
				(arc
					(start 77.133958 -37.042852)
					(mid 77.517498 -36.659312)
					(end 77.133958 -36.275772)
				)
				(arc
					(start 76.15682 -36.275772)
					(mid 75.773534 -36.659439)
					(end 76.157074 -37.042852)
				)
			)
		)
		(polygon
			(pts
				(arc
					(start 86.49716 -36.19246)
					(mid 86.44395 -36.101372)
					(end 86.34476 -36.06546)
				)
				(arc
					(start 86.09076 -36.06546)
					(mid 85.981201 -36.110841)
					(end 85.93582 -36.2204)
				)
				(arc
					(start 85.93582 -36.4236)
					(mid 85.981201 -36.533159)
					(end 86.09076 -36.57854)
				)
				(arc
					(start 86.34476 -36.57854)
					(mid 86.44395 -36.542628)
					(end 86.49716 -36.45154)
				)
				(arc
					(start 86.49716 -36.45154)
					(mid 86.55037 -36.542628)
					(end 86.64956 -36.57854)
				)
				(arc
					(start 86.90356 -36.57854)
					(mid 87.013119 -36.533159)
					(end 87.0585 -36.4236)
				)
				(arc
					(start 87.0585 -36.2204)
					(mid 87.013119 -36.110841)
					(end 86.90356 -36.06546)
				)
				(arc
					(start 86.64956 -36.06546)
					(mid 86.55037 -36.101372)
					(end 86.49716 -36.19246)
				)
			)
		)
		(polygon
			(pts
				(arc
					(start 81.61274 -36.334954)
					(mid 81.229073 -35.951668)
					(end 80.84566 -36.335208)
				)
				(arc
					(start 80.84566 -37.312092)
					(mid 81.2292 -37.695632)
					(end 81.61274 -37.312092)
				)
			)
		)
		(polygon
			(pts
				(arc
					(start 93.90761 -35.406838)
					(mid 93.548454 -35.049714)
					(end 93.19133 -35.40887)
				)
				(arc
					(start 93.193616 -36.197032)
					(mid 93.552645 -36.55441)
					(end 93.909896 -36.195254)
				)
				(xy 93.90761 -35.40887) (xy 93.90761 -35.407854)
			)
		)
		(polygon
			(pts
				(arc
					(start 86.49716 -35.17646)
					(mid 86.44395 -35.085372)
					(end 86.34476 -35.04946)
				)
				(arc
					(start 86.09076 -35.04946)
					(mid 85.981201 -35.094841)
					(end 85.93582 -35.2044)
				)
				(arc
					(start 85.93582 -35.4076)
					(mid 85.981201 -35.517159)
					(end 86.09076 -35.56254)
				)
				(arc
					(start 86.34476 -35.56254)
					(mid 86.44395 -35.526628)
					(end 86.49716 -35.43554)
				)
				(arc
					(start 86.49716 -35.43554)
					(mid 86.55037 -35.526628)
					(end 86.64956 -35.56254)
				)
				(arc
					(start 86.90356 -35.56254)
					(mid 87.013119 -35.517159)
					(end 87.0585 -35.4076)
				)
				(arc
					(start 87.0585 -35.2044)
					(mid 87.013119 -35.094841)
					(end 86.90356 -35.04946)
				)
				(arc
					(start 86.64956 -35.04946)
					(mid 86.55037 -35.085372)
					(end 86.49716 -35.17646)
				)
			)
		)
		(polygon
			(pts
				(arc
					(start 96.30664 -35.406838)
					(mid 95.947738 -35.04946)
					(end 95.59036 -35.408362)
				)
				(xy 95.592138 -36.199318) (xy 95.592138 -36.20008)
				(arc
					(start 95.592138 -36.200588)
					(mid 95.950913 -36.55822)
					(end 96.308418 -36.199318)
				)
				(xy 96.30664 -35.408362) (xy 96.30664 -35.4076)
			)
		)
		(polygon
			(pts
				(arc
					(start 95.50654 -35.404298)
					(mid 95.147638 -35.04692)
					(end 94.79026 -35.405822)
				)
				(xy 94.79026 -35.406838) (xy 94.79026 -35.407854) (xy 94.792038 -36.195254) (xy 94.792038 -36.196016)
				(arc
					(start 94.792038 -36.200588)
					(mid 95.150813 -36.55822)
					(end 95.508318 -36.199318)
				)
				(xy 95.50654 -35.40506)
			)
		)
		(polygon
			(pts
				(arc
					(start 98.700082 -35.397694)
					(mid 98.338132 -35.043364)
					(end 97.983802 -35.405314)
				)
				(arc
					(start 97.992184 -36.203636)
					(mid 98.354007 -36.558219)
					(end 98.708464 -36.19627)
				)
			)
		)
		(polygon
			(pts
				(arc
					(start 103.508302 -35.400234)
					(mid 103.150162 -35.042094)
					(end 102.792022 -35.400234)
				)
				(arc
					(start 102.792022 -36.200334)
					(mid 103.150289 -36.55822)
					(end 103.508302 -36.20008)
				)
			)
		)
		(polygon
			(pts
				(arc
					(start 97.898966 -35.395916)
					(mid 97.536508 -35.042094)
					(end 97.182686 -35.404552)
				)
				(arc
					(start 97.192084 -36.204144)
					(mid 97.554415 -36.558219)
					(end 97.908364 -36.195762)
				)
			)
		)
		(polygon
			(pts
				(arc
					(start 102.708202 -35.39998)
					(mid 102.349935 -35.04184)
					(end 101.991922 -35.400234)
				)
				(xy 101.991922 -35.40125)
				(arc
					(start 101.992176 -36.199826)
					(mid 102.350316 -36.55822)
					(end 102.708456 -36.199826)
				)
				(xy 102.708202 -35.75812)
			)
		)
		(polygon
			(pts
				(arc
					(start 101.115622 -35.40125)
					(mid 100.760784 -35.039808)
					(end 100.399342 -35.394646)
				)
				(arc
					(start 100.39223 -36.196524)
					(mid 100.746941 -36.558221)
					(end 101.10851 -36.203382)
				)
			)
		)
		(polygon
			(pts
				(arc
					(start 100.30968 -35.392868)
					(mid 99.952048 -35.03422)
					(end 99.5934 -35.391852)
				)
				(xy 99.5934 -35.397694) (xy 99.59213 -36.19627)
				(arc
					(start 99.59213 -36.199318)
					(mid 99.949635 -36.55822)
					(end 100.30841 -36.200588)
				)
				(xy 100.30841 -36.20008) (xy 100.30841 -36.199318)
			)
		)
		(polygon
			(pts
				(arc
					(start 86.49716 -34.54146)
					(mid 86.44395 -34.450372)
					(end 86.34476 -34.41446)
				)
				(arc
					(start 86.09076 -34.41446)
					(mid 85.981201 -34.459841)
					(end 85.93582 -34.5694)
				)
				(arc
					(start 85.93582 -34.7726)
					(mid 85.981201 -34.882159)
					(end 86.09076 -34.92754)
				)
				(arc
					(start 86.34476 -34.92754)
					(mid 86.44395 -34.891628)
					(end 86.49716 -34.80054)
				)
				(arc
					(start 86.49716 -34.80054)
					(mid 86.55037 -34.891628)
					(end 86.64956 -34.92754)
				)
				(arc
					(start 86.90356 -34.92754)
					(mid 87.013119 -34.882159)
					(end 87.0585 -34.7726)
				)
				(arc
					(start 87.0585 -34.5694)
					(mid 87.013119 -34.459841)
					(end 86.90356 -34.41446)
				)
				(arc
					(start 86.64956 -34.41446)
					(mid 86.55037 -34.450372)
					(end 86.49716 -34.54146)
				)
			)
		)
		(polygon
			(pts
				(arc
					(start 94.352618 -34.958274)
					(mid 94.707964 -34.59734)
					(end 94.34703 -34.241994)
				)
				(arc
					(start 93.544644 -34.248344)
					(mid 93.189297 -34.609151)
					(end 93.549978 -34.964624)
				)
			)
		)
		(polygon
			(pts
				(arc
					(start 83.46694 -34.618422)
					(mid 83.083273 -34.235136)
					(end 82.69986 -34.618676)
				)
				(arc
					(start 82.69986 -35.523678)
					(mid 83.0834 -35.907218)
					(end 83.46694 -35.523678)
				)
			)
		)
		(polygon
			(pts
				(arc
					(start 86.49716 -33.52546)
					(mid 86.44395 -33.434372)
					(end 86.34476 -33.39846)
				)
				(arc
					(start 86.09076 -33.39846)
					(mid 85.981201 -33.443841)
					(end 85.93582 -33.5534)
				)
				(arc
					(start 85.93582 -33.7566)
					(mid 85.981201 -33.866159)
					(end 86.09076 -33.91154)
				)
				(arc
					(start 86.34476 -33.91154)
					(mid 86.44395 -33.875628)
					(end 86.49716 -33.78454)
				)
				(arc
					(start 86.49716 -33.78454)
					(mid 86.55037 -33.875628)
					(end 86.64956 -33.91154)
				)
				(arc
					(start 86.90356 -33.91154)
					(mid 87.013119 -33.866159)
					(end 87.0585 -33.7566)
				)
				(arc
					(start 87.0585 -33.5534)
					(mid 87.013119 -33.443841)
					(end 86.90356 -33.39846)
				)
				(arc
					(start 86.64956 -33.39846)
					(mid 86.55037 -33.434372)
					(end 86.49716 -33.52546)
				)
			)
		)
		(polygon
			(pts
				(arc
					(start 86.49716 -32.89046)
					(mid 86.44395 -32.799372)
					(end 86.34476 -32.76346)
				)
				(arc
					(start 86.09076 -32.76346)
					(mid 85.981201 -32.808841)
					(end 85.93582 -32.9184)
				)
				(arc
					(start 85.93582 -33.1216)
					(mid 85.981201 -33.231159)
					(end 86.09076 -33.27654)
				)
				(arc
					(start 86.34476 -33.27654)
					(mid 86.44395 -33.240628)
					(end 86.49716 -33.14954)
				)
				(arc
					(start 86.49716 -33.14954)
					(mid 86.55037 -33.240628)
					(end 86.64956 -33.27654)
				)
				(arc
					(start 86.90356 -33.27654)
					(mid 87.013119 -33.231159)
					(end 87.0585 -33.1216)
				)
				(arc
					(start 87.0585 -32.9184)
					(mid 87.013119 -32.808841)
					(end 86.90356 -32.76346)
				)
				(arc
					(start 86.64956 -32.76346)
					(mid 86.55037 -32.799372)
					(end 86.49716 -32.89046)
				)
			)
		)
		(polygon
			(pts
				(arc
					(start 85.37194 -32.884618)
					(mid 84.988273 -32.501332)
					(end 84.60486 -32.884872)
				)
				(arc
					(start 84.60486 -33.789874)
					(mid 84.9884 -34.173414)
					(end 85.37194 -33.789874)
				)
			)
		)
		(polygon
			(pts
				(arc
					(start 277.84933 -32.51454)
					(mid 278.232616 -32.130873)
					(end 277.849076 -31.74746)
				)
				(arc
					(start 276.867112 -31.74746)
					(mid 276.483572 -32.131)
					(end 276.867112 -32.51454)
				)
			)
		)
		(polygon
			(pts
				(arc
					(start 278.249634 -26.045668)
					(mid 278.189374 -25.900188)
					(end 278.043894 -25.839928)
				)
				(arc
					(start 277.688294 -25.839928)
					(mid 277.542814 -25.900188)
					(end 277.482554 -26.045668)
				)
				(xy 277.482554 -26.068528) (xy 277.406354 -26.068528) (xy 277.406354 -27.191208) (xy 278.275034 -27.191208)
				(xy 278.275034 -26.068528) (xy 278.249634 -26.068528)
			)
		)
		(polygon
			(pts
				(arc
					(start 277.233634 -26.045668)
					(mid 277.173374 -25.900188)
					(end 277.027894 -25.839928)
				)
				(arc
					(start 276.672294 -25.839928)
					(mid 276.526814 -25.900188)
					(end 276.466554 -26.045668)
				)
				(xy 276.466554 -26.068528) (xy 276.441154 -26.068528) (xy 276.441154 -27.191208) (xy 277.309834 -27.191208)
				(xy 277.309834 -26.068528) (xy 277.233634 -26.068528)
			)
		)
		(polygon
			(pts
				(xy 278.275034 -24.392128) (xy 277.406354 -24.392128) (xy 277.406354 -25.514808) (xy 277.482554 -25.514808)
				(arc
					(start 277.482554 -25.537668)
					(mid 277.542814 -25.683148)
					(end 277.688294 -25.743408)
				)
				(arc
					(start 278.043894 -25.743408)
					(mid 278.189374 -25.683148)
					(end 278.249634 -25.537668)
				)
				(xy 278.249634 -25.514808) (xy 278.275034 -25.514808)
			)
		)
		(polygon
			(pts
				(xy 277.309834 -24.392128) (xy 276.441154 -24.392128) (xy 276.441154 -25.514808) (xy 276.466554 -25.514808)
				(arc
					(start 276.466554 -25.537668)
					(mid 276.526814 -25.683148)
					(end 276.672294 -25.743408)
				)
				(arc
					(start 277.027894 -25.743408)
					(mid 277.173374 -25.683148)
					(end 277.233634 -25.537668)
				)
				(xy 277.233634 -25.514808) (xy 277.309834 -25.514808)
			)
		)
		(polygon
			(pts
				(xy 278.33574 -22.32406) (xy 277.54326 -22.32406) (xy 277.54326 -23.54834) (xy 278.33574 -23.54834)
			)
		)
		(polygon
			(pts
				(xy 278.33574 -19.63166) (xy 277.54326 -19.63166) (xy 277.54326 -20.85594) (xy 278.33574 -20.85594)
			)
		)
		(polygon
			(pts
				(arc
					(start 272.999962 -11.779758)
					(mid 273.789902 -10.989818)
					(end 272.999962 -10.199878)
				)
				(arc
					(start 270.999966 -10.199878)
					(mid 270.210026 -10.989818)
					(end 270.999966 -11.779758)
				)
			)
		)
		(polygon
			(pts
				(arc
					(start 107.54995 -5.324348)
					(mid 107.54995 -6.675628)
					(end 107.54995 -5.324348)
				)
			)
		)
		(polygon
			(pts
				(arc
					(start 104.950006 -5.324348)
					(mid 104.950006 -6.675628)
					(end 104.950006 -5.324348)
				)
			)
		)
		(polygon
			(pts
				(arc
					(start 102.350062 -5.324348)
					(mid 102.350062 -6.675628)
					(end 102.350062 -5.324348)
				)
			)
		)
		(polygon
			(pts
				(xy 98.786696 -1.354328) (xy 97.435416 -1.354328) (xy 97.435416 -2.705608) (xy 98.786696 -2.705608)
			)
		)
		(polygon
			(pts
				(xy 95.644716 -1.354328) (xy 94.293436 -1.354328) (xy 94.293436 -2.705608) (xy 95.644716 -2.705608)
			)
		)
		(polygon
			(pts
				(xy 110.531656 -1.303528) (xy 109.281976 -1.303528) (xy 109.281976 -2.756408) (xy 110.531656 -2.756408)
			)
		)
		(polygon
			(pts
				(xy 107.798108 -1.303528) (xy 106.548428 -1.303528) (xy 106.548428 -2.756408) (xy 107.798108 -2.756408)
			)
		)
	)
	(zone
		(layer "In1.Cu")
		(hatch none 0.5)
		(connect_pads
			(clearance 0)
		)
		(min_thickness 0.25)
		(keepout
			(tracks not_allowed)
			(vias allowed)
			(pads allowed)
			(copperpour not_allowed)
			(footprints allowed)
		)
		(placement
			(enabled no)
			(sheetname "")
		)
		(fill
			(thermal_gap 0.5)
			(thermal_bridge_width 0.5)
			(island_removal_mode 0)
		)
		(polygon
			(pts
				(arc
					(start 86.90356 -45.46854)
					(mid 87.013119 -45.423159)
					(end 87.0585 -45.3136)
				)
				(arc
					(start 87.0585 -45.1104)
					(mid 87.013119 -45.000841)
					(end 86.90356 -44.95546)
				)
				(arc
					(start 86.64956 -44.95546)
					(mid 86.540001 -45.000841)
					(end 86.49462 -45.1104)
				)
				(arc
					(start 86.49462 -45.3136)
					(mid 86.540001 -45.423159)
					(end 86.64956 -45.46854)
				)
			)
		)
	)
	(zone
		(layer "In1.Cu")
		(hatch none 0.5)
		(connect_pads
			(clearance 0)
		)
		(min_thickness 0.25)
		(keepout
			(tracks not_allowed)
			(vias allowed)
			(pads allowed)
			(copperpour not_allowed)
			(footprints allowed)
		)
		(placement
			(enabled no)
			(sheetname "")
		)
		(fill
			(thermal_gap 0.5)
			(thermal_bridge_width 0.5)
			(island_removal_mode 0)
		)
		(polygon
			(pts
				(arc
					(start 86.90356 -38.22954)
					(mid 87.013119 -38.184159)
					(end 87.0585 -38.0746)
				)
				(arc
					(start 87.0585 -37.8714)
					(mid 87.013119 -37.761841)
					(end 86.90356 -37.71646)
				)
				(arc
					(start 86.64956 -37.71646)
					(mid 86.540001 -37.761841)
					(end 86.49462 -37.8714)
				)
				(arc
					(start 86.49462 -38.0746)
					(mid 86.540001 -38.184159)
					(end 86.64956 -38.22954)
				)
			)
		)
	)
	(zone
		(layer "In1.Cu")
		(hatch none 0.5)
		(connect_pads
			(clearance 0)
		)
		(min_thickness 0.25)
		(keepout
			(tracks not_allowed)
			(vias allowed)
			(pads allowed)
			(copperpour not_allowed)
			(footprints allowed)
		)
		(placement
			(enabled no)
			(sheetname "")
		)
		(fill
			(thermal_gap 0.5)
			(thermal_bridge_width 0.5)
			(island_removal_mode 0)
		)
		(polygon
			(pts
				(arc
					(start 130.9116 -90.16746)
					(mid 130.802041 -90.212841)
					(end 130.75666 -90.3224)
				)
				(arc
					(start 130.75666 -90.5256)
					(mid 130.802041 -90.635159)
					(end 130.9116 -90.68054)
				)
				(arc
					(start 131.1656 -90.68054)
					(mid 131.275159 -90.635159)
					(end 131.32054 -90.5256)
				)
				(arc
					(start 131.32054 -90.3224)
					(mid 131.275159 -90.212841)
					(end 131.1656 -90.16746)
				)
			)
		)
	)
	(zone
		(layer "In1.Cu")
		(hatch none 0.5)
		(connect_pads
			(clearance 0)
		)
		(min_thickness 0.25)
		(keepout
			(tracks not_allowed)
			(vias allowed)
			(pads allowed)
			(copperpour not_allowed)
			(footprints allowed)
		)
		(placement
			(enabled no)
			(sheetname "")
		)
		(fill
			(thermal_gap 0.5)
			(thermal_bridge_width 0.5)
			(island_removal_mode 0)
		)
		(polygon
			(pts
				(arc
					(start 133.330442 -83.635342)
					(mid 133.220883 -83.680723)
					(end 133.175502 -83.790282)
				)
				(arc
					(start 133.175502 -83.993482)
					(mid 133.220883 -84.103041)
					(end 133.330442 -84.148422)
				)
				(arc
					(start 133.584442 -84.148422)
					(mid 133.694001 -84.103041)
					(end 133.739382 -83.993482)
				)
				(arc
					(start 133.739382 -83.790282)
					(mid 133.694001 -83.680723)
					(end 133.584442 -83.635342)
				)
			)
		)
	)
	(zone
		(layer "In1.Cu")
		(hatch none 0.5)
		(connect_pads
			(clearance 0)
		)
		(min_thickness 0.25)
		(keepout
			(tracks not_allowed)
			(vias allowed)
			(pads allowed)
			(copperpour not_allowed)
			(footprints allowed)
		)
		(placement
			(enabled no)
			(sheetname "")
		)
		(fill
			(thermal_gap 0.5)
			(thermal_bridge_width 0.5)
			(island_removal_mode 0)
		)
		(polygon
			(pts
				(arc
					(start 86.34476 -44.83354)
					(mid 86.454319 -44.788159)
					(end 86.4997 -44.6786)
				)
				(arc
					(start 86.4997 -44.4754)
					(mid 86.454319 -44.365841)
					(end 86.34476 -44.32046)
				)
				(arc
					(start 86.09076 -44.32046)
					(mid 85.981201 -44.365841)
					(end 85.93582 -44.4754)
				)
				(arc
					(start 85.93582 -44.6786)
					(mid 85.981201 -44.788159)
					(end 86.09076 -44.83354)
				)
			)
		)
	)
	(zone
		(layer "In1.Cu")
		(hatch none 0.5)
		(connect_pads
			(clearance 0)
		)
		(min_thickness 0.25)
		(keepout
			(tracks not_allowed)
			(vias allowed)
			(pads allowed)
			(copperpour not_allowed)
			(footprints allowed)
		)
		(placement
			(enabled no)
			(sheetname "")
		)
		(fill
			(thermal_gap 0.5)
			(thermal_bridge_width 0.5)
			(island_removal_mode 0)
		)
		(polygon
			(pts
				(arc
					(start 86.34476 -37.21354)
					(mid 86.454319 -37.168159)
					(end 86.4997 -37.0586)
				)
				(arc
					(start 86.4997 -36.8554)
					(mid 86.454319 -36.745841)
					(end 86.34476 -36.70046)
				)
				(arc
					(start 86.09076 -36.70046)
					(mid 85.981201 -36.745841)
					(end 85.93582 -36.8554)
				)
				(arc
					(start 85.93582 -37.0586)
					(mid 85.981201 -37.168159)
					(end 86.09076 -37.21354)
				)
			)
		)
	)
	(zone
		(layer "In1.Cu")
		(hatch none 0.5)
		(connect_pads
			(clearance 0)
		)
		(min_thickness 0.25)
		(keepout
			(tracks not_allowed)
			(vias allowed)
			(pads allowed)
			(copperpour not_allowed)
			(footprints allowed)
		)
		(placement
			(enabled no)
			(sheetname "")
		)
		(fill
			(thermal_gap 0.5)
			(thermal_bridge_width 0.5)
			(island_removal_mode 0)
		)
		(polygon
			(pts
				(xy 312.039 -82.296) (xy 312.039 -80.899) (xy 314.198 -80.899) (xy 314.198 -82.296)
			)
		)
	)
	(zone
		(layer "In1.Cu")
		(hatch none 0.5)
		(connect_pads
			(clearance 0)
		)
		(min_thickness 0.25)
		(keepout
			(tracks not_allowed)
			(vias allowed)
			(pads allowed)
			(copperpour not_allowed)
			(footprints allowed)
		)
		(placement
			(enabled no)
			(sheetname "")
		)
		(fill
			(thermal_gap 0.5)
			(thermal_bridge_width 0.5)
			(island_removal_mode 0)
		)
		(polygon
			(pts
				(arc
					(start 107.96651 -114.4524)
					(mid 107.921129 -114.342841)
					(end 107.81157 -114.29746)
				)
				(arc
					(start 107.60837 -114.29746)
					(mid 107.498811 -114.342841)
					(end 107.45343 -114.4524)
				)
				(arc
					(start 107.45343 -114.7064)
					(mid 107.498811 -114.815959)
					(end 107.60837 -114.86134)
				)
				(arc
					(start 107.81157 -114.86134)
					(mid 107.921129 -114.815959)
					(end 107.96651 -114.7064)
				)
			)
		)
	)
	(zone
		(layer "In1.Cu")
		(hatch none 0.5)
		(connect_pads
			(clearance 0)
		)
		(min_thickness 0.25)
		(keepout
			(tracks not_allowed)
			(vias allowed)
			(pads allowed)
			(copperpour not_allowed)
			(footprints allowed)
		)
		(placement
			(enabled no)
			(sheetname "")
		)
		(fill
			(thermal_gap 0.5)
			(thermal_bridge_width 0.5)
			(island_removal_mode 0)
		)
		(polygon
			(pts
				(arc
					(start 86.34476 -41.53154)
					(mid 86.454319 -41.486159)
					(end 86.4997 -41.3766)
				)
				(arc
					(start 86.4997 -41.1734)
					(mid 86.454319 -41.063841)
					(end 86.34476 -41.01846)
				)
				(arc
					(start 86.09076 -41.01846)
					(mid 85.981201 -41.063841)
					(end 85.93582 -41.1734)
				)
				(arc
					(start 85.93582 -41.3766)
					(mid 85.981201 -41.486159)
					(end 86.09076 -41.53154)
				)
			)
		)
	)
	(zone
		(layer "In1.Cu")
		(hatch none 0.5)
		(connect_pads
			(clearance 0)
		)
		(min_thickness 0.25)
		(keepout
			(tracks not_allowed)
			(vias allowed)
			(pads allowed)
			(copperpour not_allowed)
			(footprints allowed)
		)
		(placement
			(enabled no)
			(sheetname "")
		)
		(fill
			(thermal_gap 0.5)
			(thermal_bridge_width 0.5)
			(island_removal_mode 0)
		)
		(polygon
			(pts
				(arc
					(start 86.34476 -43.81754)
					(mid 86.454319 -43.772159)
					(end 86.4997 -43.6626)
				)
				(arc
					(start 86.4997 -43.4594)
					(mid 86.454319 -43.349841)
					(end 86.34476 -43.30446)
				)
				(arc
					(start 86.09076 -43.30446)
					(mid 85.981201 -43.349841)
					(end 85.93582 -43.4594)
				)
				(arc
					(start 85.93582 -43.6626)
					(mid 85.981201 -43.772159)
					(end 86.09076 -43.81754)
				)
			)
		)
	)
	(zone
		(layer "In1.Cu")
		(hatch none 0.5)
		(connect_pads
			(clearance 0)
		)
		(min_thickness 0.25)
		(keepout
			(tracks not_allowed)
			(vias allowed)
			(pads allowed)
			(copperpour not_allowed)
			(footprints allowed)
		)
		(placement
			(enabled no)
			(sheetname "")
		)
		(fill
			(thermal_gap 0.5)
			(thermal_bridge_width 0.5)
			(island_removal_mode 0)
		)
		(polygon
			(pts
				(arc
					(start 103.77551 -114.4524)
					(mid 103.730129 -114.342841)
					(end 103.62057 -114.29746)
				)
				(arc
					(start 103.41737 -114.29746)
					(mid 103.307811 -114.342841)
					(end 103.26243 -114.4524)
				)
				(arc
					(start 103.26243 -114.7064)
					(mid 103.307811 -114.815959)
					(end 103.41737 -114.86134)
				)
				(arc
					(start 103.62057 -114.86134)
					(mid 103.730129 -114.815959)
					(end 103.77551 -114.7064)
				)
			)
		)
	)
	(zone
		(layer "In1.Cu")
		(hatch none 0.5)
		(connect_pads
			(clearance 0)
		)
		(min_thickness 0.25)
		(keepout
			(tracks not_allowed)
			(vias allowed)
			(pads allowed)
			(copperpour not_allowed)
			(footprints allowed)
		)
		(placement
			(enabled no)
			(sheetname "")
		)
		(fill
			(thermal_gap 0.5)
			(thermal_bridge_width 0.5)
			(island_removal_mode 0)
		)
		(polygon
			(pts
				(arc
					(start 133.889242 -83.635342)
					(mid 133.779683 -83.680723)
					(end 133.734302 -83.790282)
				)
				(arc
					(start 133.734302 -83.993482)
					(mid 133.779683 -84.103041)
					(end 133.889242 -84.148422)
				)
				(arc
					(start 134.143242 -84.148422)
					(mid 134.252801 -84.103041)
					(end 134.298182 -83.993482)
				)
				(arc
					(start 134.298182 -83.790282)
					(mid 134.252801 -83.680723)
					(end 134.143242 -83.635342)
				)
			)
		)
	)
	(zone
		(layer "In1.Cu")
		(hatch none 0.5)
		(connect_pads
			(clearance 0)
		)
		(min_thickness 0.25)
		(keepout
			(tracks not_allowed)
			(vias allowed)
			(pads allowed)
			(copperpour not_allowed)
			(footprints allowed)
		)
		(placement
			(enabled no)
			(sheetname "")
		)
		(fill
			(thermal_gap 0.5)
			(thermal_bridge_width 0.5)
			(island_removal_mode 0)
		)
		(polygon
			(pts
				(arc
					(start 44.71797 -80.314038)
					(mid 44.99991 -80.595978)
					(end 45.28185 -80.314038)
				)
				(arc
					(start 45.28185 -78.866238)
					(mid 44.99991 -78.584298)
					(end 44.71797 -78.866238)
				)
			)
		)
	)
	(zone
		(layer "In1.Cu")
		(hatch none 0.5)
		(connect_pads
			(clearance 0)
		)
		(min_thickness 0.25)
		(keepout
			(tracks not_allowed)
			(vias allowed)
			(pads allowed)
			(copperpour not_allowed)
			(footprints allowed)
		)
		(placement
			(enabled no)
			(sheetname "")
		)
		(fill
			(thermal_gap 0.5)
			(thermal_bridge_width 0.5)
			(island_removal_mode 0)
		)
		(polygon
			(pts
				(arc
					(start 112.795812 -204.16266)
					(mid 112.650332 -204.22292)
					(end 112.590072 -204.3684)
				)
				(arc
					(start 112.590072 -204.724)
					(mid 112.650332 -204.86948)
					(end 112.795812 -204.92974)
				)
				(arc
					(start 113.151412 -204.92974)
					(mid 113.296892 -204.86948)
					(end 113.357152 -204.724)
				)
				(arc
					(start 113.357152 -204.3684)
					(mid 113.296892 -204.22292)
					(end 113.151412 -204.16266)
				)
			)
		)
	)
	(zone
		(layer "In1.Cu")
		(hatch none 0.5)
		(connect_pads
			(clearance 0)
		)
		(min_thickness 0.25)
		(keepout
			(tracks not_allowed)
			(vias allowed)
			(pads allowed)
			(copperpour not_allowed)
			(footprints allowed)
		)
		(placement
			(enabled no)
			(sheetname "")
		)
		(fill
			(thermal_gap 0.5)
			(thermal_bridge_width 0.5)
			(island_removal_mode 0)
		)
		(polygon
			(pts
				(arc
					(start 122.19051 -114.4524)
					(mid 122.145129 -114.342841)
					(end 122.03557 -114.29746)
				)
				(arc
					(start 121.83237 -114.29746)
					(mid 121.722811 -114.342841)
					(end 121.67743 -114.4524)
				)
				(arc
					(start 121.67743 -114.7064)
					(mid 121.722811 -114.815959)
					(end 121.83237 -114.86134)
				)
				(arc
					(start 122.03557 -114.86134)
					(mid 122.145129 -114.815959)
					(end 122.19051 -114.7064)
				)
			)
		)
	)
	(zone
		(layer "In1.Cu")
		(hatch none 0.5)
		(connect_pads
			(clearance 0)
		)
		(min_thickness 0.25)
		(keepout
			(tracks not_allowed)
			(vias allowed)
			(pads allowed)
			(copperpour not_allowed)
			(footprints allowed)
		)
		(placement
			(enabled no)
			(sheetname "")
		)
		(fill
			(thermal_gap 0.5)
			(thermal_bridge_width 0.5)
			(island_removal_mode 0)
		)
		(polygon
			(pts
				(arc
					(start 109.74451 -113.8936)
					(mid 109.699129 -113.784041)
					(end 109.58957 -113.73866)
				)
				(arc
					(start 109.38637 -113.73866)
					(mid 109.276811 -113.784041)
					(end 109.23143 -113.8936)
				)
				(arc
					(start 109.23143 -114.1476)
					(mid 109.276811 -114.257159)
					(end 109.38637 -114.30254)
				)
				(arc
					(start 109.58957 -114.30254)
					(mid 109.699129 -114.257159)
					(end 109.74451 -114.1476)
				)
			)
		)
	)
	(zone
		(layer "In1.Cu")
		(hatch none 0.5)
		(connect_pads
			(clearance 0)
		)
		(min_thickness 0.25)
		(keepout
			(tracks not_allowed)
			(vias allowed)
			(pads allowed)
			(copperpour not_allowed)
			(footprints allowed)
		)
		(placement
			(enabled no)
			(sheetname "")
		)
		(fill
			(thermal_gap 0.5)
			(thermal_bridge_width 0.5)
			(island_removal_mode 0)
		)
		(polygon
			(pts
				(arc
					(start 131.4704 -91.69146)
					(mid 131.360841 -91.736841)
					(end 131.31546 -91.8464)
				)
				(arc
					(start 131.31546 -92.0496)
					(mid 131.360841 -92.159159)
					(end 131.4704 -92.20454)
				)
				(arc
					(start 131.7244 -92.20454)
					(mid 131.833959 -92.159159)
					(end 131.87934 -92.0496)
				)
				(arc
					(start 131.87934 -91.8464)
					(mid 131.833959 -91.736841)
					(end 131.7244 -91.69146)
				)
			)
		)
	)
	(zone
		(layer "In1.Cu")
		(hatch none 0.5)
		(connect_pads
			(clearance 0)
		)
		(min_thickness 0.25)
		(keepout
			(tracks not_allowed)
			(vias allowed)
			(pads allowed)
			(copperpour not_allowed)
			(footprints allowed)
		)
		(placement
			(enabled no)
			(sheetname "")
		)
		(fill
			(thermal_gap 0.5)
			(thermal_bridge_width 0.5)
			(island_removal_mode 0)
		)
		(polygon
			(pts
				(arc
					(start 41.518078 -80.314038)
					(mid 41.800018 -80.595978)
					(end 42.081958 -80.314038)
				)
				(arc
					(start 42.081958 -78.866238)
					(mid 41.800018 -78.584298)
					(end 41.518078 -78.866238)
				)
			)
		)
	)
	(zone
		(layer "In1.Cu")
		(hatch none 0.5)
		(connect_pads
			(clearance 0)
		)
		(min_thickness 0.25)
		(keepout
			(tracks not_allowed)
			(vias allowed)
			(pads allowed)
			(copperpour not_allowed)
			(footprints allowed)
		)
		(placement
			(enabled no)
			(sheetname "")
		)
		(fill
			(thermal_gap 0.5)
			(thermal_bridge_width 0.5)
			(island_removal_mode 0)
		)
		(polygon
			(pts
				(arc
					(start 121.025412 -206.68234)
					(mid 121.170892 -206.62208)
					(end 121.231152 -206.4766)
				)
				(arc
					(start 121.231152 -206.121)
					(mid 121.170892 -205.97552)
					(end 121.025412 -205.91526)
				)
				(arc
					(start 120.669812 -205.91526)
					(mid 120.524332 -205.97552)
					(end 120.464072 -206.121)
				)
				(arc
					(start 120.464072 -206.4766)
					(mid 120.524332 -206.62208)
					(end 120.669812 -206.68234)
				)
			)
		)
	)
	(zone
		(layer "In1.Cu")
		(hatch none 0.5)
		(connect_pads
			(clearance 0)
		)
		(min_thickness 0.25)
		(keepout
			(tracks not_allowed)
			(vias allowed)
			(pads allowed)
			(copperpour not_allowed)
			(footprints allowed)
		)
		(placement
			(enabled no)
			(sheetname "")
		)
		(fill
			(thermal_gap 0.5)
			(thermal_bridge_width 0.5)
			(island_removal_mode 0)
		)
		(polygon
			(pts
				(arc
					(start 86.90356 -40.51554)
					(mid 87.013119 -40.470159)
					(end 87.0585 -40.3606)
				)
				(arc
					(start 87.0585 -40.1574)
					(mid 87.013119 -40.047841)
					(end 86.90356 -40.00246)
				)
				(arc
					(start 86.64956 -40.00246)
					(mid 86.540001 -40.047841)
					(end 86.49462 -40.1574)
				)
				(arc
					(start 86.49462 -40.3606)
					(mid 86.540001 -40.470159)
					(end 86.64956 -40.51554)
				)
			)
		)
	)
	(zone
		(layer "In1.Cu")
		(hatch none 0.5)
		(connect_pads
			(clearance 0)
		)
		(min_thickness 0.25)
		(keepout
			(tracks not_allowed)
			(vias allowed)
			(pads allowed)
			(copperpour not_allowed)
			(footprints allowed)
		)
		(placement
			(enabled no)
			(sheetname "")
		)
		(fill
			(thermal_gap 0.5)
			(thermal_bridge_width 0.5)
			(island_removal_mode 0)
		)
		(polygon
			(pts
				(arc
					(start 13.31849 -100.704142)
					(mid 13.60043 -100.986082)
					(end 13.88237 -100.704142)
				)
				(arc
					(start 13.88237 -99.256342)
					(mid 13.60043 -98.974402)
					(end 13.31849 -99.256342)
				)
			)
		)
	)
	(zone
		(layer "In1.Cu")
		(hatch none 0.5)
		(connect_pads
			(clearance 0)
		)
		(min_thickness 0.25)
		(keepout
			(tracks not_allowed)
			(vias allowed)
			(pads allowed)
			(copperpour not_allowed)
			(footprints allowed)
		)
		(placement
			(enabled no)
			(sheetname "")
		)
		(fill
			(thermal_gap 0.5)
			(thermal_bridge_width 0.5)
			(island_removal_mode 0)
		)
		(polygon
			(pts
				(arc
					(start 130.9116 -91.05646)
					(mid 130.802041 -91.101841)
					(end 130.75666 -91.2114)
				)
				(arc
					(start 130.75666 -91.4146)
					(mid 130.802041 -91.524159)
					(end 130.9116 -91.56954)
				)
				(arc
					(start 131.1656 -91.56954)
					(mid 131.275159 -91.524159)
					(end 131.32054 -91.4146)
				)
				(arc
					(start 131.32054 -91.2114)
					(mid 131.275159 -91.101841)
					(end 131.1656 -91.05646)
				)
			)
		)
	)
	(zone
		(layer "In1.Cu")
		(hatch none 0.5)
		(connect_pads
			(clearance 0)
		)
		(min_thickness 0.25)
		(keepout
			(tracks not_allowed)
			(vias allowed)
			(pads allowed)
			(copperpour not_allowed)
			(footprints allowed)
		)
		(placement
			(enabled no)
			(sheetname "")
		)
		(fill
			(thermal_gap 0.5)
			(thermal_bridge_width 0.5)
			(island_removal_mode 0)
		)
		(polygon
			(pts
				(arc
					(start 130.9116 -88.89746)
					(mid 130.802041 -88.942841)
					(end 130.75666 -89.0524)
				)
				(arc
					(start 130.75666 -89.2556)
					(mid 130.802041 -89.365159)
					(end 130.9116 -89.41054)
				)
				(arc
					(start 131.1656 -89.41054)
					(mid 131.275159 -89.365159)
					(end 131.32054 -89.2556)
				)
				(arc
					(start 131.32054 -89.0524)
					(mid 131.275159 -88.942841)
					(end 131.1656 -88.89746)
				)
			)
		)
	)
	(zone
		(layer "In1.Cu")
		(hatch none 0.5)
		(connect_pads
			(clearance 0)
		)
		(min_thickness 0.25)
		(keepout
			(tracks not_allowed)
			(vias allowed)
			(pads allowed)
			(copperpour not_allowed)
			(footprints allowed)
		)
		(placement
			(enabled no)
			(sheetname "")
		)
		(fill
			(thermal_gap 0.5)
			(thermal_bridge_width 0.5)
			(island_removal_mode 0)
		)
		(polygon
			(pts
				(arc
					(start 302.503332 -68.39204)
					(mid 302.563592 -68.53752)
					(end 302.709072 -68.59778)
				)
				(arc
					(start 303.064672 -68.59778)
					(mid 303.210152 -68.53752)
					(end 303.270412 -68.39204)
				)
				(arc
					(start 303.270412 -68.03644)
					(mid 303.210152 -67.89096)
					(end 303.064672 -67.8307)
				)
				(arc
					(start 302.709072 -67.8307)
					(mid 302.563592 -67.89096)
					(end 302.503332 -68.03644)
				)
			)
		)
	)
	(zone
		(layer "In1.Cu")
		(hatch none 0.5)
		(connect_pads
			(clearance 0)
		)
		(min_thickness 0.25)
		(keepout
			(tracks not_allowed)
			(vias allowed)
			(pads allowed)
			(copperpour not_allowed)
			(footprints allowed)
		)
		(placement
			(enabled no)
			(sheetname "")
		)
		(fill
			(thermal_gap 0.5)
			(thermal_bridge_width 0.5)
			(island_removal_mode 0)
		)
		(polygon
			(pts
				(arc
					(start 86.34476 -34.92754)
					(mid 86.454319 -34.882159)
					(end 86.4997 -34.7726)
				)
				(arc
					(start 86.4997 -34.5694)
					(mid 86.454319 -34.459841)
					(end 86.34476 -34.41446)
				)
				(arc
					(start 86.09076 -34.41446)
					(mid 85.981201 -34.459841)
					(end 85.93582 -34.5694)
				)
				(arc
					(start 85.93582 -34.7726)
					(mid 85.981201 -34.882159)
					(end 86.09076 -34.92754)
				)
			)
		)
	)
	(zone
		(layer "In1.Cu")
		(hatch none 0.5)
		(connect_pads
			(clearance 0)
		)
		(min_thickness 0.25)
		(keepout
			(tracks not_allowed)
			(vias allowed)
			(pads allowed)
			(copperpour not_allowed)
			(footprints allowed)
		)
		(placement
			(enabled no)
			(sheetname "")
		)
		(fill
			(thermal_gap 0.5)
			(thermal_bridge_width 0.5)
			(island_removal_mode 0)
		)
		(polygon
			(pts
				(arc
					(start 117.99951 -113.8936)
					(mid 117.954129 -113.784041)
					(end 117.84457 -113.73866)
				)
				(arc
					(start 117.64137 -113.73866)
					(mid 117.531811 -113.784041)
					(end 117.48643 -113.8936)
				)
				(arc
					(start 117.48643 -114.1476)
					(mid 117.531811 -114.257159)
					(end 117.64137 -114.30254)
				)
				(arc
					(start 117.84457 -114.30254)
					(mid 117.954129 -114.257159)
					(end 117.99951 -114.1476)
				)
			)
		)
	)
	(zone
		(layer "In1.Cu")
		(hatch none 0.5)
		(connect_pads
			(clearance 0)
		)
		(min_thickness 0.25)
		(keepout
			(tracks not_allowed)
			(vias allowed)
			(pads allowed)
			(copperpour not_allowed)
			(footprints allowed)
		)
		(placement
			(enabled no)
			(sheetname "")
		)
		(fill
			(thermal_gap 0.5)
			(thermal_bridge_width 0.5)
			(island_removal_mode 0)
		)
		(polygon
			(pts
				(arc
					(start 109.10951 -114.4524)
					(mid 109.064129 -114.342841)
					(end 108.95457 -114.29746)
				)
				(arc
					(start 108.75137 -114.29746)
					(mid 108.641811 -114.342841)
					(end 108.59643 -114.4524)
				)
				(arc
					(start 108.59643 -114.7064)
					(mid 108.641811 -114.815959)
					(end 108.75137 -114.86134)
				)
				(arc
					(start 108.95457 -114.86134)
					(mid 109.064129 -114.815959)
					(end 109.10951 -114.7064)
				)
			)
		)
	)
	(zone
		(layer "In1.Cu")
		(hatch none 0.5)
		(connect_pads
			(clearance 0)
		)
		(min_thickness 0.25)
		(keepout
			(tracks not_allowed)
			(vias allowed)
			(pads allowed)
			(copperpour not_allowed)
			(footprints allowed)
		)
		(placement
			(enabled no)
			(sheetname "")
		)
		(fill
			(thermal_gap 0.5)
			(thermal_bridge_width 0.5)
			(island_removal_mode 0)
		)
		(polygon
			(pts
				(arc
					(start 276.672294 -25.839928)
					(mid 276.526814 -25.900188)
					(end 276.466554 -26.045668)
				)
				(arc
					(start 276.466554 -26.401268)
					(mid 276.526814 -26.546748)
					(end 276.672294 -26.607008)
				)
				(arc
					(start 277.027894 -26.607008)
					(mid 277.173374 -26.546748)
					(end 277.233634 -26.401268)
				)
				(arc
					(start 277.233634 -26.045668)
					(mid 277.173374 -25.900188)
					(end 277.027894 -25.839928)
				)
			)
		)
	)
	(zone
		(layer "In1.Cu")
		(hatch none 0.5)
		(connect_pads
			(clearance 0)
		)
		(min_thickness 0.25)
		(keepout
			(tracks not_allowed)
			(vias allowed)
			(pads allowed)
			(copperpour not_allowed)
			(footprints allowed)
		)
		(placement
			(enabled no)
			(sheetname "")
		)
		(fill
			(thermal_gap 0.5)
			(thermal_bridge_width 0.5)
			(island_removal_mode 0)
		)
		(polygon
			(pts
				(arc
					(start 86.34476 -45.46854)
					(mid 86.454319 -45.423159)
					(end 86.4997 -45.3136)
				)
				(arc
					(start 86.4997 -45.1104)
					(mid 86.454319 -45.000841)
					(end 86.34476 -44.95546)
				)
				(arc
					(start 86.09076 -44.95546)
					(mid 85.981201 -45.000841)
					(end 85.93582 -45.1104)
				)
				(arc
					(start 85.93582 -45.3136)
					(mid 85.981201 -45.423159)
					(end 86.09076 -45.46854)
				)
			)
		)
	)
	(zone
		(layer "In1.Cu")
		(hatch none 0.5)
		(connect_pads
			(clearance 0)
		)
		(min_thickness 0.25)
		(keepout
			(tracks not_allowed)
			(vias allowed)
			(pads allowed)
			(copperpour not_allowed)
			(footprints allowed)
		)
		(placement
			(enabled no)
			(sheetname "")
		)
		(fill
			(thermal_gap 0.5)
			(thermal_bridge_width 0.5)
			(island_removal_mode 0)
		)
		(polygon
			(pts
				(xy 307.594 -71.12) (xy 307.594 -69.723) (xy 309.753 -69.723) (xy 309.753 -71.12)
			)
		)
	)
	(zone
		(layer "In1.Cu")
		(hatch none 0.5)
		(connect_pads
			(clearance 0)
		)
		(min_thickness 0.25)
		(keepout
			(tracks not_allowed)
			(vias allowed)
			(pads allowed)
			(copperpour not_allowed)
			(footprints allowed)
		)
		(placement
			(enabled no)
			(sheetname "")
		)
		(fill
			(thermal_gap 0.5)
			(thermal_bridge_width 0.5)
			(island_removal_mode 0)
		)
		(polygon
			(pts
				(arc
					(start 111.500412 -206.68234)
					(mid 111.645892 -206.62208)
					(end 111.706152 -206.4766)
				)
				(arc
					(start 111.706152 -206.121)
					(mid 111.645892 -205.97552)
					(end 111.500412 -205.91526)
				)
				(arc
					(start 111.144812 -205.91526)
					(mid 110.999332 -205.97552)
					(end 110.939072 -206.121)
				)
				(arc
					(start 110.939072 -206.4766)
					(mid 110.999332 -206.62208)
					(end 111.144812 -206.68234)
				)
			)
		)
	)
	(zone
		(layer "In1.Cu")
		(hatch none 0.5)
		(connect_pads
			(clearance 0)
		)
		(min_thickness 0.25)
		(keepout
			(tracks not_allowed)
			(vias allowed)
			(pads allowed)
			(copperpour not_allowed)
			(footprints allowed)
		)
		(placement
			(enabled no)
			(sheetname "")
		)
		(fill
			(thermal_gap 0.5)
			(thermal_bridge_width 0.5)
			(island_removal_mode 0)
		)
		(polygon
			(pts
				(arc
					(start 115.07851 -113.8936)
					(mid 115.033129 -113.784041)
					(end 114.92357 -113.73866)
				)
				(arc
					(start 114.72037 -113.73866)
					(mid 114.610811 -113.784041)
					(end 114.56543 -113.8936)
				)
				(arc
					(start 114.56543 -114.1476)
					(mid 114.610811 -114.257159)
					(end 114.72037 -114.30254)
				)
				(arc
					(start 114.92357 -114.30254)
					(mid 115.033129 -114.257159)
					(end 115.07851 -114.1476)
				)
			)
		)
	)
	(zone
		(layer "In1.Cu")
		(hatch none 0.5)
		(connect_pads
			(clearance 0)
		)
		(min_thickness 0.25)
		(keepout
			(tracks not_allowed)
			(vias allowed)
			(pads allowed)
			(copperpour not_allowed)
			(footprints allowed)
		)
		(placement
			(enabled no)
			(sheetname "")
		)
		(fill
			(thermal_gap 0.5)
			(thermal_bridge_width 0.5)
			(island_removal_mode 0)
		)
		(polygon
			(pts
				(xy 277.406354 -26.068528) (xy 278.275034 -26.068528) (xy 278.275034 -27.191208) (xy 277.406354 -27.191208)
			)
		)
	)
	(zone
		(layer "In1.Cu")
		(hatch none 0.5)
		(connect_pads
			(clearance 0)
		)
		(min_thickness 0.25)
		(keepout
			(tracks not_allowed)
			(vias allowed)
			(pads allowed)
			(copperpour not_allowed)
			(footprints allowed)
		)
		(placement
			(enabled no)
			(sheetname "")
		)
		(fill
			(thermal_gap 0.5)
			(thermal_bridge_width 0.5)
			(island_removal_mode 0)
		)
		(polygon
			(pts
				(arc
					(start 111.144812 -204.16266)
					(mid 110.999332 -204.22292)
					(end 110.939072 -204.3684)
				)
				(arc
					(start 110.939072 -204.724)
					(mid 110.999332 -204.86948)
					(end 111.144812 -204.92974)
				)
				(arc
					(start 111.500412 -204.92974)
					(mid 111.645892 -204.86948)
					(end 111.706152 -204.724)
				)
				(arc
					(start 111.706152 -204.3684)
					(mid 111.645892 -204.22292)
					(end 111.500412 -204.16266)
				)
			)
		)
	)
	(zone
		(layer "In1.Cu")
		(hatch none 0.5)
		(connect_pads
			(clearance 0)
		)
		(min_thickness 0.25)
		(keepout
			(tracks not_allowed)
			(vias allowed)
			(pads allowed)
			(copperpour not_allowed)
			(footprints allowed)
		)
		(placement
			(enabled no)
			(sheetname "")
		)
		(fill
			(thermal_gap 0.5)
			(thermal_bridge_width 0.5)
			(island_removal_mode 0)
		)
		(polygon
			(pts
				(arc
					(start 277.688294 -24.976328)
					(mid 277.542814 -25.036588)
					(end 277.482554 -25.182068)
				)
				(arc
					(start 277.482554 -25.537668)
					(mid 277.542814 -25.683148)
					(end 277.688294 -25.743408)
				)
				(arc
					(start 278.043894 -25.743408)
					(mid 278.189374 -25.683148)
					(end 278.249634 -25.537668)
				)
				(arc
					(start 278.249634 -25.182068)
					(mid 278.189374 -25.036588)
					(end 278.043894 -24.976328)
				)
			)
		)
	)
	(zone
		(layer "In1.Cu")
		(hatch none 0.5)
		(connect_pads
			(clearance 0)
		)
		(min_thickness 0.25)
		(keepout
			(tracks not_allowed)
			(vias allowed)
			(pads allowed)
			(copperpour not_allowed)
			(footprints allowed)
		)
		(placement
			(enabled no)
			(sheetname "")
		)
		(fill
			(thermal_gap 0.5)
			(thermal_bridge_width 0.5)
			(island_removal_mode 0)
		)
		(polygon
			(pts
				(arc
					(start 348.438978 -155.476448)
					(mid 348.499238 -155.621928)
					(end 348.644718 -155.682188)
				)
				(arc
					(start 349.000318 -155.682188)
					(mid 349.145798 -155.621928)
					(end 349.206058 -155.476448)
				)
				(arc
					(start 349.206058 -155.120848)
					(mid 349.145798 -154.975368)
					(end 349.000318 -154.915108)
				)
				(arc
					(start 348.644718 -154.915108)
					(mid 348.499238 -154.975368)
					(end 348.438978 -155.120848)
				)
			)
		)
	)
	(zone
		(layer "In1.Cu")
		(hatch none 0.5)
		(connect_pads
			(clearance 0)
		)
		(min_thickness 0.25)
		(keepout
			(tracks not_allowed)
			(vias allowed)
			(pads allowed)
			(copperpour not_allowed)
			(footprints allowed)
		)
		(placement
			(enabled no)
			(sheetname "")
		)
		(fill
			(thermal_gap 0.5)
			(thermal_bridge_width 0.5)
			(island_removal_mode 0)
		)
		(polygon
			(pts
				(arc
					(start 86.34476 -38.22954)
					(mid 86.454319 -38.184159)
					(end 86.4997 -38.0746)
				)
				(arc
					(start 86.4997 -37.8714)
					(mid 86.454319 -37.761841)
					(end 86.34476 -37.71646)
				)
				(arc
					(start 86.09076 -37.71646)
					(mid 85.981201 -37.761841)
					(end 85.93582 -37.8714)
				)
				(arc
					(start 85.93582 -38.0746)
					(mid 85.981201 -38.184159)
					(end 86.09076 -38.22954)
				)
			)
		)
	)
	(zone
		(layer "In1.Cu")
		(hatch none 0.5)
		(connect_pads
			(clearance 0)
		)
		(min_thickness 0.25)
		(keepout
			(tracks not_allowed)
			(vias allowed)
			(pads allowed)
			(copperpour not_allowed)
			(footprints allowed)
		)
		(placement
			(enabled no)
			(sheetname "")
		)
		(fill
			(thermal_gap 0.5)
			(thermal_bridge_width 0.5)
			(island_removal_mode 0)
		)
		(polygon
			(pts
				(arc
					(start 14.11859 -100.704142)
					(mid 14.40053 -100.986082)
					(end 14.68247 -100.704142)
				)
				(arc
					(start 14.68247 -99.256342)
					(mid 14.40053 -98.974402)
					(end 14.11859 -99.256342)
				)
			)
		)
	)
	(zone
		(layer "In1.Cu")
		(hatch none 0.5)
		(connect_pads
			(clearance 0)
		)
		(min_thickness 0.25)
		(keepout
			(tracks not_allowed)
			(vias allowed)
			(pads allowed)
			(copperpour not_allowed)
			(footprints allowed)
		)
		(placement
			(enabled no)
			(sheetname "")
		)
		(fill
			(thermal_gap 0.5)
			(thermal_bridge_width 0.5)
			(island_removal_mode 0)
		)
		(polygon
			(pts
				(arc
					(start 303.366932 -67.24904)
					(mid 303.427192 -67.39452)
					(end 303.572672 -67.45478)
				)
				(arc
					(start 303.928272 -67.45478)
					(mid 304.073752 -67.39452)
					(end 304.134012 -67.24904)
				)
				(arc
					(start 304.134012 -66.89344)
					(mid 304.073752 -66.74796)
					(end 303.928272 -66.6877)
				)
				(arc
					(start 303.572672 -66.6877)
					(mid 303.427192 -66.74796)
					(end 303.366932 -66.89344)
				)
			)
		)
	)
	(zone
		(layer "In1.Cu")
		(hatch none 0.5)
		(connect_pads
			(clearance 0)
		)
		(min_thickness 0.25)
		(keepout
			(tracks not_allowed)
			(vias allowed)
			(pads allowed)
			(copperpour not_allowed)
			(footprints allowed)
		)
		(placement
			(enabled no)
			(sheetname "")
		)
		(fill
			(thermal_gap 0.5)
			(thermal_bridge_width 0.5)
			(island_removal_mode 0)
		)
		(polygon
			(pts
				(arc
					(start 131.28625 -98.51644)
					(mid 131.240869 -98.406881)
					(end 131.13131 -98.3615)
				)
				(arc
					(start 130.92811 -98.3615)
					(mid 130.818551 -98.406881)
					(end 130.77317 -98.51644)
				)
				(arc
					(start 130.77317 -98.77044)
					(mid 130.818551 -98.879999)
					(end 130.92811 -98.92538)
				)
				(arc
					(start 131.13131 -98.92538)
					(mid 131.240869 -98.879999)
					(end 131.28625 -98.77044)
				)
			)
		)
	)
	(zone
		(layer "In1.Cu")
		(hatch none 0.5)
		(connect_pads
			(clearance 0)
		)
		(min_thickness 0.25)
		(keepout
			(tracks not_allowed)
			(vias allowed)
			(pads allowed)
			(copperpour not_allowed)
			(footprints allowed)
		)
		(placement
			(enabled no)
			(sheetname "")
		)
		(fill
			(thermal_gap 0.5)
			(thermal_bridge_width 0.5)
			(island_removal_mode 0)
		)
		(polygon
			(pts
				(arc
					(start 347.575378 -153.190448)
					(mid 347.635638 -153.335928)
					(end 347.781118 -153.396188)
				)
				(arc
					(start 348.136718 -153.396188)
					(mid 348.282198 -153.335928)
					(end 348.342458 -153.190448)
				)
				(arc
					(start 348.342458 -152.834848)
					(mid 348.282198 -152.689368)
					(end 348.136718 -152.629108)
				)
				(arc
					(start 347.781118 -152.629108)
					(mid 347.635638 -152.689368)
					(end 347.575378 -152.834848)
				)
			)
		)
	)
	(zone
		(layer "In1.Cu")
		(hatch none 0.5)
		(connect_pads
			(clearance 0)
		)
		(min_thickness 0.25)
		(keepout
			(tracks not_allowed)
			(vias allowed)
			(pads allowed)
			(copperpour not_allowed)
			(footprints allowed)
		)
		(placement
			(enabled no)
			(sheetname "")
		)
		(fill
			(thermal_gap 0.5)
			(thermal_bridge_width 0.5)
			(island_removal_mode 0)
		)
		(polygon
			(pts
				(arc
					(start 42.717974 -77.80401)
					(mid 42.999914 -78.08595)
					(end 43.281854 -77.80401)
				)
				(arc
					(start 43.281854 -76.35621)
					(mid 42.999914 -76.07427)
					(end 42.717974 -76.35621)
				)
			)
		)
	)
	(zone
		(layer "In1.Cu")
		(hatch none 0.5)
		(connect_pads
			(clearance 0)
		)
		(min_thickness 0.25)
		(keepout
			(tracks not_allowed)
			(vias allowed)
			(pads allowed)
			(copperpour not_allowed)
			(footprints allowed)
		)
		(placement
			(enabled no)
			(sheetname "")
		)
		(fill
			(thermal_gap 0.5)
			(thermal_bridge_width 0.5)
			(island_removal_mode 0)
		)
		(polygon
			(pts
				(arc
					(start 113.30051 -114.4524)
					(mid 113.255129 -114.342841)
					(end 113.14557 -114.29746)
				)
				(arc
					(start 112.94237 -114.29746)
					(mid 112.832811 -114.342841)
					(end 112.78743 -114.4524)
				)
				(arc
					(start 112.78743 -114.7064)
					(mid 112.832811 -114.815959)
					(end 112.94237 -114.86134)
				)
				(arc
					(start 113.14557 -114.86134)
					(mid 113.255129 -114.815959)
					(end 113.30051 -114.7064)
				)
			)
		)
	)
	(zone
		(layer "In1.Cu")
		(hatch none 0.5)
		(connect_pads
			(clearance 0)
		)
		(min_thickness 0.25)
		(keepout
			(tracks not_allowed)
			(vias allowed)
			(pads allowed)
			(copperpour not_allowed)
			(footprints allowed)
		)
		(placement
			(enabled no)
			(sheetname "")
		)
		(fill
			(thermal_gap 0.5)
			(thermal_bridge_width 0.5)
			(island_removal_mode 0)
		)
		(polygon
			(pts
				(arc
					(start 131.806442 -82.873342)
					(mid 131.696883 -82.918723)
					(end 131.651502 -83.028282)
				)
				(arc
					(start 131.651502 -83.231482)
					(mid 131.696883 -83.341041)
					(end 131.806442 -83.386422)
				)
				(arc
					(start 132.060442 -83.386422)
					(mid 132.170001 -83.341041)
					(end 132.215382 -83.231482)
				)
				(arc
					(start 132.215382 -83.028282)
					(mid 132.170001 -82.918723)
					(end 132.060442 -82.873342)
				)
			)
		)
	)
	(zone
		(layer "In1.Cu")
		(hatch none 0.5)
		(connect_pads
			(clearance 0)
		)
		(min_thickness 0.25)
		(keepout
			(tracks not_allowed)
			(vias allowed)
			(pads allowed)
			(copperpour not_allowed)
			(footprints allowed)
		)
		(placement
			(enabled no)
			(sheetname "")
		)
		(fill
			(thermal_gap 0.5)
			(thermal_bridge_width 0.5)
			(island_removal_mode 0)
		)
		(polygon
			(pts
				(arc
					(start 18.11782 -100.704142)
					(mid 18.39976 -100.986082)
					(end 18.6817 -100.704142)
				)
				(arc
					(start 18.6817 -99.256342)
					(mid 18.39976 -98.974402)
					(end 18.11782 -99.256342)
				)
			)
		)
	)
	(zone
		(layer "In1.Cu")
		(hatch none 0.5)
		(connect_pads
			(clearance 0)
		)
		(min_thickness 0.25)
		(keepout
			(tracks not_allowed)
			(vias allowed)
			(pads allowed)
			(copperpour not_allowed)
			(footprints allowed)
		)
		(placement
			(enabled no)
			(sheetname "")
		)
		(fill
			(thermal_gap 0.5)
			(thermal_bridge_width 0.5)
			(island_removal_mode 0)
		)
		(polygon
			(pts
				(arc
					(start 120.161812 -222.06966)
					(mid 120.016332 -222.12992)
					(end 119.956072 -222.2754)
				)
				(arc
					(start 119.956072 -222.631)
					(mid 120.016332 -222.77648)
					(end 120.161812 -222.83674)
				)
				(arc
					(start 120.517412 -222.83674)
					(mid 120.662892 -222.77648)
					(end 120.723152 -222.631)
				)
				(arc
					(start 120.723152 -222.2754)
					(mid 120.662892 -222.12992)
					(end 120.517412 -222.06966)
				)
			)
		)
	)
	(zone
		(layer "In1.Cu")
		(hatch none 0.5)
		(connect_pads
			(clearance 0)
		)
		(min_thickness 0.25)
		(keepout
			(tracks not_allowed)
			(vias allowed)
			(pads allowed)
			(copperpour not_allowed)
			(footprints allowed)
		)
		(placement
			(enabled no)
			(sheetname "")
		)
		(fill
			(thermal_gap 0.5)
			(thermal_bridge_width 0.5)
			(island_removal_mode 0)
		)
		(polygon
			(pts
				(arc
					(start 133.889242 -84.270342)
					(mid 133.779683 -84.315723)
					(end 133.734302 -84.425282)
				)
				(arc
					(start 133.734302 -84.628482)
					(mid 133.779683 -84.738041)
					(end 133.889242 -84.783422)
				)
				(arc
					(start 134.143242 -84.783422)
					(mid 134.252801 -84.738041)
					(end 134.298182 -84.628482)
				)
				(arc
					(start 134.298182 -84.425282)
					(mid 134.252801 -84.315723)
					(end 134.143242 -84.270342)
				)
			)
		)
	)
	(zone
		(layer "In1.Cu")
		(hatch none 0.5)
		(connect_pads
			(clearance 0)
		)
		(min_thickness 0.25)
		(keepout
			(tracks not_allowed)
			(vias allowed)
			(pads allowed)
			(copperpour not_allowed)
			(footprints allowed)
		)
		(placement
			(enabled no)
			(sheetname "")
		)
		(fill
			(thermal_gap 0.5)
			(thermal_bridge_width 0.5)
			(island_removal_mode 0)
		)
		(polygon
			(pts
				(xy 312.039 -79.0956) (xy 312.039 -77.6986) (xy 314.198 -77.6986) (xy 314.198 -79.0956)
			)
		)
	)
	(zone
		(layer "In1.Cu")
		(hatch none 0.5)
		(connect_pads
			(clearance 0)
		)
		(min_thickness 0.25)
		(keepout
			(tracks not_allowed)
			(vias allowed)
			(pads allowed)
			(copperpour not_allowed)
			(footprints allowed)
		)
		(placement
			(enabled no)
			(sheetname "")
		)
		(fill
			(thermal_gap 0.5)
			(thermal_bridge_width 0.5)
			(island_removal_mode 0)
		)
		(polygon
			(pts
				(arc
					(start 86.90356 -37.21354)
					(mid 87.013119 -37.168159)
					(end 87.0585 -37.0586)
				)
				(arc
					(start 87.0585 -36.8554)
					(mid 87.013119 -36.745841)
					(end 86.90356 -36.70046)
				)
				(arc
					(start 86.64956 -36.70046)
					(mid 86.540001 -36.745841)
					(end 86.49462 -36.8554)
				)
				(arc
					(start 86.49462 -37.0586)
					(mid 86.540001 -37.168159)
					(end 86.64956 -37.21354)
				)
			)
		)
	)
	(zone
		(layer "In1.Cu")
		(hatch none 0.5)
		(connect_pads
			(clearance 0)
		)
		(min_thickness 0.25)
		(keepout
			(tracks not_allowed)
			(vias allowed)
			(pads allowed)
			(copperpour not_allowed)
			(footprints allowed)
		)
		(placement
			(enabled no)
			(sheetname "")
		)
		(fill
			(thermal_gap 0.5)
			(thermal_bridge_width 0.5)
			(island_removal_mode 0)
		)
		(polygon
			(pts
				(arc
					(start 118.63451 -114.4524)
					(mid 118.589129 -114.342841)
					(end 118.47957 -114.29746)
				)
				(arc
					(start 118.27637 -114.29746)
					(mid 118.166811 -114.342841)
					(end 118.12143 -114.4524)
				)
				(arc
					(start 118.12143 -114.7064)
					(mid 118.166811 -114.815959)
					(end 118.27637 -114.86134)
				)
				(arc
					(start 118.47957 -114.86134)
					(mid 118.589129 -114.815959)
					(end 118.63451 -114.7064)
				)
			)
		)
	)
	(zone
		(layer "In1.Cu")
		(hatch none 0.5)
		(connect_pads
			(clearance 0)
		)
		(min_thickness 0.25)
		(keepout
			(tracks not_allowed)
			(vias allowed)
			(pads allowed)
			(copperpour not_allowed)
			(footprints allowed)
		)
		(placement
			(enabled no)
			(sheetname "")
		)
		(fill
			(thermal_gap 0.5)
			(thermal_bridge_width 0.5)
			(island_removal_mode 0)
		)
		(polygon
			(pts
				(arc
					(start 86.34476 -33.91154)
					(mid 86.454319 -33.866159)
					(end 86.4997 -33.7566)
				)
				(arc
					(start 86.4997 -33.5534)
					(mid 86.454319 -33.443841)
					(end 86.34476 -33.39846)
				)
				(arc
					(start 86.09076 -33.39846)
					(mid 85.981201 -33.443841)
					(end 85.93582 -33.5534)
				)
				(arc
					(start 85.93582 -33.7566)
					(mid 85.981201 -33.866159)
					(end 86.09076 -33.91154)
				)
			)
		)
	)
	(zone
		(layer "In1.Cu")
		(hatch none 0.5)
		(connect_pads
			(clearance 0)
		)
		(min_thickness 0.25)
		(keepout
			(tracks not_allowed)
			(vias allowed)
			(pads allowed)
			(copperpour not_allowed)
			(footprints allowed)
		)
		(placement
			(enabled no)
			(sheetname "")
		)
		(fill
			(thermal_gap 0.5)
			(thermal_bridge_width 0.5)
			(island_removal_mode 0)
		)
		(polygon
			(pts
				(arc
					(start 131.806442 -82.238342)
					(mid 131.696883 -82.283723)
					(end 131.651502 -82.393282)
				)
				(arc
					(start 131.651502 -82.596482)
					(mid 131.696883 -82.706041)
					(end 131.806442 -82.751422)
				)
				(arc
					(start 132.060442 -82.751422)
					(mid 132.170001 -82.706041)
					(end 132.215382 -82.596482)
				)
				(arc
					(start 132.215382 -82.393282)
					(mid 132.170001 -82.283723)
					(end 132.060442 -82.238342)
				)
			)
		)
	)
	(zone
		(layer "In1.Cu")
		(hatch none 0.5)
		(connect_pads
			(clearance 0)
		)
		(min_thickness 0.25)
		(keepout
			(tracks not_allowed)
			(vias allowed)
			(pads allowed)
			(copperpour not_allowed)
			(footprints allowed)
		)
		(placement
			(enabled no)
			(sheetname "")
		)
		(fill
			(thermal_gap 0.5)
			(thermal_bridge_width 0.5)
			(island_removal_mode 0)
		)
		(polygon
			(pts
				(arc
					(start 102.63251 -113.8936)
					(mid 102.587129 -113.784041)
					(end 102.47757 -113.73866)
				)
				(arc
					(start 102.27437 -113.73866)
					(mid 102.164811 -113.784041)
					(end 102.11943 -113.8936)
				)
				(arc
					(start 102.11943 -114.1476)
					(mid 102.164811 -114.257159)
					(end 102.27437 -114.30254)
				)
				(arc
					(start 102.47757 -114.30254)
					(mid 102.587129 -114.257159)
					(end 102.63251 -114.1476)
				)
			)
		)
	)
	(zone
		(layer "In1.Cu")
		(hatch none 0.5)
		(connect_pads
			(clearance 0)
		)
		(min_thickness 0.25)
		(keepout
			(tracks not_allowed)
			(vias allowed)
			(pads allowed)
			(copperpour not_allowed)
			(footprints allowed)
		)
		(placement
			(enabled no)
			(sheetname "")
		)
		(fill
			(thermal_gap 0.5)
			(thermal_bridge_width 0.5)
			(island_removal_mode 0)
		)
		(polygon
			(pts
				(arc
					(start 114.319812 -222.06966)
					(mid 114.174332 -222.12992)
					(end 114.114072 -222.2754)
				)
				(arc
					(start 114.114072 -222.631)
					(mid 114.174332 -222.77648)
					(end 114.319812 -222.83674)
				)
				(arc
					(start 114.675412 -222.83674)
					(mid 114.820892 -222.77648)
					(end 114.881152 -222.631)
				)
				(arc
					(start 114.881152 -222.2754)
					(mid 114.820892 -222.12992)
					(end 114.675412 -222.06966)
				)
			)
		)
	)
	(zone
		(layer "In1.Cu")
		(hatch none 0.5)
		(connect_pads
			(clearance 0)
		)
		(min_thickness 0.25)
		(keepout
			(tracks not_allowed)
			(vias allowed)
			(pads allowed)
			(copperpour not_allowed)
			(footprints allowed)
		)
		(placement
			(enabled no)
			(sheetname "")
		)
		(fill
			(thermal_gap 0.5)
			(thermal_bridge_width 0.5)
			(island_removal_mode 0)
		)
		(polygon
			(pts
				(arc
					(start 120.161812 -222.93326)
					(mid 120.016332 -222.99352)
					(end 119.956072 -223.139)
				)
				(arc
					(start 119.956072 -223.4946)
					(mid 120.016332 -223.64008)
					(end 120.161812 -223.70034)
				)
				(arc
					(start 120.517412 -223.70034)
					(mid 120.662892 -223.64008)
					(end 120.723152 -223.4946)
				)
				(arc
					(start 120.723152 -223.139)
					(mid 120.662892 -222.99352)
					(end 120.517412 -222.93326)
				)
			)
		)
	)
	(zone
		(layer "In1.Cu")
		(hatch none 0.5)
		(connect_pads
			(clearance 0)
		)
		(min_thickness 0.25)
		(keepout
			(tracks not_allowed)
			(vias allowed)
			(pads allowed)
			(copperpour not_allowed)
			(footprints allowed)
		)
		(placement
			(enabled no)
			(sheetname "")
		)
		(fill
			(thermal_gap 0.5)
			(thermal_bridge_width 0.5)
			(island_removal_mode 0)
		)
		(polygon
			(pts
				(arc
					(start 121.55551 -114.4524)
					(mid 121.510129 -114.342841)
					(end 121.40057 -114.29746)
				)
				(arc
					(start 121.19737 -114.29746)
					(mid 121.087811 -114.342841)
					(end 121.04243 -114.4524)
				)
				(arc
					(start 121.04243 -114.7064)
					(mid 121.087811 -114.815959)
					(end 121.19737 -114.86134)
				)
				(arc
					(start 121.40057 -114.86134)
					(mid 121.510129 -114.815959)
					(end 121.55551 -114.7064)
				)
			)
		)
	)
	(zone
		(layer "In1.Cu")
		(hatch none 0.5)
		(connect_pads
			(clearance 0)
		)
		(min_thickness 0.25)
		(keepout
			(tracks not_allowed)
			(vias allowed)
			(pads allowed)
			(copperpour not_allowed)
			(footprints allowed)
		)
		(placement
			(enabled no)
			(sheetname "")
		)
		(fill
			(thermal_gap 0.5)
			(thermal_bridge_width 0.5)
			(island_removal_mode 0)
		)
		(polygon
			(pts
				(arc
					(start 131.641342 -81.553558)
					(mid 131.686723 -81.663117)
					(end 131.796282 -81.708498)
				)
				(arc
					(start 131.999482 -81.708498)
					(mid 132.109041 -81.663117)
					(end 132.154422 -81.553558)
				)
				(arc
					(start 132.154422 -81.299558)
					(mid 132.109041 -81.189999)
					(end 131.999482 -81.144618)
				)
				(arc
					(start 131.796282 -81.144618)
					(mid 131.686723 -81.189999)
					(end 131.641342 -81.299558)
				)
			)
		)
	)
	(zone
		(layer "In1.Cu")
		(hatch none 0.5)
		(connect_pads
			(clearance 0)
		)
		(min_thickness 0.25)
		(keepout
			(tracks not_allowed)
			(vias allowed)
			(pads allowed)
			(copperpour not_allowed)
			(footprints allowed)
		)
		(placement
			(enabled no)
			(sheetname "")
		)
		(fill
			(thermal_gap 0.5)
			(thermal_bridge_width 0.5)
			(island_removal_mode 0)
		)
		(polygon
			(pts
				(arc
					(start 109.10951 -113.8936)
					(mid 109.064129 -113.784041)
					(end 108.95457 -113.73866)
				)
				(arc
					(start 108.75137 -113.73866)
					(mid 108.641811 -113.784041)
					(end 108.59643 -113.8936)
				)
				(arc
					(start 108.59643 -114.1476)
					(mid 108.641811 -114.257159)
					(end 108.75137 -114.30254)
				)
				(arc
					(start 108.95457 -114.30254)
					(mid 109.064129 -114.257159)
					(end 109.10951 -114.1476)
				)
			)
		)
	)
	(zone
		(layer "In1.Cu")
		(hatch none 0.5)
		(connect_pads
			(clearance 0)
		)
		(min_thickness 0.25)
		(keepout
			(tracks not_allowed)
			(vias allowed)
			(pads allowed)
			(copperpour not_allowed)
			(footprints allowed)
		)
		(placement
			(enabled no)
			(sheetname "")
		)
		(fill
			(thermal_gap 0.5)
			(thermal_bridge_width 0.5)
			(island_removal_mode 0)
		)
		(polygon
			(pts
				(arc
					(start 10.51814 -103.213662)
					(mid 10.80008 -103.495602)
					(end 11.08202 -103.213662)
				)
				(arc
					(start 11.08202 -101.765862)
					(mid 10.80008 -101.483922)
					(end 10.51814 -101.765862)
				)
			)
		)
	)
	(zone
		(layer "In1.Cu")
		(hatch none 0.5)
		(connect_pads
			(clearance 0)
		)
		(min_thickness 0.25)
		(keepout
			(tracks not_allowed)
			(vias allowed)
			(pads allowed)
			(copperpour not_allowed)
			(footprints allowed)
		)
		(placement
			(enabled no)
			(sheetname "")
		)
		(fill
			(thermal_gap 0.5)
			(thermal_bridge_width 0.5)
			(island_removal_mode 0)
		)
		(polygon
			(pts
				(arc
					(start 86.90356 -34.92754)
					(mid 87.013119 -34.882159)
					(end 87.0585 -34.7726)
				)
				(arc
					(start 87.0585 -34.5694)
					(mid 87.013119 -34.459841)
					(end 86.90356 -34.41446)
				)
				(arc
					(start 86.64956 -34.41446)
					(mid 86.540001 -34.459841)
					(end 86.49462 -34.5694)
				)
				(arc
					(start 86.49462 -34.7726)
					(mid 86.540001 -34.882159)
					(end 86.64956 -34.92754)
				)
			)
		)
	)
	(zone
		(layer "In1.Cu")
		(hatch none 0.5)
		(connect_pads
			(clearance 0)
		)
		(min_thickness 0.25)
		(keepout
			(tracks not_allowed)
			(vias allowed)
			(pads allowed)
			(copperpour not_allowed)
			(footprints allowed)
		)
		(placement
			(enabled no)
			(sheetname "")
		)
		(fill
			(thermal_gap 0.5)
			(thermal_bridge_width 0.5)
			(island_removal_mode 0)
		)
		(polygon
			(pts
				(arc
					(start 113.024412 -221.94774)
					(mid 113.169892 -221.88748)
					(end 113.230152 -221.742)
				)
				(arc
					(start 113.230152 -221.3864)
					(mid 113.169892 -221.24092)
					(end 113.024412 -221.18066)
				)
				(arc
					(start 112.668812 -221.18066)
					(mid 112.523332 -221.24092)
					(end 112.463072 -221.3864)
				)
				(arc
					(start 112.463072 -221.742)
					(mid 112.523332 -221.88748)
					(end 112.668812 -221.94774)
				)
			)
		)
	)
	(zone
		(layer "In1.Cu")
		(hatch none 0.5)
		(connect_pads
			(clearance 0)
		)
		(min_thickness 0.25)
		(keepout
			(tracks not_allowed)
			(vias allowed)
			(pads allowed)
			(copperpour not_allowed)
			(footprints allowed)
		)
		(placement
			(enabled no)
			(sheetname "")
		)
		(fill
			(thermal_gap 0.5)
			(thermal_bridge_width 0.5)
			(island_removal_mode 0)
		)
		(polygon
			(pts
				(arc
					(start 51.518058 -77.80401)
					(mid 51.799998 -78.08595)
					(end 52.081938 -77.80401)
				)
				(arc
					(start 52.081938 -76.35621)
					(mid 51.799998 -76.07427)
					(end 51.518058 -76.35621)
				)
			)
		)
	)
	(zone
		(layer "In1.Cu")
		(hatch none 0.5)
		(connect_pads
			(clearance 0)
		)
		(min_thickness 0.25)
		(keepout
			(tracks not_allowed)
			(vias allowed)
			(pads allowed)
			(copperpour not_allowed)
			(footprints allowed)
		)
		(placement
			(enabled no)
			(sheetname "")
		)
		(fill
			(thermal_gap 0.5)
			(thermal_bridge_width 0.5)
			(island_removal_mode 0)
		)
		(polygon
			(pts
				(arc
					(start 316.53226 -69.3928)
					(mid 316.59252 -69.53828)
					(end 316.738 -69.59854)
				)
				(arc
					(start 317.0936 -69.59854)
					(mid 317.23908 -69.53828)
					(end 317.29934 -69.3928)
				)
				(arc
					(start 317.29934 -69.0372)
					(mid 317.23908 -68.89172)
					(end 317.0936 -68.83146)
				)
				(arc
					(start 316.738 -68.83146)
					(mid 316.59252 -68.89172)
					(end 316.53226 -69.0372)
				)
			)
		)
	)
	(zone
		(layer "In1.Cu")
		(hatch none 0.5)
		(connect_pads
			(clearance 0)
		)
		(min_thickness 0.25)
		(keepout
			(tracks not_allowed)
			(vias allowed)
			(pads allowed)
			(copperpour not_allowed)
			(footprints allowed)
		)
		(placement
			(enabled no)
			(sheetname "")
		)
		(fill
			(thermal_gap 0.5)
			(thermal_bridge_width 0.5)
			(island_removal_mode 0)
		)
		(polygon
			(pts
				(arc
					(start 121.812812 -222.06966)
					(mid 121.667332 -222.12992)
					(end 121.607072 -222.2754)
				)
				(arc
					(start 121.607072 -222.631)
					(mid 121.667332 -222.77648)
					(end 121.812812 -222.83674)
				)
				(arc
					(start 122.168412 -222.83674)
					(mid 122.313892 -222.77648)
					(end 122.374152 -222.631)
				)
				(arc
					(start 122.374152 -222.2754)
					(mid 122.313892 -222.12992)
					(end 122.168412 -222.06966)
				)
			)
		)
	)
	(zone
		(layer "In1.Cu")
		(hatch none 0.5)
		(connect_pads
			(clearance 0)
		)
		(min_thickness 0.25)
		(keepout
			(tracks not_allowed)
			(vias allowed)
			(pads allowed)
			(copperpour not_allowed)
			(footprints allowed)
		)
		(placement
			(enabled no)
			(sheetname "")
		)
		(fill
			(thermal_gap 0.5)
			(thermal_bridge_width 0.5)
			(island_removal_mode 0)
		)
		(polygon
			(pts
				(arc
					(start 131.4704 -89.53246)
					(mid 131.360841 -89.577841)
					(end 131.31546 -89.6874)
				)
				(arc
					(start 131.31546 -89.8906)
					(mid 131.360841 -90.000159)
					(end 131.4704 -90.04554)
				)
				(arc
					(start 131.7244 -90.04554)
					(mid 131.833959 -90.000159)
					(end 131.87934 -89.8906)
				)
				(arc
					(start 131.87934 -89.6874)
					(mid 131.833959 -89.577841)
					(end 131.7244 -89.53246)
				)
			)
		)
	)
	(zone
		(layer "In1.Cu")
		(hatch none 0.5)
		(connect_pads
			(clearance 0)
		)
		(min_thickness 0.25)
		(keepout
			(tracks not_allowed)
			(vias allowed)
			(pads allowed)
			(copperpour not_allowed)
			(footprints allowed)
		)
		(placement
			(enabled no)
			(sheetname "")
		)
		(fill
			(thermal_gap 0.5)
			(thermal_bridge_width 0.5)
			(island_removal_mode 0)
		)
		(polygon
			(pts
				(arc
					(start 53.518054 -80.314038)
					(mid 53.799994 -80.595978)
					(end 54.081934 -80.314038)
				)
				(arc
					(start 54.081934 -78.866238)
					(mid 53.799994 -78.584298)
					(end 53.518054 -78.866238)
				)
			)
		)
	)
	(zone
		(layer "In1.Cu")
		(hatch none 0.5)
		(connect_pads
			(clearance 0)
		)
		(min_thickness 0.25)
		(keepout
			(tracks not_allowed)
			(vias allowed)
			(pads allowed)
			(copperpour not_allowed)
			(footprints allowed)
		)
		(placement
			(enabled no)
			(sheetname "")
		)
		(fill
			(thermal_gap 0.5)
			(thermal_bridge_width 0.5)
			(island_removal_mode 0)
		)
		(polygon
			(pts
				(arc
					(start 86.90356 -35.56254)
					(mid 87.013119 -35.517159)
					(end 87.0585 -35.4076)
				)
				(arc
					(start 87.0585 -35.2044)
					(mid 87.013119 -35.094841)
					(end 86.90356 -35.04946)
				)
				(arc
					(start 86.64956 -35.04946)
					(mid 86.540001 -35.094841)
					(end 86.49462 -35.2044)
				)
				(arc
					(start 86.49462 -35.4076)
					(mid 86.540001 -35.517159)
					(end 86.64956 -35.56254)
				)
			)
		)
	)
	(zone
		(layer "In1.Cu")
		(hatch none 0.5)
		(connect_pads
			(clearance 0)
		)
		(min_thickness 0.25)
		(keepout
			(tracks not_allowed)
			(vias allowed)
			(pads allowed)
			(copperpour not_allowed)
			(footprints allowed)
		)
		(placement
			(enabled no)
			(sheetname "")
		)
		(fill
			(thermal_gap 0.5)
			(thermal_bridge_width 0.5)
			(island_removal_mode 0)
		)
		(polygon
			(pts
				(arc
					(start 130.879342 -80.994758)
					(mid 130.924723 -81.104317)
					(end 131.034282 -81.149698)
				)
				(arc
					(start 131.237482 -81.149698)
					(mid 131.347041 -81.104317)
					(end 131.392422 -80.994758)
				)
				(arc
					(start 131.392422 -80.740758)
					(mid 131.347041 -80.631199)
					(end 131.237482 -80.585818)
				)
				(arc
					(start 131.034282 -80.585818)
					(mid 130.924723 -80.631199)
					(end 130.879342 -80.740758)
				)
			)
		)
	)
	(zone
		(layer "In1.Cu")
		(hatch none 0.5)
		(connect_pads
			(clearance 0)
		)
		(min_thickness 0.25)
		(keepout
			(tracks not_allowed)
			(vias allowed)
			(pads allowed)
			(copperpour not_allowed)
			(footprints allowed)
		)
		(placement
			(enabled no)
			(sheetname "")
		)
		(fill
			(thermal_gap 0.5)
			(thermal_bridge_width 0.5)
			(island_removal_mode 0)
		)
		(polygon
			(pts
				(arc
					(start 15.31747 -103.213662)
					(mid 15.59941 -103.495602)
					(end 15.88135 -103.213662)
				)
				(arc
					(start 15.88135 -101.765862)
					(mid 15.59941 -101.483922)
					(end 15.31747 -101.765862)
				)
			)
		)
	)
	(zone
		(layer "In1.Cu")
		(hatch none 0.5)
		(connect_pads
			(clearance 0)
		)
		(min_thickness 0.25)
		(keepout
			(tracks not_allowed)
			(vias allowed)
			(pads allowed)
			(copperpour not_allowed)
			(footprints allowed)
		)
		(placement
			(enabled no)
			(sheetname "")
		)
		(fill
			(thermal_gap 0.5)
			(thermal_bridge_width 0.5)
			(island_removal_mode 0)
		)
		(polygon
			(pts
				(xy 277.54326 -19.63166) (xy 278.33574 -19.63166) (xy 278.33574 -20.85594) (xy 277.54326 -20.85594)
			)
		)
	)
	(zone
		(layer "In1.Cu")
		(hatch none 0.5)
		(connect_pads
			(clearance 0)
		)
		(min_thickness 0.25)
		(keepout
			(tracks not_allowed)
			(vias allowed)
			(pads allowed)
			(copperpour not_allowed)
			(footprints allowed)
		)
		(placement
			(enabled no)
			(sheetname "")
		)
		(fill
			(thermal_gap 0.5)
			(thermal_bridge_width 0.5)
			(island_removal_mode 0)
		)
		(polygon
			(pts
				(arc
					(start 113.151412 -206.68234)
					(mid 113.296892 -206.62208)
					(end 113.357152 -206.4766)
				)
				(arc
					(start 113.357152 -206.121)
					(mid 113.296892 -205.97552)
					(end 113.151412 -205.91526)
				)
				(arc
					(start 112.795812 -205.91526)
					(mid 112.650332 -205.97552)
					(end 112.590072 -206.121)
				)
				(arc
					(start 112.590072 -206.4766)
					(mid 112.650332 -206.62208)
					(end 112.795812 -206.68234)
				)
			)
		)
	)
	(zone
		(layer "In1.Cu")
		(hatch none 0.5)
		(connect_pads
			(clearance 0)
		)
		(min_thickness 0.25)
		(keepout
			(tracks not_allowed)
			(vias allowed)
			(pads allowed)
			(copperpour not_allowed)
			(footprints allowed)
		)
		(placement
			(enabled no)
			(sheetname "")
		)
		(fill
			(thermal_gap 0.5)
			(thermal_bridge_width 0.5)
			(island_removal_mode 0)
		)
		(polygon
			(pts
				(arc
					(start 116.85651 -113.8936)
					(mid 116.811129 -113.784041)
					(end 116.70157 -113.73866)
				)
				(arc
					(start 116.49837 -113.73866)
					(mid 116.388811 -113.784041)
					(end 116.34343 -113.8936)
				)
				(arc
					(start 116.34343 -114.1476)
					(mid 116.388811 -114.257159)
					(end 116.49837 -114.30254)
				)
				(arc
					(start 116.70157 -114.30254)
					(mid 116.811129 -114.257159)
					(end 116.85651 -114.1476)
				)
			)
		)
	)
	(zone
		(layer "In1.Cu")
		(hatch none 0.5)
		(connect_pads
			(clearance 0)
		)
		(min_thickness 0.25)
		(keepout
			(tracks not_allowed)
			(vias allowed)
			(pads allowed)
			(copperpour not_allowed)
			(footprints allowed)
		)
		(placement
			(enabled no)
			(sheetname "")
		)
		(fill
			(thermal_gap 0.5)
			(thermal_bridge_width 0.5)
			(island_removal_mode 0)
		)
		(polygon
			(pts
				(arc
					(start 135.39851 -98.9584)
					(mid 135.353129 -98.848841)
					(end 135.24357 -98.80346)
				)
				(arc
					(start 135.04037 -98.80346)
					(mid 134.930811 -98.848841)
					(end 134.88543 -98.9584)
				)
				(arc
					(start 134.88543 -99.2124)
					(mid 134.930811 -99.321959)
					(end 135.04037 -99.36734)
				)
				(arc
					(start 135.24357 -99.36734)
					(mid 135.353129 -99.321959)
					(end 135.39851 -99.2124)
				)
			)
		)
	)
	(zone
		(layer "In1.Cu")
		(hatch none 0.5)
		(connect_pads
			(clearance 0)
		)
		(min_thickness 0.25)
		(keepout
			(tracks not_allowed)
			(vias allowed)
			(pads allowed)
			(copperpour not_allowed)
			(footprints allowed)
		)
		(placement
			(enabled no)
			(sheetname "")
		)
		(fill
			(thermal_gap 0.5)
			(thermal_bridge_width 0.5)
			(island_removal_mode 0)
		)
		(polygon
			(pts
				(arc
					(start 120.669812 -205.02626)
					(mid 120.524332 -205.08652)
					(end 120.464072 -205.232)
				)
				(arc
					(start 120.464072 -205.5876)
					(mid 120.524332 -205.73308)
					(end 120.669812 -205.79334)
				)
				(arc
					(start 121.025412 -205.79334)
					(mid 121.170892 -205.73308)
					(end 121.231152 -205.5876)
				)
				(arc
					(start 121.231152 -205.232)
					(mid 121.170892 -205.08652)
					(end 121.025412 -205.02626)
				)
			)
		)
	)
	(zone
		(layer "In1.Cu")
		(hatch none 0.5)
		(connect_pads
			(clearance 0)
		)
		(min_thickness 0.25)
		(keepout
			(tracks not_allowed)
			(vias allowed)
			(pads allowed)
			(copperpour not_allowed)
			(footprints allowed)
		)
		(placement
			(enabled no)
			(sheetname "")
		)
		(fill
			(thermal_gap 0.5)
			(thermal_bridge_width 0.5)
			(island_removal_mode 0)
		)
		(polygon
			(pts
				(xy 312.039 -69.4944) (xy 312.039 -68.0974) (xy 314.198 -68.0974) (xy 314.198 -69.4944)
			)
		)
	)
	(zone
		(layer "In1.Cu")
		(hatch none 0.5)
		(connect_pads
			(clearance 0)
		)
		(min_thickness 0.25)
		(keepout
			(tracks not_allowed)
			(vias allowed)
			(pads allowed)
			(copperpour not_allowed)
			(footprints allowed)
		)
		(placement
			(enabled no)
			(sheetname "")
		)
		(fill
			(thermal_gap 0.5)
			(thermal_bridge_width 0.5)
			(island_removal_mode 0)
		)
		(polygon
			(pts
				(arc
					(start 130.879342 -81.553558)
					(mid 130.924723 -81.663117)
					(end 131.034282 -81.708498)
				)
				(arc
					(start 131.237482 -81.708498)
					(mid 131.347041 -81.663117)
					(end 131.392422 -81.553558)
				)
				(arc
					(start 131.392422 -81.299558)
					(mid 131.347041 -81.189999)
					(end 131.237482 -81.144618)
				)
				(arc
					(start 131.034282 -81.144618)
					(mid 130.924723 -81.189999)
					(end 130.879342 -81.299558)
				)
			)
		)
	)
	(zone
		(layer "In1.Cu")
		(hatch none 0.5)
		(connect_pads
			(clearance 0)
		)
		(min_thickness 0.25)
		(keepout
			(tracks not_allowed)
			(vias allowed)
			(pads allowed)
			(copperpour not_allowed)
			(footprints allowed)
		)
		(placement
			(enabled no)
			(sheetname "")
		)
		(fill
			(thermal_gap 0.5)
			(thermal_bridge_width 0.5)
			(island_removal_mode 0)
		)
		(polygon
			(pts
				(arc
					(start 86.34476 -38.86454)
					(mid 86.454319 -38.819159)
					(end 86.4997 -38.7096)
				)
				(arc
					(start 86.4997 -38.5064)
					(mid 86.454319 -38.396841)
					(end 86.34476 -38.35146)
				)
				(arc
					(start 86.09076 -38.35146)
					(mid 85.981201 -38.396841)
					(end 85.93582 -38.5064)
				)
				(arc
					(start 85.93582 -38.7096)
					(mid 85.981201 -38.819159)
					(end 86.09076 -38.86454)
				)
			)
		)
	)
	(zone
		(layer "In1.Cu")
		(hatch none 0.5)
		(connect_pads
			(clearance 0)
		)
		(min_thickness 0.25)
		(keepout
			(tracks not_allowed)
			(vias allowed)
			(pads allowed)
			(copperpour not_allowed)
			(footprints allowed)
		)
		(placement
			(enabled no)
			(sheetname "")
		)
		(fill
			(thermal_gap 0.5)
			(thermal_bridge_width 0.5)
			(island_removal_mode 0)
		)
		(polygon
			(pts
				(arc
					(start 116.22151 -114.4524)
					(mid 116.176129 -114.342841)
					(end 116.06657 -114.29746)
				)
				(arc
					(start 115.86337 -114.29746)
					(mid 115.753811 -114.342841)
					(end 115.70843 -114.4524)
				)
				(arc
					(start 115.70843 -114.7064)
					(mid 115.753811 -114.815959)
					(end 115.86337 -114.86134)
				)
				(arc
					(start 116.06657 -114.86134)
					(mid 116.176129 -114.815959)
					(end 116.22151 -114.7064)
				)
			)
		)
	)
	(zone
		(layer "In1.Cu")
		(hatch none 0.5)
		(connect_pads
			(clearance 0)
		)
		(min_thickness 0.25)
		(keepout
			(tracks not_allowed)
			(vias allowed)
			(pads allowed)
			(copperpour not_allowed)
			(footprints allowed)
		)
		(placement
			(enabled no)
			(sheetname "")
		)
		(fill
			(thermal_gap 0.5)
			(thermal_bridge_width 0.5)
			(island_removal_mode 0)
		)
		(polygon
			(pts
				(arc
					(start 110.88751 -114.4524)
					(mid 110.842129 -114.342841)
					(end 110.73257 -114.29746)
				)
				(arc
					(start 110.52937 -114.29746)
					(mid 110.419811 -114.342841)
					(end 110.37443 -114.4524)
				)
				(arc
					(start 110.37443 -114.7064)
					(mid 110.419811 -114.815959)
					(end 110.52937 -114.86134)
				)
				(arc
					(start 110.73257 -114.86134)
					(mid 110.842129 -114.815959)
					(end 110.88751 -114.7064)
				)
			)
		)
	)
	(zone
		(layer "In1.Cu")
		(hatch none 0.5)
		(connect_pads
			(clearance 0)
		)
		(min_thickness 0.25)
		(keepout
			(tracks not_allowed)
			(vias allowed)
			(pads allowed)
			(copperpour not_allowed)
			(footprints allowed)
		)
		(placement
			(enabled no)
			(sheetname "")
		)
		(fill
			(thermal_gap 0.5)
			(thermal_bridge_width 0.5)
			(island_removal_mode 0)
		)
		(polygon
			(pts
				(arc
					(start 86.90356 -42.16654)
					(mid 87.013119 -42.121159)
					(end 87.0585 -42.0116)
				)
				(arc
					(start 87.0585 -41.8084)
					(mid 87.013119 -41.698841)
					(end 86.90356 -41.65346)
				)
				(arc
					(start 86.64956 -41.65346)
					(mid 86.540001 -41.698841)
					(end 86.49462 -41.8084)
				)
				(arc
					(start 86.49462 -42.0116)
					(mid 86.540001 -42.121159)
					(end 86.64956 -42.16654)
				)
			)
		)
	)
	(zone
		(layer "In1.Cu")
		(hatch none 0.5)
		(connect_pads
			(clearance 0)
		)
		(min_thickness 0.25)
		(keepout
			(tracks not_allowed)
			(vias allowed)
			(pads allowed)
			(copperpour not_allowed)
			(footprints allowed)
		)
		(placement
			(enabled no)
			(sheetname "")
		)
		(fill
			(thermal_gap 0.5)
			(thermal_bridge_width 0.5)
			(island_removal_mode 0)
		)
		(polygon
			(pts
				(xy 277.54326 -22.32406) (xy 278.33574 -22.32406) (xy 278.33574 -23.54834) (xy 277.54326 -23.54834)
			)
		)
	)
	(zone
		(layer "In1.Cu")
		(hatch none 0.5)
		(connect_pads
			(clearance 0)
		)
		(min_thickness 0.25)
		(keepout
			(tracks not_allowed)
			(vias allowed)
			(pads allowed)
			(copperpour not_allowed)
			(footprints allowed)
		)
		(placement
			(enabled no)
			(sheetname "")
		)
		(fill
			(thermal_gap 0.5)
			(thermal_bridge_width 0.5)
			(island_removal_mode 0)
		)
		(polygon
			(pts
				(arc
					(start 347.575378 -148.872448)
					(mid 347.635638 -149.017928)
					(end 347.781118 -149.078188)
				)
				(arc
					(start 348.136718 -149.078188)
					(mid 348.282198 -149.017928)
					(end 348.342458 -148.872448)
				)
				(arc
					(start 348.342458 -148.516848)
					(mid 348.282198 -148.371368)
					(end 348.136718 -148.311108)
				)
				(arc
					(start 347.781118 -148.311108)
					(mid 347.635638 -148.371368)
					(end 347.575378 -148.516848)
				)
			)
		)
	)
	(zone
		(layer "In1.Cu")
		(hatch none 0.5)
		(connect_pads
			(clearance 0)
		)
		(min_thickness 0.25)
		(keepout
			(tracks not_allowed)
			(vias allowed)
			(pads allowed)
			(copperpour not_allowed)
			(footprints allowed)
		)
		(placement
			(enabled no)
			(sheetname "")
		)
		(fill
			(thermal_gap 0.5)
			(thermal_bridge_width 0.5)
			(island_removal_mode 0)
		)
		(polygon
			(pts
				(xy 307.594 -67.8942) (xy 307.594 -66.4972) (xy 309.753 -66.4972) (xy 309.753 -67.8942)
			)
		)
	)
	(zone
		(layer "In1.Cu")
		(hatch none 0.5)
		(connect_pads
			(clearance 0)
		)
		(min_thickness 0.25)
		(keepout
			(tracks not_allowed)
			(vias allowed)
			(pads allowed)
			(copperpour not_allowed)
			(footprints allowed)
		)
		(placement
			(enabled no)
			(sheetname "")
		)
		(fill
			(thermal_gap 0.5)
			(thermal_bridge_width 0.5)
			(island_removal_mode 0)
		)
		(polygon
			(pts
				(arc
					(start 53.91785 -77.80401)
					(mid 54.19979 -78.08595)
					(end 54.48173 -77.80401)
				)
				(arc
					(start 54.48173 -76.35621)
					(mid 54.19979 -76.07427)
					(end 53.91785 -76.35621)
				)
			)
		)
	)
	(zone
		(layer "In1.Cu")
		(hatch none 0.5)
		(connect_pads
			(clearance 0)
		)
		(min_thickness 0.25)
		(keepout
			(tracks not_allowed)
			(vias allowed)
			(pads allowed)
			(copperpour not_allowed)
			(footprints allowed)
		)
		(placement
			(enabled no)
			(sheetname "")
		)
		(fill
			(thermal_gap 0.5)
			(thermal_bridge_width 0.5)
			(island_removal_mode 0)
		)
		(polygon
			(pts
				(arc
					(start 18.91792 -100.704142)
					(mid 19.19986 -100.986082)
					(end 19.4818 -100.704142)
				)
				(arc
					(start 19.4818 -99.256342)
					(mid 19.19986 -98.974402)
					(end 18.91792 -99.256342)
				)
			)
		)
	)
	(zone
		(layer "In1.Cu")
		(hatch none 0.5)
		(connect_pads
			(clearance 0)
		)
		(min_thickness 0.25)
		(keepout
			(tracks not_allowed)
			(vias allowed)
			(pads allowed)
			(copperpour not_allowed)
			(footprints allowed)
		)
		(placement
			(enabled no)
			(sheetname "")
		)
		(fill
			(thermal_gap 0.5)
			(thermal_bridge_width 0.5)
			(island_removal_mode 0)
		)
		(polygon
			(pts
				(arc
					(start 86.90356 -43.18254)
					(mid 87.013119 -43.137159)
					(end 87.0585 -43.0276)
				)
				(arc
					(start 87.0585 -42.8244)
					(mid 87.013119 -42.714841)
					(end 86.90356 -42.66946)
				)
				(arc
					(start 86.64956 -42.66946)
					(mid 86.540001 -42.714841)
					(end 86.49462 -42.8244)
				)
				(arc
					(start 86.49462 -43.0276)
					(mid 86.540001 -43.137159)
					(end 86.64956 -43.18254)
				)
			)
		)
	)
	(zone
		(layer "In1.Cu")
		(hatch none 0.5)
		(connect_pads
			(clearance 0)
		)
		(min_thickness 0.25)
		(keepout
			(tracks not_allowed)
			(vias allowed)
			(pads allowed)
			(copperpour not_allowed)
			(footprints allowed)
		)
		(placement
			(enabled no)
			(sheetname "")
		)
		(fill
			(thermal_gap 0.5)
			(thermal_bridge_width 0.5)
			(island_removal_mode 0)
		)
		(polygon
			(pts
				(arc
					(start 133.62051 -98.9584)
					(mid 133.575129 -98.848841)
					(end 133.46557 -98.80346)
				)
				(arc
					(start 133.26237 -98.80346)
					(mid 133.152811 -98.848841)
					(end 133.10743 -98.9584)
				)
				(arc
					(start 133.10743 -99.2124)
					(mid 133.152811 -99.321959)
					(end 133.26237 -99.36734)
				)
				(arc
					(start 133.46557 -99.36734)
					(mid 133.575129 -99.321959)
					(end 133.62051 -99.2124)
				)
			)
		)
	)
	(zone
		(layer "In1.Cu")
		(hatch none 0.5)
		(connect_pads
			(clearance 0)
		)
		(min_thickness 0.25)
		(keepout
			(tracks not_allowed)
			(vias allowed)
			(pads allowed)
			(copperpour not_allowed)
			(footprints allowed)
		)
		(placement
			(enabled no)
			(sheetname "")
		)
		(fill
			(thermal_gap 0.5)
			(thermal_bridge_width 0.5)
			(island_removal_mode 0)
		)
		(polygon
			(pts
				(arc
					(start 12.91844 -103.213662)
					(mid 13.20038 -103.495602)
					(end 13.48232 -103.213662)
				)
				(arc
					(start 13.48232 -101.765862)
					(mid 13.20038 -101.483922)
					(end 12.91844 -101.765862)
				)
			)
		)
	)
	(zone
		(layer "In1.Cu")
		(hatch none 0.5)
		(connect_pads
			(clearance 0)
		)
		(min_thickness 0.25)
		(keepout
			(tracks not_allowed)
			(vias allowed)
			(pads allowed)
			(copperpour not_allowed)
			(footprints allowed)
		)
		(placement
			(enabled no)
			(sheetname "")
		)
		(fill
			(thermal_gap 0.5)
			(thermal_bridge_width 0.5)
			(island_removal_mode 0)
		)
		(polygon
			(pts
				(arc
					(start 348.438978 -153.190448)
					(mid 348.499238 -153.335928)
					(end 348.644718 -153.396188)
				)
				(arc
					(start 349.000318 -153.396188)
					(mid 349.145798 -153.335928)
					(end 349.206058 -153.190448)
				)
				(arc
					(start 349.206058 -152.834848)
					(mid 349.145798 -152.689368)
					(end 349.000318 -152.629108)
				)
				(arc
					(start 348.644718 -152.629108)
					(mid 348.499238 -152.689368)
					(end 348.438978 -152.834848)
				)
			)
		)
	)
	(zone
		(layer "In1.Cu")
		(hatch none 0.5)
		(connect_pads
			(clearance 0)
		)
		(min_thickness 0.25)
		(keepout
			(tracks not_allowed)
			(vias allowed)
			(pads allowed)
			(copperpour not_allowed)
			(footprints allowed)
		)
		(placement
			(enabled no)
			(sheetname "")
		)
		(fill
			(thermal_gap 0.5)
			(thermal_bridge_width 0.5)
			(island_removal_mode 0)
		)
		(polygon
			(pts
				(arc
					(start 347.575378 -155.476448)
					(mid 347.635638 -155.621928)
					(end 347.781118 -155.682188)
				)
				(arc
					(start 348.136718 -155.682188)
					(mid 348.282198 -155.621928)
					(end 348.342458 -155.476448)
				)
				(arc
					(start 348.342458 -155.120848)
					(mid 348.282198 -154.975368)
					(end 348.136718 -154.915108)
				)
				(arc
					(start 347.781118 -154.915108)
					(mid 347.635638 -154.975368)
					(end 347.575378 -155.120848)
				)
			)
		)
	)
	(zone
		(layer "In1.Cu")
		(hatch none 0.5)
		(connect_pads
			(clearance 0)
		)
		(min_thickness 0.25)
		(keepout
			(tracks not_allowed)
			(vias allowed)
			(pads allowed)
			(copperpour not_allowed)
			(footprints allowed)
		)
		(placement
			(enabled no)
			(sheetname "")
		)
		(fill
			(thermal_gap 0.5)
			(thermal_bridge_width 0.5)
			(island_removal_mode 0)
		)
		(polygon
			(pts
				(arc
					(start 131.4704 -88.89746)
					(mid 131.360841 -88.942841)
					(end 131.31546 -89.0524)
				)
				(arc
					(start 131.31546 -89.2556)
					(mid 131.360841 -89.365159)
					(end 131.4704 -89.41054)
				)
				(arc
					(start 131.7244 -89.41054)
					(mid 131.833959 -89.365159)
					(end 131.87934 -89.2556)
				)
				(arc
					(start 131.87934 -89.0524)
					(mid 131.833959 -88.942841)
					(end 131.7244 -88.89746)
				)
			)
		)
	)
	(zone
		(layer "In1.Cu")
		(hatch none 0.5)
		(connect_pads
			(clearance 0)
		)
		(min_thickness 0.25)
		(keepout
			(tracks not_allowed)
			(vias allowed)
			(pads allowed)
			(copperpour not_allowed)
			(footprints allowed)
		)
		(placement
			(enabled no)
			(sheetname "")
		)
		(fill
			(thermal_gap 0.5)
			(thermal_bridge_width 0.5)
			(island_removal_mode 0)
		)
		(polygon
			(pts
				(arc
					(start 11.71829 -100.704142)
					(mid 12.00023 -100.986082)
					(end 12.28217 -100.704142)
				)
				(arc
					(start 12.28217 -99.256342)
					(mid 12.00023 -98.974402)
					(end 11.71829 -99.256342)
				)
			)
		)
	)
	(zone
		(layer "In1.Cu")
		(hatch none 0.5)
		(connect_pads
			(clearance 0)
		)
		(min_thickness 0.25)
		(keepout
			(tracks not_allowed)
			(vias allowed)
			(pads allowed)
			(copperpour not_allowed)
			(footprints allowed)
		)
		(placement
			(enabled no)
			(sheetname "")
		)
		(fill
			(thermal_gap 0.5)
			(thermal_bridge_width 0.5)
			(island_removal_mode 0)
		)
		(polygon
			(pts
				(arc
					(start 86.90356 -44.83354)
					(mid 87.013119 -44.788159)
					(end 87.0585 -44.6786)
				)
				(arc
					(start 87.0585 -44.4754)
					(mid 87.013119 -44.365841)
					(end 86.90356 -44.32046)
				)
				(arc
					(start 86.64956 -44.32046)
					(mid 86.540001 -44.365841)
					(end 86.49462 -44.4754)
				)
				(arc
					(start 86.49462 -44.6786)
					(mid 86.540001 -44.788159)
					(end 86.64956 -44.83354)
				)
			)
		)
	)
	(zone
		(layer "In1.Cu")
		(hatch none 0.5)
		(connect_pads
			(clearance 0)
		)
		(min_thickness 0.25)
		(keepout
			(tracks not_allowed)
			(vias allowed)
			(pads allowed)
			(copperpour not_allowed)
			(footprints allowed)
		)
		(placement
			(enabled no)
			(sheetname "")
		)
		(fill
			(thermal_gap 0.5)
			(thermal_bridge_width 0.5)
			(island_removal_mode 0)
		)
		(polygon
			(pts
				(arc
					(start 119.018812 -205.02626)
					(mid 118.873332 -205.08652)
					(end 118.813072 -205.232)
				)
				(arc
					(start 118.813072 -205.5876)
					(mid 118.873332 -205.73308)
					(end 119.018812 -205.79334)
				)
				(arc
					(start 119.374412 -205.79334)
					(mid 119.519892 -205.73308)
					(end 119.580152 -205.5876)
				)
				(arc
					(start 119.580152 -205.232)
					(mid 119.519892 -205.08652)
					(end 119.374412 -205.02626)
				)
			)
		)
	)
	(zone
		(layer "In1.Cu")
		(hatch none 0.5)
		(connect_pads
			(clearance 0)
		)
		(min_thickness 0.25)
		(keepout
			(tracks not_allowed)
			(vias allowed)
			(pads allowed)
			(copperpour not_allowed)
			(footprints allowed)
		)
		(placement
			(enabled no)
			(sheetname "")
		)
		(fill
			(thermal_gap 0.5)
			(thermal_bridge_width 0.5)
			(island_removal_mode 0)
		)
		(polygon
			(pts
				(arc
					(start 117.99951 -114.4524)
					(mid 117.954129 -114.342841)
					(end 117.84457 -114.29746)
				)
				(arc
					(start 117.64137 -114.29746)
					(mid 117.531811 -114.342841)
					(end 117.48643 -114.4524)
				)
				(arc
					(start 117.48643 -114.7064)
					(mid 117.531811 -114.815959)
					(end 117.64137 -114.86134)
				)
				(arc
					(start 117.84457 -114.86134)
					(mid 117.954129 -114.815959)
					(end 117.99951 -114.7064)
				)
			)
		)
	)
	(zone
		(layer "In1.Cu")
		(hatch none 0.5)
		(connect_pads
			(clearance 0)
		)
		(min_thickness 0.25)
		(keepout
			(tracks not_allowed)
			(vias allowed)
			(pads allowed)
			(copperpour not_allowed)
			(footprints allowed)
		)
		(placement
			(enabled no)
			(sheetname "")
		)
		(fill
			(thermal_gap 0.5)
			(thermal_bridge_width 0.5)
			(island_removal_mode 0)
		)
		(polygon
			(pts
				(arc
					(start 134.76351 -98.9584)
					(mid 134.718129 -98.848841)
					(end 134.60857 -98.80346)
				)
				(arc
					(start 134.40537 -98.80346)
					(mid 134.295811 -98.848841)
					(end 134.25043 -98.9584)
				)
				(arc
					(start 134.25043 -99.2124)
					(mid 134.295811 -99.321959)
					(end 134.40537 -99.36734)
				)
				(arc
					(start 134.60857 -99.36734)
					(mid 134.718129 -99.321959)
					(end 134.76351 -99.2124)
				)
			)
		)
	)
	(zone
		(layer "In1.Cu")
		(hatch none 0.5)
		(connect_pads
			(clearance 0)
		)
		(min_thickness 0.25)
		(keepout
			(tracks not_allowed)
			(vias allowed)
			(pads allowed)
			(copperpour not_allowed)
			(footprints allowed)
		)
		(placement
			(enabled no)
			(sheetname "")
		)
		(fill
			(thermal_gap 0.5)
			(thermal_bridge_width 0.5)
			(island_removal_mode 0)
		)
		(polygon
			(pts
				(arc
					(start 116.85651 -114.4524)
					(mid 116.811129 -114.342841)
					(end 116.70157 -114.29746)
				)
				(arc
					(start 116.49837 -114.29746)
					(mid 116.388811 -114.342841)
					(end 116.34343 -114.4524)
				)
				(arc
					(start 116.34343 -114.7064)
					(mid 116.388811 -114.815959)
					(end 116.49837 -114.86134)
				)
				(arc
					(start 116.70157 -114.86134)
					(mid 116.811129 -114.815959)
					(end 116.85651 -114.7064)
				)
			)
		)
	)
	(zone
		(layer "In1.Cu")
		(hatch none 0.5)
		(connect_pads
			(clearance 0)
		)
		(min_thickness 0.25)
		(keepout
			(tracks not_allowed)
			(vias allowed)
			(pads allowed)
			(copperpour not_allowed)
			(footprints allowed)
		)
		(placement
			(enabled no)
			(sheetname "")
		)
		(fill
			(thermal_gap 0.5)
			(thermal_bridge_width 0.5)
			(island_removal_mode 0)
		)
		(polygon
			(pts
				(xy 307.594 -74.295) (xy 307.594 -72.898) (xy 309.753 -72.898) (xy 309.753 -74.295)
			)
		)
	)
	(zone
		(layer "In1.Cu")
		(hatch none 0.5)
		(connect_pads
			(clearance 0)
		)
		(min_thickness 0.25)
		(keepout
			(tracks not_allowed)
			(vias allowed)
			(pads allowed)
			(copperpour not_allowed)
			(footprints allowed)
		)
		(placement
			(enabled no)
			(sheetname "")
		)
		(fill
			(thermal_gap 0.5)
			(thermal_bridge_width 0.5)
			(island_removal_mode 0)
		)
		(polygon
			(pts
				(arc
					(start 86.90356 -41.53154)
					(mid 87.013119 -41.486159)
					(end 87.0585 -41.3766)
				)
				(arc
					(start 87.0585 -41.1734)
					(mid 87.013119 -41.063841)
					(end 86.90356 -41.01846)
				)
				(arc
					(start 86.64956 -41.01846)
					(mid 86.540001 -41.063841)
					(end 86.49462 -41.1734)
				)
				(arc
					(start 86.49462 -41.3766)
					(mid 86.540001 -41.486159)
					(end 86.64956 -41.53154)
				)
			)
		)
	)
	(zone
		(layer "In1.Cu")
		(hatch none 0.5)
		(connect_pads
			(clearance 0)
		)
		(min_thickness 0.25)
		(keepout
			(tracks not_allowed)
			(vias allowed)
			(pads allowed)
			(copperpour not_allowed)
			(footprints allowed)
		)
		(placement
			(enabled no)
			(sheetname "")
		)
		(fill
			(thermal_gap 0.5)
			(thermal_bridge_width 0.5)
			(island_removal_mode 0)
		)
		(polygon
			(pts
				(arc
					(start 41.917874 -77.80401)
					(mid 42.199814 -78.08595)
					(end 42.481754 -77.80401)
				)
				(arc
					(start 42.481754 -76.35621)
					(mid 42.199814 -76.07427)
					(end 41.917874 -76.35621)
				)
			)
		)
	)
	(zone
		(layer "In1.Cu")
		(hatch none 0.5)
		(connect_pads
			(clearance 0)
		)
		(min_thickness 0.25)
		(keepout
			(tracks not_allowed)
			(vias allowed)
			(pads allowed)
			(copperpour not_allowed)
			(footprints allowed)
		)
		(placement
			(enabled no)
			(sheetname "")
		)
		(fill
			(thermal_gap 0.5)
			(thermal_bridge_width 0.5)
			(island_removal_mode 0)
		)
		(polygon
			(pts
				(arc
					(start 86.34476 -39.88054)
					(mid 86.454319 -39.835159)
					(end 86.4997 -39.7256)
				)
				(arc
					(start 86.4997 -39.5224)
					(mid 86.454319 -39.412841)
					(end 86.34476 -39.36746)
				)
				(arc
					(start 86.09076 -39.36746)
					(mid 85.981201 -39.412841)
					(end 85.93582 -39.5224)
				)
				(arc
					(start 85.93582 -39.7256)
					(mid 85.981201 -39.835159)
					(end 86.09076 -39.88054)
				)
			)
		)
	)
	(zone
		(layer "In1.Cu")
		(hatch none 0.5)
		(connect_pads
			(clearance 0)
		)
		(min_thickness 0.25)
		(keepout
			(tracks not_allowed)
			(vias allowed)
			(pads allowed)
			(copperpour not_allowed)
			(footprints allowed)
		)
		(placement
			(enabled no)
			(sheetname "")
		)
		(fill
			(thermal_gap 0.5)
			(thermal_bridge_width 0.5)
			(island_removal_mode 0)
		)
		(polygon
			(pts
				(arc
					(start 18.51787 -103.213662)
					(mid 18.79981 -103.495602)
					(end 19.08175 -103.213662)
				)
				(arc
					(start 19.08175 -101.765862)
					(mid 18.79981 -101.483922)
					(end 18.51787 -101.765862)
				)
			)
		)
	)
	(zone
		(layer "In1.Cu")
		(hatch none 0.5)
		(connect_pads
			(clearance 0)
		)
		(min_thickness 0.25)
		(keepout
			(tracks not_allowed)
			(vias allowed)
			(pads allowed)
			(copperpour not_allowed)
			(footprints allowed)
		)
		(placement
			(enabled no)
			(sheetname "")
		)
		(fill
			(thermal_gap 0.5)
			(thermal_bridge_width 0.5)
			(island_removal_mode 0)
		)
		(polygon
			(pts
				(arc
					(start 17.71777 -103.213662)
					(mid 17.99971 -103.495602)
					(end 18.28165 -103.213662)
				)
				(arc
					(start 18.28165 -101.765862)
					(mid 17.99971 -101.483922)
					(end 17.71777 -101.765862)
				)
			)
		)
	)
	(zone
		(layer "In1.Cu")
		(hatch none 0.5)
		(connect_pads
			(clearance 0)
		)
		(min_thickness 0.25)
		(keepout
			(tracks not_allowed)
			(vias allowed)
			(pads allowed)
			(copperpour not_allowed)
			(footprints allowed)
		)
		(placement
			(enabled no)
			(sheetname "")
		)
		(fill
			(thermal_gap 0.5)
			(thermal_bridge_width 0.5)
			(island_removal_mode 0)
		)
		(polygon
			(pts
				(arc
					(start 15.71752 -100.704142)
					(mid 15.99946 -100.986082)
					(end 16.2814 -100.704142)
				)
				(arc
					(start 16.2814 -99.256342)
					(mid 15.99946 -98.974402)
					(end 15.71752 -99.256342)
				)
			)
		)
	)
	(zone
		(layer "In1.Cu")
		(hatch none 0.5)
		(connect_pads
			(clearance 0)
		)
		(min_thickness 0.25)
		(keepout
			(tracks not_allowed)
			(vias allowed)
			(pads allowed)
			(copperpour not_allowed)
			(footprints allowed)
		)
		(placement
			(enabled no)
			(sheetname "")
		)
		(fill
			(thermal_gap 0.5)
			(thermal_bridge_width 0.5)
			(island_removal_mode 0)
		)
		(polygon
			(pts
				(xy 312.039 -72.6948) (xy 312.039 -71.2978) (xy 314.198 -71.2978) (xy 314.198 -72.6948)
			)
		)
	)
	(zone
		(layer "In1.Cu")
		(hatch none 0.5)
		(connect_pads
			(clearance 0)
		)
		(min_thickness 0.25)
		(keepout
			(tracks not_allowed)
			(vias allowed)
			(pads allowed)
			(copperpour not_allowed)
			(footprints allowed)
		)
		(placement
			(enabled no)
			(sheetname "")
		)
		(fill
			(thermal_gap 0.5)
			(thermal_bridge_width 0.5)
			(island_removal_mode 0)
		)
		(polygon
			(pts
				(arc
					(start 119.018812 -204.16266)
					(mid 118.873332 -204.22292)
					(end 118.813072 -204.3684)
				)
				(arc
					(start 118.813072 -204.724)
					(mid 118.873332 -204.86948)
					(end 119.018812 -204.92974)
				)
				(arc
					(start 119.374412 -204.92974)
					(mid 119.519892 -204.86948)
					(end 119.580152 -204.724)
				)
				(arc
					(start 119.580152 -204.3684)
					(mid 119.519892 -204.22292)
					(end 119.374412 -204.16266)
				)
			)
		)
	)
	(zone
		(layer "In1.Cu")
		(hatch none 0.5)
		(connect_pads
			(clearance 0)
		)
		(min_thickness 0.25)
		(keepout
			(tracks not_allowed)
			(vias allowed)
			(pads allowed)
			(copperpour not_allowed)
			(footprints allowed)
		)
		(placement
			(enabled no)
			(sheetname "")
		)
		(fill
			(thermal_gap 0.5)
			(thermal_bridge_width 0.5)
			(island_removal_mode 0)
		)
		(polygon
			(pts
				(arc
					(start 45.11802 -77.80401)
					(mid 45.39996 -78.08595)
					(end 45.6819 -77.80401)
				)
				(arc
					(start 45.6819 -76.35621)
					(mid 45.39996 -76.07427)
					(end 45.11802 -76.35621)
				)
			)
		)
	)
	(zone
		(layer "In1.Cu")
		(hatch none 0.5)
		(connect_pads
			(clearance 0)
		)
		(min_thickness 0.25)
		(keepout
			(tracks not_allowed)
			(vias allowed)
			(pads allowed)
			(copperpour not_allowed)
			(footprints allowed)
		)
		(placement
			(enabled no)
			(sheetname "")
		)
		(fill
			(thermal_gap 0.5)
			(thermal_bridge_width 0.5)
			(island_removal_mode 0)
		)
		(polygon
			(pts
				(arc
					(start 86.90356 -36.57854)
					(mid 87.013119 -36.533159)
					(end 87.0585 -36.4236)
				)
				(arc
					(start 87.0585 -36.2204)
					(mid 87.013119 -36.110841)
					(end 86.90356 -36.06546)
				)
				(arc
					(start 86.64956 -36.06546)
					(mid 86.540001 -36.110841)
					(end 86.49462 -36.2204)
				)
				(arc
					(start 86.49462 -36.4236)
					(mid 86.540001 -36.533159)
					(end 86.64956 -36.57854)
				)
			)
		)
	)
	(zone
		(layers "In1.Cu" "In3.Cu" "In4.Cu" "In6.Cu")
		(hatch none 0.5)
		(connect_pads
			(clearance 0)
		)
		(min_thickness 0.25)
		(keepout
			(tracks not_allowed)
			(vias allowed)
			(pads allowed)
			(copperpour not_allowed)
			(footprints allowed)
		)
		(placement
			(enabled no)
			(sheetname "")
		)
		(fill yes
			(thermal_gap 0.5)
			(thermal_bridge_width 0.5)
			(island_removal_mode 0)
		)
		(polygon
			(pts
				(arc
					(start 285.550356 -185.54573)
					(mid 285.87573 -185.111644)
					(end 285.441644 -184.78627)
				)
				(arc
					(start 284.552898 -184.91327)
					(mid 284.227506 -185.347232)
					(end 284.661356 -185.67273)
				)
			)
		)
	)
	(zone
		(layers "In1.Cu" "In3.Cu" "In4.Cu" "In6.Cu")
		(hatch none 0.5)
		(connect_pads
			(clearance 0)
		)
		(min_thickness 0.25)
		(keepout
			(tracks not_allowed)
			(vias allowed)
			(pads allowed)
			(copperpour not_allowed)
			(footprints allowed)
		)
		(placement
			(enabled no)
			(sheetname "")
		)
		(fill yes
			(thermal_gap 0.5)
			(thermal_bridge_width 0.5)
			(island_removal_mode 0)
		)
		(polygon
			(pts
				(arc
					(start 133.858254 -81.500726)
					(mid 134.242048 -81.117313)
					(end 133.858508 -80.733646)
				)
				(arc
					(start 132.930392 -80.733646)
					(mid 132.546852 -81.117186)
					(end 132.930392 -81.500726)
				)
			)
		)
	)
	(zone
		(layers "In1.Cu" "In3.Cu" "In4.Cu" "In6.Cu")
		(hatch none 0.5)
		(connect_pads
			(clearance 0)
		)
		(min_thickness 0.25)
		(keepout
			(tracks not_allowed)
			(vias allowed)
			(pads allowed)
			(copperpour not_allowed)
			(footprints allowed)
		)
		(placement
			(enabled no)
			(sheetname "")
		)
		(fill yes
			(thermal_gap 0.5)
			(thermal_bridge_width 0.5)
			(island_removal_mode 0)
		)
		(polygon
			(pts
				(arc
					(start 83.294728 -37.831776)
					(mid 82.911188 -37.448236)
					(end 82.527648 -37.831776)
				)
				(arc
					(start 82.527648 -38.736524)
					(mid 82.911061 -39.120318)
					(end 83.294728 -38.736778)
				)
			)
		)
	)
	(zone
		(layers "In1.Cu" "In3.Cu" "In4.Cu" "In6.Cu")
		(hatch none 0.5)
		(connect_pads
			(clearance 0)
		)
		(min_thickness 0.25)
		(keepout
			(tracks not_allowed)
			(vias allowed)
			(pads allowed)
			(copperpour not_allowed)
			(footprints allowed)
		)
		(placement
			(enabled no)
			(sheetname "")
		)
		(fill yes
			(thermal_gap 0.5)
			(thermal_bridge_width 0.5)
			(island_removal_mode 0)
		)
		(polygon
			(pts
				(arc
					(start 41.693592 -83.106006)
					(mid 41.309798 -83.489419)
					(end 41.693338 -83.873086)
				)
				(arc
					(start 42.670222 -83.873086)
					(mid 43.053762 -83.489546)
					(end 42.670222 -83.106006)
				)
			)
		)
	)
	(zone
		(layers "In1.Cu" "In3.Cu" "In4.Cu" "In6.Cu")
		(hatch none 0.5)
		(connect_pads
			(clearance 0)
		)
		(min_thickness 0.25)
		(keepout
			(tracks not_allowed)
			(vias allowed)
			(pads allowed)
			(copperpour not_allowed)
			(footprints allowed)
		)
		(placement
			(enabled no)
			(sheetname "")
		)
		(fill yes
			(thermal_gap 0.5)
			(thermal_bridge_width 0.5)
			(island_removal_mode 0)
		)
		(polygon
			(pts
				(arc
					(start 111.207804 -102.850442)
					(mid 110.849791 -102.492048)
					(end 110.491524 -102.850188)
				)
				(arc
					(start 110.491524 -103.850186)
					(mid 110.849664 -104.208326)
					(end 111.207804 -103.850186)
				)
			)
		)
	)
	(zone
		(layers "In1.Cu" "In3.Cu" "In4.Cu" "In6.Cu")
		(hatch none 0.5)
		(connect_pads
			(clearance 0)
		)
		(min_thickness 0.25)
		(keepout
			(tracks not_allowed)
			(vias allowed)
			(pads allowed)
			(copperpour not_allowed)
			(footprints allowed)
		)
		(placement
			(enabled no)
			(sheetname "")
		)
		(fill yes
			(thermal_gap 0.5)
			(thermal_bridge_width 0.5)
			(island_removal_mode 0)
		)
		(polygon
			(pts
				(arc
					(start 45.488098 -75.290426)
					(mid 45.871892 -74.907013)
					(end 45.488352 -74.523346)
				)
				(arc
					(start 44.511468 -74.523346)
					(mid 44.127928 -74.906886)
					(end 44.511468 -75.290426)
				)
			)
		)
	)
	(zone
		(layers "In1.Cu" "In3.Cu" "In4.Cu" "In6.Cu")
		(hatch none 0.5)
		(connect_pads
			(clearance 0)
		)
		(min_thickness 0.25)
		(keepout
			(tracks not_allowed)
			(vias allowed)
			(pads allowed)
			(copperpour not_allowed)
			(footprints allowed)
		)
		(placement
			(enabled no)
			(sheetname "")
		)
		(fill yes
			(thermal_gap 0.5)
			(thermal_bridge_width 0.5)
			(island_removal_mode 0)
		)
		(polygon
			(pts
				(arc
					(start 80.580738 -40.00754)
					(mid 80.964532 -39.624127)
					(end 80.580992 -39.24046)
				)
				(arc
					(start 79.604108 -39.24046)
					(mid 79.220568 -39.624)
					(end 79.604108 -40.00754)
				)
			)
		)
	)
	(zone
		(layers "In1.Cu" "In3.Cu" "In4.Cu" "In6.Cu")
		(hatch none 0.5)
		(connect_pads
			(clearance 0)
		)
		(min_thickness 0.25)
		(keepout
			(tracks not_allowed)
			(vias allowed)
			(pads allowed)
			(copperpour not_allowed)
			(footprints allowed)
		)
		(placement
			(enabled no)
			(sheetname "")
		)
		(fill yes
			(thermal_gap 0.5)
			(thermal_bridge_width 0.5)
			(island_removal_mode 0)
		)
		(polygon
			(pts
				(arc
					(start 200.928478 -77.40904)
					(mid 201.312272 -77.025627)
					(end 200.928732 -76.64196)
				)
				(arc
					(start 199.946768 -76.64196)
					(mid 199.563228 -77.0255)
					(end 199.946768 -77.40904)
				)
			)
		)
	)
	(zone
		(layers "In1.Cu" "In3.Cu" "In4.Cu" "In6.Cu")
		(hatch none 0.5)
		(connect_pads
			(clearance 0)
		)
		(min_thickness 0.25)
		(keepout
			(tracks not_allowed)
			(vias allowed)
			(pads allowed)
			(copperpour not_allowed)
			(footprints allowed)
		)
		(placement
			(enabled no)
			(sheetname "")
		)
		(fill yes
			(thermal_gap 0.5)
			(thermal_bridge_width 0.5)
			(island_removal_mode 0)
		)
		(polygon
			(pts
				(arc
					(start 76.157328 -36.275772)
					(mid 75.773534 -36.659185)
					(end 76.157074 -37.042852)
				)
				(arc
					(start 77.133958 -37.042852)
					(mid 77.517498 -36.659312)
					(end 77.133958 -36.275772)
				)
			)
		)
	)
	(zone
		(layers "In1.Cu" "In3.Cu" "In4.Cu" "In6.Cu")
		(hatch none 0.5)
		(connect_pads
			(clearance 0)
		)
		(min_thickness 0.25)
		(keepout
			(tracks not_allowed)
			(vias allowed)
			(pads allowed)
			(copperpour not_allowed)
			(footprints allowed)
		)
		(placement
			(enabled no)
			(sheetname "")
		)
		(fill yes
			(thermal_gap 0.5)
			(thermal_bridge_width 0.5)
			(island_removal_mode 0)
		)
		(polygon
			(pts
				(xy 84.444586 -38.750748) (xy 84.416392 -37.734494)
				(arc
					(start 84.413852 -37.734494)
					(mid 84.04606 -37.386514)
					(end 83.69808 -37.754306)
				)
				(xy 83.69554 -37.754306) (xy 83.723734 -38.770306) (xy 83.723988 -38.77056)
				(arc
					(start 83.726274 -38.77056)
					(mid 84.094066 -39.11854)
					(end 84.442046 -38.750748)
				)
			)
		)
	)
	(zone
		(layers "In1.Cu" "In3.Cu" "In4.Cu" "In6.Cu")
		(hatch none 0.5)
		(connect_pads
			(clearance 0)
		)
		(min_thickness 0.25)
		(keepout
			(tracks not_allowed)
			(vias allowed)
			(pads allowed)
			(copperpour not_allowed)
			(footprints allowed)
		)
		(placement
			(enabled no)
			(sheetname "")
		)
		(fill yes
			(thermal_gap 0.5)
			(thermal_bridge_width 0.5)
			(island_removal_mode 0)
		)
		(polygon
			(pts
				(arc
					(start 81.61274 -36.335462)
					(mid 81.229327 -35.951668)
					(end 80.84566 -36.335208)
				)
				(arc
					(start 80.84566 -37.312092)
					(mid 81.2292 -37.695632)
					(end 81.61274 -37.312092)
				)
			)
		)
	)
	(zone
		(layers "In1.Cu" "In3.Cu" "In4.Cu" "In6.Cu")
		(hatch none 0.5)
		(connect_pads
			(clearance 0)
		)
		(min_thickness 0.25)
		(keepout
			(tracks not_allowed)
			(vias allowed)
			(pads allowed)
			(copperpour not_allowed)
			(footprints allowed)
		)
		(placement
			(enabled no)
			(sheetname "")
		)
		(fill yes
			(thermal_gap 0.5)
			(thermal_bridge_width 0.5)
			(island_removal_mode 0)
		)
		(polygon
			(pts
				(arc
					(start 95.50654 -35.404298)
					(mid 95.147638 -35.04692)
					(end 94.79026 -35.405822)
				)
				(arc
					(start 94.792038 -36.200588)
					(mid 95.150813 -36.55822)
					(end 95.508318 -36.199318)
				)
				(xy 95.50654 -35.40506)
			)
		)
	)
	(zone
		(layers "In1.Cu" "In3.Cu" "In4.Cu" "In6.Cu")
		(hatch none 0.5)
		(connect_pads
			(clearance 0)
		)
		(min_thickness 0.25)
		(keepout
			(tracks not_allowed)
			(vias allowed)
			(pads allowed)
			(copperpour not_allowed)
			(footprints allowed)
		)
		(placement
			(enabled no)
			(sheetname "")
		)
		(fill yes
			(thermal_gap 0.5)
			(thermal_bridge_width 0.5)
			(island_removal_mode 0)
		)
		(polygon
			(pts
				(arc
					(start 118.208298 -102.850188)
					(mid 117.850158 -102.492048)
					(end 117.492018 -102.850188)
				)
				(arc
					(start 117.492018 -103.849932)
					(mid 117.850031 -104.208326)
					(end 118.208298 -103.850186)
				)
			)
		)
	)
	(zone
		(layers "In1.Cu" "In3.Cu" "In4.Cu" "In6.Cu")
		(hatch none 0.5)
		(connect_pads
			(clearance 0)
		)
		(min_thickness 0.25)
		(keepout
			(tracks not_allowed)
			(vias allowed)
			(pads allowed)
			(copperpour not_allowed)
			(footprints allowed)
		)
		(placement
			(enabled no)
			(sheetname "")
		)
		(fill yes
			(thermal_gap 0.5)
			(thermal_bridge_width 0.5)
			(island_removal_mode 0)
		)
		(polygon
			(pts
				(arc
					(start 132.59054 -91.170252)
					(mid 132.207127 -90.786458)
					(end 131.82346 -91.169998)
				)
				(arc
					(start 131.82346 -92.075)
					(mid 132.207 -92.45854)
					(end 132.59054 -92.075)
				)
			)
		)
	)
	(zone
		(layers "In1.Cu" "In3.Cu" "In4.Cu" "In6.Cu")
		(hatch none 0.5)
		(connect_pads
			(clearance 0)
		)
		(min_thickness 0.25)
		(keepout
			(tracks not_allowed)
			(vias allowed)
			(pads allowed)
			(copperpour not_allowed)
			(footprints allowed)
		)
		(placement
			(enabled no)
			(sheetname "")
		)
		(fill yes
			(thermal_gap 0.5)
			(thermal_bridge_width 0.5)
			(island_removal_mode 0)
		)
		(polygon
			(pts
				(arc
					(start 299.643546 -174.676054)
					(mid 299.280328 -175.028987)
					(end 299.633132 -175.392334)
				)
				(arc
					(start 300.430438 -175.40351)
					(mid 300.793658 -175.05045)
					(end 300.440598 -174.68723)
				)
			)
		)
	)
	(zone
		(layers "In1.Cu" "In3.Cu" "In4.Cu" "In6.Cu")
		(hatch none 0.5)
		(connect_pads
			(clearance 0)
		)
		(min_thickness 0.25)
		(keepout
			(tracks not_allowed)
			(vias allowed)
			(pads allowed)
			(copperpour not_allowed)
			(footprints allowed)
		)
		(placement
			(enabled no)
			(sheetname "")
		)
		(fill yes
			(thermal_gap 0.5)
			(thermal_bridge_width 0.5)
			(island_removal_mode 0)
		)
		(polygon
			(pts
				(arc
					(start 39.975536 -82.070194)
					(mid 39.591996 -81.686654)
					(end 39.208456 -82.070194)
				)
				(arc
					(start 39.208456 -83.046824)
					(mid 39.591869 -83.430618)
					(end 39.975536 -83.047078)
				)
			)
		)
	)
	(zone
		(layers "In1.Cu" "In3.Cu" "In4.Cu" "In6.Cu")
		(hatch none 0.5)
		(connect_pads
			(clearance 0)
		)
		(min_thickness 0.25)
		(keepout
			(tracks not_allowed)
			(vias allowed)
			(pads allowed)
			(copperpour not_allowed)
			(footprints allowed)
		)
		(placement
			(enabled no)
			(sheetname "")
		)
		(fill yes
			(thermal_gap 0.5)
			(thermal_bridge_width 0.5)
			(island_removal_mode 0)
		)
		(polygon
			(pts
				(arc
					(start 102.708202 -35.39998)
					(mid 102.349935 -35.04184)
					(end 101.991922 -35.400234)
				)
				(arc
					(start 101.992176 -36.199826)
					(mid 102.350316 -36.55822)
					(end 102.708456 -36.199826)
				)
				(xy 102.708202 -35.75812)
			)
		)
	)
	(zone
		(layers "In1.Cu" "In3.Cu" "In4.Cu" "In6.Cu")
		(hatch none 0.5)
		(connect_pads
			(clearance 0)
		)
		(min_thickness 0.25)
		(keepout
			(tracks not_allowed)
			(vias allowed)
			(pads allowed)
			(copperpour not_allowed)
			(footprints allowed)
		)
		(placement
			(enabled no)
			(sheetname "")
		)
		(fill yes
			(thermal_gap 0.5)
			(thermal_bridge_width 0.5)
			(island_removal_mode 0)
		)
		(polygon
			(pts
				(arc
					(start 134.11454 -89.654126)
					(mid 133.731 -89.270586)
					(end 133.34746 -89.654126)
				)
				(arc
					(start 133.34746 -90.558874)
					(mid 133.730873 -90.942668)
					(end 134.11454 -90.559128)
				)
			)
		)
	)
	(zone
		(layers "In1.Cu" "In3.Cu" "In4.Cu" "In6.Cu")
		(hatch none 0.5)
		(connect_pads
			(clearance 0)
		)
		(min_thickness 0.25)
		(keepout
			(tracks not_allowed)
			(vias allowed)
			(pads allowed)
			(copperpour not_allowed)
			(footprints allowed)
		)
		(placement
			(enabled no)
			(sheetname "")
		)
		(fill yes
			(thermal_gap 0.5)
			(thermal_bridge_width 0.5)
			(island_removal_mode 0)
		)
		(polygon
			(pts
				(arc
					(start 42.111676 -74.370946)
					(mid 41.727882 -74.754359)
					(end 42.111422 -75.138026)
				)
				(arc
					(start 43.088306 -75.138026)
					(mid 43.471846 -74.754486)
					(end 43.088306 -74.370946)
				)
			)
		)
	)
	(zone
		(layers "In1.Cu" "In3.Cu" "In4.Cu" "In6.Cu")
		(hatch none 0.5)
		(connect_pads
			(clearance 0)
		)
		(min_thickness 0.25)
		(keepout
			(tracks not_allowed)
			(vias allowed)
			(pads allowed)
			(copperpour not_allowed)
			(footprints allowed)
		)
		(placement
			(enabled no)
			(sheetname "")
		)
		(fill yes
			(thermal_gap 0.5)
			(thermal_bridge_width 0.5)
			(island_removal_mode 0)
		)
		(polygon
			(pts
				(arc
					(start 108.20781 -102.850442)
					(mid 107.849797 -102.492048)
					(end 107.49153 -102.850188)
				)
				(arc
					(start 107.49153 -103.850186)
					(mid 107.84967 -104.208326)
					(end 108.20781 -103.850186)
				)
			)
		)
	)
	(zone
		(layers "In1.Cu" "In3.Cu" "In4.Cu" "In6.Cu")
		(hatch none 0.5)
		(connect_pads
			(clearance 0)
		)
		(min_thickness 0.25)
		(keepout
			(tracks not_allowed)
			(vias allowed)
			(pads allowed)
			(copperpour not_allowed)
			(footprints allowed)
		)
		(placement
			(enabled no)
			(sheetname "")
		)
		(fill yes
			(thermal_gap 0.5)
			(thermal_bridge_width 0.5)
			(island_removal_mode 0)
		)
		(polygon
			(pts
				(arc
					(start 13.52931 -98.086672)
					(mid 13.12545 -98.448876)
					(end 13.487654 -98.852736)
				)
				(xy 14.4272 -98.903536)
				(arc
					(start 14.427454 -98.903536)
					(mid 14.831314 -98.541332)
					(end 14.46911 -98.137472)
				)
			)
		)
	)
	(zone
		(layers "In1.Cu" "In3.Cu" "In4.Cu" "In6.Cu")
		(hatch none 0.5)
		(connect_pads
			(clearance 0)
		)
		(min_thickness 0.25)
		(keepout
			(tracks not_allowed)
			(vias allowed)
			(pads allowed)
			(copperpour not_allowed)
			(footprints allowed)
		)
		(placement
			(enabled no)
			(sheetname "")
		)
		(fill yes
			(thermal_gap 0.5)
			(thermal_bridge_width 0.5)
			(island_removal_mode 0)
		)
		(polygon
			(pts
				(arc
					(start 45.623734 -83.885786)
					(mid 46.007528 -83.502373)
					(end 45.623988 -83.118706)
				)
				(arc
					(start 44.647104 -83.118706)
					(mid 44.263564 -83.502246)
					(end 44.647104 -83.885786)
				)
			)
		)
	)
	(zone
		(layers "In1.Cu" "In3.Cu" "In4.Cu" "In6.Cu")
		(hatch none 0.5)
		(connect_pads
			(clearance 0)
		)
		(min_thickness 0.25)
		(keepout
			(tracks not_allowed)
			(vias allowed)
			(pads allowed)
			(copperpour not_allowed)
			(footprints allowed)
		)
		(placement
			(enabled no)
			(sheetname "")
		)
		(fill yes
			(thermal_gap 0.5)
			(thermal_bridge_width 0.5)
			(island_removal_mode 0)
		)
		(polygon
			(pts
				(arc
					(start 350.369124 -154.275028)
					(mid 350.010984 -153.916888)
					(end 349.652844 -154.275028)
				)
				(arc
					(start 349.652844 -155.154884)
					(mid 350.010857 -155.513278)
					(end 350.369124 -155.155138)
				)
			)
		)
	)
	(zone
		(layers "In1.Cu" "In3.Cu" "In4.Cu" "In6.Cu")
		(hatch none 0.5)
		(connect_pads
			(clearance 0)
		)
		(min_thickness 0.25)
		(keepout
			(tracks not_allowed)
			(vias allowed)
			(pads allowed)
			(copperpour not_allowed)
			(footprints allowed)
		)
		(placement
			(enabled no)
			(sheetname "")
		)
		(fill yes
			(thermal_gap 0.5)
			(thermal_bridge_width 0.5)
			(island_removal_mode 0)
		)
		(polygon
			(pts
				(arc
					(start 100.30968 -35.392868)
					(mid 99.952048 -35.03422)
					(end 99.5934 -35.391852)
				)
				(arc
					(start 99.59213 -36.199318)
					(mid 99.949635 -36.55822)
					(end 100.30841 -36.200588)
				)
				(xy 100.30841 -36.20008)
			)
		)
	)
	(zone
		(layers "In1.Cu" "In3.Cu" "In4.Cu" "In6.Cu")
		(hatch none 0.5)
		(connect_pads
			(clearance 0)
		)
		(min_thickness 0.25)
		(keepout
			(tracks not_allowed)
			(vias allowed)
			(pads allowed)
			(copperpour not_allowed)
			(footprints allowed)
		)
		(placement
			(enabled no)
			(sheetname "")
		)
		(fill yes
			(thermal_gap 0.5)
			(thermal_bridge_width 0.5)
			(island_removal_mode 0)
		)
		(polygon
			(pts
				(arc
					(start 107.207812 -102.850442)
					(mid 106.849799 -102.492048)
					(end 106.491532 -102.850188)
				)
				(arc
					(start 106.491532 -103.850186)
					(mid 106.849672 -104.208326)
					(end 107.207812 -103.850186)
				)
			)
		)
	)
	(zone
		(layers "In1.Cu" "In3.Cu" "In4.Cu" "In6.Cu")
		(hatch none 0.5)
		(connect_pads
			(clearance 0)
		)
		(min_thickness 0.25)
		(keepout
			(tracks not_allowed)
			(vias allowed)
			(pads allowed)
			(copperpour not_allowed)
			(footprints allowed)
		)
		(placement
			(enabled no)
			(sheetname "")
		)
		(fill yes
			(thermal_gap 0.5)
			(thermal_bridge_width 0.5)
			(island_removal_mode 0)
		)
		(polygon
			(pts
				(arc
					(start 92.753942 -41.438576)
					(mid 92.392247 -41.793033)
					(end 92.746576 -42.154856)
				)
				(arc
					(start 93.550994 -42.16273)
					(mid 93.91269 -41.808146)
					(end 93.558106 -41.44645)
				)
			)
		)
	)
	(zone
		(layers "In1.Cu" "In3.Cu" "In4.Cu" "In6.Cu")
		(hatch none 0.5)
		(connect_pads
			(clearance 0)
		)
		(min_thickness 0.25)
		(keepout
			(tracks not_allowed)
			(vias allowed)
			(pads allowed)
			(copperpour not_allowed)
			(footprints allowed)
		)
		(placement
			(enabled no)
			(sheetname "")
		)
		(fill yes
			(thermal_gap 0.5)
			(thermal_bridge_width 0.5)
			(island_removal_mode 0)
		)
		(polygon
			(pts
				(arc
					(start 132.00507 -80.13954)
					(mid 132.388864 -79.756127)
					(end 132.005324 -79.37246)
				)
				(arc
					(start 131.02844 -79.37246)
					(mid 130.6449 -79.756)
					(end 131.02844 -80.13954)
				)
			)
		)
	)
	(zone
		(layers "In1.Cu" "In3.Cu" "In4.Cu" "In6.Cu")
		(hatch none 0.5)
		(connect_pads
			(clearance 0)
		)
		(min_thickness 0.25)
		(keepout
			(tracks not_allowed)
			(vias allowed)
			(pads allowed)
			(copperpour not_allowed)
			(footprints allowed)
		)
		(placement
			(enabled no)
			(sheetname "")
		)
		(fill yes
			(thermal_gap 0.5)
			(thermal_bridge_width 0.5)
			(island_removal_mode 0)
		)
		(polygon
			(pts
				(arc
					(start 155.946602 -76.64196)
					(mid 155.562808 -77.025373)
					(end 155.946348 -77.40904)
				)
				(arc
					(start 156.928312 -77.40904)
					(mid 157.311852 -77.0255)
					(end 156.928312 -76.64196)
				)
			)
		)
	)
	(zone
		(layers "In1.Cu" "In3.Cu" "In4.Cu" "In6.Cu")
		(hatch none 0.5)
		(connect_pads
			(clearance 0)
		)
		(min_thickness 0.25)
		(keepout
			(tracks not_allowed)
			(vias allowed)
			(pads allowed)
			(copperpour not_allowed)
			(footprints allowed)
		)
		(placement
			(enabled no)
			(sheetname "")
		)
		(fill yes
			(thermal_gap 0.5)
			(thermal_bridge_width 0.5)
			(island_removal_mode 0)
		)
		(polygon
			(pts
				(arc
					(start 119.208296 -102.850188)
					(mid 118.850156 -102.492048)
					(end 118.492016 -102.850188)
				)
				(arc
					(start 118.492016 -103.849932)
					(mid 118.850029 -104.208326)
					(end 119.208296 -103.850186)
				)
			)
		)
	)
	(zone
		(layers "In1.Cu" "In3.Cu" "In4.Cu" "In6.Cu")
		(hatch none 0.5)
		(connect_pads
			(clearance 0)
		)
		(min_thickness 0.25)
		(keepout
			(tracks not_allowed)
			(vias allowed)
			(pads allowed)
			(copperpour not_allowed)
			(footprints allowed)
		)
		(placement
			(enabled no)
			(sheetname "")
		)
		(fill yes
			(thermal_gap 0.5)
			(thermal_bridge_width 0.5)
			(island_removal_mode 0)
		)
		(polygon
			(pts
				(arc
					(start 124.779532 -79.868268)
					(mid 124.395738 -80.251681)
					(end 124.779278 -80.635348)
				)
				(arc
					(start 125.756162 -80.635348)
					(mid 126.139702 -80.251808)
					(end 125.756162 -79.868268)
				)
			)
		)
	)
	(zone
		(layers "In1.Cu" "In3.Cu" "In4.Cu" "In6.Cu")
		(hatch none 0.5)
		(connect_pads
			(clearance 0)
		)
		(min_thickness 0.25)
		(keepout
			(tracks not_allowed)
			(vias allowed)
			(pads allowed)
			(copperpour not_allowed)
			(footprints allowed)
		)
		(placement
			(enabled no)
			(sheetname "")
		)
		(fill yes
			(thermal_gap 0.5)
			(thermal_bridge_width 0.5)
			(island_removal_mode 0)
		)
		(polygon
			(pts
				(arc
					(start 41.351708 -89.712546)
					(mid 40.967914 -90.095959)
					(end 41.351454 -90.479626)
				)
				(arc
					(start 42.328338 -90.479626)
					(mid 42.711878 -90.096086)
					(end 42.328338 -89.712546)
				)
			)
		)
	)
	(zone
		(layers "In1.Cu" "In3.Cu" "In4.Cu" "In6.Cu")
		(hatch none 0.5)
		(connect_pads
			(clearance 0)
		)
		(min_thickness 0.25)
		(keepout
			(tracks not_allowed)
			(vias allowed)
			(pads allowed)
			(copperpour not_allowed)
			(footprints allowed)
		)
		(placement
			(enabled no)
			(sheetname "")
		)
		(fill yes
			(thermal_gap 0.5)
			(thermal_bridge_width 0.5)
			(island_removal_mode 0)
		)
		(polygon
			(pts
				(arc
					(start 93.898974 -40.193722)
					(mid 93.534484 -39.841932)
					(end 93.182694 -40.206422)
				)
				(arc
					(start 93.196664 -41.001696)
					(mid 93.561027 -41.353738)
					(end 93.912944 -40.98925)
				)
			)
		)
	)
	(zone
		(layers "In1.Cu" "In3.Cu" "In4.Cu" "In6.Cu")
		(hatch none 0.5)
		(connect_pads
			(clearance 0)
		)
		(min_thickness 0.25)
		(keepout
			(tracks not_allowed)
			(vias allowed)
			(pads allowed)
			(copperpour not_allowed)
			(footprints allowed)
		)
		(placement
			(enabled no)
			(sheetname "")
		)
		(fill yes
			(thermal_gap 0.5)
			(thermal_bridge_width 0.5)
			(island_removal_mode 0)
		)
		(polygon
			(pts
				(arc
					(start 294.03294 -79.44993)
					(mid 293.6494 -79.06639)
					(end 293.26586 -79.44993)
				)
				(arc
					(start 293.26586 -80.366616)
					(mid 293.649273 -80.75041)
					(end 294.03294 -80.36687)
				)
			)
		)
	)
	(zone
		(layers "In1.Cu" "In3.Cu" "In4.Cu" "In6.Cu")
		(hatch none 0.5)
		(connect_pads
			(clearance 0)
		)
		(min_thickness 0.25)
		(keepout
			(tracks not_allowed)
			(vias allowed)
			(pads allowed)
			(copperpour not_allowed)
			(footprints allowed)
		)
		(placement
			(enabled no)
			(sheetname "")
		)
		(fill yes
			(thermal_gap 0.5)
			(thermal_bridge_width 0.5)
			(island_removal_mode 0)
		)
		(polygon
			(pts
				(arc
					(start 301.975012 -73.22566)
					(mid 301.591218 -73.609073)
					(end 301.974758 -73.99274)
				)
				(arc
					(start 302.956722 -73.99274)
					(mid 303.340262 -73.6092)
					(end 302.956722 -73.22566)
				)
			)
		)
	)
	(zone
		(layers "In1.Cu" "In3.Cu" "In4.Cu" "In6.Cu")
		(hatch none 0.5)
		(connect_pads
			(clearance 0)
		)
		(min_thickness 0.25)
		(keepout
			(tracks not_allowed)
			(vias allowed)
			(pads allowed)
			(copperpour not_allowed)
			(footprints allowed)
		)
		(placement
			(enabled no)
			(sheetname "")
		)
		(fill yes
			(thermal_gap 0.5)
			(thermal_bridge_width 0.5)
			(island_removal_mode 0)
		)
		(polygon
			(pts
				(arc
					(start 39.975536 -79.746348)
					(mid 39.592123 -79.362554)
					(end 39.208456 -79.746094)
				)
				(arc
					(start 39.208456 -80.722978)
					(mid 39.591996 -81.106518)
					(end 39.975536 -80.722978)
				)
			)
		)
	)
	(zone
		(layers "In1.Cu" "In3.Cu" "In4.Cu" "In6.Cu")
		(hatch none 0.5)
		(connect_pads
			(clearance 0)
		)
		(min_thickness 0.25)
		(keepout
			(tracks not_allowed)
			(vias allowed)
			(pads allowed)
			(copperpour not_allowed)
			(footprints allowed)
		)
		(placement
			(enabled no)
			(sheetname "")
		)
		(fill yes
			(thermal_gap 0.5)
			(thermal_bridge_width 0.5)
			(island_removal_mode 0)
		)
		(polygon
			(pts
				(arc
					(start 319.139316 -68.216272)
					(mid 318.755903 -67.832478)
					(end 318.372236 -68.216018)
				)
				(arc
					(start 318.372236 -69.197982)
					(mid 318.755776 -69.581522)
					(end 319.139316 -69.197982)
				)
			)
		)
	)
	(zone
		(layers "In1.Cu" "In3.Cu" "In4.Cu" "In6.Cu")
		(hatch none 0.5)
		(connect_pads
			(clearance 0)
		)
		(min_thickness 0.25)
		(keepout
			(tracks not_allowed)
			(vias allowed)
			(pads allowed)
			(copperpour not_allowed)
			(footprints allowed)
		)
		(placement
			(enabled no)
			(sheetname "")
		)
		(fill yes
			(thermal_gap 0.5)
			(thermal_bridge_width 0.5)
			(island_removal_mode 0)
		)
		(polygon
			(pts
				(arc
					(start 122.850402 -82.49158)
					(mid 122.492008 -82.849593)
					(end 122.850148 -83.20786)
				)
				(arc
					(start 123.850146 -83.20786)
					(mid 124.208286 -82.84972)
					(end 123.850146 -82.49158)
				)
			)
		)
	)
	(zone
		(layers "In1.Cu" "In3.Cu" "In4.Cu" "In6.Cu")
		(hatch none 0.5)
		(connect_pads
			(clearance 0)
		)
		(min_thickness 0.25)
		(keepout
			(tracks not_allowed)
			(vias allowed)
			(pads allowed)
			(copperpour not_allowed)
			(footprints allowed)
		)
		(placement
			(enabled no)
			(sheetname "")
		)
		(fill yes
			(thermal_gap 0.5)
			(thermal_bridge_width 0.5)
			(island_removal_mode 0)
		)
		(polygon
			(pts
				(arc
					(start 191.947038 -76.64196)
					(mid 191.563498 -77.0255)
					(end 191.947038 -77.40904)
				)
				(arc
					(start 192.928748 -77.40904)
					(mid 193.312542 -77.025627)
					(end 192.929002 -76.64196)
				)
			)
		)
	)
	(zone
		(layers "In1.Cu" "In3.Cu" "In4.Cu" "In6.Cu")
		(hatch none 0.5)
		(connect_pads
			(clearance 0)
		)
		(min_thickness 0.25)
		(keepout
			(tracks not_allowed)
			(vias allowed)
			(pads allowed)
			(copperpour not_allowed)
			(footprints allowed)
		)
		(placement
			(enabled no)
			(sheetname "")
		)
		(fill yes
			(thermal_gap 0.5)
			(thermal_bridge_width 0.5)
			(island_removal_mode 0)
		)
		(polygon
			(pts
				(arc
					(start 163.946332 -76.64196)
					(mid 163.562538 -77.025373)
					(end 163.946078 -77.40904)
				)
				(arc
					(start 164.928042 -77.40904)
					(mid 165.311582 -77.0255)
					(end 164.928042 -76.64196)
				)
			)
		)
	)
	(zone
		(layers "In1.Cu" "In3.Cu" "In4.Cu" "In6.Cu")
		(hatch none 0.5)
		(connect_pads
			(clearance 0)
		)
		(min_thickness 0.25)
		(keepout
			(tracks not_allowed)
			(vias allowed)
			(pads allowed)
			(copperpour not_allowed)
			(footprints allowed)
		)
		(placement
			(enabled no)
			(sheetname "")
		)
		(fill yes
			(thermal_gap 0.5)
			(thermal_bridge_width 0.5)
			(island_removal_mode 0)
		)
		(polygon
			(pts
				(arc
					(start 272.999962 -11.779758)
					(mid 273.789902 -10.989818)
					(end 272.999962 -10.199878)
				)
				(arc
					(start 270.999966 -10.199878)
					(mid 270.210026 -10.989818)
					(end 270.999966 -11.779758)
				)
			)
		)
	)
	(zone
		(layers "In1.Cu" "In3.Cu" "In4.Cu" "In6.Cu")
		(hatch none 0.5)
		(connect_pads
			(clearance 0)
		)
		(min_thickness 0.25)
		(keepout
			(tracks not_allowed)
			(vias allowed)
			(pads allowed)
			(copperpour not_allowed)
			(footprints allowed)
		)
		(placement
			(enabled no)
			(sheetname "")
		)
		(fill yes
			(thermal_gap 0.5)
			(thermal_bridge_width 0.5)
			(island_removal_mode 0)
		)
		(polygon
			(pts
				(arc
					(start 130.047746 -81.66354)
					(mid 130.43154 -81.280127)
					(end 130.048 -80.89646)
				)
				(arc
					(start 129.159 -80.89646)
					(mid 128.77546 -81.28)
					(end 129.159 -81.66354)
				)
			)
		)
	)
	(zone
		(layers "In1.Cu" "In3.Cu" "In4.Cu" "In6.Cu")
		(hatch none 0.5)
		(connect_pads
			(clearance 0)
		)
		(min_thickness 0.25)
		(keepout
			(tracks not_allowed)
			(vias allowed)
			(pads allowed)
			(copperpour not_allowed)
			(footprints allowed)
		)
		(placement
			(enabled no)
			(sheetname "")
		)
		(fill yes
			(thermal_gap 0.5)
			(thermal_bridge_width 0.5)
			(island_removal_mode 0)
		)
		(polygon
			(pts
				(arc
					(start 85.37194 -32.885126)
					(mid 84.988527 -32.501332)
					(end 84.60486 -32.884872)
				)
				(arc
					(start 84.60486 -33.789874)
					(mid 84.9884 -34.173414)
					(end 85.37194 -33.789874)
				)
			)
		)
	)
	(zone
		(layers "In1.Cu" "In3.Cu" "In4.Cu" "In6.Cu")
		(hatch none 0.5)
		(connect_pads
			(clearance 0)
		)
		(min_thickness 0.25)
		(keepout
			(tracks not_allowed)
			(vias allowed)
			(pads allowed)
			(copperpour not_allowed)
			(footprints allowed)
		)
		(placement
			(enabled no)
			(sheetname "")
		)
		(fill yes
			(thermal_gap 0.5)
			(thermal_bridge_width 0.5)
			(island_removal_mode 0)
		)
		(polygon
			(pts
				(arc
					(start 93.55582 -39.755318)
					(mid 93.914722 -39.39794)
					(end 93.557344 -39.039038)
				)
				(arc
					(start 92.746576 -39.03726)
					(mid 92.387674 -39.394511)
					(end 92.744798 -39.75354)
				)
			)
		)
	)
	(zone
		(layers "In1.Cu" "In3.Cu" "In4.Cu" "In6.Cu")
		(hatch none 0.5)
		(connect_pads
			(clearance 0)
		)
		(min_thickness 0.25)
		(keepout
			(tracks not_allowed)
			(vias allowed)
			(pads allowed)
			(copperpour not_allowed)
			(footprints allowed)
		)
		(placement
			(enabled no)
			(sheetname "")
		)
		(fill yes
			(thermal_gap 0.5)
			(thermal_bridge_width 0.5)
			(island_removal_mode 0)
		)
		(polygon
			(pts
				(arc
					(start 123.7488 -82.120486)
					(mid 124.095256 -81.75117)
					(end 123.72594 -81.404714)
				)
				(xy 123.72594 -81.402174) (xy 122.924824 -81.427574) (xy 122.92457 -81.427828)
				(arc
					(start 122.92457 -81.430114)
					(mid 122.578114 -81.79943)
					(end 122.94743 -82.145886)
				)
				(xy 122.94743 -82.148426) (xy 123.7488 -82.123026) (xy 123.7488 -82.12074)
			)
		)
	)
	(zone
		(layers "In1.Cu" "In3.Cu" "In4.Cu" "In6.Cu")
		(hatch none 0.5)
		(connect_pads
			(clearance 0)
		)
		(min_thickness 0.25)
		(keepout
			(tracks not_allowed)
			(vias allowed)
			(pads allowed)
			(copperpour not_allowed)
			(footprints allowed)
		)
		(placement
			(enabled no)
			(sheetname "")
		)
		(fill yes
			(thermal_gap 0.5)
			(thermal_bridge_width 0.5)
			(island_removal_mode 0)
		)
		(polygon
			(pts
				(arc
					(start 11.147044 -98.109786)
					(mid 10.762742 -98.492564)
					(end 11.14552 -98.876866)
				)
				(arc
					(start 12.059666 -98.878644)
					(mid 12.444222 -98.495993)
					(end 12.061444 -98.111564)
				)
			)
		)
	)
	(zone
		(layers "In1.Cu" "In3.Cu" "In4.Cu" "In6.Cu")
		(hatch none 0.5)
		(connect_pads
			(clearance 0)
		)
		(min_thickness 0.25)
		(keepout
			(tracks not_allowed)
			(vias allowed)
			(pads allowed)
			(copperpour not_allowed)
			(footprints allowed)
		)
		(placement
			(enabled no)
			(sheetname "")
		)
		(fill yes
			(thermal_gap 0.5)
			(thermal_bridge_width 0.5)
			(island_removal_mode 0)
		)
		(polygon
			(pts
				(arc
					(start 112.207802 -102.850188)
					(mid 111.849662 -102.492048)
					(end 111.491522 -102.850188)
				)
				(arc
					(start 111.491522 -103.849932)
					(mid 111.849535 -104.208326)
					(end 112.207802 -103.850186)
				)
			)
		)
	)
	(zone
		(layers "In1.Cu" "In3.Cu" "In4.Cu" "In6.Cu")
		(hatch none 0.5)
		(connect_pads
			(clearance 0)
		)
		(min_thickness 0.25)
		(keepout
			(tracks not_allowed)
			(vias allowed)
			(pads allowed)
			(copperpour not_allowed)
			(footprints allowed)
		)
		(placement
			(enabled no)
			(sheetname "")
		)
		(fill yes
			(thermal_gap 0.5)
			(thermal_bridge_width 0.5)
			(island_removal_mode 0)
		)
		(polygon
			(pts
				(arc
					(start 96.30664 -35.406838)
					(mid 95.947738 -35.04946)
					(end 95.59036 -35.408362)
				)
				(arc
					(start 95.592138 -36.200588)
					(mid 95.950913 -36.55822)
					(end 96.308418 -36.199318)
				)
				(xy 96.30664 -35.4076)
			)
		)
	)
	(zone
		(layers "In1.Cu" "In3.Cu" "In4.Cu" "In6.Cu")
		(hatch none 0.5)
		(connect_pads
			(clearance 0)
		)
		(min_thickness 0.25)
		(keepout
			(tracks not_allowed)
			(vias allowed)
			(pads allowed)
			(copperpour not_allowed)
			(footprints allowed)
		)
		(placement
			(enabled no)
			(sheetname "")
		)
		(fill yes
			(thermal_gap 0.5)
			(thermal_bridge_width 0.5)
			(island_removal_mode 0)
		)
		(polygon
			(pts
				(arc
					(start 93.90761 -35.406838)
					(mid 93.548454 -35.049714)
					(end 93.19133 -35.40887)
				)
				(arc
					(start 93.193616 -36.197032)
					(mid 93.552645 -36.55441)
					(end 93.909896 -36.195254)
				)
				(xy 93.90761 -35.407854)
			)
		)
	)
	(zone
		(layers "In1.Cu" "In3.Cu" "In4.Cu" "In6.Cu")
		(hatch none 0.5)
		(connect_pads
			(clearance 0)
		)
		(min_thickness 0.25)
		(keepout
			(tracks not_allowed)
			(vias allowed)
			(pads allowed)
			(copperpour not_allowed)
			(footprints allowed)
		)
		(placement
			(enabled no)
			(sheetname "")
		)
		(fill yes
			(thermal_gap 0.5)
			(thermal_bridge_width 0.5)
			(island_removal_mode 0)
		)
		(polygon
			(pts
				(arc
					(start 122.925332 -80.56626)
					(mid 122.566684 -80.923765)
					(end 122.924062 -81.28254)
				)
				(xy 123.831858 -81.308956)
				(arc
					(start 123.85294 -81.309464)
					(mid 124.236988 -80.926432)
					(end 123.853956 -80.542384)
				)
				(xy 123.833128 -80.542892)
			)
		)
	)
	(zone
		(layers "In1.Cu" "In3.Cu" "In4.Cu" "In6.Cu")
		(hatch none 0.5)
		(connect_pads
			(clearance 0)
		)
		(min_thickness 0.25)
		(keepout
			(tracks not_allowed)
			(vias allowed)
			(pads allowed)
			(copperpour not_allowed)
			(footprints allowed)
		)
		(placement
			(enabled no)
			(sheetname "")
		)
		(fill yes
			(thermal_gap 0.5)
			(thermal_bridge_width 0.5)
			(island_removal_mode 0)
		)
		(polygon
			(pts
				(arc
					(start 203.947522 -76.64196)
					(mid 203.563728 -77.025373)
					(end 203.947268 -77.40904)
				)
				(arc
					(start 204.929232 -77.40904)
					(mid 205.312772 -77.0255)
					(end 204.929232 -76.64196)
				)
			)
		)
	)
	(zone
		(layers "In1.Cu" "In3.Cu" "In4.Cu" "In6.Cu")
		(hatch none 0.5)
		(connect_pads
			(clearance 0)
		)
		(min_thickness 0.25)
		(keepout
			(tracks not_allowed)
			(vias allowed)
			(pads allowed)
			(copperpour not_allowed)
			(footprints allowed)
		)
		(placement
			(enabled no)
			(sheetname "")
		)
		(fill yes
			(thermal_gap 0.5)
			(thermal_bridge_width 0.5)
			(island_removal_mode 0)
		)
		(polygon
			(pts
				(xy 318.794384 -79.46136) (xy 318.819784 -78.44536)
				(arc
					(start 318.817498 -78.44536)
					(mid 318.418718 -78.02626)
					(end 317.999618 -78.42504)
				)
				(xy 317.997332 -78.42504) (xy 317.971932 -79.440786) (xy 317.972186 -79.44104)
				(arc
					(start 317.974218 -79.44104)
					(mid 318.372998 -79.86014)
					(end 318.792098 -79.46136)
				)
			)
		)
	)
	(zone
		(layers "In1.Cu" "In3.Cu" "In4.Cu" "In6.Cu")
		(hatch none 0.5)
		(connect_pads
			(clearance 0)
		)
		(min_thickness 0.25)
		(keepout
			(tracks not_allowed)
			(vias allowed)
			(pads allowed)
			(copperpour not_allowed)
			(footprints allowed)
		)
		(placement
			(enabled no)
			(sheetname "")
		)
		(fill yes
			(thermal_gap 0.5)
			(thermal_bridge_width 0.5)
			(island_removal_mode 0)
		)
		(polygon
			(pts
				(arc
					(start 123.84532 -85.151214)
					(mid 124.182625 -84.773135)
					(end 123.804426 -84.43595)
				)
				(arc
					(start 122.829574 -84.492084)
					(mid 122.492516 -84.87029)
					(end 122.870722 -85.207348)
				)
			)
		)
	)
	(zone
		(layers "In1.Cu" "In3.Cu" "In4.Cu" "In6.Cu")
		(hatch none 0.5)
		(connect_pads
			(clearance 0)
		)
		(min_thickness 0.25)
		(keepout
			(tracks not_allowed)
			(vias allowed)
			(pads allowed)
			(copperpour not_allowed)
			(footprints allowed)
		)
		(placement
			(enabled no)
			(sheetname "")
		)
		(fill yes
			(thermal_gap 0.5)
			(thermal_bridge_width 0.5)
			(island_removal_mode 0)
		)
		(polygon
			(pts
				(arc
					(start 36.359084 -90.479626)
					(mid 36.742878 -90.096213)
					(end 36.359338 -89.712546)
				)
				(arc
					(start 35.382454 -89.712546)
					(mid 34.998914 -90.096086)
					(end 35.382454 -90.479626)
				)
			)
		)
	)
	(zone
		(layers "In1.Cu" "In3.Cu" "In4.Cu" "In6.Cu")
		(hatch none 0.5)
		(connect_pads
			(clearance 0)
		)
		(min_thickness 0.25)
		(keepout
			(tracks not_allowed)
			(vias allowed)
			(pads allowed)
			(copperpour not_allowed)
			(footprints allowed)
		)
		(placement
			(enabled no)
			(sheetname "")
		)
		(fill yes
			(thermal_gap 0.5)
			(thermal_bridge_width 0.5)
			(island_removal_mode 0)
		)
		(polygon
			(pts
				(xy 16.897096 -98.134678) (xy 15.95755 -98.109278) (xy 15.957296 -98.109532)
				(arc
					(start 15.957296 -98.111818)
					(mid 15.563596 -98.48469)
					(end 15.936468 -98.87839)
				)
				(xy 15.936468 -98.88093) (xy 16.876268 -98.90633)
				(arc
					(start 16.876268 -98.90379)
					(mid 17.269968 -98.530918)
					(end 16.897096 -98.137218)
				)
			)
		)
	)
	(zone
		(layers "In1.Cu" "In3.Cu" "In4.Cu" "In6.Cu")
		(hatch none 0.5)
		(connect_pads
			(clearance 0)
		)
		(min_thickness 0.25)
		(keepout
			(tracks not_allowed)
			(vias allowed)
			(pads allowed)
			(copperpour not_allowed)
			(footprints allowed)
		)
		(placement
			(enabled no)
			(sheetname "")
		)
		(fill yes
			(thermal_gap 0.5)
			(thermal_bridge_width 0.5)
			(island_removal_mode 0)
		)
		(polygon
			(pts
				(arc
					(start 18.258536 -98.162364)
					(mid 17.874742 -98.545777)
					(end 18.258282 -98.929444)
				)
				(arc
					(start 19.325082 -98.929444)
					(mid 19.708622 -98.545904)
					(end 19.325082 -98.162364)
				)
			)
		)
	)
	(zone
		(layers "In1.Cu" "In3.Cu" "In4.Cu" "In6.Cu")
		(hatch none 0.5)
		(connect_pads
			(clearance 0)
		)
		(min_thickness 0.25)
		(keepout
			(tracks not_allowed)
			(vias allowed)
			(pads allowed)
			(copperpour not_allowed)
			(footprints allowed)
		)
		(placement
			(enabled no)
			(sheetname "")
		)
		(fill yes
			(thermal_gap 0.5)
			(thermal_bridge_width 0.5)
			(island_removal_mode 0)
		)
		(polygon
			(pts
				(arc
					(start 304.719736 -87.908892)
					(mid 305.10353 -87.525479)
					(end 304.71999 -87.141812)
				)
				(arc
					(start 303.80305 -87.141812)
					(mid 303.41951 -87.525352)
					(end 303.80305 -87.908892)
				)
			)
		)
	)
	(zone
		(layers "In1.Cu" "In3.Cu" "In4.Cu" "In6.Cu")
		(hatch none 0.5)
		(connect_pads
			(clearance 0)
		)
		(min_thickness 0.25)
		(keepout
			(tracks not_allowed)
			(vias allowed)
			(pads allowed)
			(copperpour not_allowed)
			(footprints allowed)
		)
		(placement
			(enabled no)
			(sheetname "")
		)
		(fill yes
			(thermal_gap 0.5)
			(thermal_bridge_width 0.5)
			(island_removal_mode 0)
		)
		(polygon
			(pts
				(arc
					(start 94.352618 -34.958274)
					(mid 94.707964 -34.59734)
					(end 94.34703 -34.241994)
				)
				(arc
					(start 93.544644 -34.248344)
					(mid 93.189297 -34.609151)
					(end 93.549978 -34.964624)
				)
			)
		)
	)
	(zone
		(layers "In1.Cu" "In3.Cu" "In4.Cu" "In6.Cu")
		(hatch none 0.5)
		(connect_pads
			(clearance 0)
		)
		(min_thickness 0.25)
		(keepout
			(tracks not_allowed)
			(vias allowed)
			(pads allowed)
			(copperpour not_allowed)
			(footprints allowed)
		)
		(placement
			(enabled no)
			(sheetname "")
		)
		(fill yes
			(thermal_gap 0.5)
			(thermal_bridge_width 0.5)
			(island_removal_mode 0)
		)
		(polygon
			(pts
				(arc
					(start 98.700082 -35.397694)
					(mid 98.338132 -35.043364)
					(end 97.983802 -35.405314)
				)
				(arc
					(start 97.992184 -36.203636)
					(mid 98.354007 -36.558219)
					(end 98.708464 -36.19627)
				)
			)
		)
	)
	(zone
		(layers "In1.Cu" "In3.Cu" "In4.Cu" "In6.Cu")
		(hatch none 0.5)
		(connect_pads
			(clearance 0)
		)
		(min_thickness 0.25)
		(keepout
			(tracks not_allowed)
			(vias allowed)
			(pads allowed)
			(copperpour not_allowed)
			(footprints allowed)
		)
		(placement
			(enabled no)
			(sheetname "")
		)
		(fill yes
			(thermal_gap 0.5)
			(thermal_bridge_width 0.5)
			(island_removal_mode 0)
		)
		(polygon
			(pts
				(arc
					(start 320.595498 -75.209908)
					(mid 320.186558 -74.800968)
					(end 319.777618 -75.209908)
				)
				(arc
					(start 319.777618 -76.191618)
					(mid 320.186431 -76.600812)
					(end 320.595498 -76.191872)
				)
			)
		)
	)
	(zone
		(layers "In1.Cu" "In3.Cu" "In4.Cu" "In6.Cu")
		(hatch none 0.5)
		(connect_pads
			(clearance 0)
		)
		(min_thickness 0.25)
		(keepout
			(tracks not_allowed)
			(vias allowed)
			(pads allowed)
			(copperpour not_allowed)
			(footprints allowed)
		)
		(placement
			(enabled no)
			(sheetname "")
		)
		(fill yes
			(thermal_gap 0.5)
			(thermal_bridge_width 0.5)
			(island_removal_mode 0)
		)
		(polygon
			(pts
				(arc
					(start 101.115622 -35.40125)
					(mid 100.760784 -35.039808)
					(end 100.399342 -35.394646)
				)
				(arc
					(start 100.39223 -36.196524)
					(mid 100.746941 -36.558221)
					(end 101.10851 -36.203382)
				)
			)
		)
	)
	(zone
		(layers "In1.Cu" "In3.Cu" "In4.Cu" "In6.Cu")
		(hatch none 0.5)
		(connect_pads
			(clearance 0)
		)
		(min_thickness 0.25)
		(keepout
			(tracks not_allowed)
			(vias allowed)
			(pads allowed)
			(copperpour not_allowed)
			(footprints allowed)
		)
		(placement
			(enabled no)
			(sheetname "")
		)
		(fill yes
			(thermal_gap 0.5)
			(thermal_bridge_width 0.5)
			(island_removal_mode 0)
		)
		(polygon
			(pts
				(arc
					(start 39.407084 -90.479626)
					(mid 39.790878 -90.096213)
					(end 39.407338 -89.712546)
				)
				(arc
					(start 38.430454 -89.712546)
					(mid 38.046914 -90.096086)
					(end 38.430454 -90.479626)
				)
			)
		)
	)
	(zone
		(layers "In1.Cu" "In3.Cu" "In4.Cu" "In6.Cu")
		(hatch none 0.5)
		(connect_pads
			(clearance 0)
		)
		(min_thickness 0.25)
		(keepout
			(tracks not_allowed)
			(vias allowed)
			(pads allowed)
			(copperpour not_allowed)
			(footprints allowed)
		)
		(placement
			(enabled no)
			(sheetname "")
		)
		(fill yes
			(thermal_gap 0.5)
			(thermal_bridge_width 0.5)
			(island_removal_mode 0)
		)
		(polygon
			(pts
				(arc
					(start 297.973496 -82.607404)
					(mid 298.35729 -82.223991)
					(end 297.97375 -81.840324)
				)
				(arc
					(start 297.05681 -81.840324)
					(mid 296.67327 -82.223864)
					(end 297.05681 -82.607404)
				)
			)
		)
	)
	(zone
		(layers "In1.Cu" "In3.Cu" "In4.Cu" "In6.Cu")
		(hatch none 0.5)
		(connect_pads
			(clearance 0)
		)
		(min_thickness 0.25)
		(keepout
			(tracks not_allowed)
			(vias allowed)
			(pads allowed)
			(copperpour not_allowed)
			(footprints allowed)
		)
		(placement
			(enabled no)
			(sheetname "")
		)
		(fill yes
			(thermal_gap 0.5)
			(thermal_bridge_width 0.5)
			(island_removal_mode 0)
		)
		(polygon
			(pts
				(arc
					(start 115.222782 -102.840536)
					(mid 114.864769 -102.482142)
					(end 114.506502 -102.840282)
				)
				(arc
					(start 114.506502 -103.830882)
					(mid 114.864642 -104.189022)
					(end 115.222782 -103.830882)
				)
			)
		)
	)
	(zone
		(layers "In1.Cu" "In3.Cu" "In4.Cu" "In6.Cu")
		(hatch none 0.5)
		(connect_pads
			(clearance 0)
		)
		(min_thickness 0.25)
		(keepout
			(tracks not_allowed)
			(vias allowed)
			(pads allowed)
			(copperpour not_allowed)
			(footprints allowed)
		)
		(placement
			(enabled no)
			(sheetname "")
		)
		(fill yes
			(thermal_gap 0.5)
			(thermal_bridge_width 0.5)
			(island_removal_mode 0)
		)
		(polygon
			(pts
				(arc
					(start 123.208288 -91.849702)
					(mid 122.850021 -91.491562)
					(end 122.492008 -91.849956)
				)
				(arc
					(start 122.492262 -92.827348)
					(mid 122.850402 -93.185742)
					(end 123.208542 -92.827348)
				)
				(xy 123.208288 -91.849956)
			)
		)
	)
	(zone
		(layers "In1.Cu" "In3.Cu" "In4.Cu" "In6.Cu")
		(hatch none 0.5)
		(connect_pads
			(clearance 0)
		)
		(min_thickness 0.25)
		(keepout
			(tracks not_allowed)
			(vias allowed)
			(pads allowed)
			(copperpour not_allowed)
			(footprints allowed)
		)
		(placement
			(enabled no)
			(sheetname "")
		)
		(fill yes
			(thermal_gap 0.5)
			(thermal_bridge_width 0.5)
			(island_removal_mode 0)
		)
		(polygon
			(pts
				(arc
					(start 298.139104 -74.07529)
					(mid 298.522898 -73.691877)
					(end 298.139358 -73.30821)
				)
				(arc
					(start 297.123358 -73.30821)
					(mid 296.739818 -73.69175)
					(end 297.123358 -74.07529)
				)
			)
		)
	)
	(zone
		(layers "In1.Cu" "In3.Cu" "In4.Cu" "In6.Cu")
		(hatch none 0.5)
		(connect_pads
			(clearance 0)
		)
		(min_thickness 0.25)
		(keepout
			(tracks not_allowed)
			(vias allowed)
			(pads allowed)
			(copperpour not_allowed)
			(footprints allowed)
		)
		(placement
			(enabled no)
			(sheetname "")
		)
		(fill yes
			(thermal_gap 0.5)
			(thermal_bridge_width 0.5)
			(island_removal_mode 0)
		)
		(polygon
			(pts
				(arc
					(start 93.914976 -42.600118)
					(mid 93.55963 -42.239184)
					(end 93.198696 -42.59453)
				)
				(arc
					(start 93.192346 -43.387772)
					(mid 93.547565 -43.748961)
					(end 93.908626 -43.393614)
				)
			)
		)
	)
	(zone
		(layers "In1.Cu" "In3.Cu" "In4.Cu" "In6.Cu")
		(hatch none 0.5)
		(connect_pads
			(clearance 0)
		)
		(min_thickness 0.25)
		(keepout
			(tracks not_allowed)
			(vias allowed)
			(pads allowed)
			(copperpour not_allowed)
			(footprints allowed)
		)
		(placement
			(enabled no)
			(sheetname "")
		)
		(fill yes
			(thermal_gap 0.5)
			(thermal_bridge_width 0.5)
			(island_removal_mode 0)
		)
		(polygon
			(pts
				(arc
					(start 318.080898 -72.009)
					(mid 317.671958 -71.60006)
					(end 317.263018 -72.009)
				)
				(arc
					(start 317.263018 -73.024746)
					(mid 317.671831 -73.43394)
					(end 318.080898 -73.025)
				)
			)
		)
	)
	(zone
		(layers "In1.Cu" "In3.Cu" "In4.Cu" "In6.Cu")
		(hatch none 0.5)
		(connect_pads
			(clearance 0)
		)
		(min_thickness 0.25)
		(keepout
			(tracks not_allowed)
			(vias allowed)
			(pads allowed)
			(copperpour not_allowed)
			(footprints allowed)
		)
		(placement
			(enabled no)
			(sheetname "")
		)
		(fill yes
			(thermal_gap 0.5)
			(thermal_bridge_width 0.5)
			(island_removal_mode 0)
		)
		(polygon
			(pts
				(arc
					(start 93.914722 -37.80282)
					(mid 93.557217 -37.444172)
					(end 93.198442 -37.80155)
				)
				(arc
					(start 93.197426 -38.596316)
					(mid 93.555058 -38.954964)
					(end 93.913706 -38.597332)
				)
				(xy 93.913706 -38.596824)
			)
		)
	)
	(zone
		(layers "In1.Cu" "In3.Cu" "In4.Cu" "In6.Cu")
		(hatch none 0.5)
		(connect_pads
			(clearance 0)
		)
		(min_thickness 0.25)
		(keepout
			(tracks not_allowed)
			(vias allowed)
			(pads allowed)
			(copperpour not_allowed)
			(footprints allowed)
		)
		(placement
			(enabled no)
			(sheetname "")
		)
		(fill yes
			(thermal_gap 0.5)
			(thermal_bridge_width 0.5)
			(island_removal_mode 0)
		)
		(polygon
			(pts
				(arc
					(start 49.373536 -86.769448)
					(mid 48.990123 -86.385654)
					(end 48.606456 -86.769194)
				)
				(arc
					(start 48.606456 -87.746078)
					(mid 48.989996 -88.129618)
					(end 49.373536 -87.746078)
				)
			)
		)
	)
	(zone
		(layers "In1.Cu" "In3.Cu" "In4.Cu" "In6.Cu")
		(hatch none 0.5)
		(connect_pads
			(clearance 0)
		)
		(min_thickness 0.25)
		(keepout
			(tracks not_allowed)
			(vias allowed)
			(pads allowed)
			(copperpour not_allowed)
			(footprints allowed)
		)
		(placement
			(enabled no)
			(sheetname "")
		)
		(fill yes
			(thermal_gap 0.5)
			(thermal_bridge_width 0.5)
			(island_removal_mode 0)
		)
		(polygon
			(pts
				(arc
					(start 103.508302 -35.400234)
					(mid 103.150162 -35.042094)
					(end 102.792022 -35.400234)
				)
				(arc
					(start 102.792022 -36.199826)
					(mid 103.150035 -36.55822)
					(end 103.508302 -36.20008)
				)
			)
		)
	)
	(zone
		(layers "In1.Cu" "In3.Cu" "In4.Cu" "In6.Cu")
		(hatch none 0.5)
		(connect_pads
			(clearance 0)
		)
		(min_thickness 0.25)
		(keepout
			(tracks not_allowed)
			(vias allowed)
			(pads allowed)
			(copperpour not_allowed)
			(footprints allowed)
		)
		(placement
			(enabled no)
			(sheetname "")
		)
		(fill yes
			(thermal_gap 0.5)
			(thermal_bridge_width 0.5)
			(island_removal_mode 0)
		)
		(polygon
			(pts
				(arc
					(start 351.11309 -151.97201)
					(mid 350.75495 -151.61387)
					(end 350.39681 -151.97201)
				)
				(arc
					(start 350.39681 -152.916636)
					(mid 350.754823 -153.27503)
					(end 351.11309 -152.91689)
				)
			)
		)
	)
	(zone
		(layers "In1.Cu" "In3.Cu" "In4.Cu" "In6.Cu")
		(hatch none 0.5)
		(connect_pads
			(clearance 0)
		)
		(min_thickness 0.25)
		(keepout
			(tracks not_allowed)
			(vias allowed)
			(pads allowed)
			(copperpour not_allowed)
			(footprints allowed)
		)
		(placement
			(enabled no)
			(sheetname "")
		)
		(fill yes
			(thermal_gap 0.5)
			(thermal_bridge_width 0.5)
			(island_removal_mode 0)
		)
		(polygon
			(pts
				(arc
					(start 83.46694 -34.61893)
					(mid 83.083527 -34.235136)
					(end 82.69986 -34.618676)
				)
				(arc
					(start 82.69986 -35.523678)
					(mid 83.0834 -35.907218)
					(end 83.46694 -35.523678)
				)
			)
		)
	)
	(zone
		(layers "In1.Cu" "In3.Cu" "In4.Cu" "In6.Cu")
		(hatch none 0.5)
		(connect_pads
			(clearance 0)
		)
		(min_thickness 0.25)
		(keepout
			(tracks not_allowed)
			(vias allowed)
			(pads allowed)
			(copperpour not_allowed)
			(footprints allowed)
		)
		(placement
			(enabled no)
			(sheetname "")
		)
		(fill yes
			(thermal_gap 0.5)
			(thermal_bridge_width 0.5)
			(island_removal_mode 0)
		)
		(polygon
			(pts
				(arc
					(start 135.880094 -81.15046)
					(mid 135.4963 -81.533873)
					(end 135.87984 -81.91754)
				)
				(arc
					(start 136.807956 -81.91754)
					(mid 137.191496 -81.534)
					(end 136.807956 -81.15046)
				)
			)
		)
	)
	(zone
		(layers "In1.Cu" "In3.Cu" "In4.Cu" "In6.Cu")
		(hatch none 0.5)
		(connect_pads
			(clearance 0)
		)
		(min_thickness 0.25)
		(keepout
			(tracks not_allowed)
			(vias allowed)
			(pads allowed)
			(copperpour not_allowed)
			(footprints allowed)
		)
		(placement
			(enabled no)
			(sheetname "")
		)
		(fill yes
			(thermal_gap 0.5)
			(thermal_bridge_width 0.5)
			(island_removal_mode 0)
		)
		(polygon
			(pts
				(arc
					(start 122.850402 -90.491564)
					(mid 122.492008 -90.849577)
					(end 122.850148 -91.207844)
				)
				(arc
					(start 123.850146 -91.207844)
					(mid 124.208286 -90.849704)
					(end 123.850146 -90.491564)
				)
			)
		)
	)
	(zone
		(layers "In1.Cu" "In3.Cu" "In4.Cu" "In6.Cu")
		(hatch none 0.5)
		(connect_pads
			(clearance 0)
		)
		(min_thickness 0.25)
		(keepout
			(tracks not_allowed)
			(vias allowed)
			(pads allowed)
			(copperpour not_allowed)
			(footprints allowed)
		)
		(placement
			(enabled no)
			(sheetname "")
		)
		(fill yes
			(thermal_gap 0.5)
			(thermal_bridge_width 0.5)
			(island_removal_mode 0)
		)
		(polygon
			(pts
				(arc
					(start 94.360492 -37.357558)
					(mid 94.717362 -36.998021)
					(end 94.357698 -36.641278)
				)
				(arc
					(start 93.550232 -36.64458)
					(mid 93.193616 -37.004244)
					(end 93.55328 -37.36086)
				)
			)
		)
	)
	(zone
		(layers "In1.Cu" "In3.Cu" "In4.Cu" "In6.Cu")
		(hatch none 0.5)
		(connect_pads
			(clearance 0)
		)
		(min_thickness 0.25)
		(keepout
			(tracks not_allowed)
			(vias allowed)
			(pads allowed)
			(copperpour not_allowed)
			(footprints allowed)
		)
		(placement
			(enabled no)
			(sheetname "")
		)
		(fill yes
			(thermal_gap 0.5)
			(thermal_bridge_width 0.5)
			(island_removal_mode 0)
		)
		(polygon
			(pts
				(arc
					(start 113.2078 -102.850442)
					(mid 112.849787 -102.492048)
					(end 112.49152 -102.850188)
				)
				(arc
					(start 112.49152 -103.850186)
					(mid 112.84966 -104.208326)
					(end 113.2078 -103.850186)
				)
			)
		)
	)
	(zone
		(layers "In1.Cu" "In3.Cu" "In4.Cu" "In6.Cu")
		(hatch none 0.5)
		(connect_pads
			(clearance 0)
		)
		(min_thickness 0.25)
		(keepout
			(tracks not_allowed)
			(vias allowed)
			(pads allowed)
			(copperpour not_allowed)
			(footprints allowed)
		)
		(placement
			(enabled no)
			(sheetname "")
		)
		(fill yes
			(thermal_gap 0.5)
			(thermal_bridge_width 0.5)
			(island_removal_mode 0)
		)
		(polygon
			(pts
				(arc
					(start 134.581646 -82.29346)
					(mid 134.197852 -82.676873)
					(end 134.581392 -83.06054)
				)
				(arc
					(start 135.509508 -83.06054)
					(mid 135.893048 -82.677)
					(end 135.509508 -82.29346)
				)
			)
		)
	)
	(zone
		(layers "In1.Cu" "In3.Cu" "In4.Cu" "In6.Cu")
		(hatch none 0.5)
		(connect_pads
			(clearance 0)
		)
		(min_thickness 0.25)
		(keepout
			(tracks not_allowed)
			(vias allowed)
			(pads allowed)
			(copperpour not_allowed)
			(footprints allowed)
		)
		(placement
			(enabled no)
			(sheetname "")
		)
		(fill yes
			(thermal_gap 0.5)
			(thermal_bridge_width 0.5)
			(island_removal_mode 0)
		)
		(polygon
			(pts
				(arc
					(start 49.373536 -83.937094)
					(mid 48.989996 -83.553554)
					(end 48.606456 -83.937094)
				)
				(arc
					(start 48.606456 -84.913724)
					(mid 48.989869 -85.297518)
					(end 49.373536 -84.913978)
				)
			)
		)
	)
	(zone
		(layers "In1.Cu" "In3.Cu" "In4.Cu" "In6.Cu")
		(hatch none 0.5)
		(connect_pads
			(clearance 0)
		)
		(min_thickness 0.25)
		(keepout
			(tracks not_allowed)
			(vias allowed)
			(pads allowed)
			(copperpour not_allowed)
			(footprints allowed)
		)
		(placement
			(enabled no)
			(sheetname "")
		)
		(fill yes
			(thermal_gap 0.5)
			(thermal_bridge_width 0.5)
			(island_removal_mode 0)
		)
		(polygon
			(pts
				(arc
					(start 132.59054 -88.376252)
					(mid 132.207127 -87.992458)
					(end 131.82346 -88.375998)
				)
				(arc
					(start 131.82346 -89.281)
					(mid 132.207 -89.66454)
					(end 132.59054 -89.281)
				)
			)
		)
	)
	(zone
		(layers "In1.Cu" "In3.Cu" "In4.Cu" "In6.Cu")
		(hatch none 0.5)
		(connect_pads
			(clearance 0)
		)
		(min_thickness 0.25)
		(keepout
			(tracks not_allowed)
			(vias allowed)
			(pads allowed)
			(copperpour not_allowed)
			(footprints allowed)
		)
		(placement
			(enabled no)
			(sheetname "")
		)
		(fill yes
			(thermal_gap 0.5)
			(thermal_bridge_width 0.5)
			(island_removal_mode 0)
		)
		(polygon
			(pts
				(arc
					(start 296.29354 -77.35951)
					(mid 295.91 -76.97597)
					(end 295.52646 -77.35951)
				)
				(arc
					(start 295.52646 -78.276196)
					(mid 295.909873 -78.65999)
					(end 296.29354 -78.27645)
				)
			)
		)
	)
	(zone
		(layers "In1.Cu" "In3.Cu" "In4.Cu" "In6.Cu")
		(hatch none 0.5)
		(connect_pads
			(clearance 0)
		)
		(min_thickness 0.25)
		(keepout
			(tracks not_allowed)
			(vias allowed)
			(pads allowed)
			(copperpour not_allowed)
			(footprints allowed)
		)
		(placement
			(enabled no)
			(sheetname "")
		)
		(fill yes
			(thermal_gap 0.5)
			(thermal_bridge_width 0.5)
			(island_removal_mode 0)
		)
		(polygon
			(pts
				(arc
					(start 351.824036 -147.98167)
					(mid 352.18243 -147.623657)
					(end 351.82429 -147.26539)
				)
				(arc
					(start 350.87941 -147.26539)
					(mid 350.52127 -147.62353)
					(end 350.87941 -147.98167)
				)
			)
		)
	)
	(zone
		(layers "In1.Cu" "In3.Cu" "In4.Cu" "In6.Cu")
		(hatch none 0.5)
		(connect_pads
			(clearance 0)
		)
		(min_thickness 0.25)
		(keepout
			(tracks not_allowed)
			(vias allowed)
			(pads allowed)
			(copperpour not_allowed)
			(footprints allowed)
		)
		(placement
			(enabled no)
			(sheetname "")
		)
		(fill yes
			(thermal_gap 0.5)
			(thermal_bridge_width 0.5)
			(island_removal_mode 0)
		)
		(polygon
			(pts
				(arc
					(start 167.946832 -76.64196)
					(mid 167.563038 -77.025373)
					(end 167.946578 -77.40904)
				)
				(arc
					(start 168.928542 -77.40904)
					(mid 169.312082 -77.0255)
					(end 168.928542 -76.64196)
				)
			)
		)
	)
	(zone
		(layers "In1.Cu" "In3.Cu" "In4.Cu" "In6.Cu")
		(hatch none 0.5)
		(connect_pads
			(clearance 0)
		)
		(min_thickness 0.25)
		(keepout
			(tracks not_allowed)
			(vias allowed)
			(pads allowed)
			(copperpour not_allowed)
			(footprints allowed)
		)
		(placement
			(enabled no)
			(sheetname "")
		)
		(fill yes
			(thermal_gap 0.5)
			(thermal_bridge_width 0.5)
			(island_removal_mode 0)
		)
		(polygon
			(pts
				(arc
					(start 116.238782 -102.840536)
					(mid 115.880769 -102.482142)
					(end 115.522502 -102.840282)
				)
				(arc
					(start 115.522502 -103.830882)
					(mid 115.880642 -104.189022)
					(end 116.238782 -103.830882)
				)
			)
		)
	)
	(zone
		(layers "In1.Cu" "In3.Cu" "In4.Cu" "In6.Cu")
		(hatch none 0.5)
		(connect_pads
			(clearance 0)
		)
		(min_thickness 0.25)
		(keepout
			(tracks not_allowed)
			(vias allowed)
			(pads allowed)
			(copperpour not_allowed)
			(footprints allowed)
		)
		(placement
			(enabled no)
			(sheetname "")
		)
		(fill yes
			(thermal_gap 0.5)
			(thermal_bridge_width 0.5)
			(island_removal_mode 0)
		)
		(polygon
			(pts
				(arc
					(start 122.850402 -89.491566)
					(mid 122.492008 -89.849579)
					(end 122.850148 -90.207846)
				)
				(arc
					(start 123.850146 -90.207846)
					(mid 124.208286 -89.849706)
					(end 123.850146 -89.491566)
				)
			)
		)
	)
	(zone
		(layers "In1.Cu" "In3.Cu" "In4.Cu" "In6.Cu")
		(hatch none 0.5)
		(connect_pads
			(clearance 0)
		)
		(min_thickness 0.25)
		(keepout
			(tracks not_allowed)
			(vias allowed)
			(pads allowed)
			(copperpour not_allowed)
			(footprints allowed)
		)
		(placement
			(enabled no)
			(sheetname "")
		)
		(fill yes
			(thermal_gap 0.5)
			(thermal_bridge_width 0.5)
			(island_removal_mode 0)
		)
		(polygon
			(pts
				(arc
					(start 97.898966 -35.395916)
					(mid 97.536508 -35.042094)
					(end 97.182686 -35.404552)
				)
				(arc
					(start 97.192084 -36.204144)
					(mid 97.554415 -36.558219)
					(end 97.908364 -36.195762)
				)
			)
		)
	)
	(zone
		(layers "In1.Cu" "In3.Cu" "In4.Cu" "In6.Cu")
		(hatch none 0.5)
		(connect_pads
			(clearance 0)
		)
		(min_thickness 0.25)
		(keepout
			(tracks not_allowed)
			(vias allowed)
			(pads allowed)
			(copperpour not_allowed)
			(footprints allowed)
		)
		(placement
			(enabled no)
			(sheetname "")
		)
		(fill yes
			(thermal_gap 0.5)
			(thermal_bridge_width 0.5)
			(island_removal_mode 0)
		)
		(polygon
			(pts
				(arc
					(start 318.715898 -81.407)
					(mid 318.306958 -80.99806)
					(end 317.898018 -81.407)
				)
				(arc
					(start 317.898018 -82.422746)
					(mid 318.306831 -82.83194)
					(end 318.715898 -82.423)
				)
			)
		)
	)
	(zone
		(layers "In1.Cu" "In3.Cu" "In4.Cu" "In6.Cu")
		(hatch none 0.5)
		(connect_pads
			(clearance 0)
		)
		(min_thickness 0.25)
		(keepout
			(tracks not_allowed)
			(vias allowed)
			(pads allowed)
			(copperpour not_allowed)
			(footprints allowed)
		)
		(placement
			(enabled no)
			(sheetname "")
		)
		(fill yes
			(thermal_gap 0.5)
			(thermal_bridge_width 0.5)
			(island_removal_mode 0)
		)
		(polygon
			(pts
				(arc
					(start 114.207798 -102.850188)
					(mid 113.849658 -102.492048)
					(end 113.491518 -102.850188)
				)
				(arc
					(start 113.491518 -103.849932)
					(mid 113.849531 -104.208326)
					(end 114.207798 -103.850186)
				)
			)
		)
	)
	(zone
		(layers "In1.Cu" "In3.Cu" "In4.Cu" "In6.Cu")
		(hatch none 0.5)
		(connect_pads
			(clearance 0)
		)
		(min_thickness 0.25)
		(keepout
			(tracks not_allowed)
			(vias allowed)
			(pads allowed)
			(copperpour not_allowed)
			(footprints allowed)
		)
		(placement
			(enabled no)
			(sheetname "")
		)
		(fill yes
			(thermal_gap 0.5)
			(thermal_bridge_width 0.5)
			(island_removal_mode 0)
		)
		(polygon
			(pts
				(arc
					(start 277.848822 -32.51454)
					(mid 278.232616 -32.131127)
					(end 277.849076 -31.74746)
				)
				(arc
					(start 276.867112 -31.74746)
					(mid 276.483572 -32.131)
					(end 276.867112 -32.51454)
				)
			)
		)
	)
	(zone
		(layers "In1.Cu" "In3.Cu" "In4.Cu" "In6.Cu")
		(hatch none 0.5)
		(connect_pads
			(clearance 0)
		)
		(min_thickness 0.25)
		(keepout
			(tracks not_allowed)
			(vias allowed)
			(pads allowed)
			(copperpour not_allowed)
			(footprints allowed)
		)
		(placement
			(enabled no)
			(sheetname "")
		)
		(fill yes
			(thermal_gap 0.5)
			(thermal_bridge_width 0.5)
			(island_removal_mode 0)
		)
		(polygon
			(pts
				(arc
					(start 303.024032 -174.096426)
					(mid 303.38903 -173.69536)
					(end 302.987964 -173.330362)
				)
				(xy 302.987964 -173.327822) (xy 302.21428 -173.36389) (xy 302.214026 -173.364144)
				(arc
					(start 302.214026 -173.36643)
					(mid 301.849028 -173.767496)
					(end 302.250094 -174.132494)
				)
				(xy 302.250094 -174.135034) (xy 303.024032 -174.098966) (xy 303.024032 -174.096934)
			)
		)
	)
	(zone
		(layers "In1.Cu" "In3.Cu" "In4.Cu" "In6.Cu")
		(hatch none 0.5)
		(connect_pads
			(clearance 0)
		)
		(min_thickness 0.25)
		(keepout
			(tracks not_allowed)
			(vias allowed)
			(pads allowed)
			(copperpour not_allowed)
			(footprints allowed)
		)
		(placement
			(enabled no)
			(sheetname "")
		)
		(fill yes
			(thermal_gap 0.5)
			(thermal_bridge_width 0.5)
			(island_removal_mode 0)
		)
		(polygon
			(pts
				(arc
					(start 122.862848 -93.470222)
					(mid 122.497342 -93.820996)
					(end 122.848116 -94.186502)
				)
				(arc
					(start 123.843542 -94.206822)
					(mid 124.209305 -93.856175)
					(end 123.858528 -93.490542)
				)
			)
		)
	)
	(zone
		(layers "In1.Cu" "In3.Cu" "In4.Cu" "In6.Cu")
		(hatch none 0.5)
		(connect_pads
			(clearance 0)
		)
		(min_thickness 0.25)
		(keepout
			(tracks not_allowed)
			(vias allowed)
			(pads allowed)
			(copperpour not_allowed)
			(footprints allowed)
		)
		(placement
			(enabled no)
			(sheetname "")
		)
		(fill yes
			(thermal_gap 0.5)
			(thermal_bridge_width 0.5)
			(island_removal_mode 0)
		)
		(polygon
			(pts
				(arc
					(start 51.888136 -75.290426)
					(mid 52.27193 -74.907013)
					(end 51.88839 -74.523346)
				)
				(arc
					(start 50.911506 -74.523346)
					(mid 50.527966 -74.906886)
					(end 50.911506 -75.290426)
				)
			)
		)
	)
	(zone
		(layers "In1.Cu" "In3.Cu" "In4.Cu" "In6.Cu")
		(hatch none 0.5)
		(connect_pads
			(clearance 0)
		)
		(min_thickness 0.25)
		(keepout
			(tracks not_allowed)
			(vias allowed)
			(pads allowed)
			(copperpour not_allowed)
			(footprints allowed)
		)
		(placement
			(enabled no)
			(sheetname "")
		)
		(fill yes
			(thermal_gap 0.5)
			(thermal_bridge_width 0.5)
			(island_removal_mode 0)
		)
		(polygon
			(pts
				(arc
					(start 78.663038 -41.98874)
					(mid 79.046832 -41.605327)
					(end 78.663292 -41.22166)
				)
				(arc
					(start 77.686408 -41.22166)
					(mid 77.302868 -41.6052)
					(end 77.686408 -41.98874)
				)
			)
		)
	)
	(zone
		(layers "In1.Cu" "In3.Cu" "In4.Cu" "In6.Cu")
		(hatch none 0.5)
		(connect_pads
			(clearance 0)
		)
		(min_thickness 0.25)
		(keepout
			(tracks not_allowed)
			(vias allowed)
			(pads allowed)
			(copperpour not_allowed)
			(footprints allowed)
		)
		(placement
			(enabled no)
			(sheetname "")
		)
		(fill yes
			(thermal_gap 0.5)
			(thermal_bridge_width 0.5)
			(island_removal_mode 0)
		)
		(polygon
			(pts
				(arc
					(start 128.130808 -80.19034)
					(mid 128.514602 -79.806927)
					(end 128.131062 -79.42326)
				)
				(arc
					(start 127.154178 -79.42326)
					(mid 126.770638 -79.8068)
					(end 127.154178 -80.19034)
				)
			)
		)
	)
	(zone
		(layers "In1.Cu" "In3.Cu" "In4.Cu" "In6.Cu")
		(hatch none 0.5)
		(connect_pads
			(clearance 0)
		)
		(min_thickness 0.25)
		(keepout
			(tracks not_allowed)
			(vias allowed)
			(pads allowed)
			(copperpour not_allowed)
			(footprints allowed)
		)
		(placement
			(enabled no)
			(sheetname "")
		)
		(fill yes
			(thermal_gap 0.5)
			(thermal_bridge_width 0.5)
			(island_removal_mode 0)
		)
		(polygon
			(pts
				(arc
					(start 159.947102 -76.64196)
					(mid 159.563308 -77.025373)
					(end 159.946848 -77.40904)
				)
				(arc
					(start 160.928812 -77.40904)
					(mid 161.312352 -77.0255)
					(end 160.928812 -76.64196)
				)
			)
		)
	)
	(zone
		(layers "In1.Cu" "In3.Cu" "In4.Cu" "In6.Cu")
		(hatch none 0.5)
		(connect_pads
			(clearance 0)
		)
		(min_thickness 0.25)
		(keepout
			(tracks not_allowed)
			(vias allowed)
			(pads allowed)
			(copperpour not_allowed)
			(footprints allowed)
		)
		(placement
			(enabled no)
			(sheetname "")
		)
		(fill yes
			(thermal_gap 0.5)
			(thermal_bridge_width 0.5)
			(island_removal_mode 0)
		)
		(polygon
			(pts
				(arc
					(start 32.334708 -89.712546)
					(mid 31.950914 -90.095959)
					(end 32.334454 -90.479626)
				)
				(arc
					(start 33.311338 -90.479626)
					(mid 33.694878 -90.096086)
					(end 33.311338 -89.712546)
				)
			)
		)
	)
	(zone
		(layers "In1.Cu" "In3.Cu" "In4.Cu" "In6.Cu")
		(hatch none 0.5)
		(connect_pads
			(clearance 0)
		)
		(min_thickness 0.25)
		(keepout
			(tracks not_allowed)
			(vias allowed)
			(pads allowed)
			(copperpour not_allowed)
			(footprints allowed)
		)
		(placement
			(enabled no)
			(sheetname "")
		)
		(fill yes
			(thermal_gap 0.5)
			(thermal_bridge_width 0.5)
			(island_removal_mode 0)
		)
		(polygon
			(pts
				(arc
					(start 110.207806 -102.850188)
					(mid 109.849666 -102.492048)
					(end 109.491526 -102.850188)
				)
				(arc
					(start 109.491526 -103.849932)
					(mid 109.849539 -104.208326)
					(end 110.207806 -103.850186)
				)
			)
		)
	)
	(zone
		(layers "In1.Cu" "In3.Cu" "In4.Cu" "In6.Cu")
		(hatch none 0.5)
		(connect_pads
			(clearance 0)
		)
		(min_thickness 0.25)
		(keepout
			(tracks not_allowed)
			(vias allowed)
			(pads allowed)
			(copperpour not_allowed)
			(footprints allowed)
		)
		(placement
			(enabled no)
			(sheetname "")
		)
		(fill yes
			(thermal_gap 0.5)
			(thermal_bridge_width 0.5)
			(island_removal_mode 0)
		)
		(polygon
			(pts
				(arc
					(start 109.207808 -102.850188)
					(mid 108.849668 -102.492048)
					(end 108.491528 -102.850188)
				)
				(arc
					(start 108.491528 -103.849932)
					(mid 108.849541 -104.208326)
					(end 109.207808 -103.850186)
				)
			)
		)
	)
	(zone
		(layers "In1.Cu" "In3.Cu" "In4.Cu" "In6.Cu")
		(hatch none 0.5)
		(connect_pads
			(clearance 0)
		)
		(min_thickness 0.25)
		(keepout
			(tracks not_allowed)
			(vias allowed)
			(pads allowed)
			(copperpour not_allowed)
			(footprints allowed)
		)
		(placement
			(enabled no)
			(sheetname "")
		)
		(fill yes
			(thermal_gap 0.5)
			(thermal_bridge_width 0.5)
			(island_removal_mode 0)
		)
		(polygon
			(pts
				(arc
					(start 195.947792 -76.64196)
					(mid 195.563998 -77.025373)
					(end 195.947538 -77.40904)
				)
				(arc
					(start 196.929502 -77.40904)
					(mid 197.313042 -77.0255)
					(end 196.929502 -76.64196)
				)
			)
		)
	)
	(zone
		(layers "In1.Cu" "In3.Cu" "In4.Cu" "In6.Cu")
		(hatch none 0.5)
		(connect_pads
			(clearance 0)
		)
		(min_thickness 0.25)
		(keepout
			(tracks not_allowed)
			(vias allowed)
			(pads allowed)
			(copperpour not_allowed)
			(footprints allowed)
		)
		(placement
			(enabled no)
			(sheetname "")
		)
		(fill yes
			(thermal_gap 0.5)
			(thermal_bridge_width 0.5)
			(island_removal_mode 0)
		)
		(polygon
			(pts
				(arc
					(start 122.850148 -83.491578)
					(mid 122.492008 -83.849718)
					(end 122.850148 -84.207858)
				)
				(arc
					(start 123.849892 -84.207858)
					(mid 124.208286 -83.849845)
					(end 123.850146 -83.491578)
				)
			)
		)
	)
	(zone
		(layers "In1.Cu" "In3.Cu" "In4.Cu" "In6.Cu")
		(hatch none 0.5)
		(connect_pads
			(clearance 0)
		)
		(min_thickness 0.25)
		(keepout
			(tracks not_allowed)
			(vias allowed)
			(pads allowed)
			(copperpour not_allowed)
			(footprints allowed)
		)
		(placement
			(enabled no)
			(sheetname "")
		)
		(fill yes
			(thermal_gap 0.5)
			(thermal_bridge_width 0.5)
			(island_removal_mode 0)
		)
		(polygon
			(pts
				(arc
					(start 54.287928 -75.290426)
					(mid 54.671722 -74.907013)
					(end 54.288182 -74.523346)
				)
				(arc
					(start 53.311298 -74.523346)
					(mid 52.927758 -74.906886)
					(end 53.311298 -75.290426)
				)
			)
		)
	)
	(zone
		(layers "In1.Cu" "In3.Cu" "In4.Cu" "In6.Cu")
		(hatch none 0.5)
		(connect_pads
			(clearance 0)
		)
		(min_thickness 0.25)
		(keepout
			(tracks not_allowed)
			(vias allowed)
			(pads allowed)
			(copperpour not_allowed)
			(footprints allowed)
		)
		(placement
			(enabled no)
			(sheetname "")
		)
		(fill yes
			(thermal_gap 0.5)
			(thermal_bridge_width 0.5)
			(island_removal_mode 0)
		)
		(polygon
			(pts
				(arc
					(start 134.11454 -87.11438)
					(mid 133.731127 -86.730586)
					(end 133.34746 -87.114126)
				)
				(arc
					(start 133.34746 -88.019128)
					(mid 133.731 -88.402668)
					(end 134.11454 -88.019128)
				)
			)
		)
	)
	(zone
		(layers "In1.Cu" "In4.Cu" "In6.Cu")
		(hatch none 0.5)
		(connect_pads
			(clearance 0)
		)
		(min_thickness 0.25)
		(keepout
			(tracks not_allowed)
			(vias allowed)
			(pads allowed)
			(copperpour not_allowed)
			(footprints allowed)
		)
		(placement
			(enabled no)
			(sheetname "")
		)
		(fill yes
			(thermal_gap 0.5)
			(thermal_bridge_width 0.5)
			(island_removal_mode 0)
		)
		(polygon
			(pts
				(arc
					(start 108.22559 -5.999988)
					(mid 106.87431 -5.999988)
					(end 108.22559 -5.999988)
				)
			)
		)
	)
	(zone
		(layers "In1.Cu" "In4.Cu" "In6.Cu")
		(hatch none 0.5)
		(connect_pads
			(clearance 0)
		)
		(min_thickness 0.25)
		(keepout
			(tracks not_allowed)
			(vias allowed)
			(pads allowed)
			(copperpour not_allowed)
			(footprints allowed)
		)
		(placement
			(enabled no)
			(sheetname "")
		)
		(fill yes
			(thermal_gap 0.5)
			(thermal_bridge_width 0.5)
			(island_removal_mode 0)
		)
		(polygon
			(pts
				(arc
					(start 103.025702 -5.999988)
					(mid 101.674422 -5.999988)
					(end 103.025702 -5.999988)
				)
			)
		)
	)
	(zone
		(layers "In1.Cu" "In4.Cu" "In6.Cu")
		(hatch none 0.5)
		(connect_pads
			(clearance 0)
		)
		(min_thickness 0.25)
		(keepout
			(tracks not_allowed)
			(vias allowed)
			(pads allowed)
			(copperpour not_allowed)
			(footprints allowed)
		)
		(placement
			(enabled no)
			(sheetname "")
		)
		(fill yes
			(thermal_gap 0.5)
			(thermal_bridge_width 0.5)
			(island_removal_mode 0)
		)
		(polygon
			(pts
				(arc
					(start 105.625646 -5.999988)
					(mid 104.274366 -5.999988)
					(end 105.625646 -5.999988)
				)
			)
		)
	)
	(zone
		(net "P5V_STBY")
		(layer "In2.Cu")
		(hatch none 0.5)
		(connect_pads
			(clearance 0.5)
		)
		(min_thickness 0.25)
		(fill yes
			(thermal_gap 0.5)
			(thermal_bridge_width 0.5)
			(island_removal_mode 0)
		)
		(polygon
			(pts
				(xy 233.299 -101.219) (xy 236.601 -97.917) (xy 252.222 -97.917) (xy 252.857 -98.552) (xy 252.857 -107.442)
				(xy 252.857 -108.966) (xy 252.349 -109.474) (xy 237.363 -109.474) (xy 227.203 -119.634) (xy 224.155 -119.634)
				(xy 206.502 -119.634) (xy 204.851 -121.285) (xy 200.025 -121.285) (xy 198.628 -121.285) (xy 197.739 -122.174)
				(xy 192.405 -122.174) (xy 191.897 -121.666) (xy 191.897 -117.475) (xy 192.659 -116.713) (xy 198.247 -116.713)
				(xy 200.66 -114.3) (xy 222.758 -114.3) (xy 227.838 -109.22) (xy 227.838 -106.68)
			)
		)
	)
	(zone
		(layer "In2.Cu")
		(hatch none 0.5)
		(connect_pads
			(clearance 0)
		)
		(min_thickness 0.25)
		(keepout
			(tracks not_allowed)
			(vias allowed)
			(pads allowed)
			(copperpour not_allowed)
			(footprints allowed)
		)
		(placement
			(enabled no)
			(sheetname "")
		)
		(fill
			(thermal_gap 0.5)
			(thermal_bridge_width 0.5)
			(island_removal_mode 0)
		)
		(polygon
			(pts
				(arc
					(start 276.867112 -31.74746)
					(mid 276.483572 -32.131)
					(end 276.867112 -32.51454)
				)
				(arc
					(start 277.043642 -32.51454)
					(mid 277.014872 -32.455978)
					(end 276.982682 -32.399224)
				)
				(arc
					(start 276.982682 -32.399224)
					(mid 276.685064 -31.902616)
					(end 277.102824 -32.303466)
				)
				(arc
					(start 277.102824 -32.303466)
					(mid 277.160898 -32.406494)
					(end 277.208996 -32.51454)
				)
				(arc
					(start 277.507192 -32.51454)
					(mid 277.555283 -32.40649)
					(end 277.613364 -32.303466)
				)
				(arc
					(start 277.613364 -32.303466)
					(mid 278.031128 -31.902611)
					(end 277.733506 -32.399224)
				)
				(arc
					(start 277.733506 -32.399224)
					(mid 277.701312 -32.455976)
					(end 277.672546 -32.51454)
				)
				(arc
					(start 277.848822 -32.51454)
					(mid 278.232616 -32.131127)
					(end 277.849076 -31.74746)
				)
			)
		)
	)
	(zone
		(net "GND")
		(layer "In2.Cu")
		(hatch none 0.5)
		(connect_pads
			(clearance 0.5)
		)
		(min_thickness 0.25)
		(fill yes
			(thermal_gap 0.5)
			(thermal_bridge_width 0.5)
			(island_removal_mode 0)
		)
		(polygon
			(pts
				(xy 150.622 -89.662) (xy 182.245 -89.662) (xy 183.769 -88.138) (xy 183.769 -83.693) (xy 182.88 -82.804)
				(xy 150.622 -82.804) (xy 149.86 -83.566) (xy 149.86 -88.9)
			)
		)
	)
	(zone
		(net "P12V")
		(layer "In2.Cu")
		(hatch none 0.5)
		(connect_pads
			(clearance 0.5)
		)
		(min_thickness 0.25)
		(fill yes
			(thermal_gap 0.5)
			(thermal_bridge_width 0.5)
			(island_removal_mode 0)
		)
		(polygon
			(pts
				(xy 89.408 -153.035) (xy 96.012 -153.035) (xy 103.505 -160.528) (xy 105.791 -162.814) (xy 152.781 -162.814)
				(xy 153.162 -163.195) (xy 153.162 -164.465) (xy 153.162 -164.846) (xy 153.162 -165.862) (xy 153.162 -168.783)
				(xy 153.162 -169.672) (xy 152.654 -170.18) (xy 102.997 -170.18) (xy 99.441 -170.18) (xy 88.138 -158.877)
				(xy 88.138 -153.797) (xy 88.9 -153.035)
			)
		)
	)
	(zone
		(net "P1V8_STBY")
		(layer "In2.Cu")
		(hatch none 0.5)
		(connect_pads
			(clearance 0.5)
		)
		(min_thickness 0.25)
		(fill yes
			(thermal_gap 0.5)
			(thermal_bridge_width 0.5)
			(island_removal_mode 0)
		)
		(polygon
			(pts
				(xy 228.092 -157.734) (xy 228.092 -156.718) (xy 227.711 -156.337) (xy 227.203 -155.829) (xy 177.038 -155.829)
				(xy 176.4665 -156.4005) (xy 175.768 -157.099) (xy 113.538 -157.099) (xy 112.776 -157.099) (xy 109.347 -157.099)
				(xy 100.457 -148.209) (xy 94.615 -142.367) (xy 75.184 -142.367) (xy 72.263 -145.288) (xy 49.403 -145.288)
				(xy 42.545 -145.288) (xy 42.037 -145.796) (xy 42.037 -148.082) (xy 43.942 -149.987) (xy 50.546 -149.987)
				(xy 75.438 -149.987) (xy 78.232 -147.193) (xy 91.8845 -147.193) (xy 106.2355 -161.544) (xy 108.712 -161.544)
				(xy 155.829 -161.544) (xy 190.754 -161.544) (xy 191.262 -161.036) (xy 191.262 -160.909) (xy 192.532 -159.639)
				(xy 226.187 -159.639)
			)
		)
	)
	(zone
		(layer "In2.Cu")
		(hatch none 0.5)
		(connect_pads
			(clearance 0)
		)
		(min_thickness 0.25)
		(keepout
			(tracks not_allowed)
			(vias allowed)
			(pads allowed)
			(copperpour not_allowed)
			(footprints allowed)
		)
		(placement
			(enabled no)
			(sheetname "")
		)
		(fill
			(thermal_gap 0.5)
			(thermal_bridge_width 0.5)
			(island_removal_mode 0)
		)
		(polygon
			(pts
				(arc
					(start 76.157328 -36.275772)
					(mid 75.773534 -36.659185)
					(end 76.157074 -37.042852)
				)
				(arc
					(start 76.31557 -37.042852)
					(mid 76.295996 -36.984584)
					(end 76.271882 -36.928044)
				)
				(arc
					(start 76.271882 -36.928044)
					(mid 75.985337 -36.423106)
					(end 76.376276 -36.852352)
				)
				(arc
					(start 76.376276 -36.852352)
					(mid 76.417079 -36.945605)
					(end 76.447142 -37.042852)
				)
				(xy 76.677266 -37.042852) (xy 76.677266 -36.999418)
				(arc
					(start 76.680822 -36.995862)
					(mid 76.68676 -36.978045)
					(end 76.6953 -36.961318)
				)
				(xy 76.6953 -36.955984) (xy 76.713842 -36.937696) (xy 76.713842 -36.937442)
				(arc
					(start 76.869036 -36.782248)
					(mid 77.365426 -36.481213)
					(end 76.947268 -36.883848)
				)
				(xy 76.804266 -37.02685) (xy 76.804266 -37.042852)
				(arc
					(start 77.133958 -37.042852)
					(mid 77.517498 -36.659312)
					(end 77.133958 -36.275772)
				)
			)
		)
	)
	(zone
		(layer "In2.Cu")
		(hatch none 0.5)
		(connect_pads
			(clearance 0)
		)
		(min_thickness 0.25)
		(keepout
			(tracks not_allowed)
			(vias allowed)
			(pads allowed)
			(copperpour not_allowed)
			(footprints allowed)
		)
		(placement
			(enabled no)
			(sheetname "")
		)
		(fill
			(thermal_gap 0.5)
			(thermal_bridge_width 0.5)
			(island_removal_mode 0)
		)
		(polygon
			(pts
				(arc
					(start 79.604108 -39.24046)
					(mid 79.220568 -39.624)
					(end 79.604108 -40.00754)
				)
				(arc
					(start 79.832962 -40.00754)
					(mid 79.802463 -39.936082)
					(end 79.759048 -39.87165)
				)
				(arc
					(start 79.759048 -39.87165)
					(mid 79.39892 -39.416071)
					(end 79.849726 -39.782242)
				)
				(arc
					(start 79.849726 -39.782242)
					(mid 79.920569 -39.888043)
					(end 79.964534 -40.00754)
				)
				(arc
					(start 80.198976 -40.00754)
					(mid 80.240451 -39.903412)
					(end 80.304894 -39.811706)
				)
				(xy 80.304894 -39.81069) (xy 80.322674 -39.792656) (xy 80.323436 -39.791894)
				(arc
					(start 80.334612 -39.780972)
					(mid 80.787363 -39.417229)
					(end 80.424528 -39.870634)
				)
				(xy 80.413352 -39.88181)
				(arc
					(start 80.41259 -39.882318)
					(mid 80.365665 -39.940644)
					(end 80.332072 -40.00754)
				)
				(arc
					(start 80.580738 -40.00754)
					(mid 80.964532 -39.624127)
					(end 80.580992 -39.24046)
				)
			)
		)
	)
	(zone
		(net "P12V_MSB")
		(layer "In2.Cu")
		(hatch none 0.5)
		(connect_pads
			(clearance 0.5)
		)
		(min_thickness 0.25)
		(fill yes
			(thermal_gap 0.5)
			(thermal_bridge_width 0.5)
			(island_removal_mode 0)
		)
		(polygon
			(pts
				(xy 219.39377 -73.279) (xy 219.39377 -73.9902) (xy 218.27617 -75.1078) (xy 218.27617 -76.4286) (xy 218.27617 -78.70317)
				(xy 219.329 -79.756) (xy 219.329 -81.407) (xy 219.964 -82.042) (xy 223.393 -82.042) (xy 224.11817 -81.31683)
				(xy 224.11817 -76.6318) (xy 224.11817 -70.485) (xy 224.11817 -68.199) (xy 219.80017 -63.881) (xy 149.86 -63.881)
				(xy 148.336 -63.881) (xy 148.082 -64.135) (xy 148.082 -65.644776) (xy 148.089112 -65.651888) (xy 148.089112 -67.429888)
				(xy 148.09597 -67.437) (xy 148.09597 -69.9262) (xy 148.09597 -71.9582) (xy 148.114512 -71.976488)
				(xy 148.114512 -72.295512) (xy 148.59 -72.771) (xy 218.88577 -72.771)
			)
		)
	)
	(zone
		(net "GND")
		(layer "In2.Cu")
		(hatch none 0.5)
		(connect_pads
			(clearance 0.5)
		)
		(min_thickness 0.25)
		(fill yes
			(thermal_gap 0.5)
			(thermal_bridge_width 0.5)
			(island_removal_mode 0)
		)
		(polygon
			(pts
				(xy 54.102 -169.418) (xy 40.513 -155.829) (xy 40.513 -152.781) (xy 41.529 -151.765) (xy 81.153 -151.765)
				(xy 85.979 -156.591) (xy 85.979 -166.751) (xy 83.312 -169.418)
			)
		)
	)
	(zone
		(net "P3V3")
		(layer "In2.Cu")
		(hatch none 0.5)
		(connect_pads
			(clearance 0.5)
		)
		(min_thickness 0.25)
		(fill yes
			(thermal_gap 0.5)
			(thermal_bridge_width 0.5)
			(island_removal_mode 0)
		)
		(polygon
			(pts
				(xy 308.61 -62.484) (xy 308.61 -57.023) (xy 308.229 -56.642) (xy 307.34 -56.642) (xy 306.578 -56.642)
				(xy 306.07 -57.15) (xy 303.403 -57.15) (xy 303.022 -57.531) (xy 303.022 -58.42) (xy 302.006 -59.436)
				(xy 294.386 -59.436) (xy 293.751 -60.071) (xy 293.751 -60.706) (xy 293.751 -62.484) (xy 293.751 -63.881)
				(xy 294.64 -64.77) (xy 308.229 -64.77) (xy 308.61 -64.389)
			)
		)
	)
	(zone
		(net "P3V3_STBY")
		(layer "In2.Cu")
		(hatch none 0.5)
		(connect_pads
			(clearance 0.5)
		)
		(min_thickness 0.25)
		(fill yes
			(thermal_gap 0.5)
			(thermal_bridge_width 0.5)
			(island_removal_mode 0)
		)
		(polygon
			(pts
				(xy 297.561 -181.102) (xy 301.879 -181.102) (xy 301.9425 -181.0385) (xy 309.4355 -181.0385) (xy 309.88 -180.594)
				(xy 309.88 -178.943) (xy 308.356 -177.419) (xy 302.768 -177.419) (xy 302.514 -177.419) (xy 302.006 -177.927)
				(xy 300.355 -177.927) (xy 298.577 -177.927) (xy 298.45 -177.8) (xy 298.45 -175.895) (xy 298.196 -175.641)
				(xy 298.196 -172.466) (xy 297.942 -172.212) (xy 296.545 -172.212) (xy 295.021 -170.688) (xy 292.227 -170.688)
				(xy 290.576 -172.339) (xy 289.179 -172.339) (xy 288.036 -173.482) (xy 288.036 -177.165) (xy 289.687 -178.816)
				(xy 293.751 -178.816) (xy 294.894 -179.959) (xy 295.148 -179.959) (xy 295.275 -180.086) (xy 296.545 -180.086)
			)
		)
	)
	(zone
		(net "GND")
		(layer "In2.Cu")
		(hatch none 0.5)
		(connect_pads
			(clearance 0.5)
		)
		(min_thickness 0.25)
		(fill yes
			(thermal_gap 0.5)
			(thermal_bridge_width 0.5)
			(island_removal_mode 0)
		)
		(polygon
			(pts
				(xy 1.27 -219.71) (xy 3.429 -219.71) (xy 5.08 -219.71) (xy 7.112 -221.742) (xy 7.112 -223.393) (xy 7.112 -225.298)
				(xy 30.607 -248.793) (xy 74.549 -248.793) (xy 77.978 -252.222) (xy 105.41 -252.222) (xy 107.442 -250.19)
				(xy 150.114 -250.19) (xy 151.003 -249.301) (xy 197.739 -249.301) (xy 200.914 -246.126) (xy 200.914 -235.458)
				(xy 214.376 -221.996) (xy 214.376 -216.027) (xy 228.092 -202.311) (xy 232.664 -202.311) (xy 233.299 -202.946)
				(xy 233.299 -245.745) (xy 228.981 -250.063) (xy 202.819 -250.063) (xy 201.549 -251.333) (xy 201.549 -257.556)
				(xy 201.422 -257.683) (xy 192.278 -257.683) (xy 192.024 -257.429) (xy 192.024 -251.714) (xy 191.008 -250.698)
				(xy 189.484 -250.698) (xy 188.468 -251.714) (xy 188.468 -257.302) (xy 187.96 -257.81) (xy 183.515 -257.81)
				(xy 183.007 -257.302) (xy 183.007 -251.206) (xy 181.991 -250.19) (xy 151.892 -250.19) (xy 150.749 -251.333)
				(xy 150.749 -257.048) (xy 150.114 -257.683) (xy 141.859 -257.683) (xy 141.351 -257.175) (xy 141.351 -251.841)
				(xy 140.335 -250.825) (xy 138.557 -250.825) (xy 137.668 -251.714) (xy 137.668 -253.111) (xy 136.779 -254)
				(xy 71.12 -254) (xy 68.199 -251.079) (xy 67.31 -250.19) (xy 47.879 -250.19) (xy 47.371 -250.698)
				(xy 36.195 -250.698) (xy 34.671 -250.698) (xy 33.782 -250.698) (xy 33.02 -251.46) (xy 28.448 -251.46)
				(xy 27.686 -250.698) (xy 27.178 -250.19) (xy 5.08 -250.19) (xy 4.445 -250.19) (xy 4.318 -250.063)
				(xy 4.191 -250.063) (xy 2.921 -248.793) (xy 0.889 -246.761) (xy 0.889 -220.091)
			)
		)
	)
	(zone
		(net "GND")
		(layer "In2.Cu")
		(hatch none 0.5)
		(connect_pads
			(clearance 0.5)
		)
		(min_thickness 0.25)
		(fill yes
			(thermal_gap 0.5)
			(thermal_bridge_width 0.5)
			(island_removal_mode 0)
		)
		(polygon
			(pts
				(xy 235.585 -87.122) (xy 243.205 -87.122) (xy 245.999 -89.916) (xy 255.524 -89.916) (xy 258.318 -87.122)
				(xy 258.318 -82.423) (xy 245.491 -69.596) (xy 245.491 -48.895) (xy 229.362 -32.766) (xy 212.471 -32.766)
				(xy 204.724 -25.019) (xy 190.5 -25.019) (xy 189.103 -26.416) (xy 189.103 -35.56) (xy 186.817 -37.846)
				(xy 179.578 -37.846) (xy 172.847 -31.115) (xy 169.037 -31.115) (xy 164.719 -26.797) (xy 145.542 -26.797)
				(xy 135.382 -16.637) (xy 118.999 -16.637) (xy 111.125 -8.763) (xy 102.997 -8.763) (xy 102.489 -9.271)
				(xy 102.489 -23.114) (xy 108.458 -29.083) (xy 121.793 -29.083) (xy 123.19 -27.686) (xy 132.207 -27.686)
				(xy 144.272 -39.751) (xy 150.749 -39.751) (xy 168.402 -57.404) (xy 220.218 -57.404) (xy 230.124 -67.31)
				(xy 230.124 -81.661)
			)
		)
	)
	(zone
		(layer "In2.Cu")
		(hatch none 0.5)
		(connect_pads
			(clearance 0)
		)
		(min_thickness 0.25)
		(keepout
			(tracks not_allowed)
			(vias allowed)
			(pads allowed)
			(copperpour not_allowed)
			(footprints allowed)
		)
		(placement
			(enabled no)
			(sheetname "")
		)
		(fill
			(thermal_gap 0.5)
			(thermal_bridge_width 0.5)
			(island_removal_mode 0)
		)
		(polygon
			(pts
				(arc
					(start 83.294728 -37.831776)
					(mid 82.911188 -37.448236)
					(end 82.527648 -37.831776)
				)
				(xy 82.527648 -38.087554) (xy 82.556858 -38.087046) (xy 82.557874 -38.087046) (xy 82.558128 -38.087046)
				(xy 82.59445 -38.088316) (xy 82.594958 -38.087808) (xy 82.760058 -38.10508)
				(arc
					(start 82.774028 -38.08984)
					(mid 82.983445 -37.548787)
					(end 82.90687 -38.123876)
				)
				(arc
					(start 82.90687 -38.123876)
					(mid 82.879853 -38.161379)
					(end 82.848958 -38.195758)
				)
				(arc
					(start 82.848958 -38.195758)
					(mid 82.816638 -38.219028)
					(end 82.7786 -38.23081)
				)
				(xy 82.777838 -38.231572) (xy 82.774536 -38.234112) (xy 82.748374 -38.231572)
				(arc
					(start 82.607912 -38.21684)
					(mid 82.582801 -38.214811)
					(end 82.55762 -38.214046)
				)
				(xy 82.556858 -38.214046) (xy 82.527648 -38.214554) (xy 82.527648 -38.418008) (xy 82.557366 -38.4175)
				(xy 82.55762 -38.4175)
				(arc
					(start 82.587338 -38.419024)
					(mid 82.673319 -38.440821)
					(end 82.749136 -38.486842)
				)
				(xy 82.751168 -38.486842)
				(arc
					(start 82.75447 -38.490144)
					(mid 83.119181 -38.941813)
					(end 82.664046 -38.58133)
				)
				(arc
					(start 82.664046 -38.58133)
					(mid 82.621879 -38.557099)
					(end 82.574638 -38.545516)
				)
				(xy 82.574384 -38.545516) (xy 82.557366 -38.5445) (xy 82.527648 -38.545262)
				(arc
					(start 82.527648 -38.736524)
					(mid 82.911061 -39.120318)
					(end 83.294728 -38.736778)
				)
			)
		)
	)
	(zone
		(net "GND")
		(layer "In2.Cu")
		(hatch none 0.5)
		(connect_pads
			(clearance 0.5)
		)
		(min_thickness 0.25)
		(fill yes
			(thermal_gap 0.5)
			(thermal_bridge_width 0.5)
			(island_removal_mode 0)
		)
		(polygon
			(pts
				(xy 107.315 -136.906) (xy 174.117 -136.906) (xy 191.516 -119.507) (xy 191.516 -115.697) (xy 190.373 -114.554)
				(xy 101.219 -114.554) (xy 99.314 -116.459) (xy 95.631 -116.459) (xy 93.345 -118.745) (xy 93.345 -122.936)
			)
		)
	)
	(zone
		(net "P0V955_C")
		(layer "In2.Cu")
		(hatch none 0.5)
		(connect_pads
			(clearance 0.5)
		)
		(min_thickness 0.25)
		(fill yes
			(thermal_gap 0.5)
			(thermal_bridge_width 0.5)
			(island_removal_mode 0)
		)
		(polygon
			(pts
				(xy 91.948 -27.559) (xy 95.377 -24.13) (xy 101.981 -17.526) (xy 101.981 -4.953) (xy 101.727 -4.699)
				(xy 95.504 -4.699) (xy 94.488 -5.715) (xy 94.488 -13.716) (xy 86.868 -21.336) (xy 82.55 -25.654)
				(xy 75.184 -25.654) (xy 74.93 -25.908) (xy 74.93 -29.464) (xy 75.057 -29.591) (xy 75.184 -29.718)
				(xy 89.789 -29.718)
			)
		)
	)
	(zone
		(net "GND")
		(layer "In2.Cu")
		(hatch none 0.5)
		(connect_pads
			(clearance 0.5)
		)
		(min_thickness 0.25)
		(fill yes
			(thermal_gap 0.5)
			(thermal_bridge_width 0.5)
			(island_removal_mode 0)
		)
		(polygon
			(pts
				(xy 278.638 -233.934) (xy 291.719 -233.934) (xy 308.483 -217.17) (xy 308.483 -213.487) (xy 307.467 -212.471)
				(xy 298.704 -212.471) (xy 297.815 -213.36) (xy 297.815 -217.805) (xy 297.053 -218.567) (xy 295.529 -218.567)
				(xy 294.64 -217.678) (xy 294.64 -215.773) (xy 293.243 -214.376) (xy 280.924 -214.376) (xy 279.908 -215.392)
				(xy 279.908 -231.267) (xy 278.257 -232.918) (xy 278.257 -233.553)
			)
		)
	)
	(zone
		(net "SAS0_VDDH")
		(layer "In2.Cu")
		(hatch none 0.5)
		(connect_pads
			(clearance 0.5)
		)
		(min_thickness 0.25)
		(fill yes
			(thermal_gap 0.5)
			(thermal_bridge_width 0.5)
			(island_removal_mode 0)
		)
		(polygon
			(pts
				(xy 71.374 -49.403) (xy 74.041 -49.403) (xy 74.549 -49.403) (xy 74.93 -49.022) (xy 74.93 -48.514)
				(xy 74.93 -36.195) (xy 75.565 -35.56) (xy 86.106 -35.56) (xy 86.995 -36.449) (xy 86.995 -43.688)
				(xy 86.995 -46.609) (xy 86.995 -47.625) (xy 87.503 -48.133) (xy 93.853 -48.133) (xy 96.012 -45.974)
				(xy 96.012 -45.466) (xy 96.012 -44.069) (xy 96.647 -43.434) (xy 96.647 -39.751) (xy 92.202 -35.306)
				(xy 92.202 -32.385) (xy 89.916 -30.099) (xy 72.517 -30.099) (xy 72.009 -30.607) (xy 72.009 -44.069)
				(xy 70.993 -45.085) (xy 70.993 -49.022)
			)
		)
	)
	(zone
		(net "P3V3_STBY")
		(layer "In2.Cu")
		(hatch none 0.5)
		(connect_pads
			(clearance 0.5)
		)
		(min_thickness 0.25)
		(fill yes
			(thermal_gap 0.5)
			(thermal_bridge_width 0.5)
			(island_removal_mode 0)
		)
		(polygon
			(pts
				(xy 294.513 -55.372) (xy 294.259 -55.626) (xy 294.259 -57.785) (xy 294.64 -58.166) (xy 300.99 -58.166)
				(xy 301.752 -58.166) (xy 302.9712 -56.9468) (xy 305.943 -56.9468) (xy 306.5018 -56.388) (xy 315.595 -56.388)
				(xy 315.976 -56.007) (xy 315.976 -51.435) (xy 315.722 -51.181) (xy 313.055 -51.181) (xy 305.562 -51.181)
				(xy 305.308 -51.435) (xy 305.308 -54.229) (xy 304.165 -55.372)
			)
		)
	)
	(zone
		(net "P1V5_C")
		(layer "In2.Cu")
		(hatch none 0.5)
		(connect_pads
			(clearance 0.5)
		)
		(min_thickness 0.25)
		(fill yes
			(thermal_gap 0.5)
			(thermal_bridge_width 0.5)
			(island_removal_mode 0)
		)
		(polygon
			(pts
				(xy 103.886 -31.877) (xy 95.885 -31.877) (xy 95.25 -32.512) (xy 95.25 -38.1) (xy 95.377 -38.227)
				(xy 103.505 -38.227) (xy 103.759 -38.227) (xy 104.521 -37.465) (xy 104.521 -32.258) (xy 104.14 -31.877)
			)
		)
	)
	(zone
		(net "GND")
		(layer "In2.Cu")
		(hatch none 0.5)
		(connect_pads
			(clearance 0.5)
		)
		(min_thickness 0.25)
		(fill yes
			(thermal_gap 0.5)
			(thermal_bridge_width 0.5)
			(island_removal_mode 0)
		)
		(polygon
			(pts
				(xy 323.723 -125.095) (xy 316.865 -118.237) (xy 316.865 -66.548) (xy 317.627 -65.786) (xy 317.627 -62.484)
				(xy 317.119 -61.976) (xy 314.579 -61.976) (xy 311.912 -64.643) (xy 311.912 -94.107) (xy 310.642 -95.377)
				(xy 307.975 -98.044) (xy 307.975 -109.347) (xy 309.499 -110.871) (xy 309.499 -113.919) (xy 309.4355 -113.9825)
				(xy 309.4355 -121.2215) (xy 316.23 -128.016) (xy 318.516 -128.016) (xy 322.834 -128.016) (xy 323.723 -127.127)
			)
		)
	)
	(zone
		(net "P1V8_STBY")
		(layer "In2.Cu")
		(hatch none 0.5)
		(connect_pads
			(clearance 0.5)
		)
		(min_thickness 0.25)
		(fill yes
			(thermal_gap 0.5)
			(thermal_bridge_width 0.5)
			(island_removal_mode 0)
		)
		(polygon
			(pts
				(xy 272.161 -29.591) (xy 273.558 -30.988) (xy 273.558 -35.687) (xy 275.463 -37.592) (xy 275.463 -55.245)
				(xy 275.971 -55.753) (xy 279.654 -59.436) (xy 279.654 -110.744) (xy 278.003 -112.395) (xy 272.288 -112.395)
				(xy 270.891 -112.395) (xy 269.748 -111.252) (xy 269.748 -61.722) (xy 269.748 -46.99) (xy 258.572 -35.814)
				(xy 258.572 -32.512) (xy 261.493 -29.591) (xy 263.906 -27.178) (xy 263.906 -20.447) (xy 263.906 -19.304)
				(xy 264.287 -18.923) (xy 271.78 -18.923) (xy 272.034 -19.177) (xy 272.034 -20.32) (xy 272.034 -29.464)
			)
		)
	)
	(zone
		(net "P3V3_STBY")
		(layer "In2.Cu")
		(hatch none 0.5)
		(connect_pads
			(clearance 0.5)
		)
		(min_thickness 0.25)
		(fill yes
			(thermal_gap 0.5)
			(thermal_bridge_width 0.5)
			(island_removal_mode 0)
		)
		(polygon
			(pts
				(xy 260.985 -233.045) (xy 271.653 -233.045) (xy 277.114 -227.584) (xy 277.114 -219.837) (xy 276.733 -219.456)
				(xy 262.001 -219.456) (xy 261.239 -220.218) (xy 261.239 -225.552) (xy 261.366 -225.679) (xy 261.366 -226.441)
				(xy 260.731 -227.076) (xy 260.731 -232.791)
			)
		)
	)
	(zone
		(net "P1V26_STBY")
		(layer "In2.Cu")
		(hatch none 0.5)
		(connect_pads
			(clearance 0.5)
		)
		(min_thickness 0.25)
		(fill yes
			(thermal_gap 0.5)
			(thermal_bridge_width 0.5)
			(island_removal_mode 0)
		)
		(polygon
			(pts
				(xy 161.925 -196.723) (xy 218.44 -196.723) (xy 218.821 -197.104) (xy 218.821 -199.771) (xy 218.567 -200.025)
				(xy 159.893 -200.025) (xy 151.892 -200.025) (xy 151.638 -199.771) (xy 151.638 -197.358) (xy 151.638 -196.977)
				(xy 151.892 -196.723) (xy 152.273 -196.723)
			)
		)
	)
	(zone
		(net "P12V")
		(layer "In2.Cu")
		(hatch none 0.5)
		(connect_pads
			(clearance 0.5)
		)
		(min_thickness 0.25)
		(fill yes
			(thermal_gap 0.5)
			(thermal_bridge_width 0.5)
			(island_removal_mode 0)
		)
		(polygon
			(pts
				(xy 271.399 -131.0005) (xy 273.4945 -131.0005) (xy 274.447 -130.048) (xy 279.527 -130.048) (xy 283.845 -125.73)
				(xy 303.657 -125.73) (xy 304.038 -125.349) (xy 304.038 -122.174) (xy 303.657 -121.793) (xy 302.387 -121.793)
				(xy 301.752 -121.793) (xy 299.974 -120.015) (xy 281.432 -120.015) (xy 277.876 -123.571) (xy 261.747 -123.571)
				(xy 260.604 -124.714) (xy 259.5245 -125.7935) (xy 212.9155 -125.7935) (xy 212.598 -126.111) (xy 211.963 -126.746)
				(xy 211.963 -131.064) (xy 212.725 -131.826) (xy 233.553 -131.826) (xy 234.061 -132.334) (xy 270.0655 -132.334)
			)
		)
	)
	(zone
		(layer "In2.Cu")
		(hatch none 0.5)
		(connect_pads
			(clearance 0)
		)
		(min_thickness 0.25)
		(keepout
			(tracks not_allowed)
			(vias allowed)
			(pads allowed)
			(copperpour not_allowed)
			(footprints allowed)
		)
		(placement
			(enabled no)
			(sheetname "")
		)
		(fill
			(thermal_gap 0.5)
			(thermal_bridge_width 0.5)
			(island_removal_mode 0)
		)
		(polygon
			(pts
				(arc
					(start 123.85294 -81.309464)
					(mid 124.236988 -80.926432)
					(end 123.853956 -80.542384)
				)
				(xy 123.833128 -80.542892) (xy 123.678188 -80.546956)
				(arc
					(start 123.775724 -80.644238)
					(mid 123.992975 -81.182673)
					(end 123.659392 -80.707484)
				)
				(arc
					(start 123.54814 -80.59674)
					(mid 123.503026 -80.566659)
					(end 123.449842 -80.5561)
				)
				(xy 123.320556 -80.5561)
				(arc
					(start 122.925332 -80.56626)
					(mid 122.738983 -80.618095)
					(end 122.606816 -80.7593)
				)
				(xy 122.705622 -80.7593) (xy 122.706384 -80.760316)
				(arc
					(start 122.714004 -80.760824)
					(mid 123.169959 -81.028704)
					(end 122.660664 -80.8863)
				)
				(arc
					(start 122.568462 -80.8863)
					(mid 122.658027 -81.163605)
					(end 122.924062 -81.28254)
				)
				(xy 123.831858 -81.308956)
			)
		)
	)
	(zone
		(net "P5V_STBY")
		(layer "In2.Cu")
		(hatch none 0.5)
		(connect_pads
			(clearance 0.5)
		)
		(min_thickness 0.25)
		(fill yes
			(thermal_gap 0.5)
			(thermal_bridge_width 0.5)
			(island_removal_mode 0)
		)
		(polygon
			(pts
				(xy 345.821 -90.17) (xy 340.614 -90.17) (xy 332.486 -90.17) (xy 323.596 -81.28) (xy 323.596 -73.152)
				(xy 323.596 -55.499) (xy 314.706 -46.609) (xy 314.706 -41.656) (xy 315.087 -41.275) (xy 317.5 -41.275)
				(xy 329.057 -52.832) (xy 329.057 -69.596) (xy 346.202 -86.741) (xy 346.202 -89.789)
			)
		)
	)
	(zone
		(net "P3V3_STBY")
		(layer "In2.Cu")
		(hatch none 0.5)
		(connect_pads
			(clearance 0.5)
		)
		(min_thickness 0.25)
		(fill yes
			(thermal_gap 0.5)
			(thermal_bridge_width 0.5)
			(island_removal_mode 0)
		)
		(polygon
			(pts
				(xy 85.598 -244.983) (xy 109.601 -244.983) (xy 119.38 -244.983) (xy 121.285 -243.078) (xy 190.627 -243.078)
				(xy 198.12 -235.585) (xy 198.12 -231.394) (xy 197.485 -230.759) (xy 125.349 -230.759) (xy 107.061 -230.759)
				(xy 103.251 -226.949) (xy 103.251 -223.012) (xy 101.092 -220.853) (xy 100.203 -220.853) (xy 99.695 -220.345)
				(xy 99.695 -219.964) (xy 99.441 -219.71) (xy 96.901 -219.71) (xy 95.25 -221.361) (xy 86.995 -221.361)
				(xy 85.344 -223.012) (xy 85.344 -244.729)
			)
		)
	)
	(zone
		(net "P3V3_STBY")
		(layer "In2.Cu")
		(hatch none 0.5)
		(connect_pads
			(clearance 0.5)
		)
		(min_thickness 0.25)
		(fill yes
			(thermal_gap 0.5)
			(thermal_bridge_width 0.5)
			(island_removal_mode 0)
		)
		(polygon
			(pts
				(xy 173.417992 -18.288) (xy 169.226992 -22.479) (xy 169.226992 -29.6672) (xy 170.039792 -30.48)
				(xy 173.036992 -30.48) (xy 179.894992 -37.338) (xy 181.672992 -37.338) (xy 186.244992 -37.338) (xy 188.530992 -35.052)
				(xy 188.530992 -25.337008) (xy 189.484 -24.384) (xy 205.105 -24.384) (xy 212.852 -32.131) (xy 239.522 -32.131)
				(xy 265.6205 -58.2295) (xy 265.811 -58.42) (xy 266.192 -58.801) (xy 268.605 -58.801) (xy 268.986 -58.42)
				(xy 268.986 -57.912) (xy 268.986 -47.244) (xy 257.556 -35.814) (xy 257.556 -34.544) (xy 234.442 -11.43)
				(xy 233.172 -11.43) (xy 222.631 -11.43) (xy 220.726 -13.335) (xy 214.63 -13.335) (xy 214.249 -13.335)
				(xy 213.487 -13.335) (xy 184.912 -13.335) (xy 178.370992 -13.335)
			)
		)
	)
	(zone
		(layer "In2.Cu")
		(hatch none 0.5)
		(connect_pads
			(clearance 0)
		)
		(min_thickness 0.25)
		(keepout
			(tracks not_allowed)
			(vias allowed)
			(pads allowed)
			(copperpour not_allowed)
			(footprints allowed)
		)
		(placement
			(enabled no)
			(sheetname "")
		)
		(fill
			(thermal_gap 0.5)
			(thermal_bridge_width 0.5)
			(island_removal_mode 0)
		)
		(polygon
			(pts
				(arc
					(start 129.159 -80.89646)
					(mid 128.77546 -81.28)
					(end 129.159 -81.66354)
				)
				(arc
					(start 130.047746 -81.66354)
					(mid 130.43154 -81.280127)
					(end 130.048 -80.89646)
				)
				(arc
					(start 129.861056 -80.89646)
					(mid 129.88146 -80.961051)
					(end 129.910078 -81.022444)
				)
				(arc
					(start 129.910078 -81.022444)
					(mid 130.240079 -81.499973)
					(end 129.812288 -81.107534)
				)
				(arc
					(start 129.812288 -81.107534)
					(mid 129.762388 -81.005563)
					(end 129.731008 -80.89646)
				)
				(arc
					(start 129.502408 -80.89646)
					(mid 129.463806 -81.012392)
					(end 129.401824 -81.117694)
				)
				(arc
					(start 129.401824 -81.117694)
					(mid 128.957746 -81.491668)
					(end 129.30886 -81.029302)
				)
				(arc
					(start 129.30886 -81.029302)
					(mid 129.345496 -80.965419)
					(end 129.371344 -80.89646)
				)
			)
		)
	)
	(zone
		(net "P3V3_STBY")
		(layer "In2.Cu")
		(hatch none 0.5)
		(connect_pads
			(clearance 0.5)
		)
		(min_thickness 0.25)
		(fill yes
			(thermal_gap 0.5)
			(thermal_bridge_width 0.5)
			(island_removal_mode 0)
		)
		(polygon
			(pts
				(xy 298.069 -99.314) (xy 298.069 -85.852) (xy 294.386 -82.169) (xy 294.386 -78.74) (xy 288.544 -72.898)
				(xy 286.385 -72.898) (xy 285.877 -73.406) (xy 285.877 -78.867) (xy 295.021 -88.011) (xy 295.021 -90.805)
				(xy 295.402 -91.186) (xy 295.402 -91.567) (xy 295.021 -91.948) (xy 295.021 -94.234) (xy 295.021 -99.568)
				(xy 295.021 -101.219) (xy 295.529 -101.727) (xy 297.688 -101.727) (xy 298.577 -100.838) (xy 298.577 -99.822)
			)
		)
	)
	(zone
		(net "GND")
		(layer "In2.Cu")
		(hatch none 0.5)
		(connect_pads
			(clearance 0.5)
		)
		(min_thickness 0.25)
		(fill yes
			(thermal_gap 0.5)
			(thermal_bridge_width 0.5)
			(island_removal_mode 0)
		)
		(polygon
			(pts
				(xy 301.752 -105.664) (xy 305.308 -105.664) (xy 305.689 -105.283) (xy 305.689 -95.885) (xy 307.467 -94.107)
				(xy 307.467 -66.167) (xy 306.451 -65.151) (xy 294.894 -65.151) (xy 294.132 -65.913) (xy 294.132 -72.136)
				(xy 301.244 -79.248) (xy 301.244 -86.36) (xy 301.244 -87.503) (xy 303.149 -89.408) (xy 303.149 -94.742)
				(xy 301.498 -96.393) (xy 301.498 -105.41)
			)
		)
	)
	(zone
		(layer "In2.Cu")
		(hatch none 0.5)
		(connect_pads
			(clearance 0)
		)
		(min_thickness 0.25)
		(keepout
			(tracks not_allowed)
			(vias allowed)
			(pads allowed)
			(copperpour not_allowed)
			(footprints allowed)
		)
		(placement
			(enabled no)
			(sheetname "")
		)
		(fill
			(thermal_gap 0.5)
			(thermal_bridge_width 0.5)
			(island_removal_mode 0)
		)
		(polygon
			(pts
				(arc
					(start 124.798836 -79.868268)
					(mid 124.818987 -79.91546)
					(end 124.833126 -79.964788)
				)
				(arc
					(start 124.833126 -79.964788)
					(mid 124.790616 -80.543615)
					(end 124.703332 -79.969868)
				)
				(arc
					(start 124.703332 -79.969868)
					(mid 124.686057 -79.926509)
					(end 124.66193 -79.886556)
				)
				(arc
					(start 124.66193 -79.886556)
					(mid 124.400263 -80.311198)
					(end 124.779278 -80.635348)
				)
				(arc
					(start 125.756162 -80.635348)
					(mid 126.139702 -80.251808)
					(end 125.756162 -79.868268)
				)
				(xy 125.295914 -79.868268)
				(arc
					(start 125.514862 -80.087216)
					(mid 126.029077 -80.355237)
					(end 125.466602 -80.214216)
				)
				(xy 125.446536 -80.197452) (xy 125.445266 -80.197452) (xy 125.426724 -80.17891) (xy 125.116082 -79.868268)
			)
		)
	)
	(zone
		(net "P1V53_STBY")
		(layer "In2.Cu")
		(hatch none 0.5)
		(connect_pads
			(clearance 0.5)
		)
		(min_thickness 0.25)
		(fill yes
			(thermal_gap 0.5)
			(thermal_bridge_width 0.5)
			(island_removal_mode 0)
		)
		(polygon
			(pts
				(xy 288.925 -204.343) (xy 296.291 -204.343) (xy 298.577 -202.057) (xy 298.577 -195.326) (xy 297.561 -194.31)
				(xy 284.607 -194.31) (xy 283.21 -195.707) (xy 283.21 -203.073) (xy 283.591 -203.454) (xy 288.036 -203.454)
			)
		)
		(polygon
			(pts
				(arc
					(start 289.22726 -199.008746)
					(mid 289.144871 -198.953737)
					(end 289.054794 -198.99503)
				)
				(arc
					(start 289.054794 -198.99503)
					(mid 288.748119 -199.204452)
					(end 288.377884 -199.175624)
				)
				(arc
					(start 288.377884 -199.175624)
					(mid 288.276454 -199.186725)
					(end 288.235898 -199.280272)
				)
				(arc
					(start 288.235898 -199.280272)
					(mid 288.231568 -199.439843)
					(end 288.182304 -199.591676)
				)
				(arc
					(start 288.182304 -199.591676)
					(mid 288.179905 -199.676358)
					(end 288.242502 -199.733408)
				)
				(arc
					(start 288.242502 -199.733408)
					(mid 288.391689 -199.806853)
					(end 288.512758 -199.92086)
				)
				(arc
					(start 288.512758 -199.92086)
					(mid 288.604031 -199.958941)
					(end 288.684462 -199.901302)
				)
				(arc
					(start 288.684462 -199.901302)
					(mid 288.944832 -199.637244)
					(end 289.313112 -199.594216)
				)
				(arc
					(start 289.313112 -199.594216)
					(mid 289.403321 -199.570483)
					(end 289.436302 -199.483218)
				)
				(arc
					(start 289.436302 -199.483218)
					(mid 289.433708 -199.382304)
					(end 289.449256 -199.282558)
				)
				(arc
					(start 289.449256 -199.282558)
					(mid 289.447188 -199.251285)
					(end 289.427158 -199.227186)
				)
				(arc
					(start 289.427158 -199.227186)
					(mid 289.31251 -199.131422)
					(end 289.22726 -199.008746)
				)
			)
		)
		(polygon
			(pts
				(arc
					(start 297.011598 -197.783958)
					(mid 296.941472 -197.743553)
					(end 296.864024 -197.767194)
				)
				(arc
					(start 296.864024 -197.767194)
					(mid 296.727648 -197.853094)
					(end 296.572432 -197.89648)
				)
				(arc
					(start 296.572432 -197.89648)
					(mid 296.492913 -197.95507)
					(end 296.500804 -198.053452)
				)
				(arc
					(start 296.500804 -198.053452)
					(mid 296.553171 -198.573642)
					(end 296.152824 -198.90994)
				)
				(arc
					(start 296.152824 -198.90994)
					(mid 296.122754 -198.929346)
					(end 296.112946 -198.963788)
				)
				(arc
					(start 296.112946 -198.963788)
					(mid 296.114755 -198.995893)
					(end 296.114724 -199.02805)
				)
				(arc
					(start 296.114724 -199.02805)
					(mid 296.141711 -199.074473)
					(end 296.195242 -199.070722)
				)
				(arc
					(start 296.195242 -199.070722)
					(mid 296.445705 -198.97062)
					(end 296.71391 -198.999348)
				)
				(arc
					(start 296.71391 -198.999348)
					(mid 296.821974 -198.974688)
					(end 296.843196 -198.865998)
				)
				(arc
					(start 296.843196 -198.865998)
					(mid 296.853807 -198.425205)
					(end 297.180508 -198.129144)
				)
				(arc
					(start 297.180508 -198.129144)
					(mid 297.248679 -198.041434)
					(end 297.195748 -197.943724)
				)
				(arc
					(start 297.195748 -197.943724)
					(mid 297.094862 -197.873996)
					(end 297.011598 -197.783958)
				)
			)
		)
	)
	(zone
		(net "P1V26_STBY")
		(layer "In2.Cu")
		(hatch none 0.5)
		(connect_pads
			(clearance 0.5)
		)
		(min_thickness 0.25)
		(fill yes
			(thermal_gap 0.5)
			(thermal_bridge_width 0.5)
			(island_removal_mode 0)
		)
		(polygon
			(pts
				(xy 155.067 -223.52) (xy 155.575 -223.012) (xy 155.575 -220.091) (xy 155.321 -219.837) (xy 129.921 -219.837)
				(xy 128.778 -219.837) (xy 127.889 -220.726) (xy 124.968 -223.647) (xy 124.968 -225.298) (xy 125.222 -225.552)
				(xy 128.397 -225.552) (xy 128.651 -225.552) (xy 129.032 -225.171) (xy 130.683 -223.52)
			)
		)
	)
	(zone
		(layer "In2.Cu")
		(hatch none 0.5)
		(connect_pads
			(clearance 0)
		)
		(min_thickness 0.25)
		(keepout
			(tracks not_allowed)
			(vias allowed)
			(pads allowed)
			(copperpour not_allowed)
			(footprints allowed)
		)
		(placement
			(enabled no)
			(sheetname "")
		)
		(fill
			(thermal_gap 0.5)
			(thermal_bridge_width 0.5)
			(island_removal_mode 0)
		)
		(polygon
			(pts
				(arc
					(start 127.154178 -79.42326)
					(mid 126.770638 -79.8068)
					(end 127.154178 -80.19034)
				)
				(arc
					(start 128.130808 -80.19034)
					(mid 128.514602 -79.806927)
					(end 128.131062 -79.42326)
				)
				(arc
					(start 127.892048 -79.42326)
					(mid 127.927 -79.495497)
					(end 127.974852 -79.559912)
				)
				(arc
					(start 127.974852 -79.559912)
					(mid 128.337448 -80.013585)
					(end 127.884428 -79.650082)
				)
				(xy 127.881888 -79.647542)
				(arc
					(start 127.881888 -79.646526)
					(mid 127.80717 -79.542079)
					(end 127.758444 -79.42326)
				)
				(arc
					(start 127.515366 -79.42326)
					(mid 127.469605 -79.541995)
					(end 127.399288 -79.64805)
				)
				(arc
					(start 127.399288 -79.64805)
					(mid 126.949077 -80.014782)
					(end 127.308356 -79.558642)
				)
				(arc
					(start 127.308356 -79.558642)
					(mid 127.351166 -79.494089)
					(end 127.382524 -79.42326)
				)
			)
		)
	)
	(zone
		(net "GB_VDDH2")
		(layer "In2.Cu")
		(hatch none 0.5)
		(connect_pads
			(clearance 0.5)
		)
		(min_thickness 0.25)
		(fill yes
			(thermal_gap 0.5)
			(thermal_bridge_width 0.5)
			(island_removal_mode 0)
		)
		(polygon
			(pts
				(xy 196.723 -100.711) (xy 196.723 -94.107) (xy 195.707 -93.091) (xy 171.704 -93.091) (xy 170.688 -94.107)
				(xy 159.385 -94.107) (xy 158.242 -92.964) (xy 146.812 -92.964) (xy 145.669 -94.107) (xy 122.174 -94.107)
				(xy 120.523 -92.456) (xy 120.523 -88.773) (xy 120.015 -88.265) (xy 110.617 -88.265) (xy 109.982 -88.9)
				(xy 109.982 -100.711) (xy 109.982 -110.744) (xy 113.665 -114.427) (xy 157.48 -114.427) (xy 160.782 -111.125)
				(xy 195.961 -111.125) (xy 196.723 -110.363) (xy 196.723 -108.966)
			)
		)
	)
	(zone
		(net "SYSPLL_VDDA18")
		(layer "In2.Cu")
		(hatch none 0.5)
		(connect_pads
			(clearance 0.5)
		)
		(min_thickness 0.25)
		(fill yes
			(thermal_gap 0.5)
			(thermal_bridge_width 0.5)
			(island_removal_mode 0)
		)
		(polygon
			(pts
				(xy 112.59185 -88.23706) (xy 113.157 -88.23706) (xy 113.25606 -88.138) (xy 113.284 -88.138) (xy 113.411 -88.011)
				(xy 113.411 -87.376) (xy 113.538 -87.249) (xy 116.22405 -87.249) (xy 116.47805 -86.995) (xy 116.47805 -81.661)
				(xy 114.29619 -79.47914) (xy 113.53419 -79.47914) (xy 112.48009 -80.53324) (xy 112.48009 -88.1253)
			)
		)
	)
	(zone
		(layer "In2.Cu")
		(hatch none 0.5)
		(connect_pads
			(clearance 0)
		)
		(min_thickness 0.25)
		(keepout
			(tracks not_allowed)
			(vias allowed)
			(pads allowed)
			(copperpour not_allowed)
			(footprints allowed)
		)
		(placement
			(enabled no)
			(sheetname "")
		)
		(fill
			(thermal_gap 0.5)
			(thermal_bridge_width 0.5)
			(island_removal_mode 0)
		)
		(polygon
			(pts
				(arc
					(start 77.686408 -41.22166)
					(mid 77.302868 -41.6052)
					(end 77.686408 -41.98874)
				)
				(arc
					(start 77.961236 -41.98874)
					(mid 77.922771 -41.936362)
					(end 77.879194 -41.888156)
				)
				(arc
					(start 77.842872 -41.851834)
					(mid 77.479528 -41.398574)
					(end 77.932788 -41.761918)
				)
				(xy 77.968348 -41.797478) (xy 77.96911 -41.798494) (xy 77.98689 -41.816274)
				(arc
					(start 77.98689 -41.816782)
					(mid 78.053372 -41.898602)
					(end 78.108048 -41.98874)
				)
				(arc
					(start 78.404466 -41.98874)
					(mid 78.423371 -41.897045)
					(end 78.453488 -41.8084)
				)
				(arc
					(start 78.453488 -41.8084)
					(mid 78.822716 -41.360472)
					(end 78.5622 -41.879266)
				)
				(arc
					(start 78.5622 -41.879266)
					(mid 78.545122 -41.933343)
					(end 78.53299 -41.98874)
				)
				(arc
					(start 78.663038 -41.98874)
					(mid 79.046832 -41.605327)
					(end 78.663292 -41.22166)
				)
			)
		)
	)
	(zone
		(net "GND")
		(layer "In2.Cu")
		(hatch none 0.5)
		(connect_pads
			(clearance 0.5)
		)
		(min_thickness 0.25)
		(fill yes
			(thermal_gap 0.5)
			(thermal_bridge_width 0.5)
			(island_removal_mode 0)
		)
		(polygon
			(pts
				(xy 77.724508 -0.762) (xy 77.724254 -0.762254) (xy 75.691746 -0.762254) (xy 75.311 -1.143) (xy 75.311 -16.764)
				(xy 74.295 -17.78) (xy 63.119 -17.78) (xy 62.738 -18.161) (xy 62.738 -57.785) (xy 61.722 -58.801)
				(xy 29.718 -58.801) (xy 28.321 -60.198) (xy 28.321 -68.199) (xy 28.321 -77.343) (xy 26.797 -78.867)
				(xy 2.667 -78.867) (xy 0.889 -80.645) (xy 0.889 -213.36) (xy 1.27 -213.741) (xy 11.557 -213.741)
				(xy 14.351 -210.947) (xy 16.51 -210.947) (xy 17.145 -211.582) (xy 17.145 -215.646) (xy 18.034 -216.535)
				(xy 22.479 -216.535) (xy 22.987 -216.027) (xy 22.987 -211.963) (xy 23.622 -211.328) (xy 34.417 -211.328)
				(xy 35.687 -210.058) (xy 35.687 -204.343) (xy 36.195 -203.835) (xy 42.418 -203.835) (xy 46.9265 -208.3435)
				(xy 62.6745 -208.3435) (xy 68.961 -214.63) (xy 102.87 -214.63) (xy 106.553 -218.313) (xy 125.095 -218.313)
				(xy 126.873 -216.535) (xy 207.264 -216.535) (xy 211.074 -212.725) (xy 211.074 -209.931) (xy 210.439 -209.296)
				(xy 150.749 -209.296) (xy 143.764 -202.311) (xy 34.925 -202.311) (xy 34.798 -202.184) (xy 23.241 -202.184)
				(xy 21.971 -203.454) (xy 21.336 -203.454) (xy 20.32 -202.438) (xy 20.32 -200.914) (xy 20.701 -200.533)
				(xy 37.592 -200.533) (xy 37.846 -200.279) (xy 139.7 -200.279) (xy 140.462 -199.517) (xy 140.462 -194.691)
				(xy 137.541 -191.77) (xy 20.447 -191.77) (xy 20.32 -191.643) (xy 20.32 -190.627) (xy 20.447 -190.5)
				(xy 138.684 -190.5) (xy 144.272 -196.088) (xy 221.234 -196.088) (xy 221.996 -195.326) (xy 221.996 -190.246)
				(xy 221.488 -189.738) (xy 169.418 -189.738) (xy 160.655 -180.975) (xy 32.766 -180.975) (xy 20.32 -168.529)
				(xy 20.32 -165.735) (xy 27.432 -158.623) (xy 28.448 -157.607) (xy 28.448 -131.572) (xy 28.448 -110.744)
				(xy 28.448 -91.821) (xy 27.559 -90.932) (xy 27.6225 -90.8685) (xy 27.6225 -81.8515) (xy 28.1305 -81.3435)
				(xy 31.496 -77.978) (xy 31.496 -74.422) (xy 32.131 -73.787) (xy 37.084 -73.787) (xy 40.386 -77.089)
				(xy 40.386 -82.296) (xy 49.53 -91.44) (xy 70.866 -91.44) (xy 76.2 -86.106) (xy 81.661 -86.106) (xy 86.868 -80.899)
				(xy 88.773 -78.994) (xy 88.773 -76.581) (xy 69.342 -57.15) (xy 69.342 -43.053) (xy 70.231 -42.164)
				(xy 70.231 -28.829) (xy 74.168 -24.892) (xy 81.534 -24.892) (xy 86.36 -20.066) (xy 86.36 -4.064)
				(xy 87.249 -3.175) (xy 101.854 -3.175) (xy 102.235 -2.794) (xy 116.332 -2.794) (xy 126.492 -12.954)
				(xy 168.529 -12.954) (xy 171.831 -9.652) (xy 220.091 -9.652) (xy 221.234 -10.795) (xy 234.315 -10.795)
				(xy 252.476 -28.956) (xy 261.62 -28.956) (xy 263.271 -27.305) (xy 263.271 -19.812) (xy 263.271 -18.796)
				(xy 263.652 -18.415) (xy 272.796 -18.415) (xy 273.177 -18.796) (xy 273.177 -19.812) (xy 273.177 -27.559)
				(xy 273.558 -27.94) (xy 274.447 -27.94) (xy 275.463 -28.956) (xy 278.13 -31.623) (xy 278.13 -54.2798)
				(xy 281.686 -57.8358) (xy 281.686 -66.675) (xy 281.559 -66.802) (xy 281.559 -67.437) (xy 282.702 -68.58)
				(xy 287.02 -68.58) (xy 291.592 -64.008) (xy 291.592 -55.88) (xy 291.084 -55.372) (xy 282.575 -55.372)
				(xy 281.559 -54.356) (xy 281.559 -1.524) (xy 280.797254 -0.762254) (xy 114.3 -0.762254) (xy 114.299746 -0.762)
			)
		)
	)
	(zone
		(net "P12V")
		(layer "In2.Cu")
		(hatch none 0.5)
		(connect_pads
			(clearance 0.5)
		)
		(min_thickness 0.25)
		(fill yes
			(thermal_gap 0.5)
			(thermal_bridge_width 0.5)
			(island_removal_mode 0)
		)
		(polygon
			(pts
				(xy 343.662 -124.206) (xy 352.933 -124.206) (xy 354.838 -122.301) (xy 354.838 -89.154) (xy 354.838 -64.77)
				(xy 354.076 -64.008) (xy 346.075 -64.008) (xy 345.821 -64.262) (xy 345.821 -68.072) (xy 346.71 -68.961)
				(xy 350.266 -72.517) (xy 350.266 -90.043) (xy 350.901 -90.678) (xy 350.901 -99.568) (xy 350.266 -100.203)
				(xy 350.266 -112.649) (xy 345.948 -116.967) (xy 345.059 -117.856) (xy 343.662 -119.253) (xy 343.408 -119.507)
				(xy 343.408 -123.952)
			)
		)
	)
	(zone
		(net "GND")
		(layer "In2.Cu")
		(hatch none 0.5)
		(connect_pads
			(clearance 0.5)
		)
		(min_thickness 0.25)
		(fill yes
			(thermal_gap 0.5)
			(thermal_bridge_width 0.5)
			(island_removal_mode 0)
		)
		(polygon
			(pts
				(xy 307.720746 -0.762254) (xy 307.34 -1.143) (xy 307.34 -35.814) (xy 308.483 -36.957) (xy 338.582 -36.957)
				(xy 339.344 -37.719) (xy 339.344 -76.581) (xy 347.853 -85.09) (xy 347.853 -92.202) (xy 332.359 -107.696)
				(xy 332.359 -110.998) (xy 333.9465 -112.5855) (xy 333.9465 -115.5065) (xy 333.9465 -125.4125) (xy 343.535 -135.001)
				(xy 343.535 -142.24) (xy 343.535 -147.066) (xy 343.535 -155.448) (xy 343.281 -155.702) (xy 339.9155 -159.0675)
				(xy 339.9155 -214.6935) (xy 334.264 -220.345) (xy 323.723 -220.345) (xy 298.8945 -245.1735) (xy 261.4295 -245.1735)
				(xy 253.8984 -237.6424) (xy 252.3236 -237.6424) (xy 251.9172 -238.0488) (xy 251.9172 -245.5926)
				(xy 256.54 -250.2154) (xy 350.6216 -250.2154) (xy 354.838 -245.999) (xy 354.838 -124.968) (xy 354.457 -124.587)
				(xy 343.535 -124.587) (xy 343.027 -124.079) (xy 343.027 -119.38) (xy 346.583 -115.824) (xy 346.71 -115.824)
				(xy 350.012 -112.522) (xy 350.012 -99.822) (xy 350.52 -99.314) (xy 350.52 -90.805) (xy 350.012 -90.297)
				(xy 350.012 -76.073) (xy 345.44 -71.501) (xy 345.44 -64.008) (xy 345.821 -63.627) (xy 354.076 -63.627)
				(xy 354.838 -62.865) (xy 354.838 -1.143254) (xy 354.457 -0.762254)
			)
		)
	)
	(zone
		(net "P1V53_STBY")
		(layer "In2.Cu")
		(hatch none 0.5)
		(connect_pads
			(clearance 0.5)
		)
		(min_thickness 0.25)
		(fill yes
			(thermal_gap 0.5)
			(thermal_bridge_width 0.5)
			(island_removal_mode 0)
		)
		(polygon
			(pts
				(xy 290.576 -180.213) (xy 294.259 -180.213) (xy 294.386 -180.086) (xy 294.386 -179.578) (xy 293.751 -178.943)
				(xy 290.576 -178.943) (xy 290.322 -179.197) (xy 290.322 -179.959)
			)
		)
	)
	(zone
		(layers "In2.Cu" "In5.Cu")
		(hatch none 0.5)
		(connect_pads
			(clearance 0)
		)
		(min_thickness 0.25)
		(keepout
			(tracks not_allowed)
			(vias allowed)
			(pads allowed)
			(copperpour not_allowed)
			(footprints allowed)
		)
		(placement
			(enabled no)
			(sheetname "")
		)
		(fill yes
			(thermal_gap 0.5)
			(thermal_bridge_width 0.5)
			(island_removal_mode 0)
		)
		(polygon
			(pts
				(arc
					(start 13.52931 -98.086672)
					(mid 13.12545 -98.448876)
					(end 13.487654 -98.852736)
				)
				(xy 14.4272 -98.903536)
				(arc
					(start 14.427454 -98.903536)
					(mid 14.729093 -98.781833)
					(end 14.828774 -98.472244)
				)
				(arc
					(start 14.736318 -98.472244)
					(mid 14.448282 -98.812555)
					(end 14.160246 -98.472244)
				)
				(arc
					(start 13.800582 -98.472244)
					(mid 13.508482 -98.761815)
					(end 13.216382 -98.472244)
				)
				(arc
					(start 13.216382 -98.469704)
					(mid 13.508482 -98.177604)
					(end 13.800582 -98.469704)
				)
				(arc
					(start 14.160754 -98.469704)
					(mid 14.448282 -98.228523)
					(end 14.73581 -98.469704)
				)
				(arc
					(start 14.82852 -98.469704)
					(mid 14.708688 -98.238812)
					(end 14.46911 -98.137472)
				)
			)
		)
	)
	(zone
		(layers "In2.Cu" "In5.Cu")
		(hatch none 0.5)
		(connect_pads
			(clearance 0)
		)
		(min_thickness 0.25)
		(keepout
			(tracks not_allowed)
			(vias allowed)
			(pads allowed)
			(copperpour not_allowed)
			(footprints allowed)
		)
		(placement
			(enabled no)
			(sheetname "")
		)
		(fill yes
			(thermal_gap 0.5)
			(thermal_bridge_width 0.5)
			(island_removal_mode 0)
		)
		(polygon
			(pts
				(arc
					(start 11.147044 -98.109786)
					(mid 10.762742 -98.492564)
					(end 11.14552 -98.876866)
				)
				(arc
					(start 12.059666 -98.878644)
					(mid 12.331257 -98.766937)
					(end 12.444222 -98.495866)
				)
				(arc
					(start 12.352782 -98.495866)
					(mid 12.060682 -98.787205)
					(end 11.768582 -98.495866)
				)
				(arc
					(start 11.438382 -98.495866)
					(mid 11.146282 -98.785437)
					(end 10.854182 -98.495866)
				)
				(arc
					(start 10.854182 -98.493326)
					(mid 11.146282 -98.201226)
					(end 11.438382 -98.493326)
				)
				(arc
					(start 11.768582 -98.493326)
					(mid 12.060682 -98.202999)
					(end 12.352782 -98.493326)
				)
				(arc
					(start 12.444222 -98.493326)
					(mid 12.331529 -98.223538)
					(end 12.061444 -98.111564)
				)
			)
		)
	)
	(zone
		(layers "In2.Cu" "In5.Cu")
		(hatch none 0.5)
		(connect_pads
			(clearance 0)
		)
		(min_thickness 0.25)
		(keepout
			(tracks not_allowed)
			(vias allowed)
			(pads allowed)
			(copperpour not_allowed)
			(footprints allowed)
		)
		(placement
			(enabled no)
			(sheetname "")
		)
		(fill yes
			(thermal_gap 0.5)
			(thermal_bridge_width 0.5)
			(island_removal_mode 0)
		)
		(polygon
			(pts
				(arc
					(start 85.37194 -32.884872)
					(mid 84.9884 -32.501332)
					(end 84.60486 -32.884872)
				)
				(arc
					(start 84.60486 -33.789874)
					(mid 84.98713 -34.173412)
					(end 85.37194 -33.792414)
				)
				(arc
					(start 85.2805 -33.792414)
					(mid 84.9884 -34.081985)
					(end 84.6963 -33.792414)
				)
				(arc
					(start 84.6963 -33.789874)
					(mid 84.9884 -33.497774)
					(end 85.2805 -33.789874)
				)
				(xy 85.37194 -33.789874) (xy 85.37194 -32.887412)
				(arc
					(start 85.2805 -32.887412)
					(mid 84.9884 -33.176983)
					(end 84.6963 -32.887412)
				)
				(arc
					(start 84.6963 -32.884872)
					(mid 84.9884 -32.592772)
					(end 85.2805 -32.884872)
				)
			)
		)
	)
	(zone
		(layers "In2.Cu" "In5.Cu")
		(hatch none 0.5)
		(connect_pads
			(clearance 0)
		)
		(min_thickness 0.25)
		(keepout
			(tracks not_allowed)
			(vias allowed)
			(pads allowed)
			(copperpour not_allowed)
			(footprints allowed)
		)
		(placement
			(enabled no)
			(sheetname "")
		)
		(fill yes
			(thermal_gap 0.5)
			(thermal_bridge_width 0.5)
			(island_removal_mode 0)
		)
		(polygon
			(pts
				(arc
					(start 49.373536 -86.769194)
					(mid 48.989996 -86.385654)
					(end 48.606456 -86.769194)
				)
				(arc
					(start 48.606456 -87.746078)
					(mid 48.988726 -88.129616)
					(end 49.373536 -87.748618)
				)
				(arc
					(start 49.282096 -87.748618)
					(mid 48.989996 -88.038189)
					(end 48.697896 -87.748618)
				)
				(arc
					(start 48.697896 -87.746078)
					(mid 48.989996 -87.453978)
					(end 49.282096 -87.746078)
				)
				(xy 49.373536 -87.746078) (xy 49.373536 -86.771734)
				(arc
					(start 49.282096 -86.771734)
					(mid 48.989996 -87.061305)
					(end 48.697896 -86.771734)
				)
				(arc
					(start 48.697896 -86.769194)
					(mid 48.989996 -86.477094)
					(end 49.282096 -86.769194)
				)
			)
		)
	)
	(zone
		(layers "In2.Cu" "In5.Cu")
		(hatch none 0.5)
		(connect_pads
			(clearance 0)
		)
		(min_thickness 0.25)
		(keepout
			(tracks not_allowed)
			(vias allowed)
			(pads allowed)
			(copperpour not_allowed)
			(footprints allowed)
		)
		(placement
			(enabled no)
			(sheetname "")
		)
		(fill yes
			(thermal_gap 0.5)
			(thermal_bridge_width 0.5)
			(island_removal_mode 0)
		)
		(polygon
			(pts
				(arc
					(start 163.946332 -76.64196)
					(mid 163.562538 -77.025373)
					(end 163.946078 -77.40904)
				)
				(arc
					(start 164.928042 -77.40904)
					(mid 165.198346 -77.2976)
					(end 165.311582 -77.02804)
				)
				(arc
					(start 165.220142 -77.02804)
					(mid 164.928042 -77.317611)
					(end 164.635942 -77.02804)
				)
				(arc
					(start 164.238178 -77.02804)
					(mid 163.946078 -77.317611)
					(end 163.653978 -77.02804)
				)
				(arc
					(start 163.653978 -77.0255)
					(mid 163.946078 -76.7334)
					(end 164.238178 -77.0255)
				)
				(arc
					(start 164.635942 -77.0255)
					(mid 164.928042 -76.7334)
					(end 165.220142 -77.0255)
				)
				(arc
					(start 165.311582 -77.0255)
					(mid 165.199246 -76.754296)
					(end 164.928042 -76.64196)
				)
			)
		)
	)
	(zone
		(layers "In2.Cu" "In5.Cu")
		(hatch none 0.5)
		(connect_pads
			(clearance 0)
		)
		(min_thickness 0.25)
		(keepout
			(tracks not_allowed)
			(vias allowed)
			(pads allowed)
			(copperpour not_allowed)
			(footprints allowed)
		)
		(placement
			(enabled no)
			(sheetname "")
		)
		(fill yes
			(thermal_gap 0.5)
			(thermal_bridge_width 0.5)
			(island_removal_mode 0)
		)
		(polygon
			(pts
				(arc
					(start 159.947102 -76.64196)
					(mid 159.563308 -77.025373)
					(end 159.946848 -77.40904)
				)
				(arc
					(start 160.928812 -77.40904)
					(mid 161.199116 -77.2976)
					(end 161.312352 -77.02804)
				)
				(arc
					(start 161.220912 -77.02804)
					(mid 160.928812 -77.317611)
					(end 160.636712 -77.02804)
				)
				(arc
					(start 160.238948 -77.02804)
					(mid 159.946848 -77.317611)
					(end 159.654748 -77.02804)
				)
				(arc
					(start 159.654748 -77.0255)
					(mid 159.946848 -76.7334)
					(end 160.238948 -77.0255)
				)
				(arc
					(start 160.636712 -77.0255)
					(mid 160.928812 -76.7334)
					(end 161.220912 -77.0255)
				)
				(arc
					(start 161.312352 -77.0255)
					(mid 161.200016 -76.754296)
					(end 160.928812 -76.64196)
				)
			)
		)
	)
	(zone
		(layers "In2.Cu" "In5.Cu")
		(hatch none 0.5)
		(connect_pads
			(clearance 0)
		)
		(min_thickness 0.25)
		(keepout
			(tracks not_allowed)
			(vias allowed)
			(pads allowed)
			(copperpour not_allowed)
			(footprints allowed)
		)
		(placement
			(enabled no)
			(sheetname "")
		)
		(fill yes
			(thermal_gap 0.5)
			(thermal_bridge_width 0.5)
			(island_removal_mode 0)
		)
		(polygon
			(pts
				(arc
					(start 319.139316 -68.216018)
					(mid 318.755776 -67.832478)
					(end 318.372236 -68.216018)
				)
				(arc
					(start 318.372236 -69.197982)
					(mid 318.754506 -69.58152)
					(end 319.139316 -69.200522)
				)
				(arc
					(start 319.047876 -69.200522)
					(mid 318.755776 -69.490093)
					(end 318.463676 -69.200522)
				)
				(arc
					(start 318.463676 -69.197982)
					(mid 318.755776 -68.905882)
					(end 319.047876 -69.197982)
				)
				(xy 319.139316 -69.197982) (xy 319.139316 -68.218558)
				(arc
					(start 319.047876 -68.218558)
					(mid 318.755776 -68.508129)
					(end 318.463676 -68.218558)
				)
				(arc
					(start 318.463676 -68.216018)
					(mid 318.755776 -67.923918)
					(end 319.047876 -68.216018)
				)
			)
		)
	)
	(zone
		(layers "In2.Cu" "In5.Cu")
		(hatch none 0.5)
		(connect_pads
			(clearance 0)
		)
		(min_thickness 0.25)
		(keepout
			(tracks not_allowed)
			(vias allowed)
			(pads allowed)
			(copperpour not_allowed)
			(footprints allowed)
		)
		(placement
			(enabled no)
			(sheetname "")
		)
		(fill yes
			(thermal_gap 0.5)
			(thermal_bridge_width 0.5)
			(island_removal_mode 0)
		)
		(polygon
			(pts
				(arc
					(start 18.258536 -98.162364)
					(mid 17.874742 -98.545777)
					(end 18.258282 -98.929444)
				)
				(arc
					(start 19.325082 -98.929444)
					(mid 19.595386 -98.818004)
					(end 19.708622 -98.548444)
				)
				(arc
					(start 19.617182 -98.548444)
					(mid 19.325082 -98.838015)
					(end 19.032982 -98.548444)
				)
				(arc
					(start 18.550382 -98.548444)
					(mid 18.258282 -98.838015)
					(end 17.966182 -98.548444)
				)
				(arc
					(start 17.966182 -98.545904)
					(mid 18.258282 -98.253804)
					(end 18.550382 -98.545904)
				)
				(arc
					(start 19.032982 -98.545904)
					(mid 19.325082 -98.253804)
					(end 19.617182 -98.545904)
				)
				(arc
					(start 19.708622 -98.545904)
					(mid 19.596286 -98.2747)
					(end 19.325082 -98.162364)
				)
			)
		)
	)
	(zone
		(layers "In2.Cu" "In5.Cu")
		(hatch none 0.5)
		(connect_pads
			(clearance 0)
		)
		(min_thickness 0.25)
		(keepout
			(tracks not_allowed)
			(vias allowed)
			(pads allowed)
			(copperpour not_allowed)
			(footprints allowed)
		)
		(placement
			(enabled no)
			(sheetname "")
		)
		(fill yes
			(thermal_gap 0.5)
			(thermal_bridge_width 0.5)
			(island_removal_mode 0)
		)
		(polygon
			(pts
				(arc
					(start 53.311298 -74.523346)
					(mid 52.927758 -74.906886)
					(end 53.311298 -75.290426)
				)
				(arc
					(start 54.287928 -75.290426)
					(mid 54.558396 -75.179076)
					(end 54.671722 -74.909426)
				)
				(arc
					(start 54.580282 -74.909426)
					(mid 54.288182 -75.198997)
					(end 53.996082 -74.909426)
				)
				(arc
					(start 53.603398 -74.909426)
					(mid 53.311298 -75.198997)
					(end 53.019198 -74.909426)
				)
				(arc
					(start 53.019198 -74.906886)
					(mid 53.311298 -74.614786)
					(end 53.603398 -74.906886)
				)
				(arc
					(start 53.996082 -74.906886)
					(mid 54.288182 -74.614786)
					(end 54.580282 -74.906886)
				)
				(arc
					(start 54.671722 -74.906886)
					(mid 54.559386 -74.635682)
					(end 54.288182 -74.523346)
				)
			)
		)
	)
	(zone
		(layers "In2.Cu" "In5.Cu")
		(hatch none 0.5)
		(connect_pads
			(clearance 0)
		)
		(min_thickness 0.25)
		(keepout
			(tracks not_allowed)
			(vias allowed)
			(pads allowed)
			(copperpour not_allowed)
			(footprints allowed)
		)
		(placement
			(enabled no)
			(sheetname "")
		)
		(fill yes
			(thermal_gap 0.5)
			(thermal_bridge_width 0.5)
			(island_removal_mode 0)
		)
		(polygon
			(pts
				(arc
					(start 81.61274 -36.335208)
					(mid 81.2292 -35.951668)
					(end 80.84566 -36.335208)
				)
				(arc
					(start 80.84566 -37.312092)
					(mid 81.22793 -37.69563)
					(end 81.61274 -37.314632)
				)
				(arc
					(start 81.5213 -37.314632)
					(mid 81.2292 -37.604203)
					(end 80.9371 -37.314632)
				)
				(arc
					(start 80.9371 -37.312092)
					(mid 81.2292 -37.019992)
					(end 81.5213 -37.312092)
				)
				(xy 81.61274 -37.312092) (xy 81.61274 -36.337748)
				(arc
					(start 81.5213 -36.337748)
					(mid 81.2292 -36.627319)
					(end 80.9371 -36.337748)
				)
				(arc
					(start 80.9371 -36.335208)
					(mid 81.2292 -36.043108)
					(end 81.5213 -36.335208)
				)
			)
		)
	)
	(zone
		(layers "In2.Cu" "In5.Cu")
		(hatch none 0.5)
		(connect_pads
			(clearance 0)
		)
		(min_thickness 0.25)
		(keepout
			(tracks not_allowed)
			(vias allowed)
			(pads allowed)
			(copperpour not_allowed)
			(footprints allowed)
		)
		(placement
			(enabled no)
			(sheetname "")
		)
		(fill yes
			(thermal_gap 0.5)
			(thermal_bridge_width 0.5)
			(island_removal_mode 0)
		)
		(polygon
			(pts
				(arc
					(start 42.111676 -74.370946)
					(mid 41.727882 -74.754359)
					(end 42.111422 -75.138026)
				)
				(arc
					(start 43.088306 -75.138026)
					(mid 43.35861 -75.026586)
					(end 43.471846 -74.757026)
				)
				(arc
					(start 43.380406 -74.757026)
					(mid 43.088306 -75.046597)
					(end 42.796206 -74.757026)
				)
				(arc
					(start 42.403522 -74.757026)
					(mid 42.111422 -75.046597)
					(end 41.819322 -74.757026)
				)
				(arc
					(start 41.819322 -74.754486)
					(mid 42.111422 -74.462386)
					(end 42.403522 -74.754486)
				)
				(arc
					(start 42.796206 -74.754486)
					(mid 43.088306 -74.462386)
					(end 43.380406 -74.754486)
				)
				(arc
					(start 43.471846 -74.754486)
					(mid 43.35951 -74.483282)
					(end 43.088306 -74.370946)
				)
			)
		)
	)
	(zone
		(layers "In2.Cu" "In5.Cu")
		(hatch none 0.5)
		(connect_pads
			(clearance 0)
		)
		(min_thickness 0.25)
		(keepout
			(tracks not_allowed)
			(vias allowed)
			(pads allowed)
			(copperpour not_allowed)
			(footprints allowed)
		)
		(placement
			(enabled no)
			(sheetname "")
		)
		(fill yes
			(thermal_gap 0.5)
			(thermal_bridge_width 0.5)
			(island_removal_mode 0)
		)
		(polygon
			(pts
				(arc
					(start 167.946832 -76.64196)
					(mid 167.563038 -77.025373)
					(end 167.946578 -77.40904)
				)
				(arc
					(start 168.928542 -77.40904)
					(mid 169.198846 -77.2976)
					(end 169.312082 -77.02804)
				)
				(arc
					(start 169.220642 -77.02804)
					(mid 168.928542 -77.317611)
					(end 168.636442 -77.02804)
				)
				(arc
					(start 168.238678 -77.02804)
					(mid 167.946578 -77.317611)
					(end 167.654478 -77.02804)
				)
				(arc
					(start 167.654478 -77.0255)
					(mid 167.946578 -76.7334)
					(end 168.238678 -77.0255)
				)
				(arc
					(start 168.636442 -77.0255)
					(mid 168.928542 -76.7334)
					(end 169.220642 -77.0255)
				)
				(arc
					(start 169.312082 -77.0255)
					(mid 169.199746 -76.754296)
					(end 168.928542 -76.64196)
				)
			)
		)
	)
	(zone
		(layers "In2.Cu" "In5.Cu")
		(hatch none 0.5)
		(connect_pads
			(clearance 0)
		)
		(min_thickness 0.25)
		(keepout
			(tracks not_allowed)
			(vias allowed)
			(pads allowed)
			(copperpour not_allowed)
			(footprints allowed)
		)
		(placement
			(enabled no)
			(sheetname "")
		)
		(fill yes
			(thermal_gap 0.5)
			(thermal_bridge_width 0.5)
			(island_removal_mode 0)
		)
		(polygon
			(pts
				(xy 15.95755 -98.109278) (xy 15.957296 -98.109532)
				(arc
					(start 15.957296 -98.111818)
					(mid 15.563596 -98.48469)
					(end 15.936468 -98.87839)
				)
				(xy 15.936468 -98.88093) (xy 16.876268 -98.90633)
				(arc
					(start 16.876268 -98.90379)
					(mid 17.162174 -98.787189)
					(end 17.26946 -98.497644)
				)
				(arc
					(start 17.177766 -98.497644)
					(mid 16.886682 -98.812484)
					(end 16.595598 -98.497644)
				)
				(arc
					(start 16.238982 -98.497644)
					(mid 15.946882 -98.787215)
					(end 15.654782 -98.497644)
				)
				(arc
					(start 15.654782 -98.495104)
					(mid 15.946882 -98.203004)
					(end 16.238982 -98.495104)
				)
				(arc
					(start 16.595598 -98.495104)
					(mid 16.886682 -98.228314)
					(end 17.177766 -98.495104)
				)
				(arc
					(start 17.26946 -98.495104)
					(mid 17.152588 -98.243993)
					(end 16.897096 -98.137218)
				)
				(xy 16.897096 -98.134678)
			)
		)
	)
	(zone
		(layers "In2.Cu" "In5.Cu")
		(hatch none 0.5)
		(connect_pads
			(clearance 0)
		)
		(min_thickness 0.25)
		(keepout
			(tracks not_allowed)
			(vias allowed)
			(pads allowed)
			(copperpour not_allowed)
			(footprints allowed)
		)
		(placement
			(enabled no)
			(sheetname "")
		)
		(fill yes
			(thermal_gap 0.5)
			(thermal_bridge_width 0.5)
			(island_removal_mode 0)
		)
		(polygon
			(pts
				(arc
					(start 199.946768 -76.64196)
					(mid 199.563228 -77.0255)
					(end 199.946768 -77.40904)
				)
				(arc
					(start 200.928478 -77.40904)
					(mid 201.198946 -77.29769)
					(end 201.312272 -77.02804)
				)
				(arc
					(start 201.220832 -77.02804)
					(mid 200.928732 -77.317611)
					(end 200.636632 -77.02804)
				)
				(arc
					(start 200.238868 -77.02804)
					(mid 199.946768 -77.317611)
					(end 199.654668 -77.02804)
				)
				(arc
					(start 199.654668 -77.0255)
					(mid 199.946768 -76.7334)
					(end 200.238868 -77.0255)
				)
				(arc
					(start 200.636632 -77.0255)
					(mid 200.928732 -76.7334)
					(end 201.220832 -77.0255)
				)
				(arc
					(start 201.312272 -77.0255)
					(mid 201.199936 -76.754296)
					(end 200.928732 -76.64196)
				)
			)
		)
	)
	(zone
		(layers "In2.Cu" "In5.Cu")
		(hatch none 0.5)
		(connect_pads
			(clearance 0)
		)
		(min_thickness 0.25)
		(keepout
			(tracks not_allowed)
			(vias allowed)
			(pads allowed)
			(copperpour not_allowed)
			(footprints allowed)
		)
		(placement
			(enabled no)
			(sheetname "")
		)
		(fill yes
			(thermal_gap 0.5)
			(thermal_bridge_width 0.5)
			(island_removal_mode 0)
		)
		(polygon
			(pts
				(arc
					(start 83.46694 -34.618676)
					(mid 83.0834 -34.235136)
					(end 82.69986 -34.618676)
				)
				(arc
					(start 82.69986 -35.523678)
					(mid 83.08213 -35.907216)
					(end 83.46694 -35.526218)
				)
				(arc
					(start 83.3755 -35.526218)
					(mid 83.0834 -35.815789)
					(end 82.7913 -35.526218)
				)
				(arc
					(start 82.7913 -35.523678)
					(mid 83.0834 -35.231578)
					(end 83.3755 -35.523678)
				)
				(xy 83.46694 -35.523678) (xy 83.46694 -34.621216)
				(arc
					(start 83.3755 -34.621216)
					(mid 83.0834 -34.910787)
					(end 82.7913 -34.621216)
				)
				(arc
					(start 82.7913 -34.618676)
					(mid 83.0834 -34.326576)
					(end 83.3755 -34.618676)
				)
			)
		)
	)
	(zone
		(layers "In2.Cu" "In5.Cu")
		(hatch none 0.5)
		(connect_pads
			(clearance 0)
		)
		(min_thickness 0.25)
		(keepout
			(tracks not_allowed)
			(vias allowed)
			(pads allowed)
			(copperpour not_allowed)
			(footprints allowed)
		)
		(placement
			(enabled no)
			(sheetname "")
		)
		(fill yes
			(thermal_gap 0.5)
			(thermal_bridge_width 0.5)
			(island_removal_mode 0)
		)
		(polygon
			(pts
				(arc
					(start 50.911506 -74.523346)
					(mid 50.527966 -74.906886)
					(end 50.911506 -75.290426)
				)
				(arc
					(start 51.888136 -75.290426)
					(mid 52.158604 -75.179076)
					(end 52.27193 -74.909426)
				)
				(arc
					(start 52.18049 -74.909426)
					(mid 51.88839 -75.198997)
					(end 51.59629 -74.909426)
				)
				(arc
					(start 51.203606 -74.909426)
					(mid 50.911506 -75.198997)
					(end 50.619406 -74.909426)
				)
				(arc
					(start 50.619406 -74.906886)
					(mid 50.911506 -74.614786)
					(end 51.203606 -74.906886)
				)
				(arc
					(start 51.59629 -74.906886)
					(mid 51.88839 -74.614786)
					(end 52.18049 -74.906886)
				)
				(arc
					(start 52.27193 -74.906886)
					(mid 52.159594 -74.635682)
					(end 51.88839 -74.523346)
				)
			)
		)
	)
	(zone
		(layers "In2.Cu" "In5.Cu")
		(hatch none 0.5)
		(connect_pads
			(clearance 0)
		)
		(min_thickness 0.25)
		(keepout
			(tracks not_allowed)
			(vias allowed)
			(pads allowed)
			(copperpour not_allowed)
			(footprints allowed)
		)
		(placement
			(enabled no)
			(sheetname "")
		)
		(fill yes
			(thermal_gap 0.5)
			(thermal_bridge_width 0.5)
			(island_removal_mode 0)
		)
		(polygon
			(pts
				(arc
					(start 39.975536 -79.746094)
					(mid 39.591996 -79.362554)
					(end 39.208456 -79.746094)
				)
				(arc
					(start 39.208456 -80.722978)
					(mid 39.590726 -81.106516)
					(end 39.975536 -80.725518)
				)
				(arc
					(start 39.884096 -80.725518)
					(mid 39.591996 -81.015089)
					(end 39.299896 -80.725518)
				)
				(arc
					(start 39.299896 -80.722978)
					(mid 39.591996 -80.430878)
					(end 39.884096 -80.722978)
				)
				(xy 39.975536 -80.722978) (xy 39.975536 -79.748634)
				(arc
					(start 39.884096 -79.748634)
					(mid 39.591996 -80.038205)
					(end 39.299896 -79.748634)
				)
				(arc
					(start 39.299896 -79.746094)
					(mid 39.591996 -79.453994)
					(end 39.884096 -79.746094)
				)
			)
		)
	)
	(zone
		(layers "In2.Cu" "In5.Cu")
		(hatch none 0.5)
		(connect_pads
			(clearance 0)
		)
		(min_thickness 0.25)
		(keepout
			(tracks not_allowed)
			(vias allowed)
			(pads allowed)
			(copperpour not_allowed)
			(footprints allowed)
		)
		(placement
			(enabled no)
			(sheetname "")
		)
		(fill yes
			(thermal_gap 0.5)
			(thermal_bridge_width 0.5)
			(island_removal_mode 0)
		)
		(polygon
			(pts
				(arc
					(start 49.373536 -83.937094)
					(mid 48.989996 -83.553554)
					(end 48.606456 -83.937094)
				)
				(arc
					(start 48.606456 -84.913724)
					(mid 48.988599 -85.297516)
					(end 49.373536 -84.916518)
				)
				(arc
					(start 49.282096 -84.916518)
					(mid 48.989996 -85.206089)
					(end 48.697896 -84.916518)
				)
				(arc
					(start 48.697896 -84.913978)
					(mid 48.989996 -84.621878)
					(end 49.282096 -84.913978)
				)
				(xy 49.373536 -84.913978) (xy 49.373536 -83.939634)
				(arc
					(start 49.282096 -83.939634)
					(mid 48.989996 -84.229205)
					(end 48.697896 -83.939634)
				)
				(arc
					(start 48.697896 -83.937094)
					(mid 48.989996 -83.644994)
					(end 49.282096 -83.937094)
				)
			)
		)
	)
	(zone
		(layers "In2.Cu" "In5.Cu")
		(hatch none 0.5)
		(connect_pads
			(clearance 0)
		)
		(min_thickness 0.25)
		(keepout
			(tracks not_allowed)
			(vias allowed)
			(pads allowed)
			(copperpour not_allowed)
			(footprints allowed)
		)
		(placement
			(enabled no)
			(sheetname "")
		)
		(fill yes
			(thermal_gap 0.5)
			(thermal_bridge_width 0.5)
			(island_removal_mode 0)
		)
		(polygon
			(pts
				(arc
					(start 84.413852 -37.734494)
					(mid 84.04606 -37.386514)
					(end 83.69808 -37.754306)
				)
				(xy 83.69554 -37.754306) (xy 83.723734 -38.770306) (xy 83.723988 -38.77056)
				(arc
					(start 83.726274 -38.77056)
					(mid 84.087844 -39.118658)
					(end 84.4423 -38.763194)
				)
				(arc
					(start 84.35086 -38.763194)
					(mid 84.08416 -39.027366)
					(end 83.81746 -38.763194)
				)
				(arc
					(start 83.81746 -38.760654)
					(mid 84.08416 -38.493954)
					(end 84.35086 -38.760654)
				)
				(xy 84.4423 -38.760654) (xy 84.442046 -38.750748) (xy 84.444586 -38.750748) (xy 84.416646 -37.74694)
				(arc
					(start 84.322666 -37.74694)
					(mid 84.055966 -38.011112)
					(end 83.789266 -37.74694)
				)
				(arc
					(start 83.789266 -37.7444)
					(mid 84.055966 -37.4777)
					(end 84.322666 -37.7444)
				)
				(xy 84.416646 -37.7444) (xy 84.416392 -37.734494)
			)
		)
	)
	(zone
		(layers "In2.Cu" "In5.Cu")
		(hatch none 0.5)
		(connect_pads
			(clearance 0)
		)
		(min_thickness 0.25)
		(keepout
			(tracks not_allowed)
			(vias allowed)
			(pads allowed)
			(copperpour not_allowed)
			(footprints allowed)
		)
		(placement
			(enabled no)
			(sheetname "")
		)
		(fill yes
			(thermal_gap 0.5)
			(thermal_bridge_width 0.5)
			(island_removal_mode 0)
		)
		(polygon
			(pts
				(arc
					(start 203.947522 -76.64196)
					(mid 203.563728 -77.025373)
					(end 203.947268 -77.40904)
				)
				(arc
					(start 204.929232 -77.40904)
					(mid 205.199536 -77.2976)
					(end 205.312772 -77.02804)
				)
				(arc
					(start 205.221332 -77.02804)
					(mid 204.929232 -77.317611)
					(end 204.637132 -77.02804)
				)
				(arc
					(start 204.239368 -77.02804)
					(mid 203.947268 -77.317611)
					(end 203.655168 -77.02804)
				)
				(arc
					(start 203.655168 -77.0255)
					(mid 203.947268 -76.7334)
					(end 204.239368 -77.0255)
				)
				(arc
					(start 204.637132 -77.0255)
					(mid 204.929232 -76.7334)
					(end 205.221332 -77.0255)
				)
				(arc
					(start 205.312772 -77.0255)
					(mid 205.200436 -76.754296)
					(end 204.929232 -76.64196)
				)
			)
		)
	)
	(zone
		(layers "In2.Cu" "In5.Cu")
		(hatch none 0.5)
		(connect_pads
			(clearance 0)
		)
		(min_thickness 0.25)
		(keepout
			(tracks not_allowed)
			(vias allowed)
			(pads allowed)
			(copperpour not_allowed)
			(footprints allowed)
		)
		(placement
			(enabled no)
			(sheetname "")
		)
		(fill yes
			(thermal_gap 0.5)
			(thermal_bridge_width 0.5)
			(island_removal_mode 0)
		)
		(polygon
			(pts
				(arc
					(start 195.947792 -76.64196)
					(mid 195.563998 -77.025373)
					(end 195.947538 -77.40904)
				)
				(arc
					(start 196.929502 -77.40904)
					(mid 197.199806 -77.2976)
					(end 197.313042 -77.02804)
				)
				(arc
					(start 197.221602 -77.02804)
					(mid 196.929502 -77.317611)
					(end 196.637402 -77.02804)
				)
				(arc
					(start 196.239638 -77.02804)
					(mid 195.947538 -77.317611)
					(end 195.655438 -77.02804)
				)
				(arc
					(start 195.655438 -77.0255)
					(mid 195.947538 -76.7334)
					(end 196.239638 -77.0255)
				)
				(arc
					(start 196.637402 -77.0255)
					(mid 196.929502 -76.7334)
					(end 197.221602 -77.0255)
				)
				(arc
					(start 197.313042 -77.0255)
					(mid 197.200706 -76.754296)
					(end 196.929502 -76.64196)
				)
			)
		)
	)
	(zone
		(layers "In2.Cu" "In5.Cu")
		(hatch none 0.5)
		(connect_pads
			(clearance 0)
		)
		(min_thickness 0.25)
		(keepout
			(tracks not_allowed)
			(vias allowed)
			(pads allowed)
			(copperpour not_allowed)
			(footprints allowed)
		)
		(placement
			(enabled no)
			(sheetname "")
		)
		(fill yes
			(thermal_gap 0.5)
			(thermal_bridge_width 0.5)
			(island_removal_mode 0)
		)
		(polygon
			(pts
				(arc
					(start 155.946602 -76.64196)
					(mid 155.562808 -77.025373)
					(end 155.946348 -77.40904)
				)
				(arc
					(start 156.928312 -77.40904)
					(mid 157.198616 -77.2976)
					(end 157.311852 -77.02804)
				)
				(arc
					(start 157.220412 -77.02804)
					(mid 156.928312 -77.317611)
					(end 156.636212 -77.02804)
				)
				(arc
					(start 156.238448 -77.02804)
					(mid 155.946348 -77.317611)
					(end 155.654248 -77.02804)
				)
				(arc
					(start 155.654248 -77.0255)
					(mid 155.946348 -76.7334)
					(end 156.238448 -77.0255)
				)
				(arc
					(start 156.636212 -77.0255)
					(mid 156.928312 -76.7334)
					(end 157.220412 -77.0255)
				)
				(arc
					(start 157.311852 -77.0255)
					(mid 157.199516 -76.754296)
					(end 156.928312 -76.64196)
				)
			)
		)
	)
	(zone
		(layers "In2.Cu" "In5.Cu")
		(hatch none 0.5)
		(connect_pads
			(clearance 0)
		)
		(min_thickness 0.25)
		(keepout
			(tracks not_allowed)
			(vias allowed)
			(pads allowed)
			(copperpour not_allowed)
			(footprints allowed)
		)
		(placement
			(enabled no)
			(sheetname "")
		)
		(fill yes
			(thermal_gap 0.5)
			(thermal_bridge_width 0.5)
			(island_removal_mode 0)
		)
		(polygon
			(pts
				(arc
					(start 44.511468 -74.523346)
					(mid 44.127928 -74.906886)
					(end 44.511468 -75.290426)
				)
				(arc
					(start 45.488098 -75.290426)
					(mid 45.758566 -75.179076)
					(end 45.871892 -74.909426)
				)
				(arc
					(start 45.780452 -74.909426)
					(mid 45.488352 -75.198997)
					(end 45.196252 -74.909426)
				)
				(arc
					(start 44.803568 -74.909426)
					(mid 44.511468 -75.198997)
					(end 44.219368 -74.909426)
				)
				(arc
					(start 44.219368 -74.906886)
					(mid 44.511468 -74.614786)
					(end 44.803568 -74.906886)
				)
				(arc
					(start 45.196252 -74.906886)
					(mid 45.488352 -74.614786)
					(end 45.780452 -74.906886)
				)
				(arc
					(start 45.871892 -74.906886)
					(mid 45.759556 -74.635682)
					(end 45.488352 -74.523346)
				)
			)
		)
	)
	(zone
		(layers "In2.Cu" "In5.Cu")
		(hatch none 0.5)
		(connect_pads
			(clearance 0)
		)
		(min_thickness 0.25)
		(keepout
			(tracks not_allowed)
			(vias allowed)
			(pads allowed)
			(copperpour not_allowed)
			(footprints allowed)
		)
		(placement
			(enabled no)
			(sheetname "")
		)
		(fill yes
			(thermal_gap 0.5)
			(thermal_bridge_width 0.5)
			(island_removal_mode 0)
		)
		(polygon
			(pts
				(arc
					(start 39.975536 -82.070194)
					(mid 39.591996 -81.686654)
					(end 39.208456 -82.070194)
				)
				(arc
					(start 39.208456 -83.046824)
					(mid 39.590599 -83.430616)
					(end 39.975536 -83.049618)
				)
				(arc
					(start 39.884096 -83.049618)
					(mid 39.591996 -83.339189)
					(end 39.299896 -83.049618)
				)
				(arc
					(start 39.299896 -83.047078)
					(mid 39.591996 -82.754978)
					(end 39.884096 -83.047078)
				)
				(xy 39.975536 -83.047078) (xy 39.975536 -82.072734)
				(arc
					(start 39.884096 -82.072734)
					(mid 39.591996 -82.362305)
					(end 39.299896 -82.072734)
				)
				(arc
					(start 39.299896 -82.070194)
					(mid 39.591996 -81.778094)
					(end 39.884096 -82.070194)
				)
			)
		)
	)
	(zone
		(net "P3V3_STBY")
		(layer "In3.Cu")
		(hatch none 0.5)
		(connect_pads
			(clearance 0.5)
		)
		(min_thickness 0.25)
		(fill yes
			(thermal_gap 0.5)
			(thermal_bridge_width 0.5)
			(island_removal_mode 0)
		)
		(polygon
			(pts
				(xy 264.365994 -145.3515) (xy 256.0955 -153.621994) (xy 256.0955 -180.134006) (xy 266.651994 -190.6905)
				(xy 336.217006 -190.6905) (xy 345.8845 -181.023006) (xy 345.8845 -158.955994) (xy 332.280006 -145.3515)
			)
		)
		(polygon
			(pts
				(arc
					(start 285.550356 -185.54573)
					(mid 285.87573 -185.111644)
					(end 285.441644 -184.78627)
				)
				(arc
					(start 284.552898 -184.91327)
					(mid 284.227506 -185.347232)
					(end 284.661356 -185.67273)
				)
			)
		)
		(polygon
			(pts
				(arc
					(start 299.643546 -174.676054)
					(mid 299.280328 -175.028987)
					(end 299.633132 -175.392334)
				)
				(arc
					(start 300.430438 -175.40351)
					(mid 300.793658 -175.05045)
					(end 300.440598 -174.68723)
				)
			)
		)
		(polygon
			(pts
				(arc
					(start 303.024032 -174.096426)
					(mid 303.38903 -173.69536)
					(end 302.987964 -173.330362)
				)
				(xy 302.987964 -173.327822) (xy 302.21428 -173.36389) (xy 302.214026 -173.364144)
				(arc
					(start 302.214026 -173.36643)
					(mid 301.849028 -173.767496)
					(end 302.250094 -174.132494)
				)
				(xy 302.250094 -174.135034) (xy 303.024032 -174.098966)
			)
		)
	)
	(zone
		(net "PCE_AVDD")
		(layer "In3.Cu")
		(hatch none 0.5)
		(connect_pads
			(clearance 0.5)
		)
		(min_thickness 0.25)
		(fill yes
			(thermal_gap 0.5)
			(thermal_bridge_width 0.5)
			(island_removal_mode 0)
		)
		(polygon
			(pts
				(xy 93.55328 -37.36086) (xy 93.5355 -37.360606) (xy 93.5355 -37.386006)
				(arc
					(start 93.595698 -37.446204)
					(mid 93.809903 -37.548991)
					(end 93.91269 -37.763196)
				)
				(xy 94.058994 -37.9095) (xy 96.471994 -37.9095) (xy 97.7265 -39.164006) (xy 97.7265 -39.672006)
				(xy 98.122994 -40.0685) (xy 103.807006 -40.0685) (xy 104.7115 -39.164006) (xy 106.7435 -37.132006)
				(xy 106.7435 -20.525994) (xy 99.362006 -13.1445) (xy 92.5195 -13.1445) (xy 92.5195 -13.159994) (xy 92.0115 -13.667994)
				(xy 92.0115 -20.876006) (xy 93.5355 -22.400006) (xy 93.5355 -34.248598) (xy 93.544644 -34.248344)
				(arc
					(start 94.34703 -34.241994)
					(mid 94.707964 -34.59734)
					(end 94.352618 -34.958274)
				)
				(xy 93.549978 -34.964624) (xy 93.5355 -34.96437)
				(arc
					(start 93.5355 -35.049968)
					(mid 93.797372 -35.149354)
					(end 93.90761 -35.406838)
				)
				(xy 93.90761 -35.407854)
				(arc
					(start 93.909896 -36.195254)
					(mid 93.799463 -36.454678)
					(end 93.5355 -36.553902)
				)
				(xy 93.5355 -36.644834) (xy 93.550232 -36.64458)
				(arc
					(start 94.357698 -36.641278)
					(mid 94.717363 -36.998021)
					(end 94.360492 -37.357558)
				)
			)
		)
		(polygon
			(pts
				(arc
					(start 96.30664 -35.406838)
					(mid 95.947738 -35.04946)
					(end 95.59036 -35.408362)
				)
				(xy 95.592138 -36.199318) (xy 95.592138 -36.20008)
				(arc
					(start 95.592138 -36.200588)
					(mid 95.950913 -36.55822)
					(end 96.308418 -36.199318)
				)
				(xy 96.30664 -35.408362) (xy 96.30664 -35.4076)
			)
		)
		(polygon
			(pts
				(arc
					(start 95.50654 -35.404298)
					(mid 95.147638 -35.04692)
					(end 94.79026 -35.405822)
				)
				(xy 94.79026 -35.406838) (xy 94.79026 -35.407854) (xy 94.792038 -36.195254) (xy 94.792038 -36.196016)
				(arc
					(start 94.792038 -36.200588)
					(mid 95.150813 -36.55822)
					(end 95.508318 -36.199318)
				)
				(xy 95.50654 -35.40506)
			)
		)
		(polygon
			(pts
				(arc
					(start 98.700082 -35.397694)
					(mid 98.338132 -35.043364)
					(end 97.983802 -35.405314)
				)
				(arc
					(start 97.992184 -36.203636)
					(mid 98.354007 -36.558219)
					(end 98.708464 -36.19627)
				)
			)
		)
		(polygon
			(pts
				(arc
					(start 103.508302 -35.400234)
					(mid 103.150162 -35.042094)
					(end 102.792022 -35.400234)
				)
				(arc
					(start 102.792022 -36.200334)
					(mid 103.150289 -36.55822)
					(end 103.508302 -36.20008)
				)
			)
		)
		(polygon
			(pts
				(arc
					(start 97.898966 -35.395916)
					(mid 97.536508 -35.042094)
					(end 97.182686 -35.404552)
				)
				(arc
					(start 97.192084 -36.204144)
					(mid 97.554415 -36.558219)
					(end 97.908364 -36.195762)
				)
			)
		)
		(polygon
			(pts
				(arc
					(start 102.708202 -35.39998)
					(mid 102.349935 -35.04184)
					(end 101.991922 -35.400234)
				)
				(xy 101.991922 -35.40125)
				(arc
					(start 101.992176 -36.199826)
					(mid 102.350316 -36.55822)
					(end 102.708456 -36.199826)
				)
				(xy 102.708202 -35.75812)
			)
		)
		(polygon
			(pts
				(arc
					(start 101.115622 -35.40125)
					(mid 100.760784 -35.039808)
					(end 100.399342 -35.394646)
				)
				(arc
					(start 100.39223 -36.196524)
					(mid 100.746941 -36.558221)
					(end 101.10851 -36.203382)
				)
			)
		)
		(polygon
			(pts
				(arc
					(start 100.30968 -35.392868)
					(mid 99.952048 -35.03422)
					(end 99.5934 -35.391852)
				)
				(xy 99.5934 -35.397694) (xy 99.59213 -36.19627)
				(arc
					(start 99.59213 -36.199318)
					(mid 99.949635 -36.55822)
					(end 100.30841 -36.200588)
				)
				(xy 100.30841 -36.20008) (xy 100.30841 -36.199318)
			)
		)
	)
	(zone
		(net "GB_VDDA")
		(layer "In3.Cu")
		(hatch none 0.5)
		(connect_pads
			(clearance 0.5)
		)
		(min_thickness 0.25)
		(fill yes
			(thermal_gap 0.5)
			(thermal_bridge_width 0.5)
			(island_removal_mode 0)
		)
		(polygon
			(pts
				(xy 125.554994 -81.2165) (xy 124.919994 -81.8515)
				(arc
					(start 124.084334 -81.8515)
					(mid 123.961456 -82.042015)
					(end 123.7488 -82.120486)
				)
				(xy 123.7488 -82.123026) (xy 122.94743 -82.148426)
				(arc
					(start 122.94743 -82.145886)
					(mid 122.710774 -82.066364)
					(end 122.583702 -81.8515)
				)
				(xy 121.490994 -81.8515) (xy 121.2215 -82.120994) (xy 121.2215 -96.217994) (xy 119.1895 -98.249994)
				(xy 119.1895 -100.027994) (xy 117.807994 -101.4095) (xy 108.155994 -101.4095) (xy 107.8865 -101.678994)
				(arc
					(start 107.8865 -102.493826)
					(mid 108.115616 -102.61014)
					(end 108.20781 -102.849934)
				)
				(arc
					(start 108.20781 -103.850186)
					(mid 108.115631 -104.090136)
					(end 107.8865 -104.206548)
				)
				(xy 107.8865 -104.599994) (xy 107.6325 -104.853994) (xy 107.6325 -108.409994) (xy 106.6165 -109.425994)
				(xy 106.6165 -113.967006) (xy 106.885994 -114.2365) (xy 150.035006 -114.2365) (xy 150.8125 -113.459006)
				(xy 150.8125 -95.582994) (xy 150.035006 -94.8055) (xy 134.414006 -94.8055)
				(arc
					(start 132.0165 -92.40774)
					(mid 131.935885 -92.346115)
					(end 131.87426 -92.2655)
				)
				(xy 131.7625 -92.153994) (xy 131.7625 -85.549994) (xy 127.429006 -81.2165)
			)
		)
		(polygon
			(pts
				(arc
					(start 119.208296 -102.850188)
					(mid 118.850156 -102.492048)
					(end 118.492016 -102.850188)
				)
				(arc
					(start 118.492016 -103.85044)
					(mid 118.850283 -104.208326)
					(end 119.208296 -103.850186)
				)
			)
		)
		(polygon
			(pts
				(arc
					(start 118.208298 -102.850188)
					(mid 117.850158 -102.492048)
					(end 117.492018 -102.850188)
				)
				(arc
					(start 117.492018 -103.85044)
					(mid 117.850285 -104.208326)
					(end 118.208298 -103.850186)
				)
			)
		)
		(polygon
			(pts
				(arc
					(start 114.207798 -102.850188)
					(mid 113.849658 -102.492048)
					(end 113.491518 -102.850188)
				)
				(arc
					(start 113.491518 -103.85044)
					(mid 113.849785 -104.208326)
					(end 114.207798 -103.850186)
				)
			)
		)
		(polygon
			(pts
				(arc
					(start 112.207802 -102.850188)
					(mid 111.849662 -102.492048)
					(end 111.491522 -102.850188)
				)
				(arc
					(start 111.491522 -103.85044)
					(mid 111.849789 -104.208326)
					(end 112.207802 -103.850186)
				)
			)
		)
		(polygon
			(pts
				(arc
					(start 110.207806 -102.850188)
					(mid 109.849666 -102.492048)
					(end 109.491526 -102.850188)
				)
				(arc
					(start 109.491526 -103.85044)
					(mid 109.849793 -104.208326)
					(end 110.207806 -103.850186)
				)
			)
		)
		(polygon
			(pts
				(arc
					(start 109.207808 -102.850188)
					(mid 108.849668 -102.492048)
					(end 108.491528 -102.850188)
				)
				(arc
					(start 108.491528 -103.85044)
					(mid 108.849795 -104.208326)
					(end 109.207808 -103.850186)
				)
			)
		)
		(polygon
			(pts
				(arc
					(start 113.2078 -102.849934)
					(mid 112.849533 -102.492048)
					(end 112.49152 -102.850188)
				)
				(arc
					(start 112.49152 -103.850186)
					(mid 112.84966 -104.208326)
					(end 113.2078 -103.850186)
				)
			)
		)
		(polygon
			(pts
				(arc
					(start 111.207804 -102.849934)
					(mid 110.849537 -102.492048)
					(end 110.491524 -102.850188)
				)
				(arc
					(start 110.491524 -103.850186)
					(mid 110.849664 -104.208326)
					(end 111.207804 -103.850186)
				)
			)
		)
		(polygon
			(pts
				(arc
					(start 116.238782 -102.840028)
					(mid 115.880515 -102.482142)
					(end 115.522502 -102.840282)
				)
				(arc
					(start 115.522502 -103.830882)
					(mid 115.880642 -104.189022)
					(end 116.238782 -103.830882)
				)
			)
		)
		(polygon
			(pts
				(arc
					(start 115.222782 -102.840028)
					(mid 114.864515 -102.482142)
					(end 114.506502 -102.840282)
				)
				(arc
					(start 114.506502 -103.830882)
					(mid 114.864642 -104.189022)
					(end 115.222782 -103.830882)
				)
			)
		)
		(polygon
			(pts
				(arc
					(start 122.862848 -93.470222)
					(mid 122.497342 -93.820996)
					(end 122.848116 -94.186502)
				)
				(arc
					(start 123.843542 -94.206822)
					(mid 124.209305 -93.856175)
					(end 123.858528 -93.490542)
				)
			)
		)
		(polygon
			(pts
				(arc
					(start 123.208288 -91.849702)
					(mid 122.850021 -91.491562)
					(end 122.492008 -91.849956)
				)
				(arc
					(start 122.492262 -92.827348)
					(mid 122.850402 -93.185742)
					(end 123.208542 -92.827348)
				)
				(xy 123.208288 -91.849956)
			)
		)
		(polygon
			(pts
				(arc
					(start 123.850146 -91.207844)
					(mid 124.208286 -90.849704)
					(end 123.850146 -90.491564)
				)
				(arc
					(start 122.849894 -90.491564)
					(mid 122.492008 -90.849831)
					(end 122.850148 -91.207844)
				)
			)
		)
		(polygon
			(pts
				(arc
					(start 123.850146 -90.207846)
					(mid 124.208286 -89.849706)
					(end 123.850146 -89.491566)
				)
				(arc
					(start 122.849894 -89.491566)
					(mid 122.492008 -89.849833)
					(end 122.850148 -90.207846)
				)
			)
		)
		(polygon
			(pts
				(arc
					(start 123.84532 -85.151214)
					(mid 124.182625 -84.773135)
					(end 123.804426 -84.43595)
				)
				(arc
					(start 122.829574 -84.492084)
					(mid 122.492516 -84.87029)
					(end 122.870722 -85.207348)
				)
			)
		)
		(polygon
			(pts
				(arc
					(start 123.8504 -84.207858)
					(mid 124.208286 -83.849591)
					(end 123.850146 -83.491578)
				)
				(arc
					(start 122.850148 -83.491578)
					(mid 122.492008 -83.849718)
					(end 122.850148 -84.207858)
				)
			)
		)
		(polygon
			(pts
				(arc
					(start 123.850146 -83.20786)
					(mid 124.208286 -82.84972)
					(end 123.850146 -82.49158)
				)
				(arc
					(start 122.849894 -82.49158)
					(mid 122.492008 -82.849847)
					(end 122.850148 -83.20786)
				)
			)
		)
	)
	(zone
		(net "GND")
		(layer "In3.Cu")
		(hatch none 0.5)
		(connect_pads
			(clearance 0.5)
		)
		(min_thickness 0.25)
		(fill yes
			(thermal_gap 0.5)
			(thermal_bridge_width 0.5)
			(island_removal_mode 0)
		)
		(polygon
			(pts
				(xy 83.517994 -2.3495) (xy 83.1215 -2.745994) (xy 83.1215 -6.936994) (xy 82.6135 -7.444994) (xy 82.6135 -15.445994)
				(xy 81.8515 -16.207994) (xy 81.739994 -16.3195) (xy 80.469994 -16.3195) (xy 80.0735 -16.715994)
				(xy 80.0735 -31.671006) (xy 80.469994 -32.0675) (xy 81.302606 -32.0675) (xy 81.7245 -31.645606)
				(xy 81.7245 -29.639006) (xy 82.598006 -28.7655) (xy 92.631006 -28.7655) (xy 93.139006 -28.2575)
				(xy 93.1545 -28.2575) (xy 93.1545 -22.557994) (xy 91.6305 -21.033994) (xy 91.6305 -13.667994) (xy 91.1225 -13.159994)
				(xy 91.1225 -13.1445) (xy 87.170006 -13.1445) (xy 86.1695 -12.143994) (xy 86.1695 -2.8575) (xy 86.154006 -2.8575)
				(xy 85.646006 -2.3495)
			)
		)
	)
	(zone
		(net "SAS0_AVDD")
		(layer "In3.Cu")
		(hatch none 0.5)
		(connect_pads
			(clearance 0.5)
		)
		(min_thickness 0.25)
		(fill yes
			(thermal_gap 0.5)
			(thermal_bridge_width 0.5)
			(island_removal_mode 0)
		)
		(polygon
			(pts
				(xy 82.755994 -29.1465) (xy 82.1055 -29.796994) (xy 82.1055 -31.671006) (xy 82.501994 -32.0675)
				(xy 85.676994 -32.0675) (xy 86.2965 -32.687006) (xy 86.2965 -43.355006) (xy 90.121994 -47.1805)
				(xy 96.822006 -47.1805) (xy 97.3455 -46.657006) (xy 97.3455 -39.321994) (xy 96.314006 -38.2905)
				(xy 93.914214 -38.2905) (xy 93.913706 -38.596316) (xy 93.913706 -38.596824)
				(arc
					(start 93.913706 -38.597332)
					(mid 93.555058 -38.954964)
					(end 93.197426 -38.596316)
				)
				(arc
					(start 93.198442 -37.80155)
					(mid 93.209563 -37.713755)
					(end 93.241876 -37.63137)
				)
				(xy 93.1545 -37.543994) (xy 93.1545 -29.6545) (xy 93.139006 -29.6545) (xy 92.631006 -29.1465)
			)
		)
		(polygon
			(pts
				(arc
					(start 93.914976 -42.600118)
					(mid 93.55963 -42.239184)
					(end 93.198696 -42.59453)
				)
				(arc
					(start 93.192346 -43.387772)
					(mid 93.547565 -43.748961)
					(end 93.908626 -43.393614)
				)
			)
		)
		(polygon
			(pts
				(arc
					(start 92.753942 -41.438576)
					(mid 92.392247 -41.793033)
					(end 92.746576 -42.154856)
				)
				(arc
					(start 93.550994 -42.16273)
					(mid 93.91269 -41.808146)
					(end 93.558106 -41.44645)
				)
			)
		)
		(polygon
			(pts
				(arc
					(start 93.898974 -40.193722)
					(mid 93.534484 -39.841932)
					(end 93.182694 -40.206422)
				)
				(arc
					(start 93.196664 -41.001696)
					(mid 93.561027 -41.353738)
					(end 93.912944 -40.98925)
				)
			)
		)
		(polygon
			(pts
				(arc
					(start 92.746576 -39.03726)
					(mid 92.387674 -39.394511)
					(end 92.744798 -39.75354)
				)
				(arc
					(start 93.55582 -39.755318)
					(mid 93.914722 -39.39794)
					(end 93.557344 -39.039038)
				)
			)
		)
	)
	(zone
		(net "P0V955_C")
		(layer "In3.Cu")
		(hatch none 0.5)
		(connect_pads
			(clearance 0.5)
		)
		(min_thickness 0.25)
		(fill yes
			(thermal_gap 0.5)
			(thermal_bridge_width 0.5)
			(island_removal_mode 0)
		)
		(polygon
			(pts
				(xy 86.946994 -2.3495) (xy 86.5505 -2.745994) (xy 86.5505 -11.986006) (xy 87.327994 -12.7635) (xy 99.519994 -12.7635)
				(xy 99.6315 -12.875006) (xy 107.1245 -20.368006) (xy 107.1245 -37.289994) (xy 103.964994 -40.4495)
				(xy 98.122994 -40.4495) (xy 97.7265 -40.845994) (xy 97.7265 -49.959006) (xy 98.249994 -50.4825)
				(xy 111.681006 -50.4825) (xy 120.4595 -41.704006) (xy 120.4595 -8.333994) (xy 114.475006 -2.3495)
			)
		)
	)
	(zone
		(net "P0V9_E")
		(layer "In3.Cu")
		(hatch none 0.5)
		(connect_pads
			(clearance 0.5)
		)
		(min_thickness 0.25)
		(fill yes
			(thermal_gap 0.5)
			(thermal_bridge_width 0.5)
			(island_removal_mode 0)
		)
		(polygon
			(pts
				(xy 72.341994 -78.6765) (xy 71.6915 -79.326994) (xy 71.6915 -92.915994) (xy 53.1495 -111.457994)
				(xy 53.1495 -143.558006) (xy 62.054994 -152.4635) (xy 136.936226 -152.4635) (xy 137.8458 -151.553926)
				(xy 137.8458 -131.765294) (xy 137.208006 -131.1275) (xy 129.872994 -131.1275) (xy 128.9685 -132.031994)
				(xy 128.9685 -141.810994) (xy 123.395994 -147.3835) (xy 62.913006 -147.3835) (xy 56.3245 -140.794994)
				(xy 56.3245 -112.316006) (xy 74.7395 -93.901006) (xy 74.7395 -79.1845) (xy 74.724006 -79.1845) (xy 74.216006 -78.6765)
			)
		)
	)
	(zone
		(net "PLLDDR_VDDA18")
		(layer "In3.Cu")
		(hatch none 0.5)
		(connect_pads
			(clearance 0.5)
		)
		(min_thickness 0.25)
		(fill yes
			(thermal_gap 0.5)
			(thermal_bridge_width 0.5)
			(island_removal_mode 0)
		)
		(polygon
			(pts
				(xy 84.025994 -76.3905) (xy 83.3755 -77.040994) (xy 83.3755 -84.249006) (xy 84.152994 -85.0265)
				(xy 108.282994 -85.0265) (xy 111.838994 -88.5825) (xy 116.380006 -88.5825) (xy 116.9035 -88.059006)
				(xy 116.9035 -80.596994) (xy 112.697006 -76.3905)
			)
		)
	)
	(zone
		(net "P12V_PCIE")
		(layer "In3.Cu")
		(hatch none 0.5)
		(connect_pads
			(clearance 0.5)
		)
		(min_thickness 0.25)
		(fill yes
			(thermal_gap 0.5)
			(thermal_bridge_width 0.5)
			(island_removal_mode 0)
		)
		(polygon
			(pts
				(xy 255.475994 -126.0475) (xy 239.0775 -142.445994) (xy 239.0775 -168.196006) (xy 239.981994 -169.1005)
				(xy 255.191006 -169.1005) (xy 255.7145 -168.577006) (xy 255.7145 -153.464006) (xy 264.208006 -144.9705)
				(xy 291.132006 -144.9705) (xy 291.6555 -144.447006) (xy 291.6555 -126.824994) (xy 290.878006 -126.0475)
			)
		)
	)
	(zone
		(net "P12V")
		(layer "In3.Cu")
		(hatch none 0.5)
		(connect_pads
			(clearance 0.5)
		)
		(min_thickness 0.25)
		(fill yes
			(thermal_gap 0.5)
			(thermal_bridge_width 0.5)
			(island_removal_mode 0)
		)
		(polygon
			(pts
				(xy 75.389994 -2.3495) (xy 75.212956 -2.526538) (xy 75.212956 -15.999968) (xy 75.21194 -16.059912)
				(xy 75.21194 -16.31569)
				(arc
					(start 75.177904 -16.349472)
					(mid 74.696539 -17.246565)
					(end 73.799446 -17.72793)
				)
				(xy 73.765664 -17.761966) (xy 73.509886 -17.761966) (xy 73.449942 -17.762982)
				(arc
					(start 62.95009 -17.762982)
					(mid 62.782518 -17.832392)
					(end 62.713108 -17.999964)
				)
				(xy 62.713108 -57.010046) (xy 62.712092 -57.069736) (xy 62.712092 -57.325768)
				(arc
					(start 62.678056 -57.359804)
					(mid 62.196726 -58.256678)
					(end 61.299852 -58.738008)
				)
				(xy 61.265816 -58.772044) (xy 61.009784 -58.772044) (xy 60.950094 -58.77306) (xy 58.9915 -58.77306)
				(xy 58.9915 -81.231994) (xy 38.2905 -101.932994) (xy 38.2905 -147.368006) (xy 58.498994 -167.5765)
				(xy 95.407226 -167.5765) (xy 95.419926 -167.5638) (xy 96.562926 -167.5638) (xy 97.4725 -166.654226)
				(xy 97.4725 -153.3525) (xy 97.457006 -153.3525) (xy 96.949006 -152.8445) (xy 61.897006 -152.8445)
				(xy 52.7685 -143.715994) (xy 52.7685 -111.300006) (xy 71.3105 -92.758006) (xy 71.3105 -79.169006)
				(xy 72.184006 -78.2955) (xy 74.216006 -78.2955) (xy 74.7395 -77.772006) (xy 74.7395 -36.624006)
				(xy 79.296006 -32.0675) (xy 79.6925 -31.671006) (xy 79.6925 -16.558006) (xy 80.312006 -15.9385)
				(xy 81.582006 -15.9385) (xy 82.2325 -15.288006) (xy 82.2325 -7.287006) (xy 82.7405 -6.779006) (xy 82.7405 -2.745994)
				(xy 82.344006 -2.3495)
			)
		)
	)
	(zone
		(net "GND")
		(layer "In3.Cu")
		(hatch none 0.5)
		(connect_pads
			(clearance 0.5)
		)
		(min_thickness 0.25)
		(fill yes
			(thermal_gap 0.5)
			(thermal_bridge_width 0.5)
			(island_removal_mode 0)
		)
		(polygon
			(pts
				(xy 250.465844 -195.238116)
				(arc
					(start 250.49988 -195.272152)
					(mid 251.396754 -195.753482)
					(end 251.878084 -196.650356)
				)
				(xy 251.91212 -196.684392) (xy 251.91212 -196.94017) (xy 251.913136 -197.000114)
				(arc
					(start 251.913136 -246.000016)
					(mid 253.154117 -248.996009)
					(end 256.15011 -250.23699)
				)
				(arc
					(start 350.60001 -250.23699)
					(mid 353.596003 -248.996009)
					(end 354.836984 -246.000016)
				)
				(arc
					(start 354.836984 -0.999998)
					(mid 354.767574 -0.832426)
					(end 354.600002 -0.763016)
				)
				(arc
					(start 307.485034 -0.763016)
					(mid 307.317462 -0.832426)
					(end 307.248052 -0.999998)
				)
				(xy 307.248052 -43.50004) (xy 307.247036 -43.559984) (xy 307.247036 -43.815762)
				(arc
					(start 307.213 -43.849798)
					(mid 306.601183 -44.864739)
					(end 305.485038 -45.263054)
				)
				(arc
					(start 305.485038 -45.263054)
					(mid 305.317466 -45.332464)
					(end 305.248056 -45.500036)
				)
				(xy 305.248056 -53.50002) (xy 305.24704 -53.559964) (xy 305.24704 -53.815742)
				(arc
					(start 305.213004 -53.849778)
					(mid 304.731674 -54.746652)
					(end 303.8348 -55.227982)
				)
				(xy 303.800764 -55.262018) (xy 303.544986 -55.262018) (xy 303.485042 -55.263034) (xy 283.485082 -55.263034)
				(xy 283.425138 -55.262018) (xy 283.16936 -55.262018)
				(arc
					(start 283.135578 -55.227982)
					(mid 282.238485 -54.746617)
					(end 281.75712 -53.849524)
				)
				(xy 281.723084 -53.815742) (xy 281.723084 -53.559964) (xy 281.722068 -53.50002)
				(arc
					(start 281.722068 -0.999998)
					(mid 281.652658 -0.832426)
					(end 281.485086 -0.763016)
				)
				(arc
					(start 75.449938 -0.763016)
					(mid 75.282366 -0.832426)
					(end 75.212956 -0.999998)
				)
				(xy 75.212956 -1.791462) (xy 75.389994 -1.9685) (xy 114.632994 -1.9685) (xy 120.8405 -8.176006)
				(xy 120.8405 -41.861994) (xy 111.838994 -50.8635) (xy 98.092006 -50.8635) (xy 97.3455 -50.116994)
				(xy 97.3455 -48.059594) (xy 96.847406 -47.5615) (xy 89.964006 -47.5615) (xy 85.9155 -43.512994)
				(xy 85.9155 -32.844994) (xy 85.519006 -32.4485) (xy 81.460594 -32.4485) (xy 81.435194 -32.4739)
				(xy 81.277206 -32.4739) (xy 81.251806 -32.4485) (xy 79.453994 -32.4485) (xy 75.1205 -36.781994)
				(xy 75.1205 -94.058994) (xy 56.7055 -112.473994) (xy 56.7055 -140.637006) (xy 63.070994 -147.0025)
				(xy 123.238006 -147.0025) (xy 128.5875 -141.653006) (xy 128.5875 -131.874006) (xy 129.715006 -130.7465)
				(xy 137.365994 -130.7465) (xy 137.4775 -130.858006) (xy 138.115294 -131.4958) (xy 138.133074 -131.4958)
				(xy 138.2522 -131.614926) (xy 138.2522 -151.553926) (xy 138.2522 -151.722074) (xy 138.133074 -151.8412)
				(xy 137.117074 -152.8572) (xy 136.948926 -152.8572) (xy 136.936226 -152.8445) (xy 98.376994 -152.8445)
				(xy 97.868994 -153.3525) (xy 97.8535 -153.3525) (xy 97.8535 -166.654226) (xy 97.8662 -166.666926)
				(xy 97.8662 -166.835074) (xy 96.8502 -167.851074) (xy 96.731074 -167.9702) (xy 96.562926 -167.9702)
				(xy 95.419926 -167.9702) (xy 95.407226 -167.9575) (xy 58.341006 -167.9575) (xy 37.9095 -147.525994)
				(xy 37.9095 -101.775006) (xy 58.6105 -81.074006) (xy 58.6105 -58.77306)
				(arc
					(start 29.500068 -58.77306)
					(mid 28.625391 -59.135363)
					(end 28.263088 -60.01004)
				)
				(xy 28.263088 -76.010008) (xy 28.262072 -76.084938) (xy 28.262072 -76.32573)
				(arc
					(start 28.242768 -76.345034)
					(mid 27.453867 -77.963799)
					(end 25.835102 -78.7527)
				)
				(xy 25.815798 -78.772004) (xy 25.575006 -78.772004) (xy 25.500076 -78.77302)
				(arc
					(start 2.999994 -78.77302)
					(mid 1.418212 -79.428216)
					(end 0.763016 -81.009998)
				)
				(arc
					(start 0.763016 -246.000016)
					(mid 2.003997 -248.996009)
					(end 4.99999 -250.23699)
				)
				(xy 26.34996 -250.23699) (xy 26.409904 -250.238006) (xy 26.665682 -250.238006)
				(arc
					(start 26.699464 -250.272042)
					(mid 27.596557 -250.753407)
					(end 28.077922 -251.6505)
				)
				(xy 28.111958 -251.684282) (xy 28.111958 -251.94006) (xy 28.112974 -252.000004) (xy 28.112974 -257.836924)
				(xy 33.78708 -257.836924) (xy 33.78708 -252.549914) (xy 33.788096 -252.490986) (xy 33.788096 -252.234192)
				(arc
					(start 33.823402 -252.198886)
					(mid 35.500056 -250.836908)
					(end 37.17671 -252.198886)
				)
				(xy 37.212016 -252.234192) (xy 37.212016 -252.490986) (xy 37.213032 -252.549914) (xy 37.213032 -257.836924)
				(xy 46.886876 -257.836924) (xy 46.886876 -252.000004) (xy 46.887892 -251.940314) (xy 46.887892 -251.684282)
				(arc
					(start 46.921928 -251.650246)
					(mid 47.403258 -250.753372)
					(end 48.300132 -250.272042)
				)
				(xy 48.334168 -250.238006) (xy 48.5902 -250.238006) (xy 48.64989 -250.23699) (xy 66.34988 -250.23699)
				(xy 66.409824 -250.238006) (xy 66.665602 -250.238006)
				(arc
					(start 66.699384 -250.272042)
					(mid 67.596477 -250.753407)
					(end 68.077842 -251.6505)
				)
				(xy 68.111878 -251.684282) (xy 68.111878 -251.94006) (xy 68.112894 -252.000004) (xy 68.112894 -257.836924)
				(xy 137.786872 -257.836924) (xy 137.786872 -252.549914) (xy 137.787888 -252.490986) (xy 137.787888 -252.234192)
				(arc
					(start 137.823194 -252.198886)
					(mid 139.500076 -250.836659)
					(end 141.176756 -252.198886)
				)
				(xy 141.212062 -252.234192) (xy 141.212062 -252.490986) (xy 141.213078 -252.549914) (xy 141.213078 -257.836924)
				(xy 150.886922 -257.836924) (xy 150.886922 -252.000004) (xy 150.887938 -251.94006) (xy 150.887938 -251.684282)
				(arc
					(start 150.921974 -251.650246)
					(mid 151.403304 -250.753372)
					(end 152.300178 -250.272042)
				)
				(xy 152.334214 -250.238006) (xy 152.589992 -250.238006) (xy 152.649936 -250.23699) (xy 181.150006 -250.23699)
				(xy 181.20995 -250.238006) (xy 181.465728 -250.238006)
				(arc
					(start 181.499764 -250.272042)
					(mid 182.396638 -250.753372)
					(end 182.877968 -251.650246)
				)
				(xy 182.912004 -251.684282) (xy 182.912004 -251.94006) (xy 182.91302 -252.000004) (xy 182.91302 -257.836924)
				(xy 188.586872 -257.836924) (xy 188.586872 -252.549914) (xy 188.587888 -252.490986) (xy 188.587888 -252.234192)
				(arc
					(start 188.623194 -252.198886)
					(mid 190.300076 -250.836659)
					(end 191.976756 -252.198886)
				)
				(xy 192.012062 -252.234192) (xy 192.012062 -252.490986) (xy 192.013078 -252.549914) (xy 192.013078 -257.836924)
				(xy 201.686922 -257.836924) (xy 201.686922 -252.000004) (xy 201.687938 -251.94006) (xy 201.687938 -251.684282)
				(arc
					(start 201.721974 -251.650246)
					(mid 202.203304 -250.753372)
					(end 203.100178 -250.272042)
				)
				(xy 203.134214 -250.238006) (xy 203.389992 -250.238006) (xy 203.449936 -250.23699)
				(arc
					(start 229.14991 -250.23699)
					(mid 232.145903 -248.996009)
					(end 233.386884 -246.000016)
				)
				(xy 233.386884 -197.000114) (xy 233.3879 -196.94017) (xy 233.3879 -196.684392)
				(arc
					(start 233.421936 -196.65061)
					(mid 233.903301 -195.753517)
					(end 234.800394 -195.272152)
				)
				(xy 234.834176 -195.238116) (xy 235.089954 -195.238116) (xy 235.149898 -195.2371) (xy 250.150122 -195.2371)
				(xy 250.210066 -195.238116)
			)
		)
		(polygon
			(pts
				(arc
					(start 350.369124 -154.275028)
					(mid 350.010984 -153.916888)
					(end 349.652844 -154.275028)
				)
				(arc
					(start 349.652844 -155.155392)
					(mid 350.011111 -155.513278)
					(end 350.369124 -155.155138)
				)
			)
		)
		(polygon
			(pts
				(arc
					(start 351.11309 -151.97201)
					(mid 350.75495 -151.61387)
					(end 350.39681 -151.97201)
				)
				(arc
					(start 350.39681 -152.917144)
					(mid 350.755077 -153.27503)
					(end 351.11309 -152.91689)
				)
			)
		)
		(polygon
			(pts
				(arc
					(start 351.824544 -147.98167)
					(mid 352.18243 -147.623403)
					(end 351.82429 -147.26539)
				)
				(arc
					(start 350.87941 -147.26539)
					(mid 350.52127 -147.62353)
					(end 350.87941 -147.98167)
				)
			)
		)
		(polygon
			(pts
				(xy 291.035994 -125.6665) (xy 255.318006 -125.6665) (xy 238.6965 -142.288006) (xy 238.6965 -168.353994)
				(xy 239.824006 -169.4815) (xy 255.191006 -169.4815) (xy 255.7145 -170.004994) (xy 255.7145 -180.291994)
				(xy 266.494006 -191.0715) (xy 336.374994 -191.0715) (xy 346.2655 -181.180994) (xy 346.2655 -158.798006)
				(xy 332.437994 -144.9705) (xy 292.559994 -144.9705) (xy 292.0365 -144.447006) (xy 292.0365 -126.667006)
				(xy 291.1475 -125.778006)
			)
		)
		(polygon
			(pts
				(arc
					(start 107.207812 -102.849934)
					(mid 106.849545 -102.492048)
					(end 106.491532 -102.850188)
				)
				(arc
					(start 106.491532 -103.850186)
					(mid 106.849672 -104.208326)
					(end 107.207812 -103.850186)
				)
			)
		)
		(polygon
			(pts
				(arc
					(start 19.325082 -98.929444)
					(mid 19.708622 -98.545904)
					(end 19.325082 -98.162364)
				)
				(arc
					(start 18.258028 -98.162364)
					(mid 17.874742 -98.546031)
					(end 18.258282 -98.929444)
				)
			)
		)
		(polygon
			(pts
				(arc
					(start 11.147044 -98.109786)
					(mid 10.762742 -98.492564)
					(end 11.14552 -98.876866)
				)
				(arc
					(start 12.059666 -98.878644)
					(mid 12.444222 -98.495993)
					(end 12.061444 -98.111564)
				)
			)
		)
		(polygon
			(pts
				(xy 15.95755 -98.109278) (xy 15.957296 -98.109532)
				(arc
					(start 15.957296 -98.111818)
					(mid 15.563596 -98.48469)
					(end 15.936468 -98.87839)
				)
				(xy 15.936468 -98.88093) (xy 16.876268 -98.90633)
				(arc
					(start 16.876268 -98.90379)
					(mid 17.269968 -98.530918)
					(end 16.897096 -98.137218)
				)
				(xy 16.897096 -98.134678)
			)
		)
		(polygon
			(pts
				(arc
					(start 13.52931 -98.086672)
					(mid 13.12545 -98.448876)
					(end 13.487654 -98.852736)
				)
				(xy 14.4272 -98.903536)
				(arc
					(start 14.427454 -98.903536)
					(mid 14.831314 -98.541332)
					(end 14.46911 -98.137472)
				)
			)
		)
		(polygon
			(pts
				(arc
					(start 42.328338 -90.479626)
					(mid 42.711878 -90.096086)
					(end 42.328338 -89.712546)
				)
				(arc
					(start 41.3512 -89.712546)
					(mid 40.967914 -90.096213)
					(end 41.351454 -90.479626)
				)
			)
		)
		(polygon
			(pts
				(arc
					(start 39.407592 -90.479626)
					(mid 39.790878 -90.095959)
					(end 39.407338 -89.712546)
				)
				(arc
					(start 38.430454 -89.712546)
					(mid 38.046914 -90.096086)
					(end 38.430454 -90.479626)
				)
			)
		)
		(polygon
			(pts
				(arc
					(start 36.359592 -90.479626)
					(mid 36.742878 -90.095959)
					(end 36.359338 -89.712546)
				)
				(arc
					(start 35.382454 -89.712546)
					(mid 34.998914 -90.096086)
					(end 35.382454 -90.479626)
				)
			)
		)
		(polygon
			(pts
				(arc
					(start 33.311338 -90.479626)
					(mid 33.694878 -90.096086)
					(end 33.311338 -89.712546)
				)
				(arc
					(start 32.3342 -89.712546)
					(mid 31.950914 -90.096213)
					(end 32.334454 -90.479626)
				)
			)
		)
		(polygon
			(pts
				(arc
					(start 134.11454 -89.654126)
					(mid 133.731 -89.270586)
					(end 133.34746 -89.654126)
				)
				(arc
					(start 133.34746 -90.559382)
					(mid 133.731127 -90.942668)
					(end 134.11454 -90.559128)
				)
			)
		)
		(polygon
			(pts
				(arc
					(start 304.720244 -87.908892)
					(mid 305.10353 -87.525225)
					(end 304.71999 -87.141812)
				)
				(arc
					(start 303.80305 -87.141812)
					(mid 303.41951 -87.525352)
					(end 303.80305 -87.908892)
				)
			)
		)
		(polygon
			(pts
				(arc
					(start 134.11454 -87.113872)
					(mid 133.730873 -86.730586)
					(end 133.34746 -87.114126)
				)
				(arc
					(start 133.34746 -88.019128)
					(mid 133.731 -88.402668)
					(end 134.11454 -88.019128)
				)
			)
		)
		(polygon
			(pts
				(arc
					(start 49.373536 -86.76894)
					(mid 48.989869 -86.385654)
					(end 48.606456 -86.769194)
				)
				(arc
					(start 48.606456 -87.746078)
					(mid 48.989996 -88.129618)
					(end 49.373536 -87.746078)
				)
			)
		)
		(polygon
			(pts
				(arc
					(start 49.373536 -83.937094)
					(mid 48.989996 -83.553554)
					(end 48.606456 -83.937094)
				)
				(arc
					(start 48.606456 -84.914232)
					(mid 48.990123 -85.297518)
					(end 49.373536 -84.913978)
				)
			)
		)
		(polygon
			(pts
				(arc
					(start 45.624242 -83.885786)
					(mid 46.007528 -83.502119)
					(end 45.623988 -83.118706)
				)
				(arc
					(start 44.647104 -83.118706)
					(mid 44.263564 -83.502246)
					(end 44.647104 -83.885786)
				)
			)
		)
		(polygon
			(pts
				(arc
					(start 42.670222 -83.873086)
					(mid 43.053762 -83.489546)
					(end 42.670222 -83.106006)
				)
				(arc
					(start 41.693084 -83.106006)
					(mid 41.309798 -83.489673)
					(end 41.693338 -83.873086)
				)
			)
		)
		(polygon
			(pts
				(arc
					(start 135.509508 -83.06054)
					(mid 135.893048 -82.677)
					(end 135.509508 -82.29346)
				)
				(arc
					(start 134.581138 -82.29346)
					(mid 134.197852 -82.677127)
					(end 134.581392 -83.06054)
				)
			)
		)
		(polygon
			(pts
				(arc
					(start 297.974004 -82.607404)
					(mid 298.35729 -82.223737)
					(end 297.97375 -81.840324)
				)
				(arc
					(start 297.05681 -81.840324)
					(mid 296.67327 -82.223864)
					(end 297.05681 -82.607404)
				)
			)
		)
		(polygon
			(pts
				(arc
					(start 39.975536 -82.070194)
					(mid 39.591996 -81.686654)
					(end 39.208456 -82.070194)
				)
				(arc
					(start 39.208456 -83.047332)
					(mid 39.592123 -83.430618)
					(end 39.975536 -83.047078)
				)
			)
		)
		(polygon
			(pts
				(arc
					(start 136.807956 -81.91754)
					(mid 137.191496 -81.534)
					(end 136.807956 -81.15046)
				)
				(arc
					(start 135.879586 -81.15046)
					(mid 135.4963 -81.534127)
					(end 135.87984 -81.91754)
				)
			)
		)
		(polygon
			(pts
				(arc
					(start 318.690498 -81.407)
					(mid 318.306958 -81.02346)
					(end 317.923418 -81.407)
				)
				(arc
					(start 317.923418 -82.423254)
					(mid 318.307085 -82.80654)
					(end 318.690498 -82.423)
				)
			)
		)
		(polygon
			(pts
				(arc
					(start 130.048254 -81.66354)
					(mid 130.43154 -81.279873)
					(end 130.048 -80.89646)
				)
				(arc
					(start 129.159 -80.89646)
					(mid 128.77546 -81.28)
					(end 129.159 -81.66354)
				)
			)
		)
		(polygon
			(pts
				(arc
					(start 132.59054 -91.169744)
					(mid 132.454638 -90.877119)
					(end 132.1435 -90.791792)
				)
				(arc
					(start 132.1435 -89.659206)
					(mid 132.454709 -89.573766)
					(end 132.59054 -89.281)
				)
				(arc
					(start 132.59054 -88.375744)
					(mid 132.454638 -88.083119)
					(end 132.1435 -87.997792)
				)
				(xy 132.1435 -85.392006) (xy 127.586994 -80.8355) (xy 125.397006 -80.8355) (xy 124.762006 -81.4705)
				(arc
					(start 123.94438 -81.4705)
					(mid 123.840536 -81.41977)
					(end 123.72594 -81.404714)
				)
				(xy 123.72594 -81.402174) (xy 122.924824 -81.427574) (xy 122.92457 -81.427828)
				(arc
					(start 122.92457 -81.430114)
					(mid 122.84521 -81.441633)
					(end 122.770392 -81.4705)
				)
				(xy 121.333006 -81.4705) (xy 120.8405 -81.963006) (xy 120.8405 -96.060006) (xy 118.8085 -98.092006)
				(xy 118.8085 -99.870006) (xy 117.650006 -101.0285) (xy 107.998006 -101.0285) (xy 107.5055 -101.521006)
				(arc
					(start 107.5055 -102.751128)
					(mid 107.495038 -102.800168)
					(end 107.49153 -102.850188)
				)
				(arc
					(start 107.49153 -103.850186)
					(mid 107.49504 -103.900206)
					(end 107.5055 -103.949246)
				)
				(xy 107.5055 -104.442006) (xy 107.2515 -104.696006) (xy 107.2515 -108.252006) (xy 106.2355 -109.268006)
				(xy 106.2355 -114.124994) (xy 106.728006 -114.6175) (xy 150.192994 -114.6175) (xy 150.3045 -114.505994)
				(xy 151.1935 -113.616994) (xy 151.1935 -113.489994) (xy 151.1935 -95.425006) (xy 150.3045 -94.536006)
				(xy 150.192994 -94.4245) (xy 134.571994 -94.4245)
				(arc
					(start 132.485892 -92.338398)
					(mid 132.563423 -92.216713)
					(end 132.59054 -92.075)
				)
			)
		)
		(polygon
			(pts
				(arc
					(start 133.858762 -81.500726)
					(mid 134.242048 -81.117059)
					(end 133.858508 -80.733646)
				)
				(arc
					(start 132.930392 -80.733646)
					(mid 132.546852 -81.117186)
					(end 132.930392 -81.500726)
				)
			)
		)
		(polygon
			(pts
				(arc
					(start 123.85294 -81.309464)
					(mid 124.236988 -80.926432)
					(end 123.853956 -80.542384)
				)
				(xy 123.833128 -80.542892)
				(arc
					(start 122.925332 -80.56626)
					(mid 122.566684 -80.923765)
					(end 122.924062 -81.28254)
				)
				(xy 123.831858 -81.308956)
			)
		)
		(polygon
			(pts
				(arc
					(start 125.756162 -80.635348)
					(mid 126.139702 -80.251808)
					(end 125.756162 -79.868268)
				)
				(arc
					(start 124.779024 -79.868268)
					(mid 124.395738 -80.251935)
					(end 124.779278 -80.635348)
				)
			)
		)
		(polygon
			(pts
				(arc
					(start 128.131316 -80.19034)
					(mid 128.514602 -79.806673)
					(end 128.131062 -79.42326)
				)
				(arc
					(start 127.154178 -79.42326)
					(mid 126.770638 -79.8068)
					(end 127.154178 -80.19034)
				)
			)
		)
		(polygon
			(pts
				(arc
					(start 132.005578 -80.13954)
					(mid 132.388864 -79.755873)
					(end 132.005324 -79.37246)
				)
				(arc
					(start 131.02844 -79.37246)
					(mid 130.6449 -79.756)
					(end 131.02844 -80.13954)
				)
			)
		)
		(polygon
			(pts
				(arc
					(start 39.975536 -79.74584)
					(mid 39.591869 -79.362554)
					(end 39.208456 -79.746094)
				)
				(arc
					(start 39.208456 -80.722978)
					(mid 39.591996 -81.106518)
					(end 39.975536 -80.722978)
				)
			)
		)
		(polygon
			(pts
				(arc
					(start 294.03294 -79.44993)
					(mid 293.6494 -79.06639)
					(end 293.26586 -79.44993)
				)
				(arc
					(start 293.26586 -80.367124)
					(mid 293.649527 -80.75041)
					(end 294.03294 -80.36687)
				)
			)
		)
		(polygon
			(pts
				(arc
					(start 318.792098 -78.445106)
					(mid 318.418337 -78.051917)
					(end 318.025018 -78.425548)
				)
				(arc
					(start 317.999618 -79.441548)
					(mid 318.373506 -79.83474)
					(end 318.766698 -79.460852)
				)
			)
		)
		(polygon
			(pts
				(arc
					(start 296.29354 -77.35951)
					(mid 295.91 -76.97597)
					(end 295.52646 -77.35951)
				)
				(arc
					(start 295.52646 -78.276704)
					(mid 295.910127 -78.65999)
					(end 296.29354 -78.27645)
				)
			)
		)
		(polygon
			(pts
				(arc
					(start 204.929232 -77.40904)
					(mid 205.312772 -77.0255)
					(end 204.929232 -76.64196)
				)
				(arc
					(start 203.947014 -76.64196)
					(mid 203.563728 -77.025627)
					(end 203.947268 -77.40904)
				)
			)
		)
		(polygon
			(pts
				(arc
					(start 200.928986 -77.40904)
					(mid 201.312272 -77.025373)
					(end 200.928732 -76.64196)
				)
				(arc
					(start 199.946768 -76.64196)
					(mid 199.563228 -77.0255)
					(end 199.946768 -77.40904)
				)
			)
		)
		(polygon
			(pts
				(arc
					(start 196.929502 -77.40904)
					(mid 197.313042 -77.0255)
					(end 196.929502 -76.64196)
				)
				(arc
					(start 195.947284 -76.64196)
					(mid 195.563998 -77.025627)
					(end 195.947538 -77.40904)
				)
			)
		)
		(polygon
			(pts
				(arc
					(start 192.929256 -77.40904)
					(mid 193.312542 -77.025373)
					(end 192.929002 -76.64196)
				)
				(arc
					(start 191.947038 -76.64196)
					(mid 191.563498 -77.0255)
					(end 191.947038 -77.40904)
				)
			)
		)
		(polygon
			(pts
				(arc
					(start 168.928542 -77.40904)
					(mid 169.312082 -77.0255)
					(end 168.928542 -76.64196)
				)
				(arc
					(start 167.946324 -76.64196)
					(mid 167.563038 -77.025627)
					(end 167.946578 -77.40904)
				)
			)
		)
		(polygon
			(pts
				(arc
					(start 164.928042 -77.40904)
					(mid 165.311582 -77.0255)
					(end 164.928042 -76.64196)
				)
				(arc
					(start 163.945824 -76.64196)
					(mid 163.562538 -77.025627)
					(end 163.946078 -77.40904)
				)
			)
		)
		(polygon
			(pts
				(arc
					(start 160.928812 -77.40904)
					(mid 161.312352 -77.0255)
					(end 160.928812 -76.64196)
				)
				(arc
					(start 159.946594 -76.64196)
					(mid 159.563308 -77.025627)
					(end 159.946848 -77.40904)
				)
			)
		)
		(polygon
			(pts
				(arc
					(start 156.928312 -77.40904)
					(mid 157.311852 -77.0255)
					(end 156.928312 -76.64196)
				)
				(arc
					(start 155.946094 -76.64196)
					(mid 155.562808 -77.025627)
					(end 155.946348 -77.40904)
				)
			)
		)
		(polygon
			(pts
				(xy 112.854994 -76.0095) (xy 83.868006 -76.0095) (xy 82.9945 -76.883006) (xy 82.9945 -84.406994)
				(xy 83.995006 -85.4075) (xy 108.125006 -85.4075) (xy 111.681006 -88.9635) (xy 116.537994 -88.9635)
				(xy 117.2845 -88.216994) (xy 117.2845 -80.439006)
			)
		)
		(polygon
			(pts
				(arc
					(start 320.570098 -75.209908)
					(mid 320.186558 -74.826368)
					(end 319.803018 -75.209908)
				)
				(arc
					(start 319.803018 -76.192126)
					(mid 320.186685 -76.575412)
					(end 320.570098 -76.191872)
				)
			)
		)
		(polygon
			(pts
				(arc
					(start 54.288436 -75.290426)
					(mid 54.671722 -74.906759)
					(end 54.288182 -74.523346)
				)
				(arc
					(start 53.311298 -74.523346)
					(mid 52.927758 -74.906886)
					(end 53.311298 -75.290426)
				)
			)
		)
		(polygon
			(pts
				(arc
					(start 51.888644 -75.290426)
					(mid 52.27193 -74.906759)
					(end 51.88839 -74.523346)
				)
				(arc
					(start 50.911506 -74.523346)
					(mid 50.527966 -74.906886)
					(end 50.911506 -75.290426)
				)
			)
		)
		(polygon
			(pts
				(arc
					(start 45.488606 -75.290426)
					(mid 45.871892 -74.906759)
					(end 45.488352 -74.523346)
				)
				(arc
					(start 44.511468 -74.523346)
					(mid 44.127928 -74.906886)
					(end 44.511468 -75.290426)
				)
			)
		)
		(polygon
			(pts
				(arc
					(start 43.088306 -75.138026)
					(mid 43.471846 -74.754486)
					(end 43.088306 -74.370946)
				)
				(arc
					(start 42.111168 -74.370946)
					(mid 41.727882 -74.754613)
					(end 42.111422 -75.138026)
				)
			)
		)
		(polygon
			(pts
				(arc
					(start 298.139612 -74.07529)
					(mid 298.522898 -73.691623)
					(end 298.139358 -73.30821)
				)
				(arc
					(start 297.123358 -73.30821)
					(mid 296.739818 -73.69175)
					(end 297.123358 -74.07529)
				)
			)
		)
		(polygon
			(pts
				(arc
					(start 302.956722 -73.99274)
					(mid 303.340262 -73.6092)
					(end 302.956722 -73.22566)
				)
				(arc
					(start 301.974504 -73.22566)
					(mid 301.591218 -73.609327)
					(end 301.974758 -73.99274)
				)
			)
		)
		(polygon
			(pts
				(arc
					(start 318.055498 -72.009)
					(mid 317.671958 -71.62546)
					(end 317.288418 -72.009)
				)
				(arc
					(start 317.288418 -73.025254)
					(mid 317.672085 -73.40854)
					(end 318.055498 -73.025)
				)
			)
		)
		(polygon
			(pts
				(arc
					(start 319.139316 -68.215764)
					(mid 318.755649 -67.832478)
					(end 318.372236 -68.216018)
				)
				(arc
					(start 318.372236 -69.197982)
					(mid 318.755776 -69.581522)
					(end 319.139316 -69.197982)
				)
			)
		)
		(polygon
			(pts
				(xy 241.251994 -53.4035) (xy 234.236006 -53.4035) (xy 233.1085 -54.531006) (xy 233.1085 -82.471006)
				(xy 230.1875 -85.392006) (xy 229.156006 -86.4235) (xy 211.249006 -86.4235) (xy 209.4865 -88.186006)
				(xy 209.4865 -100.789994) (xy 212.011006 -103.3145) (xy 216.994994 -103.3145) (xy 217.1065 -103.202994)
				(xy 219.788994 -100.5205) (xy 240.108994 -100.5205) (xy 240.2205 -100.408994) (xy 242.2525 -98.376994)
				(xy 242.2525 -54.404006)
			)
		)
		(polygon
			(pts
				(arc
					(start 78.663546 -41.98874)
					(mid 79.046832 -41.605073)
					(end 78.663292 -41.22166)
				)
				(arc
					(start 77.686408 -41.22166)
					(mid 77.302868 -41.6052)
					(end 77.686408 -41.98874)
				)
			)
		)
		(polygon
			(pts
				(arc
					(start 80.581246 -40.00754)
					(mid 80.964532 -39.623873)
					(end 80.580992 -39.24046)
				)
				(arc
					(start 79.604108 -39.24046)
					(mid 79.220568 -39.624)
					(end 79.604108 -40.00754)
				)
			)
		)
		(polygon
			(pts
				(arc
					(start 83.294728 -37.831776)
					(mid 82.911188 -37.448236)
					(end 82.527648 -37.831776)
				)
				(arc
					(start 82.527648 -38.737032)
					(mid 82.911315 -39.120318)
					(end 83.294728 -38.736778)
				)
			)
		)
		(polygon
			(pts
				(arc
					(start 84.413852 -37.734494)
					(mid 84.04606 -37.386514)
					(end 83.69808 -37.754306)
				)
				(xy 83.69554 -37.754306) (xy 83.723734 -38.770306) (xy 83.723988 -38.77056)
				(arc
					(start 83.726274 -38.77056)
					(mid 84.094066 -39.11854)
					(end 84.442046 -38.750748)
				)
				(xy 84.444586 -38.750748) (xy 84.416392 -37.734494)
			)
		)
		(polygon
			(pts
				(arc
					(start 77.133958 -37.042852)
					(mid 77.517498 -36.659312)
					(end 77.133958 -36.275772)
				)
				(arc
					(start 76.15682 -36.275772)
					(mid 75.773534 -36.659439)
					(end 76.157074 -37.042852)
				)
			)
		)
		(polygon
			(pts
				(arc
					(start 81.61274 -36.334954)
					(mid 81.229073 -35.951668)
					(end 80.84566 -36.335208)
				)
				(arc
					(start 80.84566 -37.312092)
					(mid 81.2292 -37.695632)
					(end 81.61274 -37.312092)
				)
			)
		)
		(polygon
			(pts
				(arc
					(start 83.46694 -34.618422)
					(mid 83.083273 -34.235136)
					(end 82.69986 -34.618676)
				)
				(arc
					(start 82.69986 -35.523678)
					(mid 83.0834 -35.907218)
					(end 83.46694 -35.523678)
				)
			)
		)
		(polygon
			(pts
				(arc
					(start 85.37194 -32.884618)
					(mid 84.988273 -32.501332)
					(end 84.60486 -32.884872)
				)
				(arc
					(start 84.60486 -33.789874)
					(mid 84.9884 -34.173414)
					(end 85.37194 -33.789874)
				)
			)
		)
		(polygon
			(pts
				(arc
					(start 277.84933 -32.51454)
					(mid 278.232616 -32.130873)
					(end 277.849076 -31.74746)
				)
				(arc
					(start 276.867112 -31.74746)
					(mid 276.483572 -32.131)
					(end 276.867112 -32.51454)
				)
			)
		)
		(polygon
			(pts
				(arc
					(start 272.999962 -11.779758)
					(mid 273.789902 -10.989818)
					(end 272.999962 -10.199878)
				)
				(arc
					(start 270.999966 -10.199878)
					(mid 270.210026 -10.989818)
					(end 270.999966 -11.779758)
				)
			)
		)
	)
	(zone
		(net "P1V5_C")
		(layer "In3.Cu")
		(hatch none 0.5)
		(connect_pads
			(clearance 0.5)
		)
		(min_thickness 0.25)
		(fill yes
			(thermal_gap 0.5)
			(thermal_bridge_width 0.5)
			(island_removal_mode 0)
		)
		(polygon
			(pts
				(xy 234.393994 -53.7845) (xy 233.4895 -54.688994) (xy 233.4895 -82.628994) (xy 229.4255 -86.692994)
				(xy 229.313994 -86.8045) (xy 211.406994 -86.8045) (xy 209.8675 -88.343994) (xy 209.8675 -100.632006)
				(xy 212.168994 -102.9335) (xy 216.837006 -102.9335) (xy 219.631006 -100.1395) (xy 239.951006 -100.1395)
				(xy 241.8715 -98.219006) (xy 241.8715 -54.561994) (xy 241.094006 -53.7845)
			)
		)
	)
	(zone
		(net "P1V5_C")
		(layer "In4.Cu")
		(hatch none 0.5)
		(connect_pads
			(clearance 0.5)
		)
		(min_thickness 0.25)
		(fill yes
			(thermal_gap 0.5)
			(thermal_bridge_width 0.5)
			(island_removal_mode 0)
		)
		(polygon
			(pts
				(xy 95.1865 -29.161994)
				(arc
					(start 95.1865 -35.048952)
					(mid 95.414519 -35.165382)
					(end 95.50654 -35.404298)
				)
				(xy 95.50654 -35.40506)
				(arc
					(start 95.508318 -36.199318)
					(mid 95.416121 -36.439698)
					(end 95.1865 -36.556188)
				)
				(xy 95.1865 -37.005006) (xy 95.963994 -37.7825) (xy 103.934006 -37.7825) (xy 104.3305 -37.386006)
				(xy 104.3305 -35.354006) (xy 110.538006 -29.1465) (xy 136.016746 -29.1465) (xy 136.095486 -29.146246)
				(xy 136.09574 -29.1465) (xy 136.095994 -29.1465) (xy 136.15162 -29.202126) (xy 170.13174 -63.0555)
				(xy 240.459006 -63.0555) (xy 241.8715 -61.643006) (xy 241.8715 -54.688994) (xy 240.586006 -53.4035)
				(xy 175.816006 -53.4035) (xy 139.367006 -16.9545) (xy 107.393994 -16.9545)
			)
		)
		(polygon
			(pts
				(arc
					(start 96.30664 -35.406838)
					(mid 95.947738 -35.04946)
					(end 95.59036 -35.408362)
				)
				(xy 95.592138 -36.199318) (xy 95.592138 -36.20008)
				(arc
					(start 95.592138 -36.200588)
					(mid 95.950913 -36.55822)
					(end 96.308418 -36.199318)
				)
				(xy 96.30664 -35.408362) (xy 96.30664 -35.4076)
			)
		)
		(polygon
			(pts
				(arc
					(start 98.700082 -35.397694)
					(mid 98.338132 -35.043364)
					(end 97.983802 -35.405314)
				)
				(arc
					(start 97.992184 -36.203636)
					(mid 98.354007 -36.558219)
					(end 98.708464 -36.19627)
				)
			)
		)
		(polygon
			(pts
				(arc
					(start 103.508302 -35.400234)
					(mid 103.150162 -35.042094)
					(end 102.792022 -35.400234)
				)
				(arc
					(start 102.792022 -36.200334)
					(mid 103.150289 -36.55822)
					(end 103.508302 -36.20008)
				)
			)
		)
		(polygon
			(pts
				(arc
					(start 97.898966 -35.395916)
					(mid 97.536508 -35.042094)
					(end 97.182686 -35.404552)
				)
				(arc
					(start 97.192084 -36.204144)
					(mid 97.554415 -36.558219)
					(end 97.908364 -36.195762)
				)
			)
		)
		(polygon
			(pts
				(arc
					(start 102.708202 -35.39998)
					(mid 102.349935 -35.04184)
					(end 101.991922 -35.400234)
				)
				(xy 101.991922 -35.40125)
				(arc
					(start 101.992176 -36.199826)
					(mid 102.350316 -36.55822)
					(end 102.708456 -36.199826)
				)
				(xy 102.708202 -35.75812)
			)
		)
		(polygon
			(pts
				(arc
					(start 101.115622 -35.40125)
					(mid 100.760784 -35.039808)
					(end 100.399342 -35.394646)
				)
				(arc
					(start 100.39223 -36.196524)
					(mid 100.746941 -36.558221)
					(end 101.10851 -36.203382)
				)
			)
		)
		(polygon
			(pts
				(arc
					(start 100.30968 -35.392868)
					(mid 99.952048 -35.03422)
					(end 99.5934 -35.391852)
				)
				(xy 99.5934 -35.397694) (xy 99.59213 -36.19627)
				(arc
					(start 99.59213 -36.199318)
					(mid 99.949635 -36.55822)
					(end 100.30841 -36.200588)
				)
				(xy 100.30841 -36.20008) (xy 100.30841 -36.199318)
			)
		)
	)
	(zone
		(net "P1V8_C")
		(layer "In4.Cu")
		(hatch none 0.5)
		(connect_pads
			(clearance 0.5)
		)
		(min_thickness 0.25)
		(fill yes
			(thermal_gap 0.5)
			(thermal_bridge_width 0.5)
			(island_removal_mode 0)
		)
		(polygon
			(pts
				(xy 110.695994 -29.5275) (xy 104.7115 -35.511994) (xy 104.7115 -37.386006) (xy 113.235994 -45.9105)
				(xy 119.555006 -45.9105) (xy 122.9995 -42.466006) (xy 122.9995 -30.050994) (xy 122.476006 -29.5275)
			)
		)
	)
	(zone
		(net "P3V3_STBY")
		(layer "In4.Cu")
		(hatch none 0.5)
		(connect_pads
			(clearance 0.5)
		)
		(min_thickness 0.25)
		(fill yes
			(thermal_gap 0.5)
			(thermal_bridge_width 0.5)
			(island_removal_mode 0)
		)
		(polygon
			(pts
				(xy 335.739994 -85.6615) (xy 335.3435 -86.057994) (xy 335.3435 -94.790006) (xy 335.866994 -95.3135)
				(xy 340.281006 -95.3135) (xy 340.8045 -94.790006) (xy 340.8045 -86.311994) (xy 340.154006 -85.6615)
			)
		)
	)
	(zone
		(net "GND")
		(layer "In4.Cu")
		(hatch none 0.5)
		(connect_pads
			(clearance 0.5)
		)
		(min_thickness 0.25)
		(fill yes
			(thermal_gap 0.5)
			(thermal_bridge_width 0.5)
			(island_removal_mode 0)
		)
		(polygon
			(pts
				(xy 250.465844 -195.238116)
				(arc
					(start 250.49988 -195.272152)
					(mid 251.396754 -195.753482)
					(end 251.878084 -196.650356)
				)
				(xy 251.91212 -196.684392) (xy 251.91212 -196.94017) (xy 251.913136 -197.000114)
				(arc
					(start 251.913136 -246.000016)
					(mid 253.154117 -248.996009)
					(end 256.15011 -250.23699)
				)
				(arc
					(start 350.60001 -250.23699)
					(mid 353.596003 -248.996009)
					(end 354.836984 -246.000016)
				)
				(arc
					(start 354.836984 -0.999998)
					(mid 354.767574 -0.832426)
					(end 354.600002 -0.763016)
				)
				(arc
					(start 307.485034 -0.763016)
					(mid 307.317462 -0.832426)
					(end 307.248052 -0.999998)
				)
				(xy 307.248052 -43.50004) (xy 307.247036 -43.559984) (xy 307.247036 -43.815762)
				(arc
					(start 307.213 -43.849798)
					(mid 306.601183 -44.864739)
					(end 305.485038 -45.263054)
				)
				(arc
					(start 305.485038 -45.263054)
					(mid 305.317466 -45.332464)
					(end 305.248056 -45.500036)
				)
				(xy 305.248056 -47.4345) (xy 308.180994 -47.4345) (xy 311.4675 -50.721006) (xy 311.4675 -59.133994)
				(xy 309.323994 -61.2775) (xy 278.051006 -61.2775) (xy 271.304766 -54.531006) (xy 270.3195 -53.545994)
				(xy 270.3195 -50.243994) (xy 268.907006 -48.8315) (xy 267.129006 -48.8315) (xy 266.3825 -48.084994)
				(xy 266.3825 -47.038006) (xy 267.637006 -45.7835) (xy 276.303994 -45.7835) (xy 278.843994 -48.3235)
				(xy 281.722068 -48.3235)
				(arc
					(start 281.722068 -0.999998)
					(mid 281.652658 -0.832426)
					(end 281.485086 -0.763016)
				)
				(arc
					(start 75.449938 -0.763016)
					(mid 75.282366 -0.832426)
					(end 75.212956 -0.999998)
				)
				(xy 75.212956 -15.999968) (xy 75.21194 -16.059912) (xy 75.21194 -16.31569)
				(arc
					(start 75.177904 -16.349472)
					(mid 74.696539 -17.246565)
					(end 73.799446 -17.72793)
				)
				(xy 73.765664 -17.761966) (xy 73.509886 -17.761966) (xy 73.449942 -17.762982)
				(arc
					(start 62.95009 -17.762982)
					(mid 62.782518 -17.832392)
					(end 62.713108 -17.999964)
				)
				(xy 62.713108 -57.010046) (xy 62.712092 -57.069736) (xy 62.712092 -57.325768)
				(arc
					(start 62.678056 -57.359804)
					(mid 62.196726 -58.256678)
					(end 61.299852 -58.738008)
				)
				(xy 61.265816 -58.772044) (xy 61.009784 -58.772044) (xy 60.950094 -58.77306)
				(arc
					(start 29.500068 -58.77306)
					(mid 28.625391 -59.135363)
					(end 28.263088 -60.01004)
				)
				(xy 28.263088 -76.010008) (xy 28.262072 -76.084938) (xy 28.262072 -76.32573)
				(arc
					(start 28.242768 -76.345034)
					(mid 27.453867 -77.963799)
					(end 25.835102 -78.7527)
				)
				(xy 25.815798 -78.772004) (xy 25.575006 -78.772004) (xy 25.500076 -78.77302)
				(arc
					(start 2.999994 -78.77302)
					(mid 1.418212 -79.428216)
					(end 0.763016 -81.009998)
				)
				(arc
					(start 0.763016 -246.000016)
					(mid 2.003997 -248.996009)
					(end 4.99999 -250.23699)
				)
				(xy 26.34996 -250.23699) (xy 26.409904 -250.238006) (xy 26.665682 -250.238006)
				(arc
					(start 26.699464 -250.272042)
					(mid 27.596557 -250.753407)
					(end 28.077922 -251.6505)
				)
				(xy 28.111958 -251.684282) (xy 28.111958 -251.94006) (xy 28.112974 -252.000004) (xy 28.112974 -257.836924)
				(xy 33.78708 -257.836924) (xy 33.78708 -252.549914) (xy 33.788096 -252.490986) (xy 33.788096 -252.234192)
				(arc
					(start 33.823402 -252.198886)
					(mid 35.500056 -250.836908)
					(end 37.17671 -252.198886)
				)
				(xy 37.212016 -252.234192) (xy 37.212016 -252.490986) (xy 37.213032 -252.549914) (xy 37.213032 -257.836924)
				(xy 46.886876 -257.836924) (xy 46.886876 -252.000004) (xy 46.887892 -251.940314) (xy 46.887892 -251.684282)
				(arc
					(start 46.921928 -251.650246)
					(mid 47.403258 -250.753372)
					(end 48.300132 -250.272042)
				)
				(xy 48.334168 -250.238006) (xy 48.5902 -250.238006) (xy 48.64989 -250.23699) (xy 66.34988 -250.23699)
				(xy 66.409824 -250.238006) (xy 66.665602 -250.238006)
				(arc
					(start 66.699384 -250.272042)
					(mid 67.596477 -250.753407)
					(end 68.077842 -251.6505)
				)
				(xy 68.111878 -251.684282) (xy 68.111878 -251.94006) (xy 68.112894 -252.000004) (xy 68.112894 -257.836924)
				(xy 137.786872 -257.836924) (xy 137.786872 -252.549914) (xy 137.787888 -252.490986) (xy 137.787888 -252.234192)
				(arc
					(start 137.823194 -252.198886)
					(mid 139.500076 -250.836659)
					(end 141.176756 -252.198886)
				)
				(xy 141.212062 -252.234192) (xy 141.212062 -252.490986) (xy 141.213078 -252.549914) (xy 141.213078 -257.836924)
				(xy 150.886922 -257.836924) (xy 150.886922 -252.000004) (xy 150.887938 -251.94006) (xy 150.887938 -251.684282)
				(arc
					(start 150.921974 -251.650246)
					(mid 151.403304 -250.753372)
					(end 152.300178 -250.272042)
				)
				(xy 152.334214 -250.238006) (xy 152.589992 -250.238006) (xy 152.649936 -250.23699) (xy 181.150006 -250.23699)
				(xy 181.20995 -250.238006) (xy 181.465728 -250.238006)
				(arc
					(start 181.499764 -250.272042)
					(mid 182.396638 -250.753372)
					(end 182.877968 -251.650246)
				)
				(xy 182.912004 -251.684282) (xy 182.912004 -251.94006) (xy 182.91302 -252.000004) (xy 182.91302 -257.836924)
				(xy 188.586872 -257.836924) (xy 188.586872 -252.549914) (xy 188.587888 -252.490986) (xy 188.587888 -252.234192)
				(arc
					(start 188.623194 -252.198886)
					(mid 190.300076 -250.836659)
					(end 191.976756 -252.198886)
				)
				(xy 192.012062 -252.234192) (xy 192.012062 -252.490986) (xy 192.013078 -252.549914) (xy 192.013078 -257.836924)
				(xy 201.686922 -257.836924) (xy 201.686922 -252.000004) (xy 201.687938 -251.94006) (xy 201.687938 -251.684282)
				(arc
					(start 201.721974 -251.650246)
					(mid 202.203304 -250.753372)
					(end 203.100178 -250.272042)
				)
				(xy 203.134214 -250.238006) (xy 203.389992 -250.238006) (xy 203.449936 -250.23699)
				(arc
					(start 229.14991 -250.23699)
					(mid 232.145903 -248.996009)
					(end 233.386884 -246.000016)
				)
				(xy 233.386884 -197.000114) (xy 233.3879 -196.94017) (xy 233.3879 -196.684392)
				(arc
					(start 233.421936 -196.65061)
					(mid 233.903301 -195.753517)
					(end 234.800394 -195.272152)
				)
				(xy 234.834176 -195.238116) (xy 235.089954 -195.238116) (xy 235.149898 -195.2371) (xy 250.150122 -195.2371)
				(xy 250.210066 -195.238116)
			)
		)
		(polygon
			(pts
				(arc
					(start 285.550356 -185.54573)
					(mid 285.87573 -185.111644)
					(end 285.441644 -184.78627)
				)
				(arc
					(start 284.552898 -184.91327)
					(mid 284.227506 -185.347232)
					(end 284.661356 -185.67273)
				)
			)
		)
		(polygon
			(pts
				(arc
					(start 299.643546 -174.676054)
					(mid 299.280328 -175.028987)
					(end 299.633132 -175.392334)
				)
				(arc
					(start 300.430438 -175.40351)
					(mid 300.793658 -175.05045)
					(end 300.440598 -174.68723)
				)
			)
		)
		(polygon
			(pts
				(arc
					(start 303.024032 -174.096426)
					(mid 303.38903 -173.69536)
					(end 302.987964 -173.330362)
				)
				(xy 302.987964 -173.327822) (xy 302.21428 -173.36389) (xy 302.214026 -173.364144)
				(arc
					(start 302.214026 -173.36643)
					(mid 301.849028 -173.767496)
					(end 302.250094 -174.132494)
				)
				(xy 302.250094 -174.135034) (xy 303.024032 -174.098966)
			)
		)
		(polygon
			(pts
				(arc
					(start 350.369124 -154.275028)
					(mid 350.010984 -153.916888)
					(end 349.652844 -154.275028)
				)
				(arc
					(start 349.652844 -155.155392)
					(mid 350.011111 -155.513278)
					(end 350.369124 -155.155138)
				)
			)
		)
		(polygon
			(pts
				(arc
					(start 351.11309 -151.97201)
					(mid 350.75495 -151.61387)
					(end 350.39681 -151.97201)
				)
				(arc
					(start 350.39681 -152.917144)
					(mid 350.755077 -153.27503)
					(end 351.11309 -152.91689)
				)
			)
		)
		(polygon
			(pts
				(arc
					(start 351.824544 -147.98167)
					(mid 352.18243 -147.623403)
					(end 351.82429 -147.26539)
				)
				(arc
					(start 350.87941 -147.26539)
					(mid 350.52127 -147.62353)
					(end 350.87941 -147.98167)
				)
			)
		)
		(polygon
			(pts
				(arc
					(start 119.208296 -102.850188)
					(mid 118.850156 -102.492048)
					(end 118.492016 -102.850188)
				)
				(arc
					(start 118.492016 -103.85044)
					(mid 118.850283 -104.208326)
					(end 119.208296 -103.850186)
				)
			)
		)
		(polygon
			(pts
				(arc
					(start 118.208298 -102.850188)
					(mid 117.850158 -102.492048)
					(end 117.492018 -102.850188)
				)
				(arc
					(start 117.492018 -103.85044)
					(mid 117.850285 -104.208326)
					(end 118.208298 -103.850186)
				)
			)
		)
		(polygon
			(pts
				(arc
					(start 114.207798 -102.850188)
					(mid 113.849658 -102.492048)
					(end 113.491518 -102.850188)
				)
				(arc
					(start 113.491518 -103.85044)
					(mid 113.849785 -104.208326)
					(end 114.207798 -103.850186)
				)
			)
		)
		(polygon
			(pts
				(arc
					(start 112.207802 -102.850188)
					(mid 111.849662 -102.492048)
					(end 111.491522 -102.850188)
				)
				(arc
					(start 111.491522 -103.85044)
					(mid 111.849789 -104.208326)
					(end 112.207802 -103.850186)
				)
			)
		)
		(polygon
			(pts
				(arc
					(start 110.207806 -102.850188)
					(mid 109.849666 -102.492048)
					(end 109.491526 -102.850188)
				)
				(arc
					(start 109.491526 -103.85044)
					(mid 109.849793 -104.208326)
					(end 110.207806 -103.850186)
				)
			)
		)
		(polygon
			(pts
				(arc
					(start 109.207808 -102.850188)
					(mid 108.849668 -102.492048)
					(end 108.491528 -102.850188)
				)
				(arc
					(start 108.491528 -103.85044)
					(mid 108.849795 -104.208326)
					(end 109.207808 -103.850186)
				)
			)
		)
		(polygon
			(pts
				(arc
					(start 113.2078 -102.849934)
					(mid 112.849533 -102.492048)
					(end 112.49152 -102.850188)
				)
				(arc
					(start 112.49152 -103.850186)
					(mid 112.84966 -104.208326)
					(end 113.2078 -103.850186)
				)
			)
		)
		(polygon
			(pts
				(arc
					(start 111.207804 -102.849934)
					(mid 110.849537 -102.492048)
					(end 110.491524 -102.850188)
				)
				(arc
					(start 110.491524 -103.850186)
					(mid 110.849664 -104.208326)
					(end 111.207804 -103.850186)
				)
			)
		)
		(polygon
			(pts
				(arc
					(start 108.20781 -102.849934)
					(mid 107.849543 -102.492048)
					(end 107.49153 -102.850188)
				)
				(arc
					(start 107.49153 -103.850186)
					(mid 107.84967 -104.208326)
					(end 108.20781 -103.850186)
				)
			)
		)
		(polygon
			(pts
				(arc
					(start 107.207812 -102.849934)
					(mid 106.849545 -102.492048)
					(end 106.491532 -102.850188)
				)
				(arc
					(start 106.491532 -103.850186)
					(mid 106.849672 -104.208326)
					(end 107.207812 -103.850186)
				)
			)
		)
		(polygon
			(pts
				(arc
					(start 116.238782 -102.840028)
					(mid 115.880515 -102.482142)
					(end 115.522502 -102.840282)
				)
				(arc
					(start 115.522502 -103.830882)
					(mid 115.880642 -104.189022)
					(end 116.238782 -103.830882)
				)
			)
		)
		(polygon
			(pts
				(arc
					(start 115.222782 -102.840028)
					(mid 114.864515 -102.482142)
					(end 114.506502 -102.840282)
				)
				(arc
					(start 114.506502 -103.830882)
					(mid 114.864642 -104.189022)
					(end 115.222782 -103.830882)
				)
			)
		)
		(polygon
			(pts
				(arc
					(start 19.325082 -98.929444)
					(mid 19.708622 -98.545904)
					(end 19.325082 -98.162364)
				)
				(arc
					(start 18.258028 -98.162364)
					(mid 17.874742 -98.546031)
					(end 18.258282 -98.929444)
				)
			)
		)
		(polygon
			(pts
				(arc
					(start 11.147044 -98.109786)
					(mid 10.762742 -98.492564)
					(end 11.14552 -98.876866)
				)
				(arc
					(start 12.059666 -98.878644)
					(mid 12.444222 -98.495993)
					(end 12.061444 -98.111564)
				)
			)
		)
		(polygon
			(pts
				(xy 15.95755 -98.109278) (xy 15.957296 -98.109532)
				(arc
					(start 15.957296 -98.111818)
					(mid 15.563596 -98.48469)
					(end 15.936468 -98.87839)
				)
				(xy 15.936468 -98.88093) (xy 16.876268 -98.90633)
				(arc
					(start 16.876268 -98.90379)
					(mid 17.269968 -98.530918)
					(end 16.897096 -98.137218)
				)
				(xy 16.897096 -98.134678)
			)
		)
		(polygon
			(pts
				(arc
					(start 13.52931 -98.086672)
					(mid 13.12545 -98.448876)
					(end 13.487654 -98.852736)
				)
				(xy 14.4272 -98.903536)
				(arc
					(start 14.427454 -98.903536)
					(mid 14.831314 -98.541332)
					(end 14.46911 -98.137472)
				)
			)
		)
		(polygon
			(pts
				(arc
					(start 122.862848 -93.470222)
					(mid 122.497342 -93.820996)
					(end 122.848116 -94.186502)
				)
				(arc
					(start 123.843542 -94.206822)
					(mid 124.209305 -93.856175)
					(end 123.858528 -93.490542)
				)
			)
		)
		(polygon
			(pts
				(arc
					(start 123.208288 -91.849702)
					(mid 122.850021 -91.491562)
					(end 122.492008 -91.849956)
				)
				(arc
					(start 122.492262 -92.827348)
					(mid 122.850402 -93.185742)
					(end 123.208542 -92.827348)
				)
				(xy 123.208288 -91.849956)
			)
		)
		(polygon
			(pts
				(arc
					(start 132.59054 -91.169744)
					(mid 132.206873 -90.786458)
					(end 131.82346 -91.169998)
				)
				(arc
					(start 131.82346 -92.075)
					(mid 132.207 -92.45854)
					(end 132.59054 -92.075)
				)
			)
		)
		(polygon
			(pts
				(arc
					(start 123.850146 -91.207844)
					(mid 124.208286 -90.849704)
					(end 123.850146 -90.491564)
				)
				(arc
					(start 122.849894 -90.491564)
					(mid 122.492008 -90.849831)
					(end 122.850148 -91.207844)
				)
			)
		)
		(polygon
			(pts
				(arc
					(start 42.328338 -90.479626)
					(mid 42.711878 -90.096086)
					(end 42.328338 -89.712546)
				)
				(arc
					(start 41.3512 -89.712546)
					(mid 40.967914 -90.096213)
					(end 41.351454 -90.479626)
				)
			)
		)
		(polygon
			(pts
				(arc
					(start 39.407592 -90.479626)
					(mid 39.790878 -90.095959)
					(end 39.407338 -89.712546)
				)
				(arc
					(start 38.430454 -89.712546)
					(mid 38.046914 -90.096086)
					(end 38.430454 -90.479626)
				)
			)
		)
		(polygon
			(pts
				(arc
					(start 36.359592 -90.479626)
					(mid 36.742878 -90.095959)
					(end 36.359338 -89.712546)
				)
				(arc
					(start 35.382454 -89.712546)
					(mid 34.998914 -90.096086)
					(end 35.382454 -90.479626)
				)
			)
		)
		(polygon
			(pts
				(arc
					(start 33.311338 -90.479626)
					(mid 33.694878 -90.096086)
					(end 33.311338 -89.712546)
				)
				(arc
					(start 32.3342 -89.712546)
					(mid 31.950914 -90.096213)
					(end 32.334454 -90.479626)
				)
			)
		)
		(polygon
			(pts
				(arc
					(start 123.850146 -90.207846)
					(mid 124.208286 -89.849706)
					(end 123.850146 -89.491566)
				)
				(arc
					(start 122.849894 -89.491566)
					(mid 122.492008 -89.849833)
					(end 122.850148 -90.207846)
				)
			)
		)
		(polygon
			(pts
				(arc
					(start 134.11454 -89.654126)
					(mid 133.731 -89.270586)
					(end 133.34746 -89.654126)
				)
				(arc
					(start 133.34746 -90.559382)
					(mid 133.731127 -90.942668)
					(end 134.11454 -90.559128)
				)
			)
		)
		(polygon
			(pts
				(arc
					(start 132.59054 -88.375744)
					(mid 132.206873 -87.992458)
					(end 131.82346 -88.375998)
				)
				(arc
					(start 131.82346 -89.281)
					(mid 132.207 -89.66454)
					(end 132.59054 -89.281)
				)
			)
		)
		(polygon
			(pts
				(arc
					(start 304.720244 -87.908892)
					(mid 305.10353 -87.525225)
					(end 304.71999 -87.141812)
				)
				(arc
					(start 303.80305 -87.141812)
					(mid 303.41951 -87.525352)
					(end 303.80305 -87.908892)
				)
			)
		)
		(polygon
			(pts
				(arc
					(start 134.11454 -87.113872)
					(mid 133.730873 -86.730586)
					(end 133.34746 -87.114126)
				)
				(arc
					(start 133.34746 -88.019128)
					(mid 133.731 -88.402668)
					(end 134.11454 -88.019128)
				)
			)
		)
		(polygon
			(pts
				(arc
					(start 49.373536 -86.76894)
					(mid 48.989869 -86.385654)
					(end 48.606456 -86.769194)
				)
				(arc
					(start 48.606456 -87.746078)
					(mid 48.989996 -88.129618)
					(end 49.373536 -87.746078)
				)
			)
		)
		(polygon
			(pts
				(xy 340.311994 -85.2805) (xy 335.582006 -85.2805) (xy 334.9625 -85.900006) (xy 334.9625 -94.947994)
				(xy 335.709006 -95.6945) (xy 340.438994 -95.6945) (xy 340.5505 -95.582994) (xy 341.1855 -94.947994)
				(xy 341.1855 -86.154006) (xy 340.4235 -85.392006)
			)
		)
		(polygon
			(pts
				(arc
					(start 123.84532 -85.151214)
					(mid 124.182625 -84.773135)
					(end 123.804426 -84.43595)
				)
				(arc
					(start 122.829574 -84.492084)
					(mid 122.492516 -84.87029)
					(end 122.870722 -85.207348)
				)
			)
		)
		(polygon
			(pts
				(arc
					(start 49.373536 -83.937094)
					(mid 48.989996 -83.553554)
					(end 48.606456 -83.937094)
				)
				(arc
					(start 48.606456 -84.914232)
					(mid 48.990123 -85.297518)
					(end 49.373536 -84.913978)
				)
			)
		)
		(polygon
			(pts
				(arc
					(start 123.8504 -84.207858)
					(mid 124.208286 -83.849591)
					(end 123.850146 -83.491578)
				)
				(arc
					(start 122.850148 -83.491578)
					(mid 122.492008 -83.849718)
					(end 122.850148 -84.207858)
				)
			)
		)
		(polygon
			(pts
				(arc
					(start 45.624242 -83.885786)
					(mid 46.007528 -83.502119)
					(end 45.623988 -83.118706)
				)
				(arc
					(start 44.647104 -83.118706)
					(mid 44.263564 -83.502246)
					(end 44.647104 -83.885786)
				)
			)
		)
		(polygon
			(pts
				(arc
					(start 42.670222 -83.873086)
					(mid 43.053762 -83.489546)
					(end 42.670222 -83.106006)
				)
				(arc
					(start 41.693084 -83.106006)
					(mid 41.309798 -83.489673)
					(end 41.693338 -83.873086)
				)
			)
		)
		(polygon
			(pts
				(arc
					(start 123.850146 -83.20786)
					(mid 124.208286 -82.84972)
					(end 123.850146 -82.49158)
				)
				(arc
					(start 122.849894 -82.49158)
					(mid 122.492008 -82.849847)
					(end 122.850148 -83.20786)
				)
			)
		)
		(polygon
			(pts
				(arc
					(start 135.509508 -83.06054)
					(mid 135.893048 -82.677)
					(end 135.509508 -82.29346)
				)
				(arc
					(start 134.581138 -82.29346)
					(mid 134.197852 -82.677127)
					(end 134.581392 -83.06054)
				)
			)
		)
		(polygon
			(pts
				(arc
					(start 297.974004 -82.607404)
					(mid 298.35729 -82.223737)
					(end 297.97375 -81.840324)
				)
				(arc
					(start 297.05681 -81.840324)
					(mid 296.67327 -82.223864)
					(end 297.05681 -82.607404)
				)
			)
		)
		(polygon
			(pts
				(arc
					(start 39.975536 -82.070194)
					(mid 39.591996 -81.686654)
					(end 39.208456 -82.070194)
				)
				(arc
					(start 39.208456 -83.047332)
					(mid 39.592123 -83.430618)
					(end 39.975536 -83.047078)
				)
			)
		)
		(polygon
			(pts
				(arc
					(start 123.7488 -82.120486)
					(mid 124.095256 -81.75117)
					(end 123.72594 -81.404714)
				)
				(xy 123.72594 -81.402174) (xy 122.924824 -81.427574) (xy 122.92457 -81.427828)
				(arc
					(start 122.92457 -81.430114)
					(mid 122.578114 -81.79943)
					(end 122.94743 -82.145886)
				)
				(xy 122.94743 -82.148426) (xy 123.7488 -82.123026)
			)
		)
		(polygon
			(pts
				(arc
					(start 136.807956 -81.91754)
					(mid 137.191496 -81.534)
					(end 136.807956 -81.15046)
				)
				(arc
					(start 135.879586 -81.15046)
					(mid 135.4963 -81.534127)
					(end 135.87984 -81.91754)
				)
			)
		)
		(polygon
			(pts
				(arc
					(start 318.690498 -81.407)
					(mid 318.306958 -81.02346)
					(end 317.923418 -81.407)
				)
				(arc
					(start 317.923418 -82.423254)
					(mid 318.307085 -82.80654)
					(end 318.690498 -82.423)
				)
			)
		)
		(polygon
			(pts
				(arc
					(start 130.048254 -81.66354)
					(mid 130.43154 -81.279873)
					(end 130.048 -80.89646)
				)
				(arc
					(start 129.159 -80.89646)
					(mid 128.77546 -81.28)
					(end 129.159 -81.66354)
				)
			)
		)
		(polygon
			(pts
				(arc
					(start 133.858762 -81.500726)
					(mid 134.242048 -81.117059)
					(end 133.858508 -80.733646)
				)
				(arc
					(start 132.930392 -80.733646)
					(mid 132.546852 -81.117186)
					(end 132.930392 -81.500726)
				)
			)
		)
		(polygon
			(pts
				(arc
					(start 123.85294 -81.309464)
					(mid 124.236988 -80.926432)
					(end 123.853956 -80.542384)
				)
				(xy 123.833128 -80.542892)
				(arc
					(start 122.925332 -80.56626)
					(mid 122.566684 -80.923765)
					(end 122.924062 -81.28254)
				)
				(xy 123.831858 -81.308956)
			)
		)
		(polygon
			(pts
				(arc
					(start 125.756162 -80.635348)
					(mid 126.139702 -80.251808)
					(end 125.756162 -79.868268)
				)
				(arc
					(start 124.779024 -79.868268)
					(mid 124.395738 -80.251935)
					(end 124.779278 -80.635348)
				)
			)
		)
		(polygon
			(pts
				(arc
					(start 128.131316 -80.19034)
					(mid 128.514602 -79.806673)
					(end 128.131062 -79.42326)
				)
				(arc
					(start 127.154178 -79.42326)
					(mid 126.770638 -79.8068)
					(end 127.154178 -80.19034)
				)
			)
		)
		(polygon
			(pts
				(arc
					(start 132.005578 -80.13954)
					(mid 132.388864 -79.755873)
					(end 132.005324 -79.37246)
				)
				(arc
					(start 131.02844 -79.37246)
					(mid 130.6449 -79.756)
					(end 131.02844 -80.13954)
				)
			)
		)
		(polygon
			(pts
				(arc
					(start 39.975536 -79.74584)
					(mid 39.591869 -79.362554)
					(end 39.208456 -79.746094)
				)
				(arc
					(start 39.208456 -80.722978)
					(mid 39.591996 -81.106518)
					(end 39.975536 -80.722978)
				)
			)
		)
		(polygon
			(pts
				(arc
					(start 294.03294 -79.44993)
					(mid 293.6494 -79.06639)
					(end 293.26586 -79.44993)
				)
				(arc
					(start 293.26586 -80.367124)
					(mid 293.649527 -80.75041)
					(end 294.03294 -80.36687)
				)
			)
		)
		(polygon
			(pts
				(arc
					(start 318.792098 -78.445106)
					(mid 318.418337 -78.051917)
					(end 318.025018 -78.425548)
				)
				(arc
					(start 317.999618 -79.441548)
					(mid 318.373506 -79.83474)
					(end 318.766698 -79.460852)
				)
			)
		)
		(polygon
			(pts
				(arc
					(start 296.29354 -77.35951)
					(mid 295.91 -76.97597)
					(end 295.52646 -77.35951)
				)
				(arc
					(start 295.52646 -78.276704)
					(mid 295.910127 -78.65999)
					(end 296.29354 -78.27645)
				)
			)
		)
		(polygon
			(pts
				(arc
					(start 204.929232 -77.40904)
					(mid 205.312772 -77.0255)
					(end 204.929232 -76.64196)
				)
				(arc
					(start 203.947014 -76.64196)
					(mid 203.563728 -77.025627)
					(end 203.947268 -77.40904)
				)
			)
		)
		(polygon
			(pts
				(arc
					(start 200.928986 -77.40904)
					(mid 201.312272 -77.025373)
					(end 200.928732 -76.64196)
				)
				(arc
					(start 199.946768 -76.64196)
					(mid 199.563228 -77.0255)
					(end 199.946768 -77.40904)
				)
			)
		)
		(polygon
			(pts
				(arc
					(start 196.929502 -77.40904)
					(mid 197.313042 -77.0255)
					(end 196.929502 -76.64196)
				)
				(arc
					(start 195.947284 -76.64196)
					(mid 195.563998 -77.025627)
					(end 195.947538 -77.40904)
				)
			)
		)
		(polygon
			(pts
				(arc
					(start 192.929256 -77.40904)
					(mid 193.312542 -77.025373)
					(end 192.929002 -76.64196)
				)
				(arc
					(start 191.947038 -76.64196)
					(mid 191.563498 -77.0255)
					(end 191.947038 -77.40904)
				)
			)
		)
		(polygon
			(pts
				(arc
					(start 168.928542 -77.40904)
					(mid 169.312082 -77.0255)
					(end 168.928542 -76.64196)
				)
				(arc
					(start 167.946324 -76.64196)
					(mid 167.563038 -77.025627)
					(end 167.946578 -77.40904)
				)
			)
		)
		(polygon
			(pts
				(arc
					(start 164.928042 -77.40904)
					(mid 165.311582 -77.0255)
					(end 164.928042 -76.64196)
				)
				(arc
					(start 163.945824 -76.64196)
					(mid 163.562538 -77.025627)
					(end 163.946078 -77.40904)
				)
			)
		)
		(polygon
			(pts
				(arc
					(start 160.928812 -77.40904)
					(mid 161.312352 -77.0255)
					(end 160.928812 -76.64196)
				)
				(arc
					(start 159.946594 -76.64196)
					(mid 159.563308 -77.025627)
					(end 159.946848 -77.40904)
				)
			)
		)
		(polygon
			(pts
				(arc
					(start 156.928312 -77.40904)
					(mid 157.311852 -77.0255)
					(end 156.928312 -76.64196)
				)
				(arc
					(start 155.946094 -76.64196)
					(mid 155.562808 -77.025627)
					(end 155.946348 -77.40904)
				)
			)
		)
		(polygon
			(pts
				(arc
					(start 320.570098 -75.209908)
					(mid 320.186558 -74.826368)
					(end 319.803018 -75.209908)
				)
				(arc
					(start 319.803018 -76.192126)
					(mid 320.186685 -76.575412)
					(end 320.570098 -76.191872)
				)
			)
		)
		(polygon
			(pts
				(arc
					(start 54.288436 -75.290426)
					(mid 54.671722 -74.906759)
					(end 54.288182 -74.523346)
				)
				(arc
					(start 53.311298 -74.523346)
					(mid 52.927758 -74.906886)
					(end 53.311298 -75.290426)
				)
			)
		)
		(polygon
			(pts
				(arc
					(start 51.888644 -75.290426)
					(mid 52.27193 -74.906759)
					(end 51.88839 -74.523346)
				)
				(arc
					(start 50.911506 -74.523346)
					(mid 50.527966 -74.906886)
					(end 50.911506 -75.290426)
				)
			)
		)
		(polygon
			(pts
				(arc
					(start 45.488606 -75.290426)
					(mid 45.871892 -74.906759)
					(end 45.488352 -74.523346)
				)
				(arc
					(start 44.511468 -74.523346)
					(mid 44.127928 -74.906886)
					(end 44.511468 -75.290426)
				)
			)
		)
		(polygon
			(pts
				(arc
					(start 43.088306 -75.138026)
					(mid 43.471846 -74.754486)
					(end 43.088306 -74.370946)
				)
				(arc
					(start 42.111168 -74.370946)
					(mid 41.727882 -74.754613)
					(end 42.111422 -75.138026)
				)
			)
		)
		(polygon
			(pts
				(arc
					(start 298.139612 -74.07529)
					(mid 298.522898 -73.691623)
					(end 298.139358 -73.30821)
				)
				(arc
					(start 297.123358 -73.30821)
					(mid 296.739818 -73.69175)
					(end 297.123358 -74.07529)
				)
			)
		)
		(polygon
			(pts
				(arc
					(start 302.956722 -73.99274)
					(mid 303.340262 -73.6092)
					(end 302.956722 -73.22566)
				)
				(arc
					(start 301.974504 -73.22566)
					(mid 301.591218 -73.609327)
					(end 301.974758 -73.99274)
				)
			)
		)
		(polygon
			(pts
				(xy 29.2735 -126.540006) (xy 29.2735 -151.208994) (xy 31.036006 -152.9715) (xy 69.420994 -152.9715)
				(xy 105.9815 -116.410994) (xy 105.9815 -102.694994) (xy 110.6805 -97.995994) (xy 110.6805 -91.137994)
				(xy 112.854994 -88.9635) (xy 118.696994 -88.9635) (xy 120.2055 -87.454994) (xy 120.2055 -78.407006)
				(xy 115.648994 -73.8505) (xy 106.250994 -73.8505) (xy 105.234994 -72.8345) (xy 82.979006 -72.8345)
				(xy 58.1025 -97.711006) (xy 58.1025 -107.744006) (xy 57.579006 -108.2675) (xy 47.546006 -108.2675)
			)
		)
		(polygon
			(pts
				(arc
					(start 318.055498 -72.009)
					(mid 317.671958 -71.62546)
					(end 317.288418 -72.009)
				)
				(arc
					(start 317.288418 -73.025254)
					(mid 317.672085 -73.40854)
					(end 318.055498 -73.025)
				)
			)
		)
		(polygon
			(pts
				(arc
					(start 319.139316 -68.215764)
					(mid 318.755649 -67.832478)
					(end 318.372236 -68.216018)
				)
				(arc
					(start 318.372236 -69.197982)
					(mid 318.755776 -69.581522)
					(end 319.139316 -69.197982)
				)
			)
		)
		(polygon
			(pts
				(arc
					(start 93.914976 -42.600118)
					(mid 93.55963 -42.239184)
					(end 93.198696 -42.59453)
				)
				(arc
					(start 93.192346 -43.387772)
					(mid 93.547565 -43.748961)
					(end 93.908626 -43.393614)
				)
			)
		)
		(polygon
			(pts
				(arc
					(start 92.753942 -41.438576)
					(mid 92.392247 -41.793033)
					(end 92.746576 -42.154856)
				)
				(arc
					(start 93.550994 -42.16273)
					(mid 93.91269 -41.808146)
					(end 93.558106 -41.44645)
				)
			)
		)
		(polygon
			(pts
				(arc
					(start 78.663546 -41.98874)
					(mid 79.046832 -41.605073)
					(end 78.663292 -41.22166)
				)
				(arc
					(start 77.686408 -41.22166)
					(mid 77.302868 -41.6052)
					(end 77.686408 -41.98874)
				)
			)
		)
		(polygon
			(pts
				(arc
					(start 93.898974 -40.193722)
					(mid 93.534484 -39.841932)
					(end 93.182694 -40.206422)
				)
				(arc
					(start 93.196664 -41.001696)
					(mid 93.561027 -41.353738)
					(end 93.912944 -40.98925)
				)
			)
		)
		(polygon
			(pts
				(arc
					(start 80.581246 -40.00754)
					(mid 80.964532 -39.623873)
					(end 80.580992 -39.24046)
				)
				(arc
					(start 79.604108 -39.24046)
					(mid 79.220568 -39.624)
					(end 79.604108 -40.00754)
				)
			)
		)
		(polygon
			(pts
				(arc
					(start 92.746576 -39.03726)
					(mid 92.387674 -39.394511)
					(end 92.744798 -39.75354)
				)
				(arc
					(start 93.55582 -39.755318)
					(mid 93.914722 -39.39794)
					(end 93.557344 -39.039038)
				)
			)
		)
		(polygon
			(pts
				(arc
					(start 83.294728 -37.831776)
					(mid 82.911188 -37.448236)
					(end 82.527648 -37.831776)
				)
				(arc
					(start 82.527648 -38.737032)
					(mid 82.911315 -39.120318)
					(end 83.294728 -38.736778)
				)
			)
		)
		(polygon
			(pts
				(arc
					(start 93.914722 -37.80282)
					(mid 93.557217 -37.444172)
					(end 93.198442 -37.80155)
				)
				(arc
					(start 93.197426 -38.596316)
					(mid 93.555058 -38.954964)
					(end 93.913706 -38.597332)
				)
				(xy 93.913706 -38.596824) (xy 93.913706 -38.596316)
			)
		)
		(polygon
			(pts
				(arc
					(start 84.413852 -37.734494)
					(mid 84.04606 -37.386514)
					(end 83.69808 -37.754306)
				)
				(xy 83.69554 -37.754306) (xy 83.723734 -38.770306) (xy 83.723988 -38.77056)
				(arc
					(start 83.726274 -38.77056)
					(mid 84.094066 -39.11854)
					(end 84.442046 -38.750748)
				)
				(xy 84.444586 -38.750748) (xy 84.416392 -37.734494)
			)
		)
		(polygon
			(pts
				(arc
					(start 94.360492 -37.357558)
					(mid 94.717362 -36.998021)
					(end 94.357698 -36.641278)
				)
				(arc
					(start 93.550232 -36.64458)
					(mid 93.193616 -37.004244)
					(end 93.55328 -37.36086)
				)
			)
		)
		(polygon
			(pts
				(arc
					(start 77.133958 -37.042852)
					(mid 77.517498 -36.659312)
					(end 77.133958 -36.275772)
				)
				(arc
					(start 76.15682 -36.275772)
					(mid 75.773534 -36.659439)
					(end 76.157074 -37.042852)
				)
			)
		)
		(polygon
			(pts
				(arc
					(start 81.61274 -36.334954)
					(mid 81.229073 -35.951668)
					(end 80.84566 -36.335208)
				)
				(arc
					(start 80.84566 -37.312092)
					(mid 81.2292 -37.695632)
					(end 81.61274 -37.312092)
				)
			)
		)
		(polygon
			(pts
				(arc
					(start 93.90761 -35.406838)
					(mid 93.548454 -35.049714)
					(end 93.19133 -35.40887)
				)
				(arc
					(start 93.193616 -36.197032)
					(mid 93.552645 -36.55441)
					(end 93.909896 -36.195254)
				)
				(xy 93.90761 -35.40887) (xy 93.90761 -35.407854)
			)
		)
		(polygon
			(pts
				(arc
					(start 94.352618 -34.958274)
					(mid 94.707964 -34.59734)
					(end 94.34703 -34.241994)
				)
				(arc
					(start 93.544644 -34.248344)
					(mid 93.189297 -34.609151)
					(end 93.549978 -34.964624)
				)
			)
		)
		(polygon
			(pts
				(arc
					(start 83.46694 -34.618422)
					(mid 83.083273 -34.235136)
					(end 82.69986 -34.618676)
				)
				(arc
					(start 82.69986 -35.523678)
					(mid 83.0834 -35.907218)
					(end 83.46694 -35.523678)
				)
			)
		)
		(polygon
			(pts
				(arc
					(start 85.37194 -32.884618)
					(mid 84.988273 -32.501332)
					(end 84.60486 -32.884872)
				)
				(arc
					(start 84.60486 -33.789874)
					(mid 84.9884 -34.173414)
					(end 85.37194 -33.789874)
				)
			)
		)
		(polygon
			(pts
				(arc
					(start 277.84933 -32.51454)
					(mid 278.232616 -32.130873)
					(end 277.849076 -31.74746)
				)
				(arc
					(start 276.867112 -31.74746)
					(mid 276.483572 -32.131)
					(end 276.867112 -32.51454)
				)
			)
		)
		(polygon
			(pts
				(xy 139.524994 -16.5735) (xy 107.236006 -16.5735) (xy 94.8055 -29.004006)
				(arc
					(start 94.8055 -35.301682)
					(mid 94.794032 -35.353189)
					(end 94.79026 -35.405822)
				)
				(xy 94.79026 -35.406838) (xy 94.79026 -35.407854) (xy 94.792038 -36.195254) (xy 94.792038 -36.196016)
				(arc
					(start 94.792038 -36.200588)
					(mid 94.795472 -36.249308)
					(end 94.8055 -36.297108)
				)
				(xy 94.8055 -37.162994) (xy 95.806006 -38.1635) (xy 104.950006 -38.1635) (xy 113.078006 -46.2915)
				(xy 119.712994 -46.2915) (xy 123.3805 -42.623994) (xy 123.3805 -30.050994) (xy 123.903994 -29.5275)
				(xy 135.93826 -29.5275) (xy 149.083776 -42.623994) (xy 169.91838 -63.380874) (xy 169.974006 -63.4365)
				(xy 169.97426 -63.4365) (xy 169.974514 -63.436754) (xy 170.053254 -63.4365) (xy 240.616994 -63.4365)
				(xy 242.2525 -61.800994) (xy 242.2525 -54.531006) (xy 240.743994 -53.0225) (xy 175.973994 -53.0225)
			)
		)
		(polygon
			(pts
				(arc
					(start 272.999962 -11.779758)
					(mid 273.789902 -10.989818)
					(end 272.999962 -10.199878)
				)
				(arc
					(start 270.999966 -10.199878)
					(mid 270.210026 -10.989818)
					(end 270.999966 -11.779758)
				)
			)
		)
		(polygon
			(pts
				(arc
					(start 107.54995 -5.324348)
					(mid 107.54995 -6.675628)
					(end 107.54995 -5.324348)
				)
			)
		)
		(polygon
			(pts
				(arc
					(start 104.950006 -5.324348)
					(mid 104.950006 -6.675628)
					(end 104.950006 -5.324348)
				)
			)
		)
		(polygon
			(pts
				(arc
					(start 102.350062 -5.324348)
					(mid 102.350062 -6.675628)
					(end 102.350062 -5.324348)
				)
			)
		)
	)
	(zone
		(net "P12V")
		(layer "In4.Cu")
		(hatch none 0.5)
		(connect_pads
			(clearance 0.5)
		)
		(min_thickness 0.25)
		(fill yes
			(thermal_gap 0.5)
			(thermal_bridge_width 0.5)
			(island_removal_mode 0)
		)
		(polygon
			(pts
				(xy 267.794994 -46.1645) (xy 266.7635 -47.195994) (xy 266.7635 -47.927006) (xy 267.286994 -48.4505)
				(xy 269.064994 -48.4505) (xy 270.7005 -50.086006) (xy 270.7005 -53.388006) (xy 278.208994 -60.8965)
				(xy 309.166006 -60.8965) (xy 311.0865 -58.976006) (xy 311.0865 -50.878994) (xy 308.023006 -47.8155)
				(xy 305.248056 -47.8155) (xy 305.248056 -53.50002) (xy 305.24704 -53.559964) (xy 305.24704 -53.815742)
				(arc
					(start 305.213004 -53.849778)
					(mid 304.731674 -54.746652)
					(end 303.8348 -55.227982)
				)
				(xy 303.800764 -55.262018) (xy 303.544986 -55.262018) (xy 303.485042 -55.263034) (xy 283.485082 -55.263034)
				(xy 283.425138 -55.262018) (xy 283.16936 -55.262018)
				(arc
					(start 283.135578 -55.227982)
					(mid 282.238485 -54.746617)
					(end 281.75712 -53.849524)
				)
				(xy 281.723084 -53.815742) (xy 281.723084 -53.559964) (xy 281.722068 -53.50002) (xy 281.722068 -48.7045)
				(xy 278.686006 -48.7045) (xy 276.146006 -46.1645)
			)
		)
	)
	(zone
		(net "P1V8_E")
		(layer "In4.Cu")
		(hatch none 0.5)
		(connect_pads
			(clearance 0.5)
		)
		(min_thickness 0.25)
		(fill yes
			(thermal_gap 0.5)
			(thermal_bridge_width 0.5)
			(island_removal_mode 0)
		)
		(polygon
			(pts
				(xy 83.136994 -73.2155) (xy 58.4835 -97.868994) (xy 58.4835 -107.901994) (xy 57.736994 -108.6485)
				(xy 47.703994 -108.6485) (xy 29.6545 -126.697994) (xy 29.6545 -151.051006) (xy 31.193994 -152.5905)
				(xy 69.263006 -152.5905) (xy 105.6005 -116.253006) (xy 105.6005 -102.537006) (xy 110.2995 -97.838006)
				(xy 110.2995 -90.980006) (xy 112.697006 -88.5825) (xy 118.539006 -88.5825) (xy 119.8245 -87.297006)
				(xy 119.8245 -78.564994) (xy 115.491006 -74.2315) (xy 106.093006 -74.2315) (xy 105.077006 -73.2155)
			)
		)
	)
	(zone
		(net "P1V8_C")
		(layer "In5.Cu")
		(hatch none 0.5)
		(connect_pads
			(clearance 0.5)
		)
		(min_thickness 0.25)
		(fill yes
			(thermal_gap 0.5)
			(thermal_bridge_width 0.5)
			(island_removal_mode 0)
		)
		(polygon
			(pts
				(xy 70.1675 -28.321) (xy 69.2785 -29.21) (xy 69.2785 -48.0695) (xy 65.405 -51.943) (xy 65.405 -57.023)
				(xy 74.549 -66.167) (xy 81.28 -66.167) (xy 81.534 -65.913) (xy 81.534 -64.389) (xy 76.073 -58.928)
				(xy 76.073 -38.989) (xy 75.311 -38.227) (xy 75.311 -36.576) (xy 76.835 -35.052) (xy 86.614 -35.052)
				(xy 88.773 -32.893) (xy 94.234 -32.893) (xy 95.504 -34.163) (xy 95.504 -37.846) (xy 94.742 -38.608)
				(xy 94.742 -46.228) (xy 94.107 -46.863) (xy 92.71 -46.863) (xy 92.329 -47.244) (xy 92.329 -52.324)
				(xy 97.917 -57.912) (xy 100.838 -57.912) (xy 102.997 -60.071) (xy 107.061 -60.071) (xy 110.998 -64.008)
				(xy 111.887 -64.008) (xy 112.395 -63.5) (xy 112.395 -60.96) (xy 110.617 -59.182) (xy 110.617 -58.547)
				(xy 109.347 -57.277) (xy 109.347 -55.626) (xy 108.966 -55.245) (xy 108.966 -54.61) (xy 109.347 -54.229)
				(xy 111.125 -54.229) (xy 111.76 -53.594) (xy 111.76 -50.292) (xy 111.379 -49.911) (xy 111.379 -46.355)
				(xy 112.2045 -45.5295) (xy 112.2045 -44.8945) (xy 112.014 -44.704) (xy 109.474 -44.704) (xy 108.204 -45.974)
				(xy 108.204 -48.895) (xy 107.442 -49.657) (xy 98.298 -49.657) (xy 97.917 -49.276) (xy 97.917 -42.545)
				(xy 100.584 -39.878) (xy 111.252 -39.878) (xy 111.506 -39.624) (xy 111.506 -37.719) (xy 110.617 -36.83)
				(xy 110.617 -34.163) (xy 104.902 -28.448) (xy 104.902 -28.321)
			)
		)
		(polygon
			(pts
				(arc
					(start 95.605092 -37.94379)
					(mid 95.535999 -37.883892)
					(end 95.44685 -37.903912)
				)
				(xy 94.742508 -38.608254)
				(arc
					(start 94.742508 -39.031164)
					(mid 94.804264 -39.114681)
					(end 94.9071 -39.100252)
				)
				(arc
					(start 94.9071 -39.100252)
					(mid 95.207121 -39.021484)
					(end 95.466408 -39.191692)
				)
				(arc
					(start 95.466408 -39.191692)
					(mid 95.550731 -39.238164)
					(end 95.63608 -39.19347)
				)
				(arc
					(start 95.63608 -39.19347)
					(mid 95.681819 -39.137888)
					(end 95.737172 -39.09187)
				)
				(arc
					(start 95.737172 -39.09187)
					(mid 95.781471 -39.007874)
					(end 95.736918 -38.923976)
				)
				(arc
					(start 95.736918 -38.923976)
					(mid 95.569271 -38.602857)
					(end 95.745554 -38.286436)
				)
				(arc
					(start 95.745554 -38.286436)
					(mid 95.792474 -38.201754)
					(end 95.747078 -38.116256)
				)
				(arc
					(start 95.747078 -38.116256)
					(mid 95.66318 -38.040648)
					(end 95.605092 -37.94379)
				)
			)
		)
	)
	(zone
		(layer "In5.Cu")
		(hatch none 0.5)
		(connect_pads
			(clearance 0)
		)
		(min_thickness 0.25)
		(keepout
			(tracks not_allowed)
			(vias allowed)
			(pads allowed)
			(copperpour not_allowed)
			(footprints allowed)
		)
		(placement
			(enabled no)
			(sheetname "")
		)
		(fill
			(thermal_gap 0.5)
			(thermal_bridge_width 0.5)
			(island_removal_mode 0)
		)
		(polygon
			(pts
				(arc
					(start 35.382454 -89.712546)
					(mid 34.998914 -90.096086)
					(end 35.382454 -90.479626)
				)
				(arc
					(start 35.656266 -90.479626)
					(mid 35.637442 -90.44602)
					(end 35.612832 -90.41638)
				)
				(arc
					(start 35.539172 -90.34272)
					(mid 35.175828 -89.88946)
					(end 35.629088 -90.252804)
				)
				(xy 35.72129 -90.345006)
				(arc
					(start 35.72129 -90.346784)
					(mid 35.763279 -90.40933)
					(end 35.790378 -90.479626)
				)
				(xy 36.0045 -90.479626) (xy 36.0045 -90.456004)
				(arc
					(start 36.005262 -90.455242)
					(mid 36.031527 -90.32888)
					(end 36.092638 -90.215212)
				)
				(arc
					(start 36.092638 -90.215212)
					(mid 36.59203 -89.919231)
					(end 36.174172 -90.322146)
				)
				(arc
					(start 36.174172 -90.322146)
					(mid 36.142702 -90.398143)
					(end 36.1315 -90.479626)
				)
				(arc
					(start 36.359084 -90.479626)
					(mid 36.742878 -90.096213)
					(end 36.359338 -89.712546)
				)
			)
		)
	)
	(zone
		(layer "In5.Cu")
		(hatch none 0.5)
		(connect_pads
			(clearance 0)
		)
		(min_thickness 0.25)
		(keepout
			(tracks not_allowed)
			(vias allowed)
			(pads allowed)
			(copperpour not_allowed)
			(footprints allowed)
		)
		(placement
			(enabled no)
			(sheetname "")
		)
		(fill
			(thermal_gap 0.5)
			(thermal_bridge_width 0.5)
			(island_removal_mode 0)
		)
		(polygon
			(pts
				(arc
					(start 318.817498 -78.44536)
					(mid 318.418718 -78.02626)
					(end 317.999618 -78.42504)
				)
				(xy 317.997332 -78.42504) (xy 317.989966 -78.719172) (xy 317.998094 -78.712568)
				(arc
					(start 318.14643 -78.564232)
					(mid 318.627886 -78.242183)
					(end 318.247268 -78.678786)
				)
				(xy 318.083438 -78.842616)
				(arc
					(start 318.079374 -78.842616)
					(mid 318.039996 -78.864238)
					(end 317.996824 -78.876652)
				)
				(xy 317.993776 -78.8797) (xy 317.985902 -78.8797) (xy 317.982854 -79.0067) (xy 317.993776 -79.0067)
				(arc
					(start 317.996824 -79.009748)
					(mid 318.039987 -79.022183)
					(end 318.079374 -79.043784)
				)
				(xy 318.083438 -79.043784)
				(arc
					(start 318.237616 -79.197962)
					(mid 318.589691 -79.657733)
					(end 318.12992 -79.305658)
				)
				(arc
					(start 317.998094 -79.173832)
					(mid 317.989112 -79.166784)
					(end 317.97879 -79.161894)
				)
				(xy 317.971932 -79.440786) (xy 317.972186 -79.44104)
				(arc
					(start 317.974218 -79.44104)
					(mid 318.372998 -79.86014)
					(end 318.792098 -79.46136)
				)
				(xy 318.794384 -79.46136) (xy 318.819784 -78.44536)
			)
		)
	)
	(zone
		(layer "In5.Cu")
		(hatch none 0.5)
		(connect_pads
			(clearance 0)
		)
		(min_thickness 0.25)
		(keepout
			(tracks not_allowed)
			(vias allowed)
			(pads allowed)
			(copperpour not_allowed)
			(footprints allowed)
		)
		(placement
			(enabled no)
			(sheetname "")
		)
		(fill
			(thermal_gap 0.5)
			(thermal_bridge_width 0.5)
			(island_removal_mode 0)
		)
		(polygon
			(pts
				(arc
					(start 135.880094 -81.15046)
					(mid 135.4963 -81.533873)
					(end 135.87984 -81.91754)
				)
				(arc
					(start 136.807956 -81.91754)
					(mid 137.191496 -81.534)
					(end 136.807956 -81.15046)
				)
				(arc
					(start 136.590532 -81.15046)
					(mid 136.617601 -81.220298)
					(end 136.656064 -81.284572)
				)
				(arc
					(start 136.656064 -81.284572)
					(mid 137.010712 -81.74418)
					(end 136.564116 -81.373218)
				)
				(arc
					(start 136.564116 -81.373218)
					(mid 136.499444 -81.267593)
					(end 136.459214 -81.15046)
				)
				(arc
					(start 136.228582 -81.15046)
					(mid 136.188335 -81.267585)
					(end 136.12368 -81.373218)
				)
				(arc
					(start 136.12368 -81.373218)
					(mid 135.677057 -81.744209)
					(end 136.031732 -81.284572)
				)
				(arc
					(start 136.031732 -81.284572)
					(mid 136.070228 -81.220314)
					(end 136.097264 -81.15046)
				)
			)
		)
	)
	(zone
		(net "SYSPLL_VDDA09")
		(layer "In5.Cu")
		(hatch none 0.5)
		(connect_pads
			(clearance 0.5)
		)
		(min_thickness 0.25)
		(fill yes
			(thermal_gap 0.5)
			(thermal_bridge_width 0.5)
			(island_removal_mode 0)
		)
		(polygon
			(pts
				(xy 111.379 -88.392) (xy 114.173 -88.392) (xy 114.554 -88.011) (xy 114.554 -81.534) (xy 113.284 -80.264)
				(xy 112.776 -80.264) (xy 112.649 -80.391) (xy 112.649 -80.899) (xy 113.157 -81.407) (xy 113.157 -85.979)
				(xy 113.03 -86.106) (xy 111.506 -86.106) (xy 111.252 -86.36) (xy 111.252 -88.265)
			)
		)
	)
	(zone
		(layer "In5.Cu")
		(hatch none 0.5)
		(connect_pads
			(clearance 0)
		)
		(min_thickness 0.25)
		(keepout
			(tracks not_allowed)
			(vias allowed)
			(pads allowed)
			(copperpour not_allowed)
			(footprints allowed)
		)
		(placement
			(enabled no)
			(sheetname "")
		)
		(fill
			(thermal_gap 0.5)
			(thermal_bridge_width 0.5)
			(island_removal_mode 0)
		)
		(polygon
			(pts
				(arc
					(start 297.123358 -73.30821)
					(mid 296.739818 -73.69175)
					(end 297.123358 -74.07529)
				)
				(arc
					(start 298.139104 -74.07529)
					(mid 298.522898 -73.691877)
					(end 298.139358 -73.30821)
				)
				(arc
					(start 297.79214 -73.30821)
					(mid 297.827883 -73.424986)
					(end 297.901614 -73.522332)
				)
				(arc
					(start 297.901614 -73.522332)
					(mid 298.414766 -73.789273)
					(end 297.847766 -73.674732)
				)
				(arc
					(start 297.847766 -73.674732)
					(mid 297.702988 -73.514466)
					(end 297.638978 -73.30821)
				)
				(arc
					(start 297.50639 -73.30821)
					(mid 297.476684 -73.410518)
					(end 297.42003 -73.500742)
				)
				(xy 297.42003 -73.502774) (xy 297.397678 -73.525126)
				(arc
					(start 297.376596 -73.546208)
					(mid 296.916825 -73.898283)
					(end 297.2689 -73.438512)
				)
				(arc
					(start 297.289982 -73.41743)
					(mid 297.328111 -73.367036)
					(end 297.351196 -73.30821)
				)
			)
		)
	)
	(zone
		(net "P0V955_C")
		(layer "In5.Cu")
		(hatch none 0.5)
		(connect_pads
			(clearance 0.5)
		)
		(min_thickness 0.25)
		(fill yes
			(thermal_gap 0.5)
			(thermal_bridge_width 0.5)
			(island_removal_mode 0)
		)
		(polygon
			(pts
				(xy 98.298 -49.403) (xy 107.315 -49.403) (xy 107.95 -48.768) (xy 107.95 -45.466) (xy 108.966 -44.45)
				(xy 115.189 -44.45) (xy 116.332 -43.307) (xy 116.332 -39.624) (xy 116.332 -38.481) (xy 120.523 -34.29)
				(xy 120.523 -29.591) (xy 120.5103 -29.5783) (xy 120.5103 -27.91968) (xy 120.09628 -27.50566) (xy 107.62234 -27.50566)
				(xy 107.061 -28.067) (xy 107.061 -29.464) (xy 107.061 -37.465) (xy 104.394 -40.132) (xy 100.838 -40.132)
				(xy 98.044 -42.926) (xy 98.044 -49.149)
			)
		)
	)
	(zone
		(layer "In5.Cu")
		(hatch none 0.5)
		(connect_pads
			(clearance 0)
		)
		(min_thickness 0.25)
		(keepout
			(tracks not_allowed)
			(vias allowed)
			(pads allowed)
			(copperpour not_allowed)
			(footprints allowed)
		)
		(placement
			(enabled no)
			(sheetname "")
		)
		(fill
			(thermal_gap 0.5)
			(thermal_bridge_width 0.5)
			(island_removal_mode 0)
		)
		(polygon
			(pts
				(arc
					(start 297.05681 -81.840324)
					(mid 296.67327 -82.223864)
					(end 297.05681 -82.607404)
				)
				(arc
					(start 297.289474 -82.607404)
					(mid 297.264773 -82.550495)
					(end 297.226736 -82.501486)
				)
				(arc
					(start 297.202352 -82.477102)
					(mid 296.850277 -82.017331)
					(end 297.310048 -82.369406)
				)
				(xy 297.356784 -82.416142)
				(arc
					(start 297.356784 -82.41792)
					(mid 297.413856 -82.506744)
					(end 297.445684 -82.607404)
				)
				(arc
					(start 297.584876 -82.607404)
					(mid 297.616757 -82.506769)
					(end 297.673776 -82.41792)
				)
				(xy 297.673776 -82.416142)
				(arc
					(start 297.720512 -82.369406)
					(mid 298.180283 -82.017331)
					(end 297.828208 -82.477102)
				)
				(arc
					(start 297.803824 -82.501486)
					(mid 297.765782 -82.550493)
					(end 297.741086 -82.607404)
				)
				(arc
					(start 297.973496 -82.607404)
					(mid 298.35729 -82.223991)
					(end 297.97375 -81.840324)
				)
			)
		)
	)
	(zone
		(layer "In5.Cu")
		(hatch none 0.5)
		(connect_pads
			(clearance 0)
		)
		(min_thickness 0.25)
		(keepout
			(tracks not_allowed)
			(vias allowed)
			(pads allowed)
			(copperpour not_allowed)
			(footprints allowed)
		)
		(placement
			(enabled no)
			(sheetname "")
		)
		(fill
			(thermal_gap 0.5)
			(thermal_bridge_width 0.5)
			(island_removal_mode 0)
		)
		(polygon
			(pts
				(arc
					(start 301.975012 -73.22566)
					(mid 301.591218 -73.609073)
					(end 301.974758 -73.99274)
				)
				(arc
					(start 302.956722 -73.99274)
					(mid 303.340262 -73.6092)
					(end 302.956722 -73.22566)
				)
				(arc
					(start 302.700944 -73.22566)
					(mid 302.718323 -73.257981)
					(end 302.741584 -73.286366)
				)
				(arc
					(start 302.81118 -73.355962)
					(mid 303.163255 -73.815733)
					(end 302.703484 -73.463658)
				)
				(xy 302.633888 -73.394062) (xy 302.611536 -73.37171)
				(arc
					(start 302.611536 -73.369424)
					(mid 302.568082 -73.301683)
					(end 302.541686 -73.22566)
				)
				(arc
					(start 302.397922 -73.22566)
					(mid 302.373596 -73.293751)
					(end 302.334676 -73.354692)
				)
				(xy 302.334676 -73.356978) (xy 302.312324 -73.37933)
				(arc
					(start 302.227996 -73.463658)
					(mid 301.768225 -73.815733)
					(end 302.1203 -73.355962)
				)
				(arc
					(start 302.204628 -73.271634)
					(mid 302.222959 -73.250033)
					(end 302.237394 -73.22566)
				)
			)
		)
	)
	(zone
		(net "P1V8_STBY")
		(layer "In5.Cu")
		(hatch none 0.5)
		(connect_pads
			(clearance 0.5)
		)
		(min_thickness 0.25)
		(fill yes
			(thermal_gap 0.5)
			(thermal_bridge_width 0.5)
			(island_removal_mode 0)
		)
		(polygon
			(pts
				(xy 229.108 -109.474) (xy 229.108 -100.965) (xy 228.346 -100.203) (xy 223.901 -100.203) (xy 223.139 -100.965)
				(xy 223.139 -110.998) (xy 223.139 -112.522) (xy 223.901 -113.284) (xy 226.822 -113.284) (xy 229.108 -110.998)
			)
		)
	)
	(zone
		(layer "In5.Cu")
		(hatch none 0.5)
		(connect_pads
			(clearance 0)
		)
		(min_thickness 0.25)
		(keepout
			(tracks not_allowed)
			(vias allowed)
			(pads allowed)
			(copperpour not_allowed)
			(footprints allowed)
		)
		(placement
			(enabled no)
			(sheetname "")
		)
		(fill
			(thermal_gap 0.5)
			(thermal_bridge_width 0.5)
			(island_removal_mode 0)
		)
		(polygon
			(pts
				(arc
					(start 296.29354 -77.35951)
					(mid 295.91 -76.97597)
					(end 295.52646 -77.35951)
				)
				(arc
					(start 295.52646 -77.622908)
					(mid 295.552172 -77.606531)
					(end 295.575228 -77.586586)
				)
				(arc
					(start 295.656762 -77.505052)
					(mid 296.116533 -77.152977)
					(end 295.764458 -77.612748)
				)
				(xy 295.682924 -77.694282) (xy 295.682924 -77.694536) (xy 295.660572 -77.716634)
				(arc
					(start 295.65854 -77.716634)
					(mid 295.596141 -77.758345)
					(end 295.52646 -77.78623)
				)
				(arc
					(start 295.52646 -77.961236)
					(mid 295.63177 -77.996866)
					(end 295.7322 -78.044548)
				)
				(arc
					(start 295.7322 -78.044548)
					(mid 296.142678 -78.452646)
					(end 295.638982 -78.167484)
				)
				(arc
					(start 295.638982 -78.167484)
					(mid 295.583622 -78.141718)
					(end 295.52646 -78.12024)
				)
				(arc
					(start 295.52646 -78.276196)
					(mid 295.909873 -78.65999)
					(end 296.29354 -78.27645)
				)
			)
		)
	)
	(zone
		(layer "In5.Cu")
		(hatch none 0.5)
		(connect_pads
			(clearance 0)
		)
		(min_thickness 0.25)
		(keepout
			(tracks not_allowed)
			(vias allowed)
			(pads allowed)
			(copperpour not_allowed)
			(footprints allowed)
		)
		(placement
			(enabled no)
			(sheetname "")
		)
		(fill
			(thermal_gap 0.5)
			(thermal_bridge_width 0.5)
			(island_removal_mode 0)
		)
		(polygon
			(pts
				(arc
					(start 294.03294 -79.44993)
					(mid 293.6494 -79.06639)
					(end 293.26586 -79.44993)
				)
				(arc
					(start 293.26586 -79.63281)
					(mid 293.32847 -79.610202)
					(end 293.38778 -79.579978)
				)
				(arc
					(start 293.38778 -79.579978)
					(mid 293.867249 -79.255252)
					(end 293.490904 -79.695294)
				)
				(arc
					(start 293.490904 -79.695294)
					(mid 293.382646 -79.752896)
					(end 293.26586 -79.79029)
				)
				(arc
					(start 293.26586 -79.95666)
					(mid 293.361998 -79.998077)
					(end 293.44747 -80.058514)
				)
				(xy 293.448994 -80.058514) (xy 293.471346 -80.080866)
				(arc
					(start 293.504112 -80.113632)
					(mid 293.855333 -80.573957)
					(end 293.396162 -80.221328)
				)
				(arc
					(start 293.36365 -80.188562)
					(mid 293.317713 -80.149944)
					(end 293.26586 -80.119728)
				)
				(arc
					(start 293.26586 -80.366616)
					(mid 293.649273 -80.75041)
					(end 294.03294 -80.36687)
				)
			)
		)
	)
	(zone
		(net "P3V3_STBY")
		(layer "In5.Cu")
		(hatch none 0.5)
		(connect_pads
			(clearance 0.5)
		)
		(min_thickness 0.25)
		(fill yes
			(thermal_gap 0.5)
			(thermal_bridge_width 0.5)
			(island_removal_mode 0)
		)
		(polygon
			(pts
				(xy 338.709 -138.938) (xy 334.772 -135.001) (xy 334.772 -118.999) (xy 338.963 -114.808) (xy 338.963 -112.014)
				(xy 338.455 -111.506) (xy 336.042 -111.506) (xy 332.6765 -108.1405) (xy 332.6765 -98.8695) (xy 335.407 -96.139)
				(xy 335.407 -86.868) (xy 335.407 -85.725) (xy 338.963 -82.169) (xy 338.963 -25.654) (xy 338.963 -21.717)
				(xy 340.614 -20.066) (xy 342.138 -20.066) (xy 345.694 -20.066) (xy 346.329 -20.701) (xy 350.266 -24.638)
				(xy 354.203 -28.575) (xy 354.203 -133.477) (xy 354.203 -140.589) (xy 349.25 -145.542) (xy 349.25 -150.495)
				(xy 346.837 -152.908) (xy 346.837 -157.734) (xy 346.837 -159.512) (xy 346.329 -160.02) (xy 346.329 -161.036)
				(xy 345.694 -161.671) (xy 344.17 -161.671) (xy 343.281 -160.782) (xy 343.281 -159.512) (xy 342.265 -158.496)
				(xy 342.265 -156.718) (xy 341.884 -156.337) (xy 339.979 -156.337) (xy 339.471 -155.829) (xy 339.471 -153.416)
				(xy 338.709 -152.654)
			)
		)
		(polygon
			(pts
				(xy 344.17 -95.758) (xy 338.328 -95.758) (xy 337.693 -96.393) (xy 337.693 -104.013) (xy 338.328 -104.648)
				(xy 344.17 -104.648) (xy 344.805 -104.013) (xy 344.805 -96.393)
			)
		)
		(polygon
			(pts
				(arc
					(start 347.755464 -64.780922)
					(mid 347.6625 -64.720255)
					(end 347.569536 -64.780922)
				)
				(arc
					(start 347.569536 -64.780922)
					(mid 347.431364 -64.983364)
					(end 347.228922 -65.121536)
				)
				(arc
					(start 347.228922 -65.121536)
					(mid 347.168255 -65.2145)
					(end 347.228922 -65.307464)
				)
				(arc
					(start 347.228922 -65.307464)
					(mid 347.431364 -65.445636)
					(end 347.569536 -65.648078)
				)
				(arc
					(start 347.569536 -65.648078)
					(mid 347.6625 -65.708745)
					(end 347.755464 -65.648078)
				)
				(arc
					(start 347.755464 -65.648078)
					(mid 347.893636 -65.445636)
					(end 348.096078 -65.307464)
				)
				(arc
					(start 348.096078 -65.307464)
					(mid 348.156745 -65.2145)
					(end 348.096078 -65.121536)
				)
				(arc
					(start 348.096078 -65.121536)
					(mid 347.893636 -64.983364)
					(end 347.755464 -64.780922)
				)
			)
		)
	)
	(zone
		(net "P3V3_STBY")
		(layer "In5.Cu")
		(hatch none 0.5)
		(connect_pads
			(clearance 0.5)
		)
		(min_thickness 0.25)
		(fill yes
			(thermal_gap 0.5)
			(thermal_bridge_width 0.5)
			(island_removal_mode 0)
		)
		(polygon
			(pts
				(xy 276.098 -220.853) (xy 277.495 -220.853) (xy 283.337 -215.011) (xy 283.337 -208.915) (xy 279.908 -205.486)
				(xy 279.908 -199.263) (xy 274.574 -193.929) (xy 274.574 -174.625) (xy 274.32 -174.371) (xy 272.669 -174.371)
				(xy 272.415 -174.625) (xy 272.415 -182.372) (xy 271.399 -183.388) (xy 271.399 -198.12) (xy 275.844 -202.565)
				(xy 275.844 -218.821) (xy 275.844 -220.599)
			)
		)
	)
	(zone
		(layer "In5.Cu")
		(hatch none 0.5)
		(connect_pads
			(clearance 0)
		)
		(min_thickness 0.25)
		(keepout
			(tracks not_allowed)
			(vias allowed)
			(pads allowed)
			(copperpour not_allowed)
			(footprints allowed)
		)
		(placement
			(enabled no)
			(sheetname "")
		)
		(fill
			(thermal_gap 0.5)
			(thermal_bridge_width 0.5)
			(island_removal_mode 0)
		)
		(polygon
			(pts
				(arc
					(start 319.832482 -75.501246)
					(mid 319.805043 -75.501798)
					(end 319.777618 -75.500738)
				)
				(arc
					(start 319.777618 -75.628246)
					(mid 319.808352 -75.629041)
					(end 319.839086 -75.628246)
				)
				(arc
					(start 319.839086 -75.628246)
					(mid 320.087628 -75.698508)
					(end 320.242692 -75.905106)
				)
				(arc
					(start 320.242692 -75.905106)
					(mid 320.211376 -76.482997)
					(end 320.083688 -75.918568)
				)
				(arc
					(start 320.083688 -75.918568)
					(mid 319.985729 -75.814281)
					(end 319.846706 -75.780646)
				)
				(arc
					(start 319.846706 -75.780646)
					(mid 319.812165 -75.781574)
					(end 319.777618 -75.7809)
				)
				(arc
					(start 319.777618 -76.191618)
					(mid 320.186431 -76.600812)
					(end 320.595498 -76.191872)
				)
				(arc
					(start 320.595498 -75.209908)
					(mid 320.186558 -74.800968)
					(end 319.777618 -75.209908)
				)
				(arc
					(start 319.777618 -75.34783)
					(mid 319.801221 -75.349232)
					(end 319.824862 -75.348846)
				)
				(arc
					(start 319.824862 -75.348846)
					(mid 319.87313 -75.342629)
					(end 319.919858 -75.329034)
				)
				(arc
					(start 319.919858 -75.329034)
					(mid 320.410985 -75.022952)
					(end 320.021204 -75.4507)
				)
				(arc
					(start 320.021204 -75.4507)
					(mid 319.929512 -75.485936)
					(end 319.832482 -75.501246)
				)
			)
		)
	)
	(zone
		(layer "In5.Cu")
		(hatch none 0.5)
		(connect_pads
			(clearance 0)
		)
		(min_thickness 0.25)
		(keepout
			(tracks not_allowed)
			(vias allowed)
			(pads allowed)
			(copperpour not_allowed)
			(footprints allowed)
		)
		(placement
			(enabled no)
			(sheetname "")
		)
		(fill
			(thermal_gap 0.5)
			(thermal_bridge_width 0.5)
			(island_removal_mode 0)
		)
		(polygon
			(pts
				(arc
					(start 318.715898 -81.407)
					(mid 318.306958 -80.99806)
					(end 317.898018 -81.407)
				)
				(arc
					(start 317.898018 -81.65719)
					(mid 317.955682 -81.636796)
					(end 318.004952 -81.600548)
				)
				(xy 318.00546 -81.60004)
				(arc
					(start 318.053466 -81.552034)
					(mid 318.513791 -81.200813)
					(end 318.161162 -81.659984)
				)
				(xy 318.113156 -81.707736) (xy 318.112394 -81.708498) (xy 318.090804 -81.730088)
				(arc
					(start 318.088772 -81.730088)
					(mid 317.99934 -81.784595)
					(end 317.898018 -81.811114)
				)
				(xy 317.898018 -81.9404) (xy 318.027558 -81.9404)
				(arc
					(start 318.029336 -81.941924)
					(mid 318.139973 -81.972727)
					(end 318.233806 -82.038952)
				)
				(arc
					(start 318.233806 -82.038952)
					(mid 318.272913 -82.082819)
					(end 318.306704 -82.1309)
				)
				(arc
					(start 318.307212 -82.1309)
					(mid 318.387428 -82.703797)
					(end 318.152018 -82.17535)
				)
				(arc
					(start 318.152018 -82.17535)
					(mid 318.139452 -82.160649)
					(end 318.12611 -82.146648)
				)
				(arc
					(start 318.12611 -82.146648)
					(mid 318.066443 -82.10678)
					(end 317.996062 -82.0928)
				)
				(xy 317.898018 -82.0928)
				(arc
					(start 317.898018 -82.422746)
					(mid 318.306831 -82.83194)
					(end 318.715898 -82.423)
				)
			)
		)
	)
	(zone
		(layer "In5.Cu")
		(hatch none 0.5)
		(connect_pads
			(clearance 0)
		)
		(min_thickness 0.25)
		(keepout
			(tracks not_allowed)
			(vias allowed)
			(pads allowed)
			(copperpour not_allowed)
			(footprints allowed)
		)
		(placement
			(enabled no)
			(sheetname "")
		)
		(fill
			(thermal_gap 0.5)
			(thermal_bridge_width 0.5)
			(island_removal_mode 0)
		)
		(polygon
			(pts
				(arc
					(start 318.080898 -72.009)
					(mid 317.671958 -71.60006)
					(end 317.263018 -72.009)
				)
				(arc
					(start 317.263018 -72.30618)
					(mid 317.279111 -72.293266)
					(end 317.29426 -72.279256)
				)
				(arc
					(start 317.41872 -72.154542)
					(mid 317.877848 -71.801956)
					(end 317.52667 -72.262238)
				)
				(xy 317.379604 -72.409304)
				(arc
					(start 317.37808 -72.409304)
					(mid 317.323291 -72.44952)
					(end 317.263018 -72.480932)
				)
				(arc
					(start 317.263018 -72.683116)
					(mid 317.385714 -72.727596)
					(end 317.501524 -72.787764)
				)
				(arc
					(start 317.501524 -72.787764)
					(mid 317.898905 -73.208912)
					(end 317.404496 -72.907398)
				)
				(arc
					(start 317.404496 -72.907398)
					(mid 317.335241 -72.872001)
					(end 317.263018 -72.843136)
				)
				(arc
					(start 317.263018 -73.024746)
					(mid 317.671831 -73.43394)
					(end 318.080898 -73.025)
				)
			)
		)
	)
	(zone
		(layer "In5.Cu")
		(hatch none 0.5)
		(connect_pads
			(clearance 0)
		)
		(min_thickness 0.25)
		(keepout
			(tracks not_allowed)
			(vias allowed)
			(pads allowed)
			(copperpour not_allowed)
			(footprints allowed)
		)
		(placement
			(enabled no)
			(sheetname "")
		)
		(fill
			(thermal_gap 0.5)
			(thermal_bridge_width 0.5)
			(island_removal_mode 0)
		)
		(polygon
			(pts
				(arc
					(start 41.351708 -89.712546)
					(mid 40.967914 -90.095959)
					(end 41.351454 -90.479626)
				)
				(xy 41.5163 -90.479626)
				(arc
					(start 41.5163 -90.437716)
					(mid 41.511364 -90.392446)
					(end 41.496742 -90.349324)
				)
				(arc
					(start 41.496742 -90.349324)
					(mid 41.153506 -89.881335)
					(end 41.593008 -90.260424)
				)
				(arc
					(start 41.593008 -90.260424)
					(mid 41.626527 -90.332433)
					(end 41.642284 -90.410284)
				)
				(xy 41.6433 -90.4113) (xy 41.6433 -90.479626) (xy 41.86428 -90.479626) (xy 41.872408 -90.466164)
				(xy 41.872408 -90.4621) (xy 41.89095 -90.443812) (xy 41.89095 -90.443558)
				(arc
					(start 42.081704 -90.252804)
					(mid 42.534964 -89.88946)
					(end 42.17162 -90.34272)
				)
				(xy 42.034714 -90.479626)
				(arc
					(start 42.328338 -90.479626)
					(mid 42.711878 -90.096086)
					(end 42.328338 -89.712546)
				)
			)
		)
	)
	(zone
		(layer "In5.Cu")
		(hatch none 0.5)
		(connect_pads
			(clearance 0)
		)
		(min_thickness 0.25)
		(keepout
			(tracks not_allowed)
			(vias allowed)
			(pads allowed)
			(copperpour not_allowed)
			(footprints allowed)
		)
		(placement
			(enabled no)
			(sheetname "")
		)
		(fill
			(thermal_gap 0.5)
			(thermal_bridge_width 0.5)
			(island_removal_mode 0)
		)
		(polygon
			(pts
				(arc
					(start 41.693592 -83.106006)
					(mid 41.309798 -83.489419)
					(end 41.693338 -83.873086)
				)
				(arc
					(start 41.894506 -83.873086)
					(mid 41.877033 -83.803459)
					(end 41.844468 -83.739482)
				)
				(arc
					(start 41.844468 -83.739482)
					(mid 41.491408 -83.278388)
					(end 41.937178 -83.650582)
				)
				(arc
					(start 41.937178 -83.650582)
					(mid 41.994856 -83.756049)
					(end 42.022268 -83.873086)
				)
				(arc
					(start 42.244518 -83.873086)
					(mid 42.300569 -83.717675)
					(end 42.3926 -83.580478)
				)
				(arc
					(start 42.3926 -83.580478)
					(mid 42.919404 -83.337469)
					(end 42.462958 -83.69554)
				)
				(arc
					(start 42.462958 -83.69554)
					(mid 42.411203 -83.780345)
					(end 42.375582 -83.873086)
				)
				(arc
					(start 42.670222 -83.873086)
					(mid 43.053762 -83.489546)
					(end 42.670222 -83.106006)
				)
			)
		)
	)
	(zone
		(net "P12V_PCIE")
		(layer "In5.Cu")
		(hatch none 0.5)
		(connect_pads
			(clearance 0.5)
		)
		(min_thickness 0.25)
		(fill yes
			(thermal_gap 0.5)
			(thermal_bridge_width 0.5)
			(island_removal_mode 0)
		)
		(polygon
			(pts
				(xy 196.596 -246.253) (xy 196.596 -245.364) (xy 196.596 -237.871) (xy 196.596 -237.363) (xy 195.834 -236.601)
				(xy 53.086 -236.601) (xy 39.243 -236.601) (xy 38.862 -236.982) (xy 38.862 -238.125) (xy 38.862 -244.602)
				(xy 38.862 -245.11) (xy 40.64 -246.888) (xy 62.738 -246.888) (xy 191.389 -246.888) (xy 195.961 -246.888)
			)
		)
	)
	(zone
		(layer "In5.Cu")
		(hatch none 0.5)
		(connect_pads
			(clearance 0)
		)
		(min_thickness 0.25)
		(keepout
			(tracks not_allowed)
			(vias allowed)
			(pads allowed)
			(copperpour not_allowed)
			(footprints allowed)
		)
		(placement
			(enabled no)
			(sheetname "")
		)
		(fill
			(thermal_gap 0.5)
			(thermal_bridge_width 0.5)
			(island_removal_mode 0)
		)
		(polygon
			(pts
				(arc
					(start 131.02844 -79.37246)
					(mid 130.6449 -79.756)
					(end 131.02844 -80.13954)
				)
				(arc
					(start 132.00507 -80.13954)
					(mid 132.388864 -79.756127)
					(end 132.005324 -79.37246)
				)
				(arc
					(start 131.781042 -79.37246)
					(mid 131.810078 -79.443343)
					(end 131.8514 -79.507842)
				)
				(arc
					(start 131.8514 -79.507842)
					(mid 132.209785 -79.964497)
					(end 131.760214 -79.59725)
				)
				(arc
					(start 131.760214 -79.59725)
					(mid 131.692003 -79.491226)
					(end 131.649724 -79.37246)
				)
				(arc
					(start 131.415536 -79.37246)
					(mid 131.375511 -79.471673)
					(end 131.313936 -79.55915)
				)
				(xy 131.313936 -79.56042) (xy 131.295394 -79.578962)
				(arc
					(start 131.275074 -79.599282)
					(mid 130.821814 -79.962626)
					(end 131.185158 -79.509366)
				)
				(arc
					(start 131.205478 -79.489046)
					(mid 131.249727 -79.434703)
					(end 131.281932 -79.37246)
				)
			)
		)
	)
	(zone
		(layer "In5.Cu")
		(hatch none 0.5)
		(connect_pads
			(clearance 0)
		)
		(min_thickness 0.25)
		(keepout
			(tracks not_allowed)
			(vias allowed)
			(pads allowed)
			(copperpour not_allowed)
			(footprints allowed)
		)
		(placement
			(enabled no)
			(sheetname "")
		)
		(fill
			(thermal_gap 0.5)
			(thermal_bridge_width 0.5)
			(island_removal_mode 0)
		)
		(polygon
			(pts
				(arc
					(start 350.369124 -154.275028)
					(mid 350.010984 -153.916888)
					(end 349.652844 -154.275028)
				)
				(xy 349.652844 -154.4828) (xy 349.695516 -154.4828)
				(arc
					(start 349.776288 -154.401774)
					(mid 350.199593 -154.086419)
					(end 349.884238 -154.509724)
				)
				(xy 349.758508 -154.6352) (xy 349.652844 -154.6352) (xy 349.652844 -154.7622) (xy 349.725742 -154.7622)
				(arc
					(start 349.884238 -154.920442)
					(mid 350.199593 -155.343747)
					(end 349.776288 -155.028392)
				)
				(xy 349.66275 -154.9146) (xy 349.652844 -154.9146)
				(arc
					(start 349.652844 -155.154884)
					(mid 350.010857 -155.513278)
					(end 350.369124 -155.155138)
				)
			)
		)
	)
	(zone
		(net "P3V3_STBY")
		(layer "In5.Cu")
		(hatch none 0.5)
		(connect_pads
			(clearance 0.5)
		)
		(min_thickness 0.25)
		(fill yes
			(thermal_gap 0.5)
			(thermal_bridge_width 0.5)
			(island_removal_mode 0)
		)
		(polygon
			(pts
				(xy 300.101 -179.578) (xy 300.228 -179.451) (xy 300.482 -179.197) (xy 309.118 -179.197) (xy 309.88 -179.959)
				(xy 310.388 -180.467) (xy 310.388 -181.483) (xy 310.388 -181.864) (xy 312.547 -184.023) (xy 312.547 -185.166)
				(xy 310.515 -187.198) (xy 310.515 -190.373) (xy 309.88 -191.008) (xy 307.975 -192.913) (xy 304.8 -192.913)
				(xy 303.53 -191.643) (xy 302.768 -190.881) (xy 302.768 -182.753) (xy 300.99 -180.975) (xy 300.228 -180.975)
				(xy 300.101 -180.848)
			)
		)
	)
	(zone
		(layer "In5.Cu")
		(hatch none 0.5)
		(connect_pads
			(clearance 0)
		)
		(min_thickness 0.25)
		(keepout
			(tracks not_allowed)
			(vias allowed)
			(pads allowed)
			(copperpour not_allowed)
			(footprints allowed)
		)
		(placement
			(enabled no)
			(sheetname "")
		)
		(fill
			(thermal_gap 0.5)
			(thermal_bridge_width 0.5)
			(island_removal_mode 0)
		)
		(polygon
			(pts
				(arc
					(start 303.80305 -87.141812)
					(mid 303.41951 -87.525352)
					(end 303.80305 -87.908892)
				)
				(arc
					(start 304.719736 -87.908892)
					(mid 305.10353 -87.525479)
					(end 304.71999 -87.141812)
				)
				(arc
					(start 304.478944 -87.141812)
					(mid 304.491225 -87.180089)
					(end 304.514758 -87.212678)
				)
				(arc
					(start 304.574448 -87.272114)
					(mid 304.927034 -87.731242)
					(end 304.466752 -87.380064)
				)
				(xy 304.407062 -87.320374) (xy 304.38471 -87.298022)
				(arc
					(start 304.38471 -87.295228)
					(mid 304.346294 -87.229334)
					(end 304.327052 -87.155528)
				)
				(xy 304.32502 -87.153496) (xy 304.32502 -87.141812) (xy 304.19802 -87.141812) (xy 304.19802 -87.153496)
				(arc
					(start 304.195988 -87.155528)
					(mid 304.176736 -87.22933)
					(end 304.13833 -87.295228)
				)
				(xy 304.13833 -87.298022) (xy 304.115978 -87.320374)
				(arc
					(start 304.056288 -87.380064)
					(mid 303.595963 -87.731285)
					(end 303.948592 -87.272114)
				)
				(arc
					(start 304.008282 -87.212678)
					(mid 304.031808 -87.180085)
					(end 304.044096 -87.141812)
				)
			)
		)
	)
	(zone
		(layer "In5.Cu")
		(hatch none 0.5)
		(connect_pads
			(clearance 0)
		)
		(min_thickness 0.25)
		(keepout
			(tracks not_allowed)
			(vias allowed)
			(pads allowed)
			(copperpour not_allowed)
			(footprints allowed)
		)
		(placement
			(enabled no)
			(sheetname "")
		)
		(fill
			(thermal_gap 0.5)
			(thermal_bridge_width 0.5)
			(island_removal_mode 0)
		)
		(polygon
			(pts
				(arc
					(start 32.334708 -89.712546)
					(mid 31.950914 -90.095959)
					(end 32.334454 -90.479626)
				)
				(arc
					(start 32.528764 -90.479626)
					(mid 32.498296 -90.417772)
					(end 32.463994 -90.35796)
				)
				(arc
					(start 32.463994 -90.35796)
					(mid 32.150678 -89.868963)
					(end 32.563562 -90.277442)
				)
				(arc
					(start 32.563562 -90.277442)
					(mid 32.619832 -90.376133)
					(end 32.666686 -90.479626)
				)
				(xy 32.9565 -90.479626) (xy 32.9565 -90.45067)
				(arc
					(start 32.957262 -90.449908)
					(mid 32.965233 -90.387602)
					(end 32.981646 -90.326972)
				)
				(xy 32.981138 -90.325956)
				(arc
					(start 33.036002 -90.193622)
					(mid 33.551985 -89.93052)
					(end 33.121854 -90.318336)
				)
				(arc
					(start 33.108646 -90.35034)
					(mid 33.089856 -90.412351)
					(end 33.0835 -90.476832)
				)
				(xy 33.0835 -90.479626)
				(arc
					(start 33.311338 -90.479626)
					(mid 33.694878 -90.096086)
					(end 33.311338 -89.712546)
				)
			)
		)
	)
	(zone
		(net "1.2V_REDV")
		(layer "In5.Cu")
		(hatch none 0.5)
		(connect_pads
			(clearance 0.5)
		)
		(min_thickness 0.25)
		(fill yes
			(thermal_gap 0.5)
			(thermal_bridge_width 0.5)
			(island_removal_mode 0)
		)
		(polygon
			(pts
				(xy 110.179612 -222.123) (xy 121.863612 -222.123) (xy 123.133612 -220.853) (xy 123.133612 -210.312)
				(xy 121.863612 -209.042) (xy 109.798612 -209.042) (xy 108.528612 -210.312) (xy 108.528612 -220.472)
			)
		)
	)
	(zone
		(layer "In5.Cu")
		(hatch none 0.5)
		(connect_pads
			(clearance 0)
		)
		(min_thickness 0.25)
		(keepout
			(tracks not_allowed)
			(vias allowed)
			(pads allowed)
			(copperpour not_allowed)
			(footprints allowed)
		)
		(placement
			(enabled no)
			(sheetname "")
		)
		(fill
			(thermal_gap 0.5)
			(thermal_bridge_width 0.5)
			(island_removal_mode 0)
		)
		(polygon
			(pts
				(arc
					(start 134.11454 -87.11438)
					(mid 133.731127 -86.730586)
					(end 133.34746 -87.114126)
				)
				(arc
					(start 133.34746 -88.019128)
					(mid 133.731 -88.402668)
					(end 134.11454 -88.019128)
				)
				(arc
					(start 134.11454 -87.827104)
					(mid 134.047738 -87.845464)
					(end 133.985 -87.874856)
				)
				(arc
					(start 133.985 -87.874856)
					(mid 133.515218 -88.216025)
					(end 133.897878 -87.779352)
				)
				(arc
					(start 133.897878 -87.779352)
					(mid 134.00179 -87.727116)
					(end 134.11454 -87.69858)
				)
				(arc
					(start 134.11454 -87.483696)
					(mid 134.008874 -87.449405)
					(end 133.916166 -87.388192)
				)
				(xy 133.914896 -87.388192)
				(arc
					(start 133.887464 -87.36076)
					(mid 133.52467 -86.907396)
					(end 133.97738 -87.271098)
				)
				(arc
					(start 133.98627 -87.279734)
					(mid 134.045519 -87.325178)
					(end 134.11454 -87.353648)
				)
			)
		)
	)
	(zone
		(layer "In5.Cu")
		(hatch none 0.5)
		(connect_pads
			(clearance 0)
		)
		(min_thickness 0.25)
		(keepout
			(tracks not_allowed)
			(vias allowed)
			(pads allowed)
			(copperpour not_allowed)
			(footprints allowed)
		)
		(placement
			(enabled no)
			(sheetname "")
		)
		(fill
			(thermal_gap 0.5)
			(thermal_bridge_width 0.5)
			(island_removal_mode 0)
		)
		(polygon
			(pts
				(arc
					(start 132.37083 -89.039192)
					(mid 132.475661 -88.981112)
					(end 132.59054 -88.94699)
				)
				(arc
					(start 132.59054 -88.725248)
					(mid 132.472054 -88.686689)
					(end 132.366258 -88.620854)
				)
				(arc
					(start 132.366258 -88.620854)
					(mid 131.99761 -88.172447)
					(end 132.455412 -88.529414)
				)
				(arc
					(start 132.455412 -88.529414)
					(mid 132.519774 -88.568785)
					(end 132.59054 -88.594946)
				)
				(arc
					(start 132.59054 -88.376252)
					(mid 132.207127 -87.992458)
					(end 131.82346 -88.375998)
				)
				(arc
					(start 131.82346 -89.281)
					(mid 132.207 -89.66454)
					(end 132.59054 -89.281)
				)
				(arc
					(start 132.59054 -89.076784)
					(mid 132.522262 -89.099293)
					(end 132.458714 -89.132918)
				)
				(arc
					(start 132.458714 -89.132918)
					(mid 131.994023 -89.480822)
					(end 132.37083 -89.039192)
				)
			)
		)
	)
	(zone
		(layer "In5.Cu")
		(hatch none 0.5)
		(connect_pads
			(clearance 0)
		)
		(min_thickness 0.25)
		(keepout
			(tracks not_allowed)
			(vias allowed)
			(pads allowed)
			(copperpour not_allowed)
			(footprints allowed)
		)
		(placement
			(enabled no)
			(sheetname "")
		)
		(fill
			(thermal_gap 0.5)
			(thermal_bridge_width 0.5)
			(island_removal_mode 0)
		)
		(polygon
			(pts
				(arc
					(start 350.87941 -147.26539)
					(mid 350.52127 -147.62353)
					(end 350.87941 -147.98167)
				)
				(xy 351.129854 -147.98167)
				(arc
					(start 351.006156 -147.858226)
					(mid 350.690801 -147.434921)
					(end 351.114106 -147.750276)
				)
				(xy 351.3328 -147.969224) (xy 351.3328 -147.98167) (xy 351.4598 -147.98167) (xy 351.4598 -147.880324)
				(arc
					(start 351.589594 -147.750276)
					(mid 352.012899 -147.434921)
					(end 351.697544 -147.858226)
				)
				(xy 351.6122 -147.943316) (xy 351.6122 -147.98167)
				(arc
					(start 351.824036 -147.98167)
					(mid 352.18243 -147.623657)
					(end 351.82429 -147.26539)
				)
			)
		)
	)
	(zone
		(layer "In5.Cu")
		(hatch none 0.5)
		(connect_pads
			(clearance 0)
		)
		(min_thickness 0.25)
		(keepout
			(tracks not_allowed)
			(vias allowed)
			(pads allowed)
			(copperpour not_allowed)
			(footprints allowed)
		)
		(placement
			(enabled no)
			(sheetname "")
		)
		(fill
			(thermal_gap 0.5)
			(thermal_bridge_width 0.5)
			(island_removal_mode 0)
		)
		(polygon
			(pts
				(arc
					(start 134.11454 -89.654126)
					(mid 133.731 -89.270586)
					(end 133.34746 -89.654126)
				)
				(arc
					(start 133.34746 -90.558874)
					(mid 133.730873 -90.942668)
					(end 134.11454 -90.559128)
				)
				(arc
					(start 134.11454 -90.475816)
					(mid 134.066031 -90.446766)
					(end 134.0104 -90.4367)
				)
				(arc
					(start 133.99643 -90.437208)
					(mid 133.502381 -90.740927)
					(end 133.909562 -90.327988)
				)
				(arc
					(start 133.909562 -90.327988)
					(mid 133.959165 -90.314355)
					(end 134.0104 -90.3097)
				)
				(arc
					(start 134.0104 -90.3097)
					(mid 134.0634 -90.31472)
					(end 134.11454 -90.329512)
				)
				(xy 134.11454 -90.109294)
				(arc
					(start 134.097268 -90.104722)
					(mid 133.94031 -90.041745)
					(end 133.80847 -89.935812)
				)
				(arc
					(start 133.80847 -89.935812)
					(mid 133.592248 -89.397247)
					(end 133.924802 -89.87282)
				)
				(arc
					(start 133.924802 -89.87282)
					(mid 134.013181 -89.937211)
					(end 134.11454 -89.97823)
				)
			)
		)
	)
	(zone
		(net "GND")
		(layer "In5.Cu")
		(hatch none 0.5)
		(connect_pads
			(clearance 0.5)
		)
		(min_thickness 0.25)
		(fill yes
			(thermal_gap 0.5)
			(thermal_bridge_width 0.5)
			(island_removal_mode 0)
		)
		(polygon
			(pts
				(xy 276.098 -243.332) (xy 289.179 -243.332) (xy 311.404 -221.107) (xy 311.404 -215.9) (xy 304.165 -208.661)
				(xy 284.734 -208.661) (xy 283.718 -209.677) (xy 283.718 -215.138) (xy 283.718 -215.773) (xy 275.336 -224.155)
				(xy 275.336 -242.57)
			)
		)
	)
	(zone
		(net "P1V8_C")
		(layer "In5.Cu")
		(hatch none 0.5)
		(connect_pads
			(clearance 0.5)
		)
		(min_thickness 0.25)
		(fill yes
			(thermal_gap 0.5)
			(thermal_bridge_width 0.5)
			(island_removal_mode 0)
		)
		(polygon
			(pts
				(xy 153.416 -58.674) (xy 155.448 -58.674) (xy 168.91 -45.212) (xy 195.707 -45.212) (xy 205.105 -54.61)
				(xy 246.634 -54.61) (xy 247.015 -54.229) (xy 247.015 -49.911) (xy 246.253 -49.149) (xy 206.375 -49.149)
				(xy 199.644 -42.418) (xy 195.834 -42.418) (xy 167.132 -42.418) (xy 153.035 -56.515) (xy 152.908 -56.642)
				(xy 152.908 -58.166)
			)
		)
	)
	(zone
		(layer "In5.Cu")
		(hatch none 0.5)
		(connect_pads
			(clearance 0)
		)
		(min_thickness 0.25)
		(keepout
			(tracks not_allowed)
			(vias allowed)
			(pads allowed)
			(copperpour not_allowed)
			(footprints allowed)
		)
		(placement
			(enabled no)
			(sheetname "")
		)
		(fill
			(thermal_gap 0.5)
			(thermal_bridge_width 0.5)
			(island_removal_mode 0)
		)
		(polygon
			(pts
				(arc
					(start 351.11309 -151.97201)
					(mid 350.75495 -151.61387)
					(end 350.39681 -151.97201)
				)
				(xy 350.39681 -152.263094)
				(arc
					(start 350.535748 -152.123902)
					(mid 350.921115 -151.763419)
					(end 350.65589 -152.21966)
				)
				(xy 350.424496 -152.4508) (xy 350.39681 -152.4508) (xy 350.39681 -152.5778) (xy 350.523556 -152.5778)
				(arc
					(start 350.628204 -152.682194)
					(mid 350.943559 -153.105499)
					(end 350.520254 -152.790144)
				)
				(xy 350.460564 -152.7302) (xy 350.39681 -152.7302)
				(arc
					(start 350.39681 -152.916636)
					(mid 350.754823 -153.27503)
					(end 351.11309 -152.91689)
				)
			)
		)
	)
	(zone
		(layer "In5.Cu")
		(hatch none 0.5)
		(connect_pads
			(clearance 0)
		)
		(min_thickness 0.25)
		(keepout
			(tracks not_allowed)
			(vias allowed)
			(pads allowed)
			(copperpour not_allowed)
			(footprints allowed)
		)
		(placement
			(enabled no)
			(sheetname "")
		)
		(fill
			(thermal_gap 0.5)
			(thermal_bridge_width 0.5)
			(island_removal_mode 0)
		)
		(polygon
			(pts
				(arc
					(start 38.430454 -89.712546)
					(mid 38.046914 -90.096086)
					(end 38.430454 -90.479626)
				)
				(xy 38.5953 -90.479626)
				(arc
					(start 38.5953 -90.437716)
					(mid 38.590364 -90.392446)
					(end 38.575742 -90.349324)
				)
				(arc
					(start 38.575742 -90.349324)
					(mid 38.232506 -89.881335)
					(end 38.672008 -90.260424)
				)
				(arc
					(start 38.672008 -90.260424)
					(mid 38.705527 -90.332433)
					(end 38.721284 -90.410284)
				)
				(xy 38.7223 -90.4113) (xy 38.7223 -90.479626) (xy 38.94328 -90.479626) (xy 38.951408 -90.466164)
				(xy 38.951408 -90.4621) (xy 38.96995 -90.443812) (xy 38.96995 -90.443558)
				(arc
					(start 39.160704 -90.252804)
					(mid 39.613964 -89.88946)
					(end 39.25062 -90.34272)
				)
				(xy 39.113714 -90.479626)
				(arc
					(start 39.407084 -90.479626)
					(mid 39.790878 -90.096213)
					(end 39.407338 -89.712546)
				)
			)
		)
	)
	(zone
		(layer "In5.Cu")
		(hatch none 0.5)
		(connect_pads
			(clearance 0)
		)
		(min_thickness 0.25)
		(keepout
			(tracks not_allowed)
			(vias allowed)
			(pads allowed)
			(copperpour not_allowed)
			(footprints allowed)
		)
		(placement
			(enabled no)
			(sheetname "")
		)
		(fill
			(thermal_gap 0.5)
			(thermal_bridge_width 0.5)
			(island_removal_mode 0)
		)
		(polygon
			(pts
				(arc
					(start 132.367528 -91.83116)
					(mid 132.473191 -91.770396)
					(end 132.59054 -91.737434)
				)
				(arc
					(start 132.59054 -91.52255)
					(mid 132.470046 -91.485032)
					(end 132.36448 -91.41587)
				)
				(arc
					(start 132.36448 -91.41587)
					(mid 131.999693 -90.964385)
					(end 132.454142 -91.325446)
				)
				(arc
					(start 132.454142 -91.325446)
					(mid 132.518347 -91.367386)
					(end 132.59054 -91.393264)
				)
				(arc
					(start 132.59054 -91.170252)
					(mid 132.207127 -90.786458)
					(end 131.82346 -91.169998)
				)
				(arc
					(start 131.82346 -92.075)
					(mid 132.207 -92.45854)
					(end 132.59054 -92.075)
				)
				(arc
					(start 132.59054 -91.866212)
					(mid 132.520736 -91.888053)
					(end 132.456682 -91.923362)
				)
				(arc
					(start 132.456682 -91.923362)
					(mid 131.99727 -92.278213)
					(end 132.367528 -91.83116)
				)
			)
		)
	)
	(zone
		(net "AGND_CURRENT_MON")
		(layer "In5.Cu")
		(hatch none 0.5)
		(connect_pads
			(clearance 0.5)
		)
		(min_thickness 0.25)
		(fill yes
			(thermal_gap 0.5)
			(thermal_bridge_width 0.5)
			(island_removal_mode 0)
		)
		(polygon
			(pts
				(xy 53.594 -228.473) (xy 71.755 -228.473) (xy 74.422 -225.806) (xy 74.422 -203.581) (xy 72.771 -201.93)
				(xy 45.72 -201.93) (xy 41.275 -206.375) (xy 41.275 -220.218) (xy 41.275 -224.663) (xy 41.275 -227.203)
				(xy 42.037 -227.965) (xy 44.577 -227.965) (xy 48.641 -227.965) (xy 53.086 -227.965)
			)
		)
	)
	(zone
		(net "GND")
		(layer "In5.Cu")
		(hatch none 0.5)
		(connect_pads
			(clearance 0.5)
		)
		(min_thickness 0.25)
		(fill yes
			(thermal_gap 0.5)
			(thermal_bridge_width 0.5)
			(island_removal_mode 0)
		)
		(polygon
			(pts
				(xy 337.566 -195.834) (xy 337.566 -214.249) (xy 333.629 -218.186) (xy 315.595 -218.186) (xy 295.91 -237.871)
				(xy 295.91 -244.221) (xy 295.529 -244.602) (xy 275.209 -244.602) (xy 271.018 -240.411) (xy 271.018 -215.392)
				(xy 253.238 -197.612) (xy 253.238 -196.342) (xy 249.936 -193.04) (xy 232.537 -193.04) (xy 211.709 -213.868)
				(xy 211.709 -219.71) (xy 209.931 -221.488) (xy 207.01 -221.488) (xy 196.85 -231.648) (xy 196.85 -246.634)
				(xy 196.215 -247.269) (xy 40.386 -247.269) (xy 38.1 -244.983) (xy 38.1 -237.109) (xy 39.243 -235.966)
				(xy 109.982 -235.966) (xy 111.76 -234.188) (xy 192.786 -234.188) (xy 207.137 -219.837) (xy 209.677 -219.837)
				(xy 210.566 -218.948) (xy 210.566 -212.725) (xy 232.029 -191.262) (xy 254.254 -191.262) (xy 258.318 -187.198)
				(xy 258.318 -183.261) (xy 256.54 -181.483) (xy 244.475 -181.483) (xy 241.046 -178.054) (xy 241.046 -120.396)
				(xy 246.888 -114.554) (xy 277.876 -114.554) (xy 286.131 -106.299) (xy 286.131 -95.24238) (xy 283.21762 -92.329)
				(xy 265.811 -92.329) (xy 230.26878 -92.329) (xy 229.3874 -93.21038) (xy 225.61296 -93.21038) (xy 217.51798 -93.21038)
				(xy 213.5886 -89.281) (xy 204.29728 -89.281) (xy 202.9714 -87.95512) (xy 194.5894 -87.95512) (xy 193.73596 -88.80856)
				(xy 193.73596 -88.81872) (xy 193.27368 -89.281) (xy 181.229 -89.281) (xy 168.529 -89.281) (xy 167.64 -90.17)
				(xy 167.64 -116.586) (xy 166.624 -117.602) (xy 151.511 -117.602) (xy 150.876 -118.237) (xy 150.876 -147.955)
				(xy 115.697 -183.134) (xy 98.933 -183.134) (xy 98.044 -182.245) (xy 98.044 -173.228) (xy 96.901 -172.085)
				(xy 47.752 -172.085) (xy 43.561 -167.894) (xy 21.463 -167.894) (xy 20.574 -167.005) (xy 12.573 -159.004)
				(xy 6.604 -153.035) (xy 6.604 -124.841) (xy 29.464 -101.981) (xy 29.464 -89.662) (xy 31.623 -87.503)
				(xy 36.322 -87.503) (xy 37.719 -87.503) (xy 41.021 -84.201) (xy 41.021 -83.185) (xy 41.529 -82.677)
				(xy 47.625 -82.677) (xy 48.133 -83.185) (xy 49.53 -83.185) (xy 50.038 -82.677) (xy 55.499 -82.677)
				(xy 71.12 -82.677) (xy 76.073 -82.677) (xy 90.17 -68.58) (xy 93.218 -68.58) (xy 93.853 -67.945)
				(xy 93.853 -66.167) (xy 82.423 -54.737) (xy 82.423 -40.767) (xy 82.423 -40.6146) (xy 86.106 -36.9316)
				(xy 86.106 -36.068) (xy 86.106 -35.814) (xy 85.725 -35.433) (xy 77.597 -35.433) (xy 77.343 -35.687)
				(xy 76.2 -36.83) (xy 75.565 -37.465) (xy 75.565 -38.354) (xy 76.2 -38.989) (xy 76.2 -58.674) (xy 81.661 -64.135)
				(xy 81.661 -66.04) (xy 81.153 -66.548) (xy 80.391 -66.548) (xy 74.041 -66.548) (xy 64.897 -57.404)
				(xy 64.897 -51.689) (xy 68.707 -47.879) (xy 68.707 -22.352) (xy 71.12 -19.939) (xy 75.184 -19.939)
				(xy 77.851 -17.272) (xy 77.851 -8.509) (xy 78.486 -7.874) (xy 80.645 -7.874) (xy 81.026 -8.255)
				(xy 81.026 -14.478) (xy 81.407 -14.859) (xy 92.964 -14.859) (xy 93.98 -15.875) (xy 95.504 -15.875)
				(xy 96.52 -16.891) (xy 96.901 -16.891) (xy 127.381 -16.891) (xy 145.415 -34.925) (xy 146.177 -35.687)
				(xy 174.498 -35.687) (xy 175.133 -36.322) (xy 176.022 -37.211) (xy 204.343 -37.211) (xy 211.074 -43.942)
				(xy 245.872 -43.942) (xy 248.158 -46.228) (xy 248.158 -57.277) (xy 249.301 -58.42) (xy 266.192 -58.42)
				(xy 268.351 -56.261) (xy 268.351 -48.26) (xy 248.031 -27.94) (xy 247.269 -27.178) (xy 228.092 -27.178)
				(xy 226.187 -25.273) (xy 226.187 -21.844) (xy 226.187 -19.558) (xy 227.584 -18.161) (xy 255.651 -18.161)
				(xy 275.463 -37.973) (xy 275.463 -39.624) (xy 275.463 -50.292) (xy 276.479 -51.308) (xy 281.051 -51.308)
				(xy 281.686 -50.673) (xy 281.686 -1.27) (xy 281.178 -0.762) (xy 75.565 -0.762) (xy 75.311 -1.016)
				(xy 75.311 -16.637) (xy 74.168 -17.78) (xy 63.119 -17.78) (xy 62.738 -18.161) (xy 62.738 -58.039)
				(xy 61.849 -58.928) (xy 29.21 -58.928) (xy 28.321 -59.817) (xy 28.321 -67.437) (xy 28.321 -72.644)
				(xy 28.321 -77.343) (xy 26.797 -78.867) (xy 3.175254 -78.867) (xy 0.762254 -81.28) (xy 0.762254 -245.618254)
				(xy 0.889 -245.745) (xy 0.889 -246.38) (xy 4.699 -250.19) (xy 27.178 -250.19) (xy 28.448 -251.46)
				(xy 34.036 -251.46) (xy 34.671 -250.825) (xy 47.244 -250.825) (xy 47.879 -250.19) (xy 67.056 -250.19)
				(xy 68.453 -251.587) (xy 68.453 -253.111) (xy 69.342 -254) (xy 137.033 -254) (xy 137.541 -253.492)
				(xy 137.541 -251.714) (xy 138.557 -250.698) (xy 140.335 -250.698) (xy 141.351 -251.714) (xy 141.351 -253.492)
				(xy 141.986 -254.127) (xy 149.987 -254.127) (xy 150.876 -253.238) (xy 150.876 -251.079) (xy 151.765 -250.19)
				(xy 181.991 -250.19) (xy 183.007 -251.206) (xy 183.007 -253.492) (xy 183.388 -253.873) (xy 187.96 -253.873)
				(xy 188.468 -253.365) (xy 188.468 -251.841) (xy 189.611 -250.698) (xy 201.93 -250.698) (xy 202.438 -250.19)
				(xy 228.981 -250.19) (xy 233.299 -245.872) (xy 233.299 -196.088) (xy 234.188 -195.199) (xy 250.952 -195.199)
				(xy 251.968 -196.215) (xy 251.968 -245.745) (xy 256.413 -250.19) (xy 350.774 -250.19) (xy 354.711 -246.253)
				(xy 354.711 -178.689) (xy 354.711 -178.308) (xy 354.203 -177.8) (xy 352.298 -177.8) (xy 337.566 -192.532)
			)
		)
		(polygon
			(pts
				(xy 73.787 -200.914) (xy 45.466 -200.914) (xy 40.386 -205.994) (xy 40.386 -227.965) (xy 41.021 -228.6)
				(xy 52.578 -228.6) (xy 53.213 -229.235) (xy 72.644 -229.235) (xy 75.819 -226.06) (xy 75.819 -202.946)
			)
		)
	)
	(zone
		(net "P0V9_E")
		(layer "In5.Cu")
		(hatch none 0.5)
		(connect_pads
			(clearance 0.5)
		)
		(min_thickness 0.25)
		(fill yes
			(thermal_gap 0.5)
			(thermal_bridge_width 0.5)
			(island_removal_mode 0)
		)
		(polygon
			(pts
				(xy 108.331 -137.922) (xy 108.331 -100.584) (xy 110.109 -98.806) (xy 110.109 -89.662) (xy 110.617 -89.154)
				(xy 114.935 -89.154) (xy 121.92 -89.154) (xy 123.825 -91.059) (xy 123.825 -122.174) (xy 133.985 -132.334)
				(xy 133.985 -139.954) (xy 133.604 -140.335) (xy 109.601 -140.335) (xy 108.331 -139.065)
			)
		)
	)
	(zone
		(net "P0V955_C")
		(layer "In5.Cu")
		(hatch none 0.5)
		(connect_pads
			(clearance 0.5)
		)
		(min_thickness 0.25)
		(fill yes
			(thermal_gap 0.5)
			(thermal_bridge_width 0.5)
			(island_removal_mode 0)
		)
		(polygon
			(pts
				(xy 102.235 -11.176) (xy 97.282 -11.176) (xy 96.647 -10.541) (xy 96.647 -4.953) (xy 97.282 -4.318)
				(xy 102.235 -4.318) (xy 102.743 -4.826) (xy 102.743 -10.668)
			)
		)
	)
	(zone
		(net "P1V26_STBY")
		(layer "In5.Cu")
		(hatch none 0.5)
		(connect_pads
			(clearance 0.5)
		)
		(min_thickness 0.25)
		(fill yes
			(thermal_gap 0.5)
			(thermal_bridge_width 0.5)
			(island_removal_mode 0)
		)
		(polygon
			(pts
				(xy 276.733 -195.58) (xy 281.94 -195.58) (xy 282.702 -194.818) (xy 282.702 -185.928) (xy 284.48 -184.15)
				(xy 288.798 -184.15) (xy 291.973 -180.975) (xy 292.862 -180.975) (xy 293.37 -180.467) (xy 293.37 -179.578)
				(xy 294.513 -178.435) (xy 297.688 -178.435) (xy 298.45 -177.673) (xy 298.45 -172.974) (xy 296.926 -171.45)
				(xy 289.306 -171.45) (xy 279.146 -181.61) (xy 279.146 -185.928) (xy 276.225 -188.849) (xy 276.225 -195.072)
			)
		)
	)
	(zone
		(layer "In5.Cu")
		(hatch none 0.5)
		(connect_pads
			(clearance 0)
		)
		(min_thickness 0.25)
		(keepout
			(tracks not_allowed)
			(vias allowed)
			(pads allowed)
			(copperpour not_allowed)
			(footprints allowed)
		)
		(placement
			(enabled no)
			(sheetname "")
		)
		(fill
			(thermal_gap 0.5)
			(thermal_bridge_width 0.5)
			(island_removal_mode 0)
		)
		(polygon
			(pts
				(arc
					(start 134.581646 -82.29346)
					(mid 134.197852 -82.676873)
					(end 134.581392 -83.06054)
				)
				(arc
					(start 135.509508 -83.06054)
					(mid 135.893048 -82.677)
					(end 135.509508 -82.29346)
				)
				(arc
					(start 135.194802 -82.29346)
					(mid 135.225487 -82.398398)
					(end 135.28548 -82.489802)
				)
				(arc
					(start 135.28548 -82.489802)
					(mid 135.770647 -82.808147)
					(end 135.225282 -82.609944)
				)
				(xy 135.210042 -82.594958) (xy 135.1915 -82.576416)
				(arc
					(start 135.1915 -82.575146)
					(mid 135.106939 -82.444176)
					(end 135.06704 -82.29346)
				)
				(arc
					(start 134.849108 -82.29346)
					(mid 134.826905 -82.386685)
					(end 134.793736 -82.476594)
				)
				(arc
					(start 134.793736 -82.476594)
					(mid 134.418735 -82.919477)
					(end 134.686294 -82.404458)
				)
				(arc
					(start 134.686294 -82.404458)
					(mid 134.705454 -82.349682)
					(end 134.719822 -82.29346)
				)
			)
		)
	)
	(zone
		(layer "In5.Cu")
		(hatch none 0.5)
		(connect_pads
			(clearance 0)
		)
		(min_thickness 0.25)
		(keepout
			(tracks not_allowed)
			(vias allowed)
			(pads allowed)
			(copperpour not_allowed)
			(footprints allowed)
		)
		(placement
			(enabled no)
			(sheetname "")
		)
		(fill
			(thermal_gap 0.5)
			(thermal_bridge_width 0.5)
			(island_removal_mode 0)
		)
		(polygon
			(pts
				(arc
					(start 44.647104 -83.118706)
					(mid 44.263564 -83.502246)
					(end 44.647104 -83.885786)
				)
				(xy 44.906946 -83.885786)
				(arc
					(start 44.906946 -83.867752)
					(mid 44.904046 -83.853172)
					(end 44.89577 -83.840828)
				)
				(arc
					(start 44.803822 -83.74888)
					(mid 44.440478 -83.29562)
					(end 44.893738 -83.658964)
				)
				(xy 45.004228 -83.769454)
				(arc
					(start 45.004228 -83.773264)
					(mid 45.021342 -83.804564)
					(end 45.031406 -83.838796)
				)
				(xy 45.033946 -83.841336) (xy 45.033946 -83.885786) (xy 45.237146 -83.885786) (xy 45.237146 -83.841336)
				(arc
					(start 45.239686 -83.838796)
					(mid 45.24969 -83.804539)
					(end 45.266864 -83.773264)
				)
				(xy 45.266864 -83.769454)
				(arc
					(start 45.377354 -83.658964)
					(mid 45.830614 -83.29562)
					(end 45.46727 -83.74888)
				)
				(arc
					(start 45.375322 -83.840828)
					(mid 45.367068 -83.853181)
					(end 45.364146 -83.867752)
				)
				(xy 45.364146 -83.885786)
				(arc
					(start 45.623734 -83.885786)
					(mid 46.007528 -83.502373)
					(end 45.623988 -83.118706)
				)
			)
		)
	)
	(zone
		(layer "In5.Cu")
		(hatch none 0.5)
		(connect_pads
			(clearance 0)
		)
		(min_thickness 0.25)
		(keepout
			(tracks allowed)
			(vias allowed)
			(pads allowed)
			(copperpour allowed)
			(footprints allowed)
		)
		(placement
			(enabled no)
			(sheetname "")
		)
		(fill
			(thermal_gap 0.5)
			(thermal_bridge_width 0.5)
			(island_removal_mode 0)
		)
		(polygon
			(pts
				(xy 134.747 -82.804) (xy 134.747 -72.898) (xy 146.4818 -72.898) (xy 148.1328 -71.247) (xy 155.067 -71.247)
				(xy 155.702 -71.247) (xy 157.353 -72.898) (xy 222.377 -72.898) (xy 222.377 -82.804) (xy 153.035 -82.804)
				(xy 152.4 -83.439) (xy 134.747 -83.439)
			)
		)
	)
	(zone
		(net "P5V_STBY")
		(layer "In5.Cu")
		(hatch none 0.5)
		(connect_pads
			(clearance 0.5)
		)
		(min_thickness 0.25)
		(fill yes
			(thermal_gap 0.5)
			(thermal_bridge_width 0.5)
			(island_removal_mode 0)
		)
		(polygon
			(pts
				(xy 247.523 -26.543) (xy 227.965 -26.543) (xy 226.695 -25.273) (xy 226.695 -22.479) (xy 226.695 -19.939)
				(xy 227.838 -18.796) (xy 255.27 -18.796) (xy 275.081746 -38.607746) (xy 275.081746 -40.004746) (xy 275.081746 -41.338246)
				(xy 275.081746 -52.069746) (xy 279.4 -56.388) (xy 313.309 -56.388) (xy 314.071 -55.626) (xy 314.071 -42.799)
				(xy 315.087 -41.783) (xy 317.881 -41.783) (xy 319.024 -42.926) (xy 319.024 -59.944) (xy 317.373 -61.595)
				(xy 314.833 -64.135) (xy 304.419 -64.135) (xy 301.879 -61.595) (xy 277.495 -61.595) (xy 276.86 -61.595)
				(xy 268.605 -53.34) (xy 268.605 -52.705) (xy 268.605 -47.625)
			)
		)
	)
	(zone
		(layer "In5.Cu")
		(hatch none 0.5)
		(connect_pads
			(clearance 0)
		)
		(min_thickness 0.25)
		(keepout
			(tracks allowed)
			(vias allowed)
			(pads allowed)
			(copperpour allowed)
			(footprints allowed)
		)
		(placement
			(enabled no)
			(sheetname "")
		)
		(fill
			(thermal_gap 0.5)
			(thermal_bridge_width 0.5)
			(island_removal_mode 0)
		)
		(polygon
			(pts
				(xy 311.023 -74.168) (xy 311.023 -70.612) (xy 318.262 -70.612) (xy 318.262 -74.168)
			)
		)
	)
	(zone
		(layer "In5.Cu")
		(hatch none 0.5)
		(connect_pads
			(clearance 0)
		)
		(min_thickness 0.25)
		(keepout
			(tracks not_allowed)
			(vias allowed)
			(pads allowed)
			(copperpour not_allowed)
			(footprints allowed)
		)
		(placement
			(enabled no)
			(sheetname "")
		)
		(fill
			(thermal_gap 0.5)
			(thermal_bridge_width 0.5)
			(island_removal_mode 0)
		)
		(polygon
			(pts
				(arc
					(start 132.930392 -80.733646)
					(mid 132.546852 -81.117186)
					(end 132.930392 -81.500726)
				)
				(arc
					(start 133.858254 -81.500726)
					(mid 134.242048 -81.117313)
					(end 133.858508 -80.733646)
				)
				(arc
					(start 133.629908 -80.733646)
					(mid 133.656788 -80.80694)
					(end 133.702044 -80.870552)
				)
				(arc
					(start 133.702044 -80.870552)
					(mid 134.064838 -81.323916)
					(end 133.612128 -80.960214)
				)
				(xy 133.600698 -80.948784)
				(arc
					(start 133.600698 -80.947768)
					(mid 133.535469 -80.847854)
					(end 133.500876 -80.733646)
				)
				(arc
					(start 133.288024 -80.733646)
					(mid 133.253499 -80.847886)
					(end 133.188202 -80.947768)
				)
				(xy 133.188202 -80.948784)
				(arc
					(start 133.176772 -80.960214)
					(mid 132.724021 -81.323957)
					(end 133.086856 -80.870552)
				)
				(arc
					(start 133.086856 -80.870552)
					(mid 133.132109 -80.806939)
					(end 133.158992 -80.733646)
				)
			)
		)
	)
	(zone
		(net "GND")
		(layer "In5.Cu")
		(hatch none 0.5)
		(connect_pads
			(clearance 0.5)
		)
		(min_thickness 0.25)
		(fill yes
			(thermal_gap 0.5)
			(thermal_bridge_width 0.5)
			(island_removal_mode 0)
		)
		(polygon
			(pts
				(xy 307.720746 -0.762254) (xy 307.34 -1.143) (xy 307.34 -34.925) (xy 307.848 -35.433) (xy 317.246 -35.433)
				(xy 318.135 -34.544) (xy 318.135 -5.08) (xy 319.024 -4.191) (xy 344.805 -4.191) (xy 352.425 -4.191)
				(xy 353.695 -5.461) (xy 353.695 -8.636) (xy 351.917 -10.414) (xy 351.917 -25.654) (xy 352.425 -26.162)
				(xy 354.457 -26.162) (xy 354.711 -25.908) (xy 354.711 -1.016) (xy 354.457254 -0.762254)
			)
		)
	)
	(zone
		(layer "In6.Cu")
		(hatch none 0.5)
		(connect_pads
			(clearance 0)
		)
		(min_thickness 0.25)
		(keepout
			(tracks not_allowed)
			(vias allowed)
			(pads allowed)
			(copperpour not_allowed)
			(footprints allowed)
		)
		(placement
			(enabled no)
			(sheetname "")
		)
		(fill
			(thermal_gap 0.5)
			(thermal_bridge_width 0.5)
			(island_removal_mode 0)
		)
		(polygon
			(pts
				(arc
					(start 16.199104 -101.267006)
					(mid 16.344584 -101.206746)
					(end 16.404844 -101.061266)
				)
				(arc
					(start 16.404844 -100.654866)
					(mid 16.344584 -100.509386)
					(end 16.199104 -100.449126)
				)
				(arc
					(start 15.792704 -100.449126)
					(mid 15.647224 -100.509386)
					(end 15.586964 -100.654866)
				)
				(arc
					(start 15.586964 -101.061266)
					(mid 15.647224 -101.206746)
					(end 15.792704 -101.267006)
				)
			)
		)
	)
	(zone
		(net "GND")
		(layer "In6.Cu")
		(hatch none 0.5)
		(connect_pads
			(clearance 0.5)
		)
		(min_thickness 0.25)
		(fill yes
			(thermal_gap 0.5)
			(thermal_bridge_width 0.5)
			(island_removal_mode 0)
		)
		(polygon
			(pts
				(xy 250.465844 -195.238116)
				(arc
					(start 250.49988 -195.272152)
					(mid 251.396754 -195.753482)
					(end 251.878084 -196.650356)
				)
				(xy 251.91212 -196.684392) (xy 251.91212 -196.94017) (xy 251.913136 -197.000114)
				(arc
					(start 251.913136 -246.000016)
					(mid 253.154117 -248.996009)
					(end 256.15011 -250.23699)
				)
				(arc
					(start 350.60001 -250.23699)
					(mid 353.596003 -248.996009)
					(end 354.836984 -246.000016)
				)
				(arc
					(start 354.836984 -0.999998)
					(mid 354.767574 -0.832426)
					(end 354.600002 -0.763016)
				)
				(arc
					(start 307.485034 -0.763016)
					(mid 307.317462 -0.832426)
					(end 307.248052 -0.999998)
				)
				(xy 307.248052 -43.50004) (xy 307.247036 -43.559984) (xy 307.247036 -43.815762)
				(arc
					(start 307.213 -43.849798)
					(mid 306.601183 -44.864739)
					(end 305.485038 -45.263054)
				)
				(arc
					(start 305.485038 -45.263054)
					(mid 305.317466 -45.332464)
					(end 305.248056 -45.500036)
				)
				(xy 305.248056 -53.50002) (xy 305.24704 -53.559964) (xy 305.24704 -53.815742)
				(arc
					(start 305.213004 -53.849778)
					(mid 304.731674 -54.746652)
					(end 303.8348 -55.227982)
				)
				(xy 303.800764 -55.262018) (xy 303.544986 -55.262018) (xy 303.485042 -55.263034) (xy 283.485082 -55.263034)
				(xy 283.425138 -55.262018) (xy 283.16936 -55.262018)
				(arc
					(start 283.135578 -55.227982)
					(mid 282.238485 -54.746617)
					(end 281.75712 -53.849524)
				)
				(xy 281.723084 -53.815742) (xy 281.723084 -53.559964) (xy 281.722068 -53.50002)
				(arc
					(start 281.722068 -0.999998)
					(mid 281.652658 -0.832426)
					(end 281.485086 -0.763016)
				)
				(arc
					(start 75.449938 -0.763016)
					(mid 75.282366 -0.832426)
					(end 75.212956 -0.999998)
				)
				(xy 75.212956 -15.999968) (xy 75.21194 -16.059912) (xy 75.21194 -16.31569)
				(arc
					(start 75.177904 -16.349472)
					(mid 74.696539 -17.246565)
					(end 73.799446 -17.72793)
				)
				(xy 73.765664 -17.761966) (xy 73.509886 -17.761966) (xy 73.449942 -17.762982)
				(arc
					(start 62.95009 -17.762982)
					(mid 62.782518 -17.832392)
					(end 62.713108 -17.999964)
				)
				(xy 62.713108 -57.010046) (xy 62.712092 -57.069736) (xy 62.712092 -57.325768)
				(arc
					(start 62.678056 -57.359804)
					(mid 62.196726 -58.256678)
					(end 61.299852 -58.738008)
				)
				(xy 61.265816 -58.772044) (xy 61.009784 -58.772044) (xy 60.950094 -58.77306)
				(arc
					(start 29.500068 -58.77306)
					(mid 28.625391 -59.135363)
					(end 28.263088 -60.01004)
				)
				(xy 28.263088 -76.010008) (xy 28.262072 -76.084938) (xy 28.262072 -76.32573)
				(arc
					(start 28.242768 -76.345034)
					(mid 27.453867 -77.963799)
					(end 25.835102 -78.7527)
				)
				(xy 25.815798 -78.772004) (xy 25.575006 -78.772004) (xy 25.500076 -78.77302)
				(arc
					(start 2.999994 -78.77302)
					(mid 1.418212 -79.428216)
					(end 0.763016 -81.009998)
				)
				(arc
					(start 0.763016 -246.000016)
					(mid 2.003997 -248.996009)
					(end 4.99999 -250.23699)
				)
				(xy 26.34996 -250.23699) (xy 26.409904 -250.238006) (xy 26.665682 -250.238006)
				(arc
					(start 26.699464 -250.272042)
					(mid 27.596557 -250.753407)
					(end 28.077922 -251.6505)
				)
				(xy 28.111958 -251.684282) (xy 28.111958 -251.94006) (xy 28.112974 -252.000004) (xy 28.112974 -257.836924)
				(xy 33.78708 -257.836924) (xy 33.78708 -252.549914) (xy 33.788096 -252.490986) (xy 33.788096 -252.234192)
				(arc
					(start 33.823402 -252.198886)
					(mid 35.500056 -250.836908)
					(end 37.17671 -252.198886)
				)
				(xy 37.212016 -252.234192) (xy 37.212016 -252.490986) (xy 37.213032 -252.549914) (xy 37.213032 -257.836924)
				(xy 46.886876 -257.836924) (xy 46.886876 -252.000004) (xy 46.887892 -251.940314) (xy 46.887892 -251.684282)
				(arc
					(start 46.921928 -251.650246)
					(mid 47.403258 -250.753372)
					(end 48.300132 -250.272042)
				)
				(xy 48.334168 -250.238006) (xy 48.5902 -250.238006) (xy 48.64989 -250.23699) (xy 66.34988 -250.23699)
				(xy 66.409824 -250.238006) (xy 66.665602 -250.238006)
				(arc
					(start 66.699384 -250.272042)
					(mid 67.596477 -250.753407)
					(end 68.077842 -251.6505)
				)
				(xy 68.111878 -251.684282) (xy 68.111878 -251.94006) (xy 68.112894 -252.000004) (xy 68.112894 -254.4064)
				(xy 137.786872 -254.4064) (xy 137.786872 -252.549914) (xy 137.787888 -252.490986) (xy 137.787888 -252.234192)
				(arc
					(start 137.823194 -252.198886)
					(mid 139.500076 -250.836659)
					(end 141.176756 -252.198886)
				)
				(xy 141.212062 -252.234192) (xy 141.212062 -252.490986) (xy 141.213078 -252.549914) (xy 141.213078 -254.4064)
				(xy 150.886922 -254.4064) (xy 150.886922 -252.000004) (xy 150.887938 -251.94006) (xy 150.887938 -251.684282)
				(arc
					(start 150.921974 -251.650246)
					(mid 151.403304 -250.753372)
					(end 152.300178 -250.272042)
				)
				(xy 152.334214 -250.238006) (xy 152.589992 -250.238006) (xy 152.649936 -250.23699) (xy 181.150006 -250.23699)
				(xy 181.20995 -250.238006) (xy 181.465728 -250.238006)
				(arc
					(start 181.499764 -250.272042)
					(mid 182.396638 -250.753372)
					(end 182.877968 -251.650246)
				)
				(xy 182.912004 -251.684282) (xy 182.912004 -251.94006) (xy 182.91302 -252.000004) (xy 182.91302 -257.836924)
				(xy 188.586872 -257.836924) (xy 188.586872 -252.549914) (xy 188.587888 -252.490986) (xy 188.587888 -252.234192)
				(arc
					(start 188.623194 -252.198886)
					(mid 190.300076 -250.836659)
					(end 191.976756 -252.198886)
				)
				(xy 192.012062 -252.234192) (xy 192.012062 -252.490986) (xy 192.013078 -252.549914) (xy 192.013078 -257.836924)
				(xy 201.686922 -257.836924) (xy 201.686922 -252.000004) (xy 201.687938 -251.94006) (xy 201.687938 -251.684282)
				(arc
					(start 201.721974 -251.650246)
					(mid 202.203304 -250.753372)
					(end 203.100178 -250.272042)
				)
				(xy 203.134214 -250.238006) (xy 203.389992 -250.238006) (xy 203.449936 -250.23699)
				(arc
					(start 229.14991 -250.23699)
					(mid 232.145903 -248.996009)
					(end 233.386884 -246.000016)
				)
				(xy 233.386884 -197.000114) (xy 233.3879 -196.94017) (xy 233.3879 -196.684392)
				(arc
					(start 233.421936 -196.65061)
					(mid 233.903301 -195.753517)
					(end 234.800394 -195.272152)
				)
				(xy 234.834176 -195.238116) (xy 235.089954 -195.238116) (xy 235.149898 -195.2371) (xy 250.150122 -195.2371)
				(xy 250.210066 -195.238116)
			)
		)
		(polygon
			(pts
				(arc
					(start 119.072152 -223.139)
					(mid 119.011892 -222.99352)
					(end 118.866412 -222.93326)
				)
				(arc
					(start 118.510812 -222.93326)
					(mid 118.365332 -222.99352)
					(end 118.305072 -223.139)
				)
				(arc
					(start 118.305072 -223.4946)
					(mid 118.365332 -223.64008)
					(end 118.510812 -223.70034)
				)
				(arc
					(start 118.866412 -223.70034)
					(mid 119.011892 -223.64008)
					(end 119.072152 -223.4946)
				)
			)
		)
		(polygon
			(pts
				(arc
					(start 117.421152 -223.139)
					(mid 117.360892 -222.99352)
					(end 117.215412 -222.93326)
				)
				(arc
					(start 116.859812 -222.93326)
					(mid 116.714332 -222.99352)
					(end 116.654072 -223.139)
				)
				(arc
					(start 116.654072 -223.4946)
					(mid 116.714332 -223.64008)
					(end 116.859812 -223.70034)
				)
				(arc
					(start 117.215412 -223.70034)
					(mid 117.360892 -223.64008)
					(end 117.421152 -223.4946)
				)
			)
		)
		(polygon
			(pts
				(arc
					(start 111.579152 -223.139)
					(mid 111.518892 -222.99352)
					(end 111.373412 -222.93326)
				)
				(arc
					(start 111.017812 -222.93326)
					(mid 110.872332 -222.99352)
					(end 110.812072 -223.139)
				)
				(arc
					(start 110.812072 -223.4946)
					(mid 110.872332 -223.64008)
					(end 111.017812 -223.70034)
				)
				(arc
					(start 111.373412 -223.70034)
					(mid 111.518892 -223.64008)
					(end 111.579152 -223.4946)
				)
			)
		)
		(polygon
			(pts
				(arc
					(start 109.928152 -223.139)
					(mid 109.867892 -222.99352)
					(end 109.722412 -222.93326)
				)
				(arc
					(start 109.366812 -222.93326)
					(mid 109.221332 -222.99352)
					(end 109.161072 -223.139)
				)
				(arc
					(start 109.161072 -223.4946)
					(mid 109.221332 -223.64008)
					(end 109.366812 -223.70034)
				)
				(arc
					(start 109.722412 -223.70034)
					(mid 109.867892 -223.64008)
					(end 109.928152 -223.4946)
				)
			)
		)
		(polygon
			(pts
				(arc
					(start 111.579152 -222.2754)
					(mid 111.518892 -222.12992)
					(end 111.373412 -222.06966)
				)
				(arc
					(start 111.017812 -222.06966)
					(mid 110.872332 -222.12992)
					(end 110.812072 -222.2754)
				)
				(arc
					(start 110.812072 -222.631)
					(mid 110.872332 -222.77648)
					(end 111.017812 -222.83674)
				)
				(arc
					(start 111.373412 -222.83674)
					(mid 111.518892 -222.77648)
					(end 111.579152 -222.631)
				)
			)
		)
		(polygon
			(pts
				(arc
					(start 119.072152 -222.25)
					(mid 119.011892 -222.10452)
					(end 118.866412 -222.04426)
				)
				(arc
					(start 118.510812 -222.04426)
					(mid 118.365332 -222.10452)
					(end 118.305072 -222.25)
				)
				(arc
					(start 118.305072 -222.6056)
					(mid 118.365332 -222.75108)
					(end 118.510812 -222.81134)
				)
				(arc
					(start 118.866412 -222.81134)
					(mid 119.011892 -222.75108)
					(end 119.072152 -222.6056)
				)
			)
		)
		(polygon
			(pts
				(arc
					(start 117.421152 -222.25)
					(mid 117.360892 -222.10452)
					(end 117.215412 -222.04426)
				)
				(arc
					(start 116.859812 -222.04426)
					(mid 116.714332 -222.10452)
					(end 116.654072 -222.25)
				)
				(arc
					(start 116.654072 -222.6056)
					(mid 116.714332 -222.75108)
					(end 116.859812 -222.81134)
				)
				(arc
					(start 117.215412 -222.81134)
					(mid 117.360892 -222.75108)
					(end 117.421152 -222.6056)
				)
			)
		)
		(polygon
			(pts
				(arc
					(start 109.928152 -222.25)
					(mid 109.867892 -222.10452)
					(end 109.722412 -222.04426)
				)
				(arc
					(start 109.366812 -222.04426)
					(mid 109.221332 -222.10452)
					(end 109.161072 -222.25)
				)
				(arc
					(start 109.161072 -222.6056)
					(mid 109.221332 -222.75108)
					(end 109.366812 -222.81134)
				)
				(arc
					(start 109.722412 -222.81134)
					(mid 109.867892 -222.75108)
					(end 109.928152 -222.6056)
				)
			)
		)
		(polygon
			(pts
				(arc
					(start 119.072152 -221.3864)
					(mid 119.011892 -221.24092)
					(end 118.866412 -221.18066)
				)
				(arc
					(start 118.510812 -221.18066)
					(mid 118.365332 -221.24092)
					(end 118.305072 -221.3864)
				)
				(arc
					(start 118.305072 -221.742)
					(mid 118.365332 -221.88748)
					(end 118.510812 -221.94774)
				)
				(arc
					(start 118.866412 -221.94774)
					(mid 119.011892 -221.88748)
					(end 119.072152 -221.742)
				)
			)
		)
		(polygon
			(pts
				(arc
					(start 117.421152 -221.3864)
					(mid 117.360892 -221.24092)
					(end 117.215412 -221.18066)
				)
				(arc
					(start 116.859812 -221.18066)
					(mid 116.714332 -221.24092)
					(end 116.654072 -221.3864)
				)
				(arc
					(start 116.654072 -221.742)
					(mid 116.714332 -221.88748)
					(end 116.859812 -221.94774)
				)
				(arc
					(start 117.215412 -221.94774)
					(mid 117.360892 -221.88748)
					(end 117.421152 -221.742)
				)
			)
		)
		(polygon
			(pts
				(arc
					(start 111.579152 -221.3864)
					(mid 111.518892 -221.24092)
					(end 111.373412 -221.18066)
				)
				(arc
					(start 111.017812 -221.18066)
					(mid 110.872332 -221.24092)
					(end 110.812072 -221.3864)
				)
				(arc
					(start 110.812072 -221.742)
					(mid 110.872332 -221.88748)
					(end 111.017812 -221.94774)
				)
				(arc
					(start 111.373412 -221.94774)
					(mid 111.518892 -221.88748)
					(end 111.579152 -221.742)
				)
			)
		)
		(polygon
			(pts
				(arc
					(start 109.928152 -221.3864)
					(mid 109.867892 -221.24092)
					(end 109.722412 -221.18066)
				)
				(arc
					(start 109.366812 -221.18066)
					(mid 109.221332 -221.24092)
					(end 109.161072 -221.3864)
				)
				(arc
					(start 109.161072 -221.742)
					(mid 109.221332 -221.88748)
					(end 109.366812 -221.94774)
				)
				(arc
					(start 109.722412 -221.94774)
					(mid 109.867892 -221.88748)
					(end 109.928152 -221.742)
				)
			)
		)
		(polygon
			(pts
				(arc
					(start 117.929152 -206.121)
					(mid 117.868892 -205.97552)
					(end 117.723412 -205.91526)
				)
				(arc
					(start 117.367812 -205.91526)
					(mid 117.222332 -205.97552)
					(end 117.162072 -206.121)
				)
				(arc
					(start 117.162072 -206.4766)
					(mid 117.222332 -206.62208)
					(end 117.367812 -206.68234)
				)
				(arc
					(start 117.723412 -206.68234)
					(mid 117.868892 -206.62208)
					(end 117.929152 -206.4766)
				)
			)
		)
		(polygon
			(pts
				(arc
					(start 116.278152 -206.121)
					(mid 116.217892 -205.97552)
					(end 116.072412 -205.91526)
				)
				(arc
					(start 115.716812 -205.91526)
					(mid 115.571332 -205.97552)
					(end 115.511072 -206.121)
				)
				(arc
					(start 115.511072 -206.4766)
					(mid 115.571332 -206.62208)
					(end 115.716812 -206.68234)
				)
				(arc
					(start 116.072412 -206.68234)
					(mid 116.217892 -206.62208)
					(end 116.278152 -206.4766)
				)
			)
		)
		(polygon
			(pts
				(arc
					(start 110.055152 -206.121)
					(mid 109.994892 -205.97552)
					(end 109.849412 -205.91526)
				)
				(arc
					(start 109.493812 -205.91526)
					(mid 109.348332 -205.97552)
					(end 109.288072 -206.121)
				)
				(arc
					(start 109.288072 -206.4766)
					(mid 109.348332 -206.62208)
					(end 109.493812 -206.68234)
				)
				(arc
					(start 109.849412 -206.68234)
					(mid 109.994892 -206.62208)
					(end 110.055152 -206.4766)
				)
			)
		)
		(polygon
			(pts
				(arc
					(start 108.404152 -206.121)
					(mid 108.343892 -205.97552)
					(end 108.198412 -205.91526)
				)
				(arc
					(start 107.842812 -205.91526)
					(mid 107.697332 -205.97552)
					(end 107.637072 -206.121)
				)
				(arc
					(start 107.637072 -206.4766)
					(mid 107.697332 -206.62208)
					(end 107.842812 -206.68234)
				)
				(arc
					(start 108.198412 -206.68234)
					(mid 108.343892 -206.62208)
					(end 108.404152 -206.4766)
				)
			)
		)
		(polygon
			(pts
				(arc
					(start 117.929152 -205.2574)
					(mid 117.868892 -205.11192)
					(end 117.723412 -205.05166)
				)
				(arc
					(start 117.367812 -205.05166)
					(mid 117.222332 -205.11192)
					(end 117.162072 -205.2574)
				)
				(arc
					(start 117.162072 -205.613)
					(mid 117.222332 -205.75848)
					(end 117.367812 -205.81874)
				)
				(arc
					(start 117.723412 -205.81874)
					(mid 117.868892 -205.75848)
					(end 117.929152 -205.613)
				)
			)
		)
		(polygon
			(pts
				(arc
					(start 116.278152 -205.2574)
					(mid 116.217892 -205.11192)
					(end 116.072412 -205.05166)
				)
				(arc
					(start 115.716812 -205.05166)
					(mid 115.571332 -205.11192)
					(end 115.511072 -205.2574)
				)
				(arc
					(start 115.511072 -205.613)
					(mid 115.571332 -205.75848)
					(end 115.716812 -205.81874)
				)
				(arc
					(start 116.072412 -205.81874)
					(mid 116.217892 -205.75848)
					(end 116.278152 -205.613)
				)
			)
		)
		(polygon
			(pts
				(arc
					(start 110.055152 -205.2574)
					(mid 109.994892 -205.11192)
					(end 109.849412 -205.05166)
				)
				(arc
					(start 109.493812 -205.05166)
					(mid 109.348332 -205.11192)
					(end 109.288072 -205.2574)
				)
				(arc
					(start 109.288072 -205.613)
					(mid 109.348332 -205.75848)
					(end 109.493812 -205.81874)
				)
				(arc
					(start 109.849412 -205.81874)
					(mid 109.994892 -205.75848)
					(end 110.055152 -205.613)
				)
			)
		)
		(polygon
			(pts
				(arc
					(start 108.404152 -205.2574)
					(mid 108.343892 -205.11192)
					(end 108.198412 -205.05166)
				)
				(arc
					(start 107.842812 -205.05166)
					(mid 107.697332 -205.11192)
					(end 107.637072 -205.2574)
				)
				(arc
					(start 107.637072 -205.613)
					(mid 107.697332 -205.75848)
					(end 107.842812 -205.81874)
				)
				(arc
					(start 108.198412 -205.81874)
					(mid 108.343892 -205.75848)
					(end 108.404152 -205.613)
				)
			)
		)
		(polygon
			(pts
				(arc
					(start 117.929152 -204.3684)
					(mid 117.868892 -204.22292)
					(end 117.723412 -204.16266)
				)
				(arc
					(start 117.367812 -204.16266)
					(mid 117.222332 -204.22292)
					(end 117.162072 -204.3684)
				)
				(arc
					(start 117.162072 -204.724)
					(mid 117.222332 -204.86948)
					(end 117.367812 -204.92974)
				)
				(arc
					(start 117.723412 -204.92974)
					(mid 117.868892 -204.86948)
					(end 117.929152 -204.724)
				)
			)
		)
		(polygon
			(pts
				(arc
					(start 116.278152 -204.3684)
					(mid 116.217892 -204.22292)
					(end 116.072412 -204.16266)
				)
				(arc
					(start 115.716812 -204.16266)
					(mid 115.571332 -204.22292)
					(end 115.511072 -204.3684)
				)
				(arc
					(start 115.511072 -204.724)
					(mid 115.571332 -204.86948)
					(end 115.716812 -204.92974)
				)
				(arc
					(start 116.072412 -204.92974)
					(mid 116.217892 -204.86948)
					(end 116.278152 -204.724)
				)
			)
		)
		(polygon
			(pts
				(arc
					(start 110.055152 -204.3684)
					(mid 109.994892 -204.22292)
					(end 109.849412 -204.16266)
				)
				(arc
					(start 109.493812 -204.16266)
					(mid 109.348332 -204.22292)
					(end 109.288072 -204.3684)
				)
				(arc
					(start 109.288072 -204.724)
					(mid 109.348332 -204.86948)
					(end 109.493812 -204.92974)
				)
				(arc
					(start 109.849412 -204.92974)
					(mid 109.994892 -204.86948)
					(end 110.055152 -204.724)
				)
			)
		)
		(polygon
			(pts
				(arc
					(start 108.404152 -204.3684)
					(mid 108.343892 -204.22292)
					(end 108.198412 -204.16266)
				)
				(arc
					(start 107.842812 -204.16266)
					(mid 107.697332 -204.22292)
					(end 107.637072 -204.3684)
				)
				(arc
					(start 107.637072 -204.724)
					(mid 107.697332 -204.86948)
					(end 107.842812 -204.92974)
				)
				(arc
					(start 108.198412 -204.92974)
					(mid 108.343892 -204.86948)
					(end 108.404152 -204.724)
				)
			)
		)
		(polygon
			(pts
				(arc
					(start 285.550356 -185.54573)
					(mid 285.87573 -185.111644)
					(end 285.441644 -184.78627)
				)
				(arc
					(start 284.552898 -184.91327)
					(mid 284.227506 -185.347232)
					(end 284.661356 -185.67273)
				)
			)
		)
		(polygon
			(pts
				(arc
					(start 299.643546 -174.676054)
					(mid 299.280328 -175.028987)
					(end 299.633132 -175.392334)
				)
				(arc
					(start 300.430438 -175.40351)
					(mid 300.793658 -175.05045)
					(end 300.440598 -174.68723)
				)
			)
		)
		(polygon
			(pts
				(arc
					(start 303.024032 -174.096426)
					(mid 303.38903 -173.69536)
					(end 302.987964 -173.330362)
				)
				(xy 302.987964 -173.327822) (xy 302.21428 -173.36389) (xy 302.214026 -173.364144)
				(arc
					(start 302.214026 -173.36643)
					(mid 301.849028 -173.767496)
					(end 302.250094 -174.132494)
				)
				(xy 302.250094 -174.135034) (xy 303.024032 -174.098966)
			)
		)
		(polygon
			(pts
				(arc
					(start 350.369124 -154.275028)
					(mid 350.010984 -153.916888)
					(end 349.652844 -154.275028)
				)
				(arc
					(start 349.652844 -155.155392)
					(mid 350.011111 -155.513278)
					(end 350.369124 -155.155138)
				)
			)
		)
		(polygon
			(pts
				(arc
					(start 351.11309 -151.97201)
					(mid 350.75495 -151.61387)
					(end 350.39681 -151.97201)
				)
				(arc
					(start 350.39681 -152.917144)
					(mid 350.755077 -153.27503)
					(end 351.11309 -152.91689)
				)
			)
		)
		(polygon
			(pts
				(arc
					(start 351.824544 -147.98167)
					(mid 352.18243 -147.623403)
					(end 351.82429 -147.26539)
				)
				(arc
					(start 350.87941 -147.26539)
					(mid 350.52127 -147.62353)
					(end 350.87941 -147.98167)
				)
			)
		)
		(polygon
			(pts
				(arc
					(start 342.754458 -135.054848)
					(mid 342.694198 -134.909368)
					(end 342.548718 -134.849108)
				)
				(arc
					(start 341.888318 -134.849108)
					(mid 341.742838 -134.909368)
					(end 341.682578 -135.054848)
				)
				(arc
					(start 341.682578 -135.715248)
					(mid 341.742838 -135.860728)
					(end 341.888318 -135.920988)
				)
				(arc
					(start 342.548718 -135.920988)
					(mid 342.694198 -135.860728)
					(end 342.754458 -135.715248)
				)
			)
		)
		(polygon
			(pts
				(arc
					(start 341.357458 -135.054848)
					(mid 341.297198 -134.909368)
					(end 341.151718 -134.849108)
				)
				(arc
					(start 340.465918 -134.849108)
					(mid 340.320438 -134.909368)
					(end 340.260178 -135.054848)
				)
				(arc
					(start 340.260178 -135.715248)
					(mid 340.320438 -135.860728)
					(end 340.465918 -135.920988)
				)
				(arc
					(start 341.151718 -135.920988)
					(mid 341.297198 -135.860728)
					(end 341.357458 -135.715248)
				)
			)
		)
		(polygon
			(pts
				(arc
					(start 339.960458 -135.054848)
					(mid 339.900198 -134.909368)
					(end 339.754718 -134.849108)
				)
				(arc
					(start 339.068918 -134.849108)
					(mid 338.923438 -134.909368)
					(end 338.863178 -135.054848)
				)
				(arc
					(start 338.863178 -135.715248)
					(mid 338.923438 -135.860728)
					(end 339.068918 -135.920988)
				)
				(arc
					(start 339.754718 -135.920988)
					(mid 339.900198 -135.860728)
					(end 339.960458 -135.715248)
				)
			)
		)
		(polygon
			(pts
				(arc
					(start 338.538058 -135.054848)
					(mid 338.477798 -134.909368)
					(end 338.332318 -134.849108)
				)
				(arc
					(start 337.671918 -134.849108)
					(mid 337.526438 -134.909368)
					(end 337.466178 -135.054848)
				)
				(arc
					(start 337.466178 -135.715248)
					(mid 337.526438 -135.860728)
					(end 337.671918 -135.920988)
				)
				(arc
					(start 338.332318 -135.920988)
					(mid 338.477798 -135.860728)
					(end 338.538058 -135.715248)
				)
			)
		)
		(polygon
			(pts
				(arc
					(start 342.754458 -133.022848)
					(mid 342.694198 -132.877368)
					(end 342.548718 -132.817108)
				)
				(arc
					(start 341.888318 -132.817108)
					(mid 341.742838 -132.877368)
					(end 341.682578 -133.022848)
				)
				(arc
					(start 341.682578 -133.683248)
					(mid 341.742838 -133.828728)
					(end 341.888318 -133.888988)
				)
				(arc
					(start 342.548718 -133.888988)
					(mid 342.694198 -133.828728)
					(end 342.754458 -133.683248)
				)
			)
		)
		(polygon
			(pts
				(arc
					(start 341.357458 -133.022848)
					(mid 341.297198 -132.877368)
					(end 341.151718 -132.817108)
				)
				(arc
					(start 340.465918 -132.817108)
					(mid 340.320438 -132.877368)
					(end 340.260178 -133.022848)
				)
				(arc
					(start 340.260178 -133.683248)
					(mid 340.320438 -133.828728)
					(end 340.465918 -133.888988)
				)
				(arc
					(start 341.151718 -133.888988)
					(mid 341.297198 -133.828728)
					(end 341.357458 -133.683248)
				)
			)
		)
		(polygon
			(pts
				(arc
					(start 339.960458 -133.022848)
					(mid 339.900198 -132.877368)
					(end 339.754718 -132.817108)
				)
				(arc
					(start 339.068918 -132.817108)
					(mid 338.923438 -132.877368)
					(end 338.863178 -133.022848)
				)
				(arc
					(start 338.863178 -133.683248)
					(mid 338.923438 -133.828728)
					(end 339.068918 -133.888988)
				)
				(arc
					(start 339.754718 -133.888988)
					(mid 339.900198 -133.828728)
					(end 339.960458 -133.683248)
				)
			)
		)
		(polygon
			(pts
				(arc
					(start 338.538058 -133.022848)
					(mid 338.477798 -132.877368)
					(end 338.332318 -132.817108)
				)
				(arc
					(start 337.671918 -132.817108)
					(mid 337.526438 -132.877368)
					(end 337.466178 -133.022848)
				)
				(arc
					(start 337.466178 -133.683248)
					(mid 337.526438 -133.828728)
					(end 337.671918 -133.888988)
				)
				(arc
					(start 338.332318 -133.888988)
					(mid 338.477798 -133.828728)
					(end 338.538058 -133.683248)
				)
			)
		)
		(polygon
			(pts
				(arc
					(start 119.208296 -102.850188)
					(mid 118.850156 -102.492048)
					(end 118.492016 -102.850188)
				)
				(arc
					(start 118.492016 -103.85044)
					(mid 118.850283 -104.208326)
					(end 119.208296 -103.850186)
				)
			)
		)
		(polygon
			(pts
				(arc
					(start 118.208298 -102.850188)
					(mid 117.850158 -102.492048)
					(end 117.492018 -102.850188)
				)
				(arc
					(start 117.492018 -103.85044)
					(mid 117.850285 -104.208326)
					(end 118.208298 -103.850186)
				)
			)
		)
		(polygon
			(pts
				(arc
					(start 114.207798 -102.850188)
					(mid 113.849658 -102.492048)
					(end 113.491518 -102.850188)
				)
				(arc
					(start 113.491518 -103.85044)
					(mid 113.849785 -104.208326)
					(end 114.207798 -103.850186)
				)
			)
		)
		(polygon
			(pts
				(arc
					(start 112.207802 -102.850188)
					(mid 111.849662 -102.492048)
					(end 111.491522 -102.850188)
				)
				(arc
					(start 111.491522 -103.85044)
					(mid 111.849789 -104.208326)
					(end 112.207802 -103.850186)
				)
			)
		)
		(polygon
			(pts
				(arc
					(start 110.207806 -102.850188)
					(mid 109.849666 -102.492048)
					(end 109.491526 -102.850188)
				)
				(arc
					(start 109.491526 -103.85044)
					(mid 109.849793 -104.208326)
					(end 110.207806 -103.850186)
				)
			)
		)
		(polygon
			(pts
				(arc
					(start 109.207808 -102.850188)
					(mid 108.849668 -102.492048)
					(end 108.491528 -102.850188)
				)
				(arc
					(start 108.491528 -103.85044)
					(mid 108.849795 -104.208326)
					(end 109.207808 -103.850186)
				)
			)
		)
		(polygon
			(pts
				(arc
					(start 113.2078 -102.849934)
					(mid 112.849533 -102.492048)
					(end 112.49152 -102.850188)
				)
				(arc
					(start 112.49152 -103.850186)
					(mid 112.84966 -104.208326)
					(end 113.2078 -103.850186)
				)
			)
		)
		(polygon
			(pts
				(arc
					(start 111.207804 -102.849934)
					(mid 110.849537 -102.492048)
					(end 110.491524 -102.850188)
				)
				(arc
					(start 110.491524 -103.850186)
					(mid 110.849664 -104.208326)
					(end 111.207804 -103.850186)
				)
			)
		)
		(polygon
			(pts
				(arc
					(start 108.20781 -102.849934)
					(mid 107.849543 -102.492048)
					(end 107.49153 -102.850188)
				)
				(arc
					(start 107.49153 -103.850186)
					(mid 107.84967 -104.208326)
					(end 108.20781 -103.850186)
				)
			)
		)
		(polygon
			(pts
				(arc
					(start 107.207812 -102.849934)
					(mid 106.849545 -102.492048)
					(end 106.491532 -102.850188)
				)
				(arc
					(start 106.491532 -103.850186)
					(mid 106.849672 -104.208326)
					(end 107.207812 -103.850186)
				)
			)
		)
		(polygon
			(pts
				(arc
					(start 116.238782 -102.840028)
					(mid 115.880515 -102.482142)
					(end 115.522502 -102.840282)
				)
				(arc
					(start 115.522502 -103.830882)
					(mid 115.880642 -104.189022)
					(end 116.238782 -103.830882)
				)
			)
		)
		(polygon
			(pts
				(arc
					(start 115.222782 -102.840028)
					(mid 114.864515 -102.482142)
					(end 114.506502 -102.840282)
				)
				(arc
					(start 114.506502 -103.830882)
					(mid 114.864642 -104.189022)
					(end 115.222782 -103.830882)
				)
			)
		)
		(polygon
			(pts
				(arc
					(start 19.579844 -100.654866)
					(mid 19.519584 -100.509386)
					(end 19.374104 -100.449126)
				)
				(arc
					(start 18.967704 -100.449126)
					(mid 18.822224 -100.509386)
					(end 18.761964 -100.654866)
				)
				(arc
					(start 18.761964 -101.061266)
					(mid 18.822224 -101.206746)
					(end 18.967704 -101.267006)
				)
				(arc
					(start 19.374104 -101.267006)
					(mid 19.519584 -101.206746)
					(end 19.579844 -101.061266)
				)
			)
		)
		(polygon
			(pts
				(arc
					(start 18.690844 -100.654866)
					(mid 18.630584 -100.509386)
					(end 18.485104 -100.449126)
				)
				(arc
					(start 18.078704 -100.449126)
					(mid 17.933224 -100.509386)
					(end 17.872964 -100.654866)
				)
				(arc
					(start 17.872964 -101.061266)
					(mid 17.933224 -101.206746)
					(end 18.078704 -101.267006)
				)
				(arc
					(start 18.485104 -101.267006)
					(mid 18.630584 -101.206746)
					(end 18.690844 -101.061266)
				)
			)
		)
		(polygon
			(pts
				(arc
					(start 17.293844 -100.654866)
					(mid 17.233584 -100.509386)
					(end 17.088104 -100.449126)
				)
				(arc
					(start 16.681704 -100.449126)
					(mid 16.536224 -100.509386)
					(end 16.475964 -100.654866)
				)
				(arc
					(start 16.475964 -101.061266)
					(mid 16.536224 -101.206746)
					(end 16.681704 -101.267006)
				)
				(arc
					(start 17.088104 -101.267006)
					(mid 17.233584 -101.206746)
					(end 17.293844 -101.061266)
				)
			)
		)
		(polygon
			(pts
				(arc
					(start 16.404844 -100.654866)
					(mid 16.344584 -100.509386)
					(end 16.199104 -100.449126)
				)
				(arc
					(start 15.792704 -100.449126)
					(mid 15.647224 -100.509386)
					(end 15.586964 -100.654866)
				)
				(arc
					(start 15.586964 -101.061266)
					(mid 15.647224 -101.206746)
					(end 15.792704 -101.267006)
				)
				(arc
					(start 16.199104 -101.267006)
					(mid 16.344584 -101.206746)
					(end 16.404844 -101.061266)
				)
			)
		)
		(polygon
			(pts
				(arc
					(start 14.880844 -100.654866)
					(mid 14.820584 -100.509386)
					(end 14.675104 -100.449126)
				)
				(arc
					(start 14.268704 -100.449126)
					(mid 14.123224 -100.509386)
					(end 14.062964 -100.654866)
				)
				(arc
					(start 14.062964 -101.061266)
					(mid 14.123224 -101.206746)
					(end 14.268704 -101.267006)
				)
				(arc
					(start 14.675104 -101.267006)
					(mid 14.820584 -101.206746)
					(end 14.880844 -101.061266)
				)
			)
		)
		(polygon
			(pts
				(arc
					(start 13.991844 -100.654866)
					(mid 13.931584 -100.509386)
					(end 13.786104 -100.449126)
				)
				(arc
					(start 13.379704 -100.449126)
					(mid 13.234224 -100.509386)
					(end 13.173964 -100.654866)
				)
				(arc
					(start 13.173964 -101.061266)
					(mid 13.234224 -101.206746)
					(end 13.379704 -101.267006)
				)
				(arc
					(start 13.786104 -101.267006)
					(mid 13.931584 -101.206746)
					(end 13.991844 -101.061266)
				)
			)
		)
		(polygon
			(pts
				(arc
					(start 12.467844 -100.654866)
					(mid 12.407584 -100.509386)
					(end 12.262104 -100.449126)
				)
				(arc
					(start 11.855704 -100.449126)
					(mid 11.710224 -100.509386)
					(end 11.649964 -100.654866)
				)
				(arc
					(start 11.649964 -101.061266)
					(mid 11.710224 -101.206746)
					(end 11.855704 -101.267006)
				)
				(arc
					(start 12.262104 -101.267006)
					(mid 12.407584 -101.206746)
					(end 12.467844 -101.061266)
				)
			)
		)
		(polygon
			(pts
				(arc
					(start 11.578844 -100.654866)
					(mid 11.518584 -100.509386)
					(end 11.373104 -100.449126)
				)
				(arc
					(start 10.966704 -100.449126)
					(mid 10.821224 -100.509386)
					(end 10.760964 -100.654866)
				)
				(arc
					(start 10.760964 -101.061266)
					(mid 10.821224 -101.206746)
					(end 10.966704 -101.267006)
				)
				(arc
					(start 11.373104 -101.267006)
					(mid 11.518584 -101.206746)
					(end 11.578844 -101.061266)
				)
			)
		)
		(polygon
			(pts
				(arc
					(start 19.579844 -99.740466)
					(mid 19.519584 -99.594986)
					(end 19.374104 -99.534726)
				)
				(arc
					(start 18.967704 -99.534726)
					(mid 18.822224 -99.594986)
					(end 18.761964 -99.740466)
				)
				(arc
					(start 18.761964 -100.146866)
					(mid 18.822224 -100.292346)
					(end 18.967704 -100.352606)
				)
				(arc
					(start 19.374104 -100.352606)
					(mid 19.519584 -100.292346)
					(end 19.579844 -100.146866)
				)
			)
		)
		(polygon
			(pts
				(arc
					(start 18.690844 -99.740466)
					(mid 18.630584 -99.594986)
					(end 18.485104 -99.534726)
				)
				(arc
					(start 18.078704 -99.534726)
					(mid 17.933224 -99.594986)
					(end 17.872964 -99.740466)
				)
				(arc
					(start 17.872964 -100.146866)
					(mid 17.933224 -100.292346)
					(end 18.078704 -100.352606)
				)
				(arc
					(start 18.485104 -100.352606)
					(mid 18.630584 -100.292346)
					(end 18.690844 -100.146866)
				)
			)
		)
		(polygon
			(pts
				(arc
					(start 17.293844 -99.740466)
					(mid 17.233584 -99.594986)
					(end 17.088104 -99.534726)
				)
				(arc
					(start 16.681704 -99.534726)
					(mid 16.536224 -99.594986)
					(end 16.475964 -99.740466)
				)
				(arc
					(start 16.475964 -100.146866)
					(mid 16.536224 -100.292346)
					(end 16.681704 -100.352606)
				)
				(arc
					(start 17.088104 -100.352606)
					(mid 17.233584 -100.292346)
					(end 17.293844 -100.146866)
				)
			)
		)
		(polygon
			(pts
				(arc
					(start 16.404844 -99.740466)
					(mid 16.344584 -99.594986)
					(end 16.199104 -99.534726)
				)
				(arc
					(start 15.792704 -99.534726)
					(mid 15.647224 -99.594986)
					(end 15.586964 -99.740466)
				)
				(arc
					(start 15.586964 -100.146866)
					(mid 15.647224 -100.292346)
					(end 15.792704 -100.352606)
				)
				(arc
					(start 16.199104 -100.352606)
					(mid 16.344584 -100.292346)
					(end 16.404844 -100.146866)
				)
			)
		)
		(polygon
			(pts
				(arc
					(start 14.880844 -99.740466)
					(mid 14.820584 -99.594986)
					(end 14.675104 -99.534726)
				)
				(arc
					(start 14.268704 -99.534726)
					(mid 14.123224 -99.594986)
					(end 14.062964 -99.740466)
				)
				(arc
					(start 14.062964 -100.146866)
					(mid 14.123224 -100.292346)
					(end 14.268704 -100.352606)
				)
				(arc
					(start 14.675104 -100.352606)
					(mid 14.820584 -100.292346)
					(end 14.880844 -100.146866)
				)
			)
		)
		(polygon
			(pts
				(arc
					(start 13.991844 -99.740466)
					(mid 13.931584 -99.594986)
					(end 13.786104 -99.534726)
				)
				(arc
					(start 13.379704 -99.534726)
					(mid 13.234224 -99.594986)
					(end 13.173964 -99.740466)
				)
				(arc
					(start 13.173964 -100.146866)
					(mid 13.234224 -100.292346)
					(end 13.379704 -100.352606)
				)
				(arc
					(start 13.786104 -100.352606)
					(mid 13.931584 -100.292346)
					(end 13.991844 -100.146866)
				)
			)
		)
		(polygon
			(pts
				(arc
					(start 12.467844 -99.740466)
					(mid 12.407584 -99.594986)
					(end 12.262104 -99.534726)
				)
				(arc
					(start 11.855704 -99.534726)
					(mid 11.710224 -99.594986)
					(end 11.649964 -99.740466)
				)
				(arc
					(start 11.649964 -100.146866)
					(mid 11.710224 -100.292346)
					(end 11.855704 -100.352606)
				)
				(arc
					(start 12.262104 -100.352606)
					(mid 12.407584 -100.292346)
					(end 12.467844 -100.146866)
				)
			)
		)
		(polygon
			(pts
				(arc
					(start 11.578844 -99.740466)
					(mid 11.518584 -99.594986)
					(end 11.373104 -99.534726)
				)
				(arc
					(start 10.966704 -99.534726)
					(mid 10.821224 -99.594986)
					(end 10.760964 -99.740466)
				)
				(arc
					(start 10.760964 -100.146866)
					(mid 10.821224 -100.292346)
					(end 10.966704 -100.352606)
				)
				(arc
					(start 11.373104 -100.352606)
					(mid 11.518584 -100.292346)
					(end 11.578844 -100.146866)
				)
			)
		)
		(polygon
			(pts
				(arc
					(start 19.325082 -98.929444)
					(mid 19.708622 -98.545904)
					(end 19.325082 -98.162364)
				)
				(arc
					(start 18.258028 -98.162364)
					(mid 17.874742 -98.546031)
					(end 18.258282 -98.929444)
				)
			)
		)
		(polygon
			(pts
				(arc
					(start 11.147044 -98.109786)
					(mid 10.762742 -98.492564)
					(end 11.14552 -98.876866)
				)
				(arc
					(start 12.059666 -98.878644)
					(mid 12.444222 -98.495993)
					(end 12.061444 -98.111564)
				)
			)
		)
		(polygon
			(pts
				(xy 15.95755 -98.109278) (xy 15.957296 -98.109532)
				(arc
					(start 15.957296 -98.111818)
					(mid 15.563596 -98.48469)
					(end 15.936468 -98.87839)
				)
				(xy 15.936468 -98.88093) (xy 16.876268 -98.90633)
				(arc
					(start 16.876268 -98.90379)
					(mid 17.269968 -98.530918)
					(end 16.897096 -98.137218)
				)
				(xy 16.897096 -98.134678)
			)
		)
		(polygon
			(pts
				(arc
					(start 13.52931 -98.086672)
					(mid 13.12545 -98.448876)
					(end 13.487654 -98.852736)
				)
				(xy 14.4272 -98.903536)
				(arc
					(start 14.427454 -98.903536)
					(mid 14.831314 -98.541332)
					(end 14.46911 -98.137472)
				)
			)
		)
		(polygon
			(pts
				(arc
					(start 122.862848 -93.470222)
					(mid 122.497342 -93.820996)
					(end 122.848116 -94.186502)
				)
				(arc
					(start 123.843542 -94.206822)
					(mid 124.209305 -93.856175)
					(end 123.858528 -93.490542)
				)
			)
		)
		(polygon
			(pts
				(arc
					(start 123.208288 -91.849702)
					(mid 122.850021 -91.491562)
					(end 122.492008 -91.849956)
				)
				(arc
					(start 122.492262 -92.827348)
					(mid 122.850402 -93.185742)
					(end 123.208542 -92.827348)
				)
				(xy 123.208288 -91.849956)
			)
		)
		(polygon
			(pts
				(arc
					(start 132.59054 -91.169744)
					(mid 132.206873 -90.786458)
					(end 131.82346 -91.169998)
				)
				(arc
					(start 131.82346 -92.075)
					(mid 132.207 -92.45854)
					(end 132.59054 -92.075)
				)
			)
		)
		(polygon
			(pts
				(arc
					(start 123.850146 -91.207844)
					(mid 124.208286 -90.849704)
					(end 123.850146 -90.491564)
				)
				(arc
					(start 122.849894 -90.491564)
					(mid 122.492008 -90.849831)
					(end 122.850148 -91.207844)
				)
			)
		)
		(polygon
			(pts
				(arc
					(start 42.328338 -90.479626)
					(mid 42.711878 -90.096086)
					(end 42.328338 -89.712546)
				)
				(arc
					(start 41.3512 -89.712546)
					(mid 40.967914 -90.096213)
					(end 41.351454 -90.479626)
				)
			)
		)
		(polygon
			(pts
				(arc
					(start 39.407592 -90.479626)
					(mid 39.790878 -90.095959)
					(end 39.407338 -89.712546)
				)
				(arc
					(start 38.430454 -89.712546)
					(mid 38.046914 -90.096086)
					(end 38.430454 -90.479626)
				)
			)
		)
		(polygon
			(pts
				(arc
					(start 36.359592 -90.479626)
					(mid 36.742878 -90.095959)
					(end 36.359338 -89.712546)
				)
				(arc
					(start 35.382454 -89.712546)
					(mid 34.998914 -90.096086)
					(end 35.382454 -90.479626)
				)
			)
		)
		(polygon
			(pts
				(arc
					(start 33.311338 -90.479626)
					(mid 33.694878 -90.096086)
					(end 33.311338 -89.712546)
				)
				(arc
					(start 32.3342 -89.712546)
					(mid 31.950914 -90.096213)
					(end 32.334454 -90.479626)
				)
			)
		)
		(polygon
			(pts
				(arc
					(start 123.850146 -90.207846)
					(mid 124.208286 -89.849706)
					(end 123.850146 -89.491566)
				)
				(arc
					(start 122.849894 -89.491566)
					(mid 122.492008 -89.849833)
					(end 122.850148 -90.207846)
				)
			)
		)
		(polygon
			(pts
				(arc
					(start 134.11454 -89.654126)
					(mid 133.731 -89.270586)
					(end 133.34746 -89.654126)
				)
				(arc
					(start 133.34746 -90.559382)
					(mid 133.731127 -90.942668)
					(end 134.11454 -90.559128)
				)
			)
		)
		(polygon
			(pts
				(arc
					(start 132.59054 -88.375744)
					(mid 132.206873 -87.992458)
					(end 131.82346 -88.375998)
				)
				(arc
					(start 131.82346 -89.281)
					(mid 132.207 -89.66454)
					(end 132.59054 -89.281)
				)
			)
		)
		(polygon
			(pts
				(arc
					(start 304.720244 -87.908892)
					(mid 305.10353 -87.525225)
					(end 304.71999 -87.141812)
				)
				(arc
					(start 303.80305 -87.141812)
					(mid 303.41951 -87.525352)
					(end 303.80305 -87.908892)
				)
			)
		)
		(polygon
			(pts
				(arc
					(start 134.11454 -87.113872)
					(mid 133.730873 -86.730586)
					(end 133.34746 -87.114126)
				)
				(arc
					(start 133.34746 -88.019128)
					(mid 133.731 -88.402668)
					(end 134.11454 -88.019128)
				)
			)
		)
		(polygon
			(pts
				(arc
					(start 49.373536 -86.76894)
					(mid 48.989869 -86.385654)
					(end 48.606456 -86.769194)
				)
				(arc
					(start 48.606456 -87.746078)
					(mid 48.989996 -88.129618)
					(end 49.373536 -87.746078)
				)
			)
		)
		(polygon
			(pts
				(arc
					(start 123.84532 -85.151214)
					(mid 124.182625 -84.773135)
					(end 123.804426 -84.43595)
				)
				(arc
					(start 122.829574 -84.492084)
					(mid 122.492516 -84.87029)
					(end 122.870722 -85.207348)
				)
			)
		)
		(polygon
			(pts
				(arc
					(start 49.373536 -83.937094)
					(mid 48.989996 -83.553554)
					(end 48.606456 -83.937094)
				)
				(arc
					(start 48.606456 -84.914232)
					(mid 48.990123 -85.297518)
					(end 49.373536 -84.913978)
				)
			)
		)
		(polygon
			(pts
				(arc
					(start 123.8504 -84.207858)
					(mid 124.208286 -83.849591)
					(end 123.850146 -83.491578)
				)
				(arc
					(start 122.850148 -83.491578)
					(mid 122.492008 -83.849718)
					(end 122.850148 -84.207858)
				)
			)
		)
		(polygon
			(pts
				(arc
					(start 45.624242 -83.885786)
					(mid 46.007528 -83.502119)
					(end 45.623988 -83.118706)
				)
				(arc
					(start 44.647104 -83.118706)
					(mid 44.263564 -83.502246)
					(end 44.647104 -83.885786)
				)
			)
		)
		(polygon
			(pts
				(arc
					(start 42.670222 -83.873086)
					(mid 43.053762 -83.489546)
					(end 42.670222 -83.106006)
				)
				(arc
					(start 41.693084 -83.106006)
					(mid 41.309798 -83.489673)
					(end 41.693338 -83.873086)
				)
			)
		)
		(polygon
			(pts
				(arc
					(start 123.850146 -83.20786)
					(mid 124.208286 -82.84972)
					(end 123.850146 -82.49158)
				)
				(arc
					(start 122.849894 -82.49158)
					(mid 122.492008 -82.849847)
					(end 122.850148 -83.20786)
				)
			)
		)
		(polygon
			(pts
				(arc
					(start 135.509508 -83.06054)
					(mid 135.893048 -82.677)
					(end 135.509508 -82.29346)
				)
				(arc
					(start 134.581138 -82.29346)
					(mid 134.197852 -82.677127)
					(end 134.581392 -83.06054)
				)
			)
		)
		(polygon
			(pts
				(arc
					(start 297.974004 -82.607404)
					(mid 298.35729 -82.223737)
					(end 297.97375 -81.840324)
				)
				(arc
					(start 297.05681 -81.840324)
					(mid 296.67327 -82.223864)
					(end 297.05681 -82.607404)
				)
			)
		)
		(polygon
			(pts
				(arc
					(start 39.975536 -82.070194)
					(mid 39.591996 -81.686654)
					(end 39.208456 -82.070194)
				)
				(arc
					(start 39.208456 -83.047332)
					(mid 39.592123 -83.430618)
					(end 39.975536 -83.047078)
				)
			)
		)
		(polygon
			(pts
				(arc
					(start 123.7488 -82.120486)
					(mid 124.095256 -81.75117)
					(end 123.72594 -81.404714)
				)
				(xy 123.72594 -81.402174) (xy 122.924824 -81.427574) (xy 122.92457 -81.427828)
				(arc
					(start 122.92457 -81.430114)
					(mid 122.578114 -81.79943)
					(end 122.94743 -82.145886)
				)
				(xy 122.94743 -82.148426) (xy 123.7488 -82.123026)
			)
		)
		(polygon
			(pts
				(arc
					(start 136.807956 -81.91754)
					(mid 137.191496 -81.534)
					(end 136.807956 -81.15046)
				)
				(arc
					(start 135.879586 -81.15046)
					(mid 135.4963 -81.534127)
					(end 135.87984 -81.91754)
				)
			)
		)
		(polygon
			(pts
				(arc
					(start 318.690498 -81.407)
					(mid 318.306958 -81.02346)
					(end 317.923418 -81.407)
				)
				(arc
					(start 317.923418 -82.423254)
					(mid 318.307085 -82.80654)
					(end 318.690498 -82.423)
				)
			)
		)
		(polygon
			(pts
				(arc
					(start 130.048254 -81.66354)
					(mid 130.43154 -81.279873)
					(end 130.048 -80.89646)
				)
				(arc
					(start 129.159 -80.89646)
					(mid 128.77546 -81.28)
					(end 129.159 -81.66354)
				)
			)
		)
		(polygon
			(pts
				(arc
					(start 133.858762 -81.500726)
					(mid 134.242048 -81.117059)
					(end 133.858508 -80.733646)
				)
				(arc
					(start 132.930392 -80.733646)
					(mid 132.546852 -81.117186)
					(end 132.930392 -81.500726)
				)
			)
		)
		(polygon
			(pts
				(arc
					(start 123.85294 -81.309464)
					(mid 124.236988 -80.926432)
					(end 123.853956 -80.542384)
				)
				(xy 123.833128 -80.542892)
				(arc
					(start 122.925332 -80.56626)
					(mid 122.566684 -80.923765)
					(end 122.924062 -81.28254)
				)
				(xy 123.831858 -81.308956)
			)
		)
		(polygon
			(pts
				(arc
					(start 125.756162 -80.635348)
					(mid 126.139702 -80.251808)
					(end 125.756162 -79.868268)
				)
				(arc
					(start 124.779024 -79.868268)
					(mid 124.395738 -80.251935)
					(end 124.779278 -80.635348)
				)
			)
		)
		(polygon
			(pts
				(arc
					(start 128.131316 -80.19034)
					(mid 128.514602 -79.806673)
					(end 128.131062 -79.42326)
				)
				(arc
					(start 127.154178 -79.42326)
					(mid 126.770638 -79.8068)
					(end 127.154178 -80.19034)
				)
			)
		)
		(polygon
			(pts
				(arc
					(start 132.005578 -80.13954)
					(mid 132.388864 -79.755873)
					(end 132.005324 -79.37246)
				)
				(arc
					(start 131.02844 -79.37246)
					(mid 130.6449 -79.756)
					(end 131.02844 -80.13954)
				)
			)
		)
		(polygon
			(pts
				(arc
					(start 39.975536 -79.74584)
					(mid 39.591869 -79.362554)
					(end 39.208456 -79.746094)
				)
				(arc
					(start 39.208456 -80.722978)
					(mid 39.591996 -81.106518)
					(end 39.975536 -80.722978)
				)
			)
		)
		(polygon
			(pts
				(arc
					(start 294.03294 -79.44993)
					(mid 293.6494 -79.06639)
					(end 293.26586 -79.44993)
				)
				(arc
					(start 293.26586 -80.367124)
					(mid 293.649527 -80.75041)
					(end 294.03294 -80.36687)
				)
			)
		)
		(polygon
			(pts
				(arc
					(start 318.792098 -78.445106)
					(mid 318.418337 -78.051917)
					(end 318.025018 -78.425548)
				)
				(arc
					(start 317.999618 -79.441548)
					(mid 318.373506 -79.83474)
					(end 318.766698 -79.460852)
				)
			)
		)
		(polygon
			(pts
				(arc
					(start 45.94987 -77.904086)
					(mid 45.88961 -77.758606)
					(end 45.74413 -77.698346)
				)
				(arc
					(start 45.33773 -77.698346)
					(mid 45.19225 -77.758606)
					(end 45.13199 -77.904086)
				)
				(arc
					(start 45.13199 -78.310486)
					(mid 45.19225 -78.455966)
					(end 45.33773 -78.516226)
				)
				(arc
					(start 45.74413 -78.516226)
					(mid 45.88961 -78.455966)
					(end 45.94987 -78.310486)
				)
			)
		)
		(polygon
			(pts
				(arc
					(start 44.93387 -77.904086)
					(mid 44.87361 -77.758606)
					(end 44.72813 -77.698346)
				)
				(arc
					(start 44.32173 -77.698346)
					(mid 44.17625 -77.758606)
					(end 44.11599 -77.904086)
				)
				(arc
					(start 44.11599 -78.310486)
					(mid 44.17625 -78.455966)
					(end 44.32173 -78.516226)
				)
				(arc
					(start 44.72813 -78.516226)
					(mid 44.87361 -78.455966)
					(end 44.93387 -78.310486)
				)
			)
		)
		(polygon
			(pts
				(arc
					(start 43.53687 -77.904086)
					(mid 43.47661 -77.758606)
					(end 43.33113 -77.698346)
				)
				(arc
					(start 42.92473 -77.698346)
					(mid 42.77925 -77.758606)
					(end 42.71899 -77.904086)
				)
				(arc
					(start 42.71899 -78.310486)
					(mid 42.77925 -78.455966)
					(end 42.92473 -78.516226)
				)
				(arc
					(start 43.33113 -78.516226)
					(mid 43.47661 -78.455966)
					(end 43.53687 -78.310486)
				)
			)
		)
		(polygon
			(pts
				(arc
					(start 42.52087 -77.904086)
					(mid 42.46061 -77.758606)
					(end 42.31513 -77.698346)
				)
				(arc
					(start 41.90873 -77.698346)
					(mid 41.76325 -77.758606)
					(end 41.70299 -77.904086)
				)
				(arc
					(start 41.70299 -78.310486)
					(mid 41.76325 -78.455966)
					(end 41.90873 -78.516226)
				)
				(arc
					(start 42.31513 -78.516226)
					(mid 42.46061 -78.455966)
					(end 42.52087 -78.310486)
				)
			)
		)
		(polygon
			(pts
				(arc
					(start 214.031576 -78.540356)
					(mid 213.740492 -77.66812)
					(end 212.868256 -77.959204)
				)
				(xy 212.86597 -77.957934) (xy 211.86648 -79.958184)
				(arc
					(start 211.868766 -79.959454)
					(mid 212.15985 -80.83169)
					(end 213.032086 -80.540606)
				)
				(xy 213.034372 -80.541876) (xy 214.033862 -78.54188) (xy 214.033608 -78.541372)
			)
		)
		(polygon
			(pts
				(arc
					(start 202.031346 -78.540356)
					(mid 201.740262 -77.66812)
					(end 200.868026 -77.959204)
				)
				(xy 200.86574 -77.957934) (xy 199.86625 -79.958184)
				(arc
					(start 199.868536 -79.959454)
					(mid 200.15962 -80.83169)
					(end 201.031856 -80.540606)
				)
				(xy 201.034142 -80.541876) (xy 202.033632 -78.54188) (xy 202.033378 -78.541372)
			)
		)
		(polygon
			(pts
				(arc
					(start 194.031616 -78.540356)
					(mid 193.740532 -77.66812)
					(end 192.868296 -77.959204)
				)
				(xy 192.86601 -77.957934) (xy 191.86652 -79.958184)
				(arc
					(start 191.868806 -79.959454)
					(mid 192.15989 -80.83169)
					(end 193.032126 -80.540606)
				)
				(xy 193.034412 -80.541876) (xy 194.033902 -78.54188) (xy 194.033648 -78.541372)
			)
		)
		(polygon
			(pts
				(arc
					(start 170.031156 -78.540356)
					(mid 169.740072 -77.66812)
					(end 168.867836 -77.959204)
				)
				(xy 168.86555 -77.957934) (xy 167.86606 -79.958184)
				(arc
					(start 167.868346 -79.959454)
					(mid 168.15943 -80.83169)
					(end 169.031666 -80.540606)
				)
				(xy 169.033952 -80.541876) (xy 170.033442 -78.54188) (xy 170.033188 -78.541372)
			)
		)
		(polygon
			(pts
				(arc
					(start 162.031426 -78.540356)
					(mid 161.740342 -77.66812)
					(end 160.868106 -77.959204)
				)
				(xy 160.86582 -77.957934) (xy 159.86633 -79.958184)
				(arc
					(start 159.868616 -79.959454)
					(mid 160.1597 -80.83169)
					(end 161.031936 -80.540606)
				)
				(xy 161.034222 -80.541876) (xy 162.033712 -78.54188) (xy 162.033458 -78.541372)
			)
		)
		(polygon
			(pts
				(arc
					(start 206.031846 -78.54061)
					(mid 205.741321 -77.668399)
					(end 204.86878 -77.958696)
				)
				(xy 204.866494 -77.95768) (xy 203.865734 -79.95793)
				(arc
					(start 203.86802 -79.958946)
					(mid 204.158342 -80.831436)
					(end 205.030832 -80.541114)
				)
				(xy 205.033118 -80.54213) (xy 206.033878 -78.542134) (xy 206.033624 -78.541626)
			)
		)
		(polygon
			(pts
				(arc
					(start 198.032116 -78.54061)
					(mid 197.741591 -77.668399)
					(end 196.86905 -77.958696)
				)
				(xy 196.866764 -77.95768) (xy 195.866004 -79.95793)
				(arc
					(start 195.86829 -79.958946)
					(mid 196.158612 -80.831436)
					(end 197.031102 -80.541114)
				)
				(xy 197.033388 -80.54213) (xy 198.034148 -78.542134) (xy 198.033894 -78.541626)
			)
		)
		(polygon
			(pts
				(arc
					(start 166.031926 -78.54061)
					(mid 165.741401 -77.668399)
					(end 164.86886 -77.958696)
				)
				(xy 164.866574 -77.95768) (xy 163.865814 -79.95793)
				(arc
					(start 163.8681 -79.958946)
					(mid 164.158422 -80.831436)
					(end 165.030912 -80.541114)
				)
				(xy 165.033198 -80.54213) (xy 166.033958 -78.542134) (xy 166.033704 -78.541626)
			)
		)
		(polygon
			(pts
				(arc
					(start 158.032196 -78.54061)
					(mid 157.741671 -77.668399)
					(end 156.86913 -77.958696)
				)
				(xy 156.866844 -77.95768) (xy 155.866084 -79.95793)
				(arc
					(start 155.86837 -79.958946)
					(mid 156.158692 -80.831436)
					(end 157.031182 -80.541114)
				)
				(xy 157.033468 -80.54213) (xy 158.034228 -78.542134) (xy 158.033974 -78.541626)
			)
		)
		(polygon
			(pts
				(arc
					(start 296.29354 -77.35951)
					(mid 295.91 -76.97597)
					(end 295.52646 -77.35951)
				)
				(arc
					(start 295.52646 -78.276704)
					(mid 295.910127 -78.65999)
					(end 296.29354 -78.27645)
				)
			)
		)
		(polygon
			(pts
				(arc
					(start 54.71287 -77.015086)
					(mid 54.65261 -76.869606)
					(end 54.50713 -76.809346)
				)
				(arc
					(start 54.10073 -76.809346)
					(mid 53.95525 -76.869606)
					(end 53.89499 -77.015086)
				)
				(arc
					(start 53.89499 -77.421486)
					(mid 53.95525 -77.566966)
					(end 54.10073 -77.627226)
				)
				(arc
					(start 54.50713 -77.627226)
					(mid 54.65261 -77.566966)
					(end 54.71287 -77.421486)
				)
			)
		)
		(polygon
			(pts
				(arc
					(start 53.69687 -77.015086)
					(mid 53.63661 -76.869606)
					(end 53.49113 -76.809346)
				)
				(arc
					(start 53.08473 -76.809346)
					(mid 52.93925 -76.869606)
					(end 52.87899 -77.015086)
				)
				(arc
					(start 52.87899 -77.421486)
					(mid 52.93925 -77.566966)
					(end 53.08473 -77.627226)
				)
				(arc
					(start 53.49113 -77.627226)
					(mid 53.63661 -77.566966)
					(end 53.69687 -77.421486)
				)
			)
		)
		(polygon
			(pts
				(arc
					(start 52.17287 -77.015086)
					(mid 52.11261 -76.869606)
					(end 51.96713 -76.809346)
				)
				(arc
					(start 51.56073 -76.809346)
					(mid 51.41525 -76.869606)
					(end 51.35499 -77.015086)
				)
				(arc
					(start 51.35499 -77.421486)
					(mid 51.41525 -77.566966)
					(end 51.56073 -77.627226)
				)
				(arc
					(start 51.96713 -77.627226)
					(mid 52.11261 -77.566966)
					(end 52.17287 -77.421486)
				)
			)
		)
		(polygon
			(pts
				(arc
					(start 51.28387 -77.015086)
					(mid 51.22361 -76.869606)
					(end 51.07813 -76.809346)
				)
				(arc
					(start 50.67173 -76.809346)
					(mid 50.52625 -76.869606)
					(end 50.46599 -77.015086)
				)
				(arc
					(start 50.46599 -77.421486)
					(mid 50.52625 -77.566966)
					(end 50.67173 -77.627226)
				)
				(arc
					(start 51.07813 -77.627226)
					(mid 51.22361 -77.566966)
					(end 51.28387 -77.421486)
				)
			)
		)
		(polygon
			(pts
				(arc
					(start 45.94987 -76.989686)
					(mid 45.88961 -76.844206)
					(end 45.74413 -76.783946)
				)
				(arc
					(start 45.33773 -76.783946)
					(mid 45.19225 -76.844206)
					(end 45.13199 -76.989686)
				)
				(arc
					(start 45.13199 -77.396086)
					(mid 45.19225 -77.541566)
					(end 45.33773 -77.601826)
				)
				(arc
					(start 45.74413 -77.601826)
					(mid 45.88961 -77.541566)
					(end 45.94987 -77.396086)
				)
			)
		)
		(polygon
			(pts
				(arc
					(start 44.93387 -76.989686)
					(mid 44.87361 -76.844206)
					(end 44.72813 -76.783946)
				)
				(arc
					(start 44.32173 -76.783946)
					(mid 44.17625 -76.844206)
					(end 44.11599 -76.989686)
				)
				(arc
					(start 44.11599 -77.396086)
					(mid 44.17625 -77.541566)
					(end 44.32173 -77.601826)
				)
				(arc
					(start 44.72813 -77.601826)
					(mid 44.87361 -77.541566)
					(end 44.93387 -77.396086)
				)
			)
		)
		(polygon
			(pts
				(arc
					(start 43.53687 -76.989686)
					(mid 43.47661 -76.844206)
					(end 43.33113 -76.783946)
				)
				(arc
					(start 42.92473 -76.783946)
					(mid 42.77925 -76.844206)
					(end 42.71899 -76.989686)
				)
				(arc
					(start 42.71899 -77.396086)
					(mid 42.77925 -77.541566)
					(end 42.92473 -77.601826)
				)
				(arc
					(start 43.33113 -77.601826)
					(mid 43.47661 -77.541566)
					(end 43.53687 -77.396086)
				)
			)
		)
		(polygon
			(pts
				(arc
					(start 42.52087 -76.989686)
					(mid 42.46061 -76.844206)
					(end 42.31513 -76.783946)
				)
				(arc
					(start 41.90873 -76.783946)
					(mid 41.76325 -76.844206)
					(end 41.70299 -76.989686)
				)
				(arc
					(start 41.70299 -77.396086)
					(mid 41.76325 -77.541566)
					(end 41.90873 -77.601826)
				)
				(arc
					(start 42.31513 -77.601826)
					(mid 42.46061 -77.541566)
					(end 42.52087 -77.396086)
				)
			)
		)
		(polygon
			(pts
				(arc
					(start 204.929232 -77.40904)
					(mid 205.312772 -77.0255)
					(end 204.929232 -76.64196)
				)
				(arc
					(start 203.947014 -76.64196)
					(mid 203.563728 -77.025627)
					(end 203.947268 -77.40904)
				)
			)
		)
		(polygon
			(pts
				(arc
					(start 200.928986 -77.40904)
					(mid 201.312272 -77.025373)
					(end 200.928732 -76.64196)
				)
				(arc
					(start 199.946768 -76.64196)
					(mid 199.563228 -77.0255)
					(end 199.946768 -77.40904)
				)
			)
		)
		(polygon
			(pts
				(arc
					(start 196.929502 -77.40904)
					(mid 197.313042 -77.0255)
					(end 196.929502 -76.64196)
				)
				(arc
					(start 195.947284 -76.64196)
					(mid 195.563998 -77.025627)
					(end 195.947538 -77.40904)
				)
			)
		)
		(polygon
			(pts
				(arc
					(start 192.929256 -77.40904)
					(mid 193.312542 -77.025373)
					(end 192.929002 -76.64196)
				)
				(arc
					(start 191.947038 -76.64196)
					(mid 191.563498 -77.0255)
					(end 191.947038 -77.40904)
				)
			)
		)
		(polygon
			(pts
				(arc
					(start 168.928542 -77.40904)
					(mid 169.312082 -77.0255)
					(end 168.928542 -76.64196)
				)
				(arc
					(start 167.946324 -76.64196)
					(mid 167.563038 -77.025627)
					(end 167.946578 -77.40904)
				)
			)
		)
		(polygon
			(pts
				(arc
					(start 164.928042 -77.40904)
					(mid 165.311582 -77.0255)
					(end 164.928042 -76.64196)
				)
				(arc
					(start 163.945824 -76.64196)
					(mid 163.562538 -77.025627)
					(end 163.946078 -77.40904)
				)
			)
		)
		(polygon
			(pts
				(arc
					(start 160.928812 -77.40904)
					(mid 161.312352 -77.0255)
					(end 160.928812 -76.64196)
				)
				(arc
					(start 159.946594 -76.64196)
					(mid 159.563308 -77.025627)
					(end 159.946848 -77.40904)
				)
			)
		)
		(polygon
			(pts
				(arc
					(start 156.928312 -77.40904)
					(mid 157.311852 -77.0255)
					(end 156.928312 -76.64196)
				)
				(arc
					(start 155.946094 -76.64196)
					(mid 155.562808 -77.025627)
					(end 155.946348 -77.40904)
				)
			)
		)
		(polygon
			(pts
				(arc
					(start 54.71287 -76.100686)
					(mid 54.65261 -75.955206)
					(end 54.50713 -75.894946)
				)
				(arc
					(start 54.10073 -75.894946)
					(mid 53.95525 -75.955206)
					(end 53.89499 -76.100686)
				)
				(arc
					(start 53.89499 -76.507086)
					(mid 53.95525 -76.652566)
					(end 54.10073 -76.712826)
				)
				(arc
					(start 54.50713 -76.712826)
					(mid 54.65261 -76.652566)
					(end 54.71287 -76.507086)
				)
			)
		)
		(polygon
			(pts
				(arc
					(start 53.69687 -76.100686)
					(mid 53.63661 -75.955206)
					(end 53.49113 -75.894946)
				)
				(arc
					(start 53.08473 -75.894946)
					(mid 52.93925 -75.955206)
					(end 52.87899 -76.100686)
				)
				(arc
					(start 52.87899 -76.507086)
					(mid 52.93925 -76.652566)
					(end 53.08473 -76.712826)
				)
				(arc
					(start 53.49113 -76.712826)
					(mid 53.63661 -76.652566)
					(end 53.69687 -76.507086)
				)
			)
		)
		(polygon
			(pts
				(arc
					(start 52.17287 -76.100686)
					(mid 52.11261 -75.955206)
					(end 51.96713 -75.894946)
				)
				(arc
					(start 51.56073 -75.894946)
					(mid 51.41525 -75.955206)
					(end 51.35499 -76.100686)
				)
				(arc
					(start 51.35499 -76.507086)
					(mid 51.41525 -76.652566)
					(end 51.56073 -76.712826)
				)
				(arc
					(start 51.96713 -76.712826)
					(mid 52.11261 -76.652566)
					(end 52.17287 -76.507086)
				)
			)
		)
		(polygon
			(pts
				(arc
					(start 51.28387 -76.100686)
					(mid 51.22361 -75.955206)
					(end 51.07813 -75.894946)
				)
				(arc
					(start 50.67173 -75.894946)
					(mid 50.52625 -75.955206)
					(end 50.46599 -76.100686)
				)
				(arc
					(start 50.46599 -76.507086)
					(mid 50.52625 -76.652566)
					(end 50.67173 -76.712826)
				)
				(arc
					(start 51.07813 -76.712826)
					(mid 51.22361 -76.652566)
					(end 51.28387 -76.507086)
				)
			)
		)
		(polygon
			(pts
				(arc
					(start 320.570098 -75.209908)
					(mid 320.186558 -74.826368)
					(end 319.803018 -75.209908)
				)
				(arc
					(start 319.803018 -76.192126)
					(mid 320.186685 -76.575412)
					(end 320.570098 -76.191872)
				)
			)
		)
		(polygon
			(pts
				(arc
					(start 54.288436 -75.290426)
					(mid 54.671722 -74.906759)
					(end 54.288182 -74.523346)
				)
				(arc
					(start 53.311298 -74.523346)
					(mid 52.927758 -74.906886)
					(end 53.311298 -75.290426)
				)
			)
		)
		(polygon
			(pts
				(arc
					(start 51.888644 -75.290426)
					(mid 52.27193 -74.906759)
					(end 51.88839 -74.523346)
				)
				(arc
					(start 50.911506 -74.523346)
					(mid 50.527966 -74.906886)
					(end 50.911506 -75.290426)
				)
			)
		)
		(polygon
			(pts
				(arc
					(start 45.488606 -75.290426)
					(mid 45.871892 -74.906759)
					(end 45.488352 -74.523346)
				)
				(arc
					(start 44.511468 -74.523346)
					(mid 44.127928 -74.906886)
					(end 44.511468 -75.290426)
				)
			)
		)
		(polygon
			(pts
				(arc
					(start 43.088306 -75.138026)
					(mid 43.471846 -74.754486)
					(end 43.088306 -74.370946)
				)
				(arc
					(start 42.111168 -74.370946)
					(mid 41.727882 -74.754613)
					(end 42.111422 -75.138026)
				)
			)
		)
		(polygon
			(pts
				(arc
					(start 298.139612 -74.07529)
					(mid 298.522898 -73.691623)
					(end 298.139358 -73.30821)
				)
				(arc
					(start 297.123358 -73.30821)
					(mid 296.739818 -73.69175)
					(end 297.123358 -74.07529)
				)
			)
		)
		(polygon
			(pts
				(arc
					(start 302.956722 -73.99274)
					(mid 303.340262 -73.6092)
					(end 302.956722 -73.22566)
				)
				(arc
					(start 301.974504 -73.22566)
					(mid 301.591218 -73.609327)
					(end 301.974758 -73.99274)
				)
			)
		)
		(polygon
			(pts
				(arc
					(start 207.031336 -73.45934)
					(mid 206.158998 -73.168942)
					(end 205.86827 -74.041254)
				)
				(xy 205.865984 -74.04227) (xy 206.866744 -76.04252)
				(arc
					(start 206.86903 -76.041504)
					(mid 207.74152 -76.331826)
					(end 208.031842 -75.459336)
				)
				(xy 208.034128 -75.45832) (xy 207.033622 -73.458324) (xy 207.033114 -73.458324)
			)
		)
		(polygon
			(pts
				(arc
					(start 195.031106 -73.45934)
					(mid 194.158768 -73.168942)
					(end 193.86804 -74.041254)
				)
				(xy 193.865754 -74.04227) (xy 194.866514 -76.04252)
				(arc
					(start 194.8688 -76.041504)
					(mid 195.74129 -76.331826)
					(end 196.031612 -75.459336)
				)
				(xy 196.033898 -75.45832) (xy 195.033392 -73.458324) (xy 195.032884 -73.458324)
			)
		)
		(polygon
			(pts
				(arc
					(start 167.031416 -73.45934)
					(mid 166.159078 -73.168942)
					(end 165.86835 -74.041254)
				)
				(xy 165.866064 -74.04227) (xy 166.866824 -76.04252)
				(arc
					(start 166.86911 -76.041504)
					(mid 167.7416 -76.331826)
					(end 168.031922 -75.459336)
				)
				(xy 168.034208 -75.45832) (xy 167.033702 -73.458324) (xy 167.033194 -73.458324)
			)
		)
		(polygon
			(pts
				(arc
					(start 203.032106 -73.459594)
					(mid 202.15987 -73.16851)
					(end 201.868786 -74.040746)
				)
				(xy 201.8665 -74.042016) (xy 202.86599 -76.042266)
				(arc
					(start 202.868276 -76.040996)
					(mid 203.740512 -76.33208)
					(end 204.031596 -75.459844)
				)
				(xy 204.033882 -75.458574) (xy 203.034392 -73.458578) (xy 203.034138 -73.458578)
			)
		)
		(polygon
			(pts
				(arc
					(start 199.031606 -73.459594)
					(mid 198.15937 -73.16851)
					(end 197.868286 -74.040746)
				)
				(xy 197.866 -74.042016) (xy 198.86549 -76.042266)
				(arc
					(start 198.867776 -76.040996)
					(mid 199.740012 -76.33208)
					(end 200.031096 -75.459844)
				)
				(xy 200.033382 -75.458574) (xy 199.033892 -73.458578) (xy 199.033638 -73.458578)
			)
		)
		(polygon
			(pts
				(arc
					(start 191.031876 -73.459594)
					(mid 190.15964 -73.16851)
					(end 189.868556 -74.040746)
				)
				(xy 189.86627 -74.042016) (xy 190.86576 -76.042266)
				(arc
					(start 190.868046 -76.040996)
					(mid 191.740282 -76.33208)
					(end 192.031366 -75.459844)
				)
				(xy 192.033652 -75.458574) (xy 191.034162 -73.458578) (xy 191.033908 -73.458578)
			)
		)
		(polygon
			(pts
				(arc
					(start 171.031916 -73.459594)
					(mid 170.15968 -73.16851)
					(end 169.868596 -74.040746)
				)
				(xy 169.86631 -74.042016) (xy 170.8658 -76.042266)
				(arc
					(start 170.868086 -76.040996)
					(mid 171.740322 -76.33208)
					(end 172.031406 -75.459844)
				)
				(xy 172.033692 -75.458574) (xy 171.034202 -73.458578) (xy 171.033948 -73.458578)
			)
		)
		(polygon
			(pts
				(arc
					(start 163.032186 -73.459594)
					(mid 162.15995 -73.16851)
					(end 161.868866 -74.040746)
				)
				(xy 161.86658 -74.042016) (xy 162.86607 -76.042266)
				(arc
					(start 162.868356 -76.040996)
					(mid 163.740592 -76.33208)
					(end 164.031676 -75.459844)
				)
				(xy 164.033962 -75.458574) (xy 163.034472 -73.458578) (xy 163.034218 -73.458578)
			)
		)
		(polygon
			(pts
				(arc
					(start 159.031686 -73.459594)
					(mid 158.15945 -73.16851)
					(end 157.868366 -74.040746)
				)
				(xy 157.86608 -74.042016) (xy 158.86557 -76.042266)
				(arc
					(start 158.867856 -76.040996)
					(mid 159.740092 -76.33208)
					(end 160.031176 -75.459844)
				)
				(xy 160.033462 -75.458574) (xy 159.033972 -73.458578) (xy 159.033718 -73.458578)
			)
		)
		(polygon
			(pts
				(arc
					(start 318.055498 -72.009)
					(mid 317.671958 -71.62546)
					(end 317.288418 -72.009)
				)
				(arc
					(start 317.288418 -73.025254)
					(mid 317.672085 -73.40854)
					(end 318.055498 -73.025)
				)
			)
		)
		(polygon
			(pts
				(arc
					(start 319.139316 -68.215764)
					(mid 318.755649 -67.832478)
					(end 318.372236 -68.216018)
				)
				(arc
					(start 318.372236 -69.197982)
					(mid 318.755776 -69.581522)
					(end 319.139316 -69.197982)
				)
			)
		)
		(polygon
			(pts
				(arc
					(start 93.914976 -42.600118)
					(mid 93.55963 -42.239184)
					(end 93.198696 -42.59453)
				)
				(arc
					(start 93.192346 -43.387772)
					(mid 93.547565 -43.748961)
					(end 93.908626 -43.393614)
				)
			)
		)
		(polygon
			(pts
				(arc
					(start 92.753942 -41.438576)
					(mid 92.392247 -41.793033)
					(end 92.746576 -42.154856)
				)
				(arc
					(start 93.550994 -42.16273)
					(mid 93.91269 -41.808146)
					(end 93.558106 -41.44645)
				)
			)
		)
		(polygon
			(pts
				(arc
					(start 78.663546 -41.98874)
					(mid 79.046832 -41.605073)
					(end 78.663292 -41.22166)
				)
				(arc
					(start 77.686408 -41.22166)
					(mid 77.302868 -41.6052)
					(end 77.686408 -41.98874)
				)
			)
		)
		(polygon
			(pts
				(arc
					(start 93.898974 -40.193722)
					(mid 93.534484 -39.841932)
					(end 93.182694 -40.206422)
				)
				(arc
					(start 93.196664 -41.001696)
					(mid 93.561027 -41.353738)
					(end 93.912944 -40.98925)
				)
			)
		)
		(polygon
			(pts
				(arc
					(start 80.581246 -40.00754)
					(mid 80.964532 -39.623873)
					(end 80.580992 -39.24046)
				)
				(arc
					(start 79.604108 -39.24046)
					(mid 79.220568 -39.624)
					(end 79.604108 -40.00754)
				)
			)
		)
		(polygon
			(pts
				(arc
					(start 92.746576 -39.03726)
					(mid 92.387674 -39.394511)
					(end 92.744798 -39.75354)
				)
				(arc
					(start 93.55582 -39.755318)
					(mid 93.914722 -39.39794)
					(end 93.557344 -39.039038)
				)
			)
		)
		(polygon
			(pts
				(arc
					(start 83.294728 -37.831776)
					(mid 82.911188 -37.448236)
					(end 82.527648 -37.831776)
				)
				(arc
					(start 82.527648 -38.737032)
					(mid 82.911315 -39.120318)
					(end 83.294728 -38.736778)
				)
			)
		)
		(polygon
			(pts
				(arc
					(start 93.914722 -37.80282)
					(mid 93.557217 -37.444172)
					(end 93.198442 -37.80155)
				)
				(arc
					(start 93.197426 -38.596316)
					(mid 93.555058 -38.954964)
					(end 93.913706 -38.597332)
				)
				(xy 93.913706 -38.596824) (xy 93.913706 -38.596316)
			)
		)
		(polygon
			(pts
				(arc
					(start 84.413852 -37.734494)
					(mid 84.04606 -37.386514)
					(end 83.69808 -37.754306)
				)
				(xy 83.69554 -37.754306) (xy 83.723734 -38.770306) (xy 83.723988 -38.77056)
				(arc
					(start 83.726274 -38.77056)
					(mid 84.094066 -39.11854)
					(end 84.442046 -38.750748)
				)
				(xy 84.444586 -38.750748) (xy 84.416392 -37.734494)
			)
		)
		(polygon
			(pts
				(arc
					(start 94.360492 -37.357558)
					(mid 94.717362 -36.998021)
					(end 94.357698 -36.641278)
				)
				(arc
					(start 93.550232 -36.64458)
					(mid 93.193616 -37.004244)
					(end 93.55328 -37.36086)
				)
			)
		)
		(polygon
			(pts
				(arc
					(start 77.133958 -37.042852)
					(mid 77.517498 -36.659312)
					(end 77.133958 -36.275772)
				)
				(arc
					(start 76.15682 -36.275772)
					(mid 75.773534 -36.659439)
					(end 76.157074 -37.042852)
				)
			)
		)
		(polygon
			(pts
				(arc
					(start 81.61274 -36.334954)
					(mid 81.229073 -35.951668)
					(end 80.84566 -36.335208)
				)
				(arc
					(start 80.84566 -37.312092)
					(mid 81.2292 -37.695632)
					(end 81.61274 -37.312092)
				)
			)
		)
		(polygon
			(pts
				(arc
					(start 93.90761 -35.406838)
					(mid 93.548454 -35.049714)
					(end 93.19133 -35.40887)
				)
				(arc
					(start 93.193616 -36.197032)
					(mid 93.552645 -36.55441)
					(end 93.909896 -36.195254)
				)
				(xy 93.90761 -35.40887) (xy 93.90761 -35.407854)
			)
		)
		(polygon
			(pts
				(arc
					(start 96.30664 -35.406838)
					(mid 95.947738 -35.04946)
					(end 95.59036 -35.408362)
				)
				(xy 95.592138 -36.199318) (xy 95.592138 -36.20008)
				(arc
					(start 95.592138 -36.200588)
					(mid 95.950913 -36.55822)
					(end 96.308418 -36.199318)
				)
				(xy 96.30664 -35.408362) (xy 96.30664 -35.4076)
			)
		)
		(polygon
			(pts
				(arc
					(start 95.50654 -35.404298)
					(mid 95.147638 -35.04692)
					(end 94.79026 -35.405822)
				)
				(xy 94.79026 -35.406838) (xy 94.79026 -35.407854) (xy 94.792038 -36.195254) (xy 94.792038 -36.196016)
				(arc
					(start 94.792038 -36.200588)
					(mid 95.150813 -36.55822)
					(end 95.508318 -36.199318)
				)
				(xy 95.50654 -35.40506)
			)
		)
		(polygon
			(pts
				(arc
					(start 98.700082 -35.397694)
					(mid 98.338132 -35.043364)
					(end 97.983802 -35.405314)
				)
				(arc
					(start 97.992184 -36.203636)
					(mid 98.354007 -36.558219)
					(end 98.708464 -36.19627)
				)
			)
		)
		(polygon
			(pts
				(arc
					(start 103.508302 -35.400234)
					(mid 103.150162 -35.042094)
					(end 102.792022 -35.400234)
				)
				(arc
					(start 102.792022 -36.200334)
					(mid 103.150289 -36.55822)
					(end 103.508302 -36.20008)
				)
			)
		)
		(polygon
			(pts
				(arc
					(start 97.898966 -35.395916)
					(mid 97.536508 -35.042094)
					(end 97.182686 -35.404552)
				)
				(arc
					(start 97.192084 -36.204144)
					(mid 97.554415 -36.558219)
					(end 97.908364 -36.195762)
				)
			)
		)
		(polygon
			(pts
				(arc
					(start 102.708202 -35.39998)
					(mid 102.349935 -35.04184)
					(end 101.991922 -35.400234)
				)
				(xy 101.991922 -35.40125)
				(arc
					(start 101.992176 -36.199826)
					(mid 102.350316 -36.55822)
					(end 102.708456 -36.199826)
				)
				(xy 102.708202 -35.75812)
			)
		)
		(polygon
			(pts
				(arc
					(start 101.115622 -35.40125)
					(mid 100.760784 -35.039808)
					(end 100.399342 -35.394646)
				)
				(arc
					(start 100.39223 -36.196524)
					(mid 100.746941 -36.558221)
					(end 101.10851 -36.203382)
				)
			)
		)
		(polygon
			(pts
				(arc
					(start 100.30968 -35.392868)
					(mid 99.952048 -35.03422)
					(end 99.5934 -35.391852)
				)
				(xy 99.5934 -35.397694) (xy 99.59213 -36.19627)
				(arc
					(start 99.59213 -36.199318)
					(mid 99.949635 -36.55822)
					(end 100.30841 -36.200588)
				)
				(xy 100.30841 -36.20008) (xy 100.30841 -36.199318)
			)
		)
		(polygon
			(pts
				(arc
					(start 94.352618 -34.958274)
					(mid 94.707964 -34.59734)
					(end 94.34703 -34.241994)
				)
				(arc
					(start 93.544644 -34.248344)
					(mid 93.189297 -34.609151)
					(end 93.549978 -34.964624)
				)
			)
		)
		(polygon
			(pts
				(arc
					(start 83.46694 -34.618422)
					(mid 83.083273 -34.235136)
					(end 82.69986 -34.618676)
				)
				(arc
					(start 82.69986 -35.523678)
					(mid 83.0834 -35.907218)
					(end 83.46694 -35.523678)
				)
			)
		)
		(polygon
			(pts
				(arc
					(start 85.37194 -32.884618)
					(mid 84.988273 -32.501332)
					(end 84.60486 -32.884872)
				)
				(arc
					(start 84.60486 -33.789874)
					(mid 84.9884 -34.173414)
					(end 85.37194 -33.789874)
				)
			)
		)
		(polygon
			(pts
				(arc
					(start 277.84933 -32.51454)
					(mid 278.232616 -32.130873)
					(end 277.849076 -31.74746)
				)
				(arc
					(start 276.867112 -31.74746)
					(mid 276.483572 -32.131)
					(end 276.867112 -32.51454)
				)
			)
		)
		(polygon
			(pts
				(arc
					(start 101.8667 -31.233618)
					(mid 101.821319 -31.124059)
					(end 101.71176 -31.078678)
				)
				(arc
					(start 101.50856 -31.078678)
					(mid 101.399001 -31.124059)
					(end 101.35362 -31.233618)
				)
				(arc
					(start 101.35362 -31.487618)
					(mid 101.389532 -31.586808)
					(end 101.48062 -31.640018)
				)
				(arc
					(start 101.48062 -31.640018)
					(mid 101.389532 -31.693228)
					(end 101.35362 -31.792418)
				)
				(arc
					(start 101.35362 -32.046418)
					(mid 101.399001 -32.155977)
					(end 101.50856 -32.201358)
				)
				(arc
					(start 101.71176 -32.201358)
					(mid 101.821319 -32.155977)
					(end 101.8667 -32.046418)
				)
				(arc
					(start 101.8667 -31.792418)
					(mid 101.830788 -31.693228)
					(end 101.7397 -31.640018)
				)
				(arc
					(start 101.7397 -31.640018)
					(mid 101.830788 -31.586808)
					(end 101.8667 -31.487618)
				)
			)
		)
		(polygon
			(pts
				(arc
					(start 101.2317 -31.233618)
					(mid 101.186319 -31.124059)
					(end 101.07676 -31.078678)
				)
				(arc
					(start 100.87356 -31.078678)
					(mid 100.764001 -31.124059)
					(end 100.71862 -31.233618)
				)
				(arc
					(start 100.71862 -31.487618)
					(mid 100.754532 -31.586808)
					(end 100.84562 -31.640018)
				)
				(arc
					(start 100.84562 -31.640018)
					(mid 100.754532 -31.693228)
					(end 100.71862 -31.792418)
				)
				(arc
					(start 100.71862 -32.046418)
					(mid 100.764001 -32.155977)
					(end 100.87356 -32.201358)
				)
				(arc
					(start 101.07676 -32.201358)
					(mid 101.186319 -32.155977)
					(end 101.2317 -32.046418)
				)
				(arc
					(start 101.2317 -31.792418)
					(mid 101.195788 -31.693228)
					(end 101.1047 -31.640018)
				)
				(arc
					(start 101.1047 -31.640018)
					(mid 101.195788 -31.586808)
					(end 101.2317 -31.487618)
				)
			)
		)
		(polygon
			(pts
				(arc
					(start 104.9147 -31.2166)
					(mid 104.869319 -31.107041)
					(end 104.75976 -31.06166)
				)
				(arc
					(start 104.55656 -31.06166)
					(mid 104.447001 -31.107041)
					(end 104.40162 -31.2166)
				)
				(arc
					(start 104.40162 -31.4706)
					(mid 104.437532 -31.56979)
					(end 104.52862 -31.623)
				)
				(arc
					(start 104.52862 -31.623)
					(mid 104.437532 -31.67621)
					(end 104.40162 -31.7754)
				)
				(arc
					(start 104.40162 -32.0294)
					(mid 104.447001 -32.138959)
					(end 104.55656 -32.18434)
				)
				(arc
					(start 104.75976 -32.18434)
					(mid 104.869319 -32.138959)
					(end 104.9147 -32.0294)
				)
				(arc
					(start 104.9147 -31.7754)
					(mid 104.878788 -31.67621)
					(end 104.7877 -31.623)
				)
				(arc
					(start 104.7877 -31.623)
					(mid 104.878788 -31.56979)
					(end 104.9147 -31.4706)
				)
			)
		)
		(polygon
			(pts
				(arc
					(start 104.2797 -31.2166)
					(mid 104.234319 -31.107041)
					(end 104.12476 -31.06166)
				)
				(arc
					(start 103.92156 -31.06166)
					(mid 103.812001 -31.107041)
					(end 103.76662 -31.2166)
				)
				(arc
					(start 103.76662 -31.4706)
					(mid 103.802532 -31.56979)
					(end 103.89362 -31.623)
				)
				(arc
					(start 103.89362 -31.623)
					(mid 103.802532 -31.67621)
					(end 103.76662 -31.7754)
				)
				(arc
					(start 103.76662 -32.0294)
					(mid 103.812001 -32.138959)
					(end 103.92156 -32.18434)
				)
				(arc
					(start 104.12476 -32.18434)
					(mid 104.234319 -32.138959)
					(end 104.2797 -32.0294)
				)
				(arc
					(start 104.2797 -31.7754)
					(mid 104.243788 -31.67621)
					(end 104.1527 -31.623)
				)
				(arc
					(start 104.1527 -31.623)
					(mid 104.243788 -31.56979)
					(end 104.2797 -31.4706)
				)
			)
		)
		(polygon
			(pts
				(arc
					(start 103.3907 -31.2166)
					(mid 103.345319 -31.107041)
					(end 103.23576 -31.06166)
				)
				(arc
					(start 103.03256 -31.06166)
					(mid 102.923001 -31.107041)
					(end 102.87762 -31.2166)
				)
				(arc
					(start 102.87762 -31.4706)
					(mid 102.913532 -31.56979)
					(end 103.00462 -31.623)
				)
				(arc
					(start 103.00462 -31.623)
					(mid 102.913532 -31.67621)
					(end 102.87762 -31.7754)
				)
				(arc
					(start 102.87762 -32.0294)
					(mid 102.923001 -32.138959)
					(end 103.03256 -32.18434)
				)
				(arc
					(start 103.23576 -32.18434)
					(mid 103.345319 -32.138959)
					(end 103.3907 -32.0294)
				)
				(arc
					(start 103.3907 -31.7754)
					(mid 103.354788 -31.67621)
					(end 103.2637 -31.623)
				)
				(arc
					(start 103.2637 -31.623)
					(mid 103.354788 -31.56979)
					(end 103.3907 -31.4706)
				)
			)
		)
		(polygon
			(pts
				(arc
					(start 102.7557 -31.2166)
					(mid 102.710319 -31.107041)
					(end 102.60076 -31.06166)
				)
				(arc
					(start 102.39756 -31.06166)
					(mid 102.288001 -31.107041)
					(end 102.24262 -31.2166)
				)
				(arc
					(start 102.24262 -31.4706)
					(mid 102.278532 -31.56979)
					(end 102.36962 -31.623)
				)
				(arc
					(start 102.36962 -31.623)
					(mid 102.278532 -31.67621)
					(end 102.24262 -31.7754)
				)
				(arc
					(start 102.24262 -32.0294)
					(mid 102.288001 -32.138959)
					(end 102.39756 -32.18434)
				)
				(arc
					(start 102.60076 -32.18434)
					(mid 102.710319 -32.138959)
					(end 102.7557 -32.0294)
				)
				(arc
					(start 102.7557 -31.7754)
					(mid 102.719788 -31.67621)
					(end 102.6287 -31.623)
				)
				(arc
					(start 102.6287 -31.623)
					(mid 102.719788 -31.56979)
					(end 102.7557 -31.4706)
				)
			)
		)
		(polygon
			(pts
				(arc
					(start 100.3427 -31.2166)
					(mid 100.297319 -31.107041)
					(end 100.18776 -31.06166)
				)
				(arc
					(start 99.98456 -31.06166)
					(mid 99.875001 -31.107041)
					(end 99.82962 -31.2166)
				)
				(arc
					(start 99.82962 -31.4706)
					(mid 99.865532 -31.56979)
					(end 99.95662 -31.623)
				)
				(arc
					(start 99.95662 -31.623)
					(mid 99.865532 -31.67621)
					(end 99.82962 -31.7754)
				)
				(arc
					(start 99.82962 -32.0294)
					(mid 99.875001 -32.138959)
					(end 99.98456 -32.18434)
				)
				(arc
					(start 100.18776 -32.18434)
					(mid 100.297319 -32.138959)
					(end 100.3427 -32.0294)
				)
				(arc
					(start 100.3427 -31.7754)
					(mid 100.306788 -31.67621)
					(end 100.2157 -31.623)
				)
				(arc
					(start 100.2157 -31.623)
					(mid 100.306788 -31.56979)
					(end 100.3427 -31.4706)
				)
			)
		)
		(polygon
			(pts
				(arc
					(start 99.7077 -31.2166)
					(mid 99.662319 -31.107041)
					(end 99.55276 -31.06166)
				)
				(arc
					(start 99.34956 -31.06166)
					(mid 99.240001 -31.107041)
					(end 99.19462 -31.2166)
				)
				(arc
					(start 99.19462 -31.4706)
					(mid 99.230532 -31.56979)
					(end 99.32162 -31.623)
				)
				(arc
					(start 99.32162 -31.623)
					(mid 99.230532 -31.67621)
					(end 99.19462 -31.7754)
				)
				(arc
					(start 99.19462 -32.0294)
					(mid 99.240001 -32.138959)
					(end 99.34956 -32.18434)
				)
				(arc
					(start 99.55276 -32.18434)
					(mid 99.662319 -32.138959)
					(end 99.7077 -32.0294)
				)
				(arc
					(start 99.7077 -31.7754)
					(mid 99.671788 -31.67621)
					(end 99.5807 -31.623)
				)
				(arc
					(start 99.5807 -31.623)
					(mid 99.671788 -31.56979)
					(end 99.7077 -31.4706)
				)
			)
		)
		(polygon
			(pts
				(arc
					(start 98.8187 -31.2166)
					(mid 98.773319 -31.107041)
					(end 98.66376 -31.06166)
				)
				(arc
					(start 98.46056 -31.06166)
					(mid 98.351001 -31.107041)
					(end 98.30562 -31.2166)
				)
				(arc
					(start 98.30562 -31.4706)
					(mid 98.341532 -31.56979)
					(end 98.43262 -31.623)
				)
				(arc
					(start 98.43262 -31.623)
					(mid 98.341532 -31.67621)
					(end 98.30562 -31.7754)
				)
				(arc
					(start 98.30562 -32.0294)
					(mid 98.351001 -32.138959)
					(end 98.46056 -32.18434)
				)
				(arc
					(start 98.66376 -32.18434)
					(mid 98.773319 -32.138959)
					(end 98.8187 -32.0294)
				)
				(arc
					(start 98.8187 -31.7754)
					(mid 98.782788 -31.67621)
					(end 98.6917 -31.623)
				)
				(arc
					(start 98.6917 -31.623)
					(mid 98.782788 -31.56979)
					(end 98.8187 -31.4706)
				)
			)
		)
		(polygon
			(pts
				(arc
					(start 98.1837 -31.2166)
					(mid 98.138319 -31.107041)
					(end 98.02876 -31.06166)
				)
				(arc
					(start 97.82556 -31.06166)
					(mid 97.716001 -31.107041)
					(end 97.67062 -31.2166)
				)
				(arc
					(start 97.67062 -31.4706)
					(mid 97.706532 -31.56979)
					(end 97.79762 -31.623)
				)
				(arc
					(start 97.79762 -31.623)
					(mid 97.706532 -31.67621)
					(end 97.67062 -31.7754)
				)
				(arc
					(start 97.67062 -32.0294)
					(mid 97.716001 -32.138959)
					(end 97.82556 -32.18434)
				)
				(arc
					(start 98.02876 -32.18434)
					(mid 98.138319 -32.138959)
					(end 98.1837 -32.0294)
				)
				(arc
					(start 98.1837 -31.7754)
					(mid 98.147788 -31.67621)
					(end 98.0567 -31.623)
				)
				(arc
					(start 98.0567 -31.623)
					(mid 98.147788 -31.56979)
					(end 98.1837 -31.4706)
				)
			)
		)
		(polygon
			(pts
				(arc
					(start 97.2947 -31.2166)
					(mid 97.249319 -31.107041)
					(end 97.13976 -31.06166)
				)
				(arc
					(start 96.93656 -31.06166)
					(mid 96.827001 -31.107041)
					(end 96.78162 -31.2166)
				)
				(arc
					(start 96.78162 -31.4706)
					(mid 96.817532 -31.56979)
					(end 96.90862 -31.623)
				)
				(arc
					(start 96.90862 -31.623)
					(mid 96.817532 -31.67621)
					(end 96.78162 -31.7754)
				)
				(arc
					(start 96.78162 -32.0294)
					(mid 96.827001 -32.138959)
					(end 96.93656 -32.18434)
				)
				(arc
					(start 97.13976 -32.18434)
					(mid 97.249319 -32.138959)
					(end 97.2947 -32.0294)
				)
				(arc
					(start 97.2947 -31.7754)
					(mid 97.258788 -31.67621)
					(end 97.1677 -31.623)
				)
				(arc
					(start 97.1677 -31.623)
					(mid 97.258788 -31.56979)
					(end 97.2947 -31.4706)
				)
			)
		)
		(polygon
			(pts
				(arc
					(start 96.6597 -31.2166)
					(mid 96.614319 -31.107041)
					(end 96.50476 -31.06166)
				)
				(arc
					(start 96.30156 -31.06166)
					(mid 96.192001 -31.107041)
					(end 96.14662 -31.2166)
				)
				(arc
					(start 96.14662 -31.4706)
					(mid 96.182532 -31.56979)
					(end 96.27362 -31.623)
				)
				(arc
					(start 96.27362 -31.623)
					(mid 96.182532 -31.67621)
					(end 96.14662 -31.7754)
				)
				(arc
					(start 96.14662 -32.0294)
					(mid 96.192001 -32.138959)
					(end 96.30156 -32.18434)
				)
				(arc
					(start 96.50476 -32.18434)
					(mid 96.614319 -32.138959)
					(end 96.6597 -32.0294)
				)
				(arc
					(start 96.6597 -31.7754)
					(mid 96.623788 -31.67621)
					(end 96.5327 -31.623)
				)
				(arc
					(start 96.5327 -31.623)
					(mid 96.623788 -31.56979)
					(end 96.6597 -31.4706)
				)
			)
		)
		(polygon
			(pts
				(arc
					(start 95.7707 -31.2166)
					(mid 95.725319 -31.107041)
					(end 95.61576 -31.06166)
				)
				(arc
					(start 95.41256 -31.06166)
					(mid 95.303001 -31.107041)
					(end 95.25762 -31.2166)
				)
				(arc
					(start 95.25762 -31.4706)
					(mid 95.293532 -31.56979)
					(end 95.38462 -31.623)
				)
				(arc
					(start 95.38462 -31.623)
					(mid 95.293532 -31.67621)
					(end 95.25762 -31.7754)
				)
				(arc
					(start 95.25762 -32.0294)
					(mid 95.303001 -32.138959)
					(end 95.41256 -32.18434)
				)
				(arc
					(start 95.61576 -32.18434)
					(mid 95.725319 -32.138959)
					(end 95.7707 -32.0294)
				)
				(arc
					(start 95.7707 -31.7754)
					(mid 95.734788 -31.67621)
					(end 95.6437 -31.623)
				)
				(arc
					(start 95.6437 -31.623)
					(mid 95.734788 -31.56979)
					(end 95.7707 -31.4706)
				)
			)
		)
		(polygon
			(pts
				(arc
					(start 95.1357 -31.2166)
					(mid 95.090319 -31.107041)
					(end 94.98076 -31.06166)
				)
				(arc
					(start 94.77756 -31.06166)
					(mid 94.668001 -31.107041)
					(end 94.62262 -31.2166)
				)
				(arc
					(start 94.62262 -31.4706)
					(mid 94.658532 -31.56979)
					(end 94.74962 -31.623)
				)
				(arc
					(start 94.74962 -31.623)
					(mid 94.658532 -31.67621)
					(end 94.62262 -31.7754)
				)
				(arc
					(start 94.62262 -32.0294)
					(mid 94.668001 -32.138959)
					(end 94.77756 -32.18434)
				)
				(arc
					(start 94.98076 -32.18434)
					(mid 95.090319 -32.138959)
					(end 95.1357 -32.0294)
				)
				(arc
					(start 95.1357 -31.7754)
					(mid 95.099788 -31.67621)
					(end 95.0087 -31.623)
				)
				(arc
					(start 95.0087 -31.623)
					(mid 95.099788 -31.56979)
					(end 95.1357 -31.4706)
				)
			)
		)
		(polygon
			(pts
				(arc
					(start 94.2467 -31.2166)
					(mid 94.201319 -31.107041)
					(end 94.09176 -31.06166)
				)
				(arc
					(start 93.88856 -31.06166)
					(mid 93.779001 -31.107041)
					(end 93.73362 -31.2166)
				)
				(arc
					(start 93.73362 -31.4706)
					(mid 93.769532 -31.56979)
					(end 93.86062 -31.623)
				)
				(arc
					(start 93.86062 -31.623)
					(mid 93.769532 -31.67621)
					(end 93.73362 -31.7754)
				)
				(arc
					(start 93.73362 -32.0294)
					(mid 93.779001 -32.138959)
					(end 93.88856 -32.18434)
				)
				(arc
					(start 94.09176 -32.18434)
					(mid 94.201319 -32.138959)
					(end 94.2467 -32.0294)
				)
				(arc
					(start 94.2467 -31.7754)
					(mid 94.210788 -31.67621)
					(end 94.1197 -31.623)
				)
				(arc
					(start 94.1197 -31.623)
					(mid 94.210788 -31.56979)
					(end 94.2467 -31.4706)
				)
			)
		)
		(polygon
			(pts
				(arc
					(start 93.6117 -31.2166)
					(mid 93.566319 -31.107041)
					(end 93.45676 -31.06166)
				)
				(arc
					(start 93.25356 -31.06166)
					(mid 93.144001 -31.107041)
					(end 93.09862 -31.2166)
				)
				(arc
					(start 93.09862 -31.4706)
					(mid 93.134532 -31.56979)
					(end 93.22562 -31.623)
				)
				(arc
					(start 93.22562 -31.623)
					(mid 93.134532 -31.67621)
					(end 93.09862 -31.7754)
				)
				(arc
					(start 93.09862 -32.0294)
					(mid 93.144001 -32.138959)
					(end 93.25356 -32.18434)
				)
				(arc
					(start 93.45676 -32.18434)
					(mid 93.566319 -32.138959)
					(end 93.6117 -32.0294)
				)
				(arc
					(start 93.6117 -31.7754)
					(mid 93.575788 -31.67621)
					(end 93.4847 -31.623)
				)
				(arc
					(start 93.4847 -31.623)
					(mid 93.575788 -31.56979)
					(end 93.6117 -31.4706)
				)
			)
		)
		(polygon
			(pts
				(arc
					(start 272.999962 -11.779758)
					(mid 273.789902 -10.989818)
					(end 272.999962 -10.199878)
				)
				(arc
					(start 270.999966 -10.199878)
					(mid 270.210026 -10.989818)
					(end 270.999966 -11.779758)
				)
			)
		)
		(polygon
			(pts
				(arc
					(start 107.54995 -5.324348)
					(mid 107.54995 -6.675628)
					(end 107.54995 -5.324348)
				)
			)
		)
		(polygon
			(pts
				(arc
					(start 104.950006 -5.324348)
					(mid 104.950006 -6.675628)
					(end 104.950006 -5.324348)
				)
			)
		)
		(polygon
			(pts
				(arc
					(start 102.350062 -5.324348)
					(mid 102.350062 -6.675628)
					(end 102.350062 -5.324348)
				)
			)
		)
	)
	(zone
		(layer "In6.Cu")
		(hatch none 0.5)
		(connect_pads
			(clearance 0)
		)
		(min_thickness 0.25)
		(keepout
			(tracks not_allowed)
			(vias allowed)
			(pads allowed)
			(copperpour not_allowed)
			(footprints allowed)
		)
		(placement
			(enabled no)
			(sheetname "")
		)
		(fill
			(thermal_gap 0.5)
			(thermal_bridge_width 0.5)
			(island_removal_mode 0)
		)
		(polygon
			(pts
				(arc
					(start 109.928152 -221.3864)
					(mid 109.867892 -221.24092)
					(end 109.722412 -221.18066)
				)
				(arc
					(start 109.366812 -221.18066)
					(mid 109.221332 -221.24092)
					(end 109.161072 -221.3864)
				)
				(arc
					(start 109.161072 -221.742)
					(mid 109.221332 -221.88748)
					(end 109.366812 -221.94774)
				)
				(arc
					(start 109.722412 -221.94774)
					(mid 109.867892 -221.88748)
					(end 109.928152 -221.742)
				)
			)
		)
	)
	(zone
		(layer "In6.Cu")
		(hatch none 0.5)
		(connect_pads
			(clearance 0)
		)
		(min_thickness 0.25)
		(keepout
			(tracks not_allowed)
			(vias allowed)
			(pads allowed)
			(copperpour not_allowed)
			(footprints allowed)
		)
		(placement
			(enabled no)
			(sheetname "")
		)
		(fill
			(thermal_gap 0.5)
			(thermal_bridge_width 0.5)
			(island_removal_mode 0)
		)
		(polygon
			(pts
				(arc
					(start 111.579152 -221.3864)
					(mid 111.518892 -221.24092)
					(end 111.373412 -221.18066)
				)
				(arc
					(start 111.017812 -221.18066)
					(mid 110.872332 -221.24092)
					(end 110.812072 -221.3864)
				)
				(arc
					(start 110.812072 -221.742)
					(mid 110.872332 -221.88748)
					(end 111.017812 -221.94774)
				)
				(arc
					(start 111.373412 -221.94774)
					(mid 111.518892 -221.88748)
					(end 111.579152 -221.742)
				)
			)
		)
	)
	(zone
		(layer "In6.Cu")
		(hatch none 0.5)
		(connect_pads
			(clearance 0)
		)
		(min_thickness 0.25)
		(keepout
			(tracks not_allowed)
			(vias allowed)
			(pads allowed)
			(copperpour not_allowed)
			(footprints allowed)
		)
		(placement
			(enabled no)
			(sheetname "")
		)
		(fill
			(thermal_gap 0.5)
			(thermal_bridge_width 0.5)
			(island_removal_mode 0)
		)
		(polygon
			(pts
				(arc
					(start 99.55276 -32.18434)
					(mid 99.662319 -32.138959)
					(end 99.7077 -32.0294)
				)
				(arc
					(start 99.7077 -31.7754)
					(mid 99.662319 -31.665841)
					(end 99.55276 -31.62046)
				)
				(arc
					(start 99.34956 -31.62046)
					(mid 99.240001 -31.665841)
					(end 99.19462 -31.7754)
				)
				(arc
					(start 99.19462 -32.0294)
					(mid 99.240001 -32.138959)
					(end 99.34956 -32.18434)
				)
			)
		)
	)
	(zone
		(layer "In6.Cu")
		(hatch none 0.5)
		(connect_pads
			(clearance 0)
		)
		(min_thickness 0.25)
		(keepout
			(tracks not_allowed)
			(vias allowed)
			(pads allowed)
			(copperpour not_allowed)
			(footprints allowed)
		)
		(placement
			(enabled no)
			(sheetname "")
		)
		(fill
			(thermal_gap 0.5)
			(thermal_bridge_width 0.5)
			(island_removal_mode 0)
		)
		(polygon
			(pts
				(arc
					(start 117.162072 -204.724)
					(mid 117.222332 -204.86948)
					(end 117.367812 -204.92974)
				)
				(arc
					(start 117.723412 -204.92974)
					(mid 117.868892 -204.86948)
					(end 117.929152 -204.724)
				)
				(arc
					(start 117.929152 -204.3684)
					(mid 117.868892 -204.22292)
					(end 117.723412 -204.16266)
				)
				(arc
					(start 117.367812 -204.16266)
					(mid 117.222332 -204.22292)
					(end 117.162072 -204.3684)
				)
			)
		)
	)
	(zone
		(layer "In6.Cu")
		(hatch none 0.5)
		(connect_pads
			(clearance 0)
		)
		(min_thickness 0.25)
		(keepout
			(tracks not_allowed)
			(vias allowed)
			(pads allowed)
			(copperpour not_allowed)
			(footprints allowed)
		)
		(placement
			(enabled no)
			(sheetname "")
		)
		(fill
			(thermal_gap 0.5)
			(thermal_bridge_width 0.5)
			(island_removal_mode 0)
		)
		(polygon
			(pts
				(arc
					(start 115.511072 -204.724)
					(mid 115.571332 -204.86948)
					(end 115.716812 -204.92974)
				)
				(arc
					(start 116.072412 -204.92974)
					(mid 116.217892 -204.86948)
					(end 116.278152 -204.724)
				)
				(arc
					(start 116.278152 -204.3684)
					(mid 116.217892 -204.22292)
					(end 116.072412 -204.16266)
				)
				(arc
					(start 115.716812 -204.16266)
					(mid 115.571332 -204.22292)
					(end 115.511072 -204.3684)
				)
			)
		)
	)
	(zone
		(layer "In6.Cu")
		(hatch none 0.5)
		(connect_pads
			(clearance 0)
		)
		(min_thickness 0.25)
		(keepout
			(tracks not_allowed)
			(vias allowed)
			(pads allowed)
			(copperpour not_allowed)
			(footprints allowed)
		)
		(placement
			(enabled no)
			(sheetname "")
		)
		(fill
			(thermal_gap 0.5)
			(thermal_bridge_width 0.5)
			(island_removal_mode 0)
		)
		(polygon
			(pts
				(arc
					(start 103.23576 -31.62554)
					(mid 103.345319 -31.580159)
					(end 103.3907 -31.4706)
				)
				(arc
					(start 103.3907 -31.2166)
					(mid 103.345319 -31.107041)
					(end 103.23576 -31.06166)
				)
				(arc
					(start 103.03256 -31.06166)
					(mid 102.923001 -31.107041)
					(end 102.87762 -31.2166)
				)
				(arc
					(start 102.87762 -31.4706)
					(mid 102.923001 -31.580159)
					(end 103.03256 -31.62554)
				)
			)
		)
	)
	(zone
		(layer "In6.Cu")
		(hatch none 0.5)
		(connect_pads
			(clearance 0)
		)
		(min_thickness 0.25)
		(keepout
			(tracks not_allowed)
			(vias allowed)
			(pads allowed)
			(copperpour not_allowed)
			(footprints allowed)
		)
		(placement
			(enabled no)
			(sheetname "")
		)
		(fill
			(thermal_gap 0.5)
			(thermal_bridge_width 0.5)
			(island_removal_mode 0)
		)
		(polygon
			(pts
				(arc
					(start 99.55276 -31.62554)
					(mid 99.662319 -31.580159)
					(end 99.7077 -31.4706)
				)
				(arc
					(start 99.7077 -31.2166)
					(mid 99.662319 -31.107041)
					(end 99.55276 -31.06166)
				)
				(arc
					(start 99.34956 -31.06166)
					(mid 99.240001 -31.107041)
					(end 99.19462 -31.2166)
				)
				(arc
					(start 99.19462 -31.4706)
					(mid 99.240001 -31.580159)
					(end 99.34956 -31.62554)
				)
			)
		)
	)
	(zone
		(layer "In6.Cu")
		(hatch none 0.5)
		(connect_pads
			(clearance 0)
		)
		(min_thickness 0.25)
		(keepout
			(tracks not_allowed)
			(vias allowed)
			(pads allowed)
			(copperpour not_allowed)
			(footprints allowed)
		)
		(placement
			(enabled no)
			(sheetname "")
		)
		(fill
			(thermal_gap 0.5)
			(thermal_bridge_width 0.5)
			(island_removal_mode 0)
		)
		(polygon
			(pts
				(arc
					(start 170.031156 -78.540356)
					(mid 169.740072 -77.66812)
					(end 168.867836 -77.959204)
				)
				(xy 168.86555 -77.957934) (xy 167.86606 -79.958184)
				(arc
					(start 167.868346 -79.959454)
					(mid 168.15943 -80.83169)
					(end 169.031666 -80.540606)
				)
				(xy 169.033952 -80.541876) (xy 170.033442 -78.54188) (xy 170.033188 -78.541372)
			)
		)
	)
	(zone
		(layer "In6.Cu")
		(hatch none 0.5)
		(connect_pads
			(clearance 0)
		)
		(min_thickness 0.25)
		(keepout
			(tracks not_allowed)
			(vias allowed)
			(pads allowed)
			(copperpour not_allowed)
			(footprints allowed)
		)
		(placement
			(enabled no)
			(sheetname "")
		)
		(fill
			(thermal_gap 0.5)
			(thermal_bridge_width 0.5)
			(island_removal_mode 0)
		)
		(polygon
			(pts
				(arc
					(start 51.96713 -77.627226)
					(mid 52.11261 -77.566966)
					(end 52.17287 -77.421486)
				)
				(arc
					(start 52.17287 -77.015086)
					(mid 52.11261 -76.869606)
					(end 51.96713 -76.809346)
				)
				(arc
					(start 51.56073 -76.809346)
					(mid 51.41525 -76.869606)
					(end 51.35499 -77.015086)
				)
				(arc
					(start 51.35499 -77.421486)
					(mid 51.41525 -77.566966)
					(end 51.56073 -77.627226)
				)
			)
		)
	)
	(zone
		(layer "In6.Cu")
		(hatch none 0.5)
		(connect_pads
			(clearance 0)
		)
		(min_thickness 0.25)
		(keepout
			(tracks not_allowed)
			(vias allowed)
			(pads allowed)
			(copperpour not_allowed)
			(footprints allowed)
		)
		(placement
			(enabled no)
			(sheetname "")
		)
		(fill
			(thermal_gap 0.5)
			(thermal_bridge_width 0.5)
			(island_removal_mode 0)
		)
		(polygon
			(pts
				(arc
					(start 117.421152 -221.3864)
					(mid 117.360892 -221.24092)
					(end 117.215412 -221.18066)
				)
				(arc
					(start 116.859812 -221.18066)
					(mid 116.714332 -221.24092)
					(end 116.654072 -221.3864)
				)
				(arc
					(start 116.654072 -221.742)
					(mid 116.714332 -221.88748)
					(end 116.859812 -221.94774)
				)
				(arc
					(start 117.215412 -221.94774)
					(mid 117.360892 -221.88748)
					(end 117.421152 -221.742)
				)
			)
		)
	)
	(zone
		(layer "In6.Cu")
		(hatch none 0.5)
		(connect_pads
			(clearance 0)
		)
		(min_thickness 0.25)
		(keepout
			(tracks not_allowed)
			(vias allowed)
			(pads allowed)
			(copperpour not_allowed)
			(footprints allowed)
		)
		(placement
			(enabled no)
			(sheetname "")
		)
		(fill
			(thermal_gap 0.5)
			(thermal_bridge_width 0.5)
			(island_removal_mode 0)
		)
		(polygon
			(pts
				(arc
					(start 44.72813 -77.601826)
					(mid 44.87361 -77.541566)
					(end 44.93387 -77.396086)
				)
				(arc
					(start 44.93387 -76.989686)
					(mid 44.87361 -76.844206)
					(end 44.72813 -76.783946)
				)
				(arc
					(start 44.32173 -76.783946)
					(mid 44.17625 -76.844206)
					(end 44.11599 -76.989686)
				)
				(arc
					(start 44.11599 -77.396086)
					(mid 44.17625 -77.541566)
					(end 44.32173 -77.601826)
				)
			)
		)
	)
	(zone
		(layer "In6.Cu")
		(hatch none 0.5)
		(connect_pads
			(clearance 0)
		)
		(min_thickness 0.25)
		(keepout
			(tracks not_allowed)
			(vias allowed)
			(pads allowed)
			(copperpour not_allowed)
			(footprints allowed)
		)
		(placement
			(enabled no)
			(sheetname "")
		)
		(fill
			(thermal_gap 0.5)
			(thermal_bridge_width 0.5)
			(island_removal_mode 0)
		)
		(polygon
			(pts
				(arc
					(start 110.812072 -223.4946)
					(mid 110.872332 -223.64008)
					(end 111.017812 -223.70034)
				)
				(arc
					(start 111.373412 -223.70034)
					(mid 111.518892 -223.64008)
					(end 111.579152 -223.4946)
				)
				(arc
					(start 111.579152 -223.139)
					(mid 111.518892 -222.99352)
					(end 111.373412 -222.93326)
				)
				(arc
					(start 111.017812 -222.93326)
					(mid 110.872332 -222.99352)
					(end 110.812072 -223.139)
				)
			)
		)
	)
	(zone
		(layer "In6.Cu")
		(hatch none 0.5)
		(connect_pads
			(clearance 0)
		)
		(min_thickness 0.25)
		(keepout
			(tracks not_allowed)
			(vias allowed)
			(pads allowed)
			(copperpour not_allowed)
			(footprints allowed)
		)
		(placement
			(enabled no)
			(sheetname "")
		)
		(fill
			(thermal_gap 0.5)
			(thermal_bridge_width 0.5)
			(island_removal_mode 0)
		)
		(polygon
			(pts
				(arc
					(start 11.373104 -100.352606)
					(mid 11.518584 -100.292346)
					(end 11.578844 -100.146866)
				)
				(arc
					(start 11.578844 -99.740466)
					(mid 11.518584 -99.594986)
					(end 11.373104 -99.534726)
				)
				(arc
					(start 10.966704 -99.534726)
					(mid 10.821224 -99.594986)
					(end 10.760964 -99.740466)
				)
				(arc
					(start 10.760964 -100.146866)
					(mid 10.821224 -100.292346)
					(end 10.966704 -100.352606)
				)
			)
		)
	)
	(zone
		(layer "In6.Cu")
		(hatch none 0.5)
		(connect_pads
			(clearance 0)
		)
		(min_thickness 0.25)
		(keepout
			(tracks not_allowed)
			(vias allowed)
			(pads allowed)
			(copperpour not_allowed)
			(footprints allowed)
		)
		(placement
			(enabled no)
			(sheetname "")
		)
		(fill
			(thermal_gap 0.5)
			(thermal_bridge_width 0.5)
			(island_removal_mode 0)
		)
		(polygon
			(pts
				(arc
					(start 341.151718 -135.920988)
					(mid 341.297198 -135.860728)
					(end 341.357458 -135.715248)
				)
				(arc
					(start 341.357458 -135.054848)
					(mid 341.297198 -134.909368)
					(end 341.151718 -134.849108)
				)
				(arc
					(start 340.491318 -134.849108)
					(mid 340.345838 -134.909368)
					(end 340.285578 -135.054848)
				)
				(arc
					(start 340.285578 -135.715248)
					(mid 340.345838 -135.860728)
					(end 340.491318 -135.920988)
				)
			)
		)
	)
	(zone
		(layer "In6.Cu")
		(hatch none 0.5)
		(connect_pads
			(clearance 0)
		)
		(min_thickness 0.25)
		(keepout
			(tracks not_allowed)
			(vias allowed)
			(pads allowed)
			(copperpour not_allowed)
			(footprints allowed)
		)
		(placement
			(enabled no)
			(sheetname "")
		)
		(fill
			(thermal_gap 0.5)
			(thermal_bridge_width 0.5)
			(island_removal_mode 0)
		)
		(polygon
			(pts
				(arc
					(start 19.374104 -101.267006)
					(mid 19.519584 -101.206746)
					(end 19.579844 -101.061266)
				)
				(arc
					(start 19.579844 -100.654866)
					(mid 19.519584 -100.509386)
					(end 19.374104 -100.449126)
				)
				(arc
					(start 18.967704 -100.449126)
					(mid 18.822224 -100.509386)
					(end 18.761964 -100.654866)
				)
				(arc
					(start 18.761964 -101.061266)
					(mid 18.822224 -101.206746)
					(end 18.967704 -101.267006)
				)
			)
		)
	)
	(zone
		(layer "In6.Cu")
		(hatch none 0.5)
		(connect_pads
			(clearance 0)
		)
		(min_thickness 0.25)
		(keepout
			(tracks not_allowed)
			(vias allowed)
			(pads allowed)
			(copperpour not_allowed)
			(footprints allowed)
		)
		(placement
			(enabled no)
			(sheetname "")
		)
		(fill
			(thermal_gap 0.5)
			(thermal_bridge_width 0.5)
			(island_removal_mode 0)
		)
		(polygon
			(pts
				(arc
					(start 118.305072 -223.4946)
					(mid 118.365332 -223.64008)
					(end 118.510812 -223.70034)
				)
				(arc
					(start 118.866412 -223.70034)
					(mid 119.011892 -223.64008)
					(end 119.072152 -223.4946)
				)
				(arc
					(start 119.072152 -223.139)
					(mid 119.011892 -222.99352)
					(end 118.866412 -222.93326)
				)
				(arc
					(start 118.510812 -222.93326)
					(mid 118.365332 -222.99352)
					(end 118.305072 -223.139)
				)
			)
		)
	)
	(zone
		(layer "In6.Cu")
		(hatch none 0.5)
		(connect_pads
			(clearance 0)
		)
		(min_thickness 0.25)
		(keepout
			(tracks not_allowed)
			(vias allowed)
			(pads allowed)
			(copperpour not_allowed)
			(footprints allowed)
		)
		(placement
			(enabled no)
			(sheetname "")
		)
		(fill
			(thermal_gap 0.5)
			(thermal_bridge_width 0.5)
			(island_removal_mode 0)
		)
		(polygon
			(pts
				(arc
					(start 108.404152 -206.121)
					(mid 108.343892 -205.97552)
					(end 108.198412 -205.91526)
				)
				(arc
					(start 107.842812 -205.91526)
					(mid 107.697332 -205.97552)
					(end 107.637072 -206.121)
				)
				(arc
					(start 107.637072 -206.4766)
					(mid 107.697332 -206.62208)
					(end 107.842812 -206.68234)
				)
				(arc
					(start 108.198412 -206.68234)
					(mid 108.343892 -206.62208)
					(end 108.404152 -206.4766)
				)
			)
		)
	)
	(zone
		(layer "In6.Cu")
		(hatch none 0.5)
		(connect_pads
			(clearance 0)
		)
		(min_thickness 0.25)
		(keepout
			(tracks not_allowed)
			(vias allowed)
			(pads allowed)
			(copperpour not_allowed)
			(footprints allowed)
		)
		(placement
			(enabled no)
			(sheetname "")
		)
		(fill
			(thermal_gap 0.5)
			(thermal_bridge_width 0.5)
			(island_removal_mode 0)
		)
		(polygon
			(pts
				(arc
					(start 195.031106 -73.45934)
					(mid 194.158768 -73.168942)
					(end 193.86804 -74.041254)
				)
				(xy 193.865754 -74.04227) (xy 194.866514 -76.04252)
				(arc
					(start 194.8688 -76.041504)
					(mid 195.74129 -76.331826)
					(end 196.031612 -75.459336)
				)
				(xy 196.033898 -75.45832) (xy 195.033392 -73.458324) (xy 195.032884 -73.458324)
			)
		)
	)
	(zone
		(layer "In6.Cu")
		(hatch none 0.5)
		(connect_pads
			(clearance 0)
		)
		(min_thickness 0.25)
		(keepout
			(tracks not_allowed)
			(vias allowed)
			(pads allowed)
			(copperpour not_allowed)
			(footprints allowed)
		)
		(placement
			(enabled no)
			(sheetname "")
		)
		(fill
			(thermal_gap 0.5)
			(thermal_bridge_width 0.5)
			(island_removal_mode 0)
		)
		(polygon
			(pts
				(arc
					(start 97.13976 -31.62554)
					(mid 97.249319 -31.580159)
					(end 97.2947 -31.4706)
				)
				(arc
					(start 97.2947 -31.2166)
					(mid 97.249319 -31.107041)
					(end 97.13976 -31.06166)
				)
				(arc
					(start 96.93656 -31.06166)
					(mid 96.827001 -31.107041)
					(end 96.78162 -31.2166)
				)
				(arc
					(start 96.78162 -31.4706)
					(mid 96.827001 -31.580159)
					(end 96.93656 -31.62554)
				)
			)
		)
	)
	(zone
		(layer "In6.Cu")
		(hatch none 0.5)
		(connect_pads
			(clearance 0)
		)
		(min_thickness 0.25)
		(keepout
			(tracks not_allowed)
			(vias allowed)
			(pads allowed)
			(copperpour not_allowed)
			(footprints allowed)
		)
		(placement
			(enabled no)
			(sheetname "")
		)
		(fill
			(thermal_gap 0.5)
			(thermal_bridge_width 0.5)
			(island_removal_mode 0)
		)
		(polygon
			(pts
				(arc
					(start 101.71176 -31.642558)
					(mid 101.821319 -31.597177)
					(end 101.8667 -31.487618)
				)
				(arc
					(start 101.8667 -31.233618)
					(mid 101.821319 -31.124059)
					(end 101.71176 -31.078678)
				)
				(arc
					(start 101.50856 -31.078678)
					(mid 101.399001 -31.124059)
					(end 101.35362 -31.233618)
				)
				(arc
					(start 101.35362 -31.487618)
					(mid 101.399001 -31.597177)
					(end 101.50856 -31.642558)
				)
			)
		)
	)
	(zone
		(layer "In6.Cu")
		(hatch none 0.5)
		(connect_pads
			(clearance 0)
		)
		(min_thickness 0.25)
		(keepout
			(tracks not_allowed)
			(vias allowed)
			(pads allowed)
			(copperpour not_allowed)
			(footprints allowed)
		)
		(placement
			(enabled no)
			(sheetname "")
		)
		(fill
			(thermal_gap 0.5)
			(thermal_bridge_width 0.5)
			(island_removal_mode 0)
		)
		(polygon
			(pts
				(arc
					(start 51.07813 -76.712826)
					(mid 51.22361 -76.652566)
					(end 51.28387 -76.507086)
				)
				(arc
					(start 51.28387 -76.100686)
					(mid 51.22361 -75.955206)
					(end 51.07813 -75.894946)
				)
				(arc
					(start 50.67173 -75.894946)
					(mid 50.52625 -75.955206)
					(end 50.46599 -76.100686)
				)
				(arc
					(start 50.46599 -76.507086)
					(mid 50.52625 -76.652566)
					(end 50.67173 -76.712826)
				)
			)
		)
	)
	(zone
		(layer "In6.Cu")
		(hatch none 0.5)
		(connect_pads
			(clearance 0)
		)
		(min_thickness 0.25)
		(keepout
			(tracks not_allowed)
			(vias allowed)
			(pads allowed)
			(copperpour not_allowed)
			(footprints allowed)
		)
		(placement
			(enabled no)
			(sheetname "")
		)
		(fill
			(thermal_gap 0.5)
			(thermal_bridge_width 0.5)
			(island_removal_mode 0)
		)
		(polygon
			(pts
				(arc
					(start 43.33113 -78.516226)
					(mid 43.47661 -78.455966)
					(end 43.53687 -78.310486)
				)
				(arc
					(start 43.53687 -77.904086)
					(mid 43.47661 -77.758606)
					(end 43.33113 -77.698346)
				)
				(arc
					(start 42.92473 -77.698346)
					(mid 42.77925 -77.758606)
					(end 42.71899 -77.904086)
				)
				(arc
					(start 42.71899 -78.310486)
					(mid 42.77925 -78.455966)
					(end 42.92473 -78.516226)
				)
			)
		)
	)
	(zone
		(layer "In6.Cu")
		(hatch none 0.5)
		(connect_pads
			(clearance 0)
		)
		(min_thickness 0.25)
		(keepout
			(tracks not_allowed)
			(vias allowed)
			(pads allowed)
			(copperpour not_allowed)
			(footprints allowed)
		)
		(placement
			(enabled no)
			(sheetname "")
		)
		(fill
			(thermal_gap 0.5)
			(thermal_bridge_width 0.5)
			(island_removal_mode 0)
		)
		(polygon
			(pts
				(arc
					(start 116.278152 -206.121)
					(mid 116.217892 -205.97552)
					(end 116.072412 -205.91526)
				)
				(arc
					(start 115.716812 -205.91526)
					(mid 115.571332 -205.97552)
					(end 115.511072 -206.121)
				)
				(arc
					(start 115.511072 -206.4766)
					(mid 115.571332 -206.62208)
					(end 115.716812 -206.68234)
				)
				(arc
					(start 116.072412 -206.68234)
					(mid 116.217892 -206.62208)
					(end 116.278152 -206.4766)
				)
			)
		)
	)
	(zone
		(layer "In6.Cu")
		(hatch none 0.5)
		(connect_pads
			(clearance 0)
		)
		(min_thickness 0.25)
		(keepout
			(tracks not_allowed)
			(vias allowed)
			(pads allowed)
			(copperpour not_allowed)
			(footprints allowed)
		)
		(placement
			(enabled no)
			(sheetname "")
		)
		(fill
			(thermal_gap 0.5)
			(thermal_bridge_width 0.5)
			(island_removal_mode 0)
		)
		(polygon
			(pts
				(arc
					(start 18.485104 -100.352606)
					(mid 18.630584 -100.292346)
					(end 18.690844 -100.146866)
				)
				(arc
					(start 18.690844 -99.740466)
					(mid 18.630584 -99.594986)
					(end 18.485104 -99.534726)
				)
				(arc
					(start 18.078704 -99.534726)
					(mid 17.933224 -99.594986)
					(end 17.872964 -99.740466)
				)
				(arc
					(start 17.872964 -100.146866)
					(mid 17.933224 -100.292346)
					(end 18.078704 -100.352606)
				)
			)
		)
	)
	(zone
		(layer "In6.Cu")
		(hatch none 0.5)
		(connect_pads
			(clearance 0)
		)
		(min_thickness 0.25)
		(keepout
			(tracks not_allowed)
			(vias allowed)
			(pads allowed)
			(copperpour not_allowed)
			(footprints allowed)
		)
		(placement
			(enabled no)
			(sheetname "")
		)
		(fill
			(thermal_gap 0.5)
			(thermal_bridge_width 0.5)
			(island_removal_mode 0)
		)
		(polygon
			(pts
				(arc
					(start 14.675104 -101.267006)
					(mid 14.820584 -101.206746)
					(end 14.880844 -101.061266)
				)
				(arc
					(start 14.880844 -100.654866)
					(mid 14.820584 -100.509386)
					(end 14.675104 -100.449126)
				)
				(arc
					(start 14.268704 -100.449126)
					(mid 14.123224 -100.509386)
					(end 14.062964 -100.654866)
				)
				(arc
					(start 14.062964 -101.061266)
					(mid 14.123224 -101.206746)
					(end 14.268704 -101.267006)
				)
			)
		)
	)
	(zone
		(layer "In6.Cu")
		(hatch none 0.5)
		(connect_pads
			(clearance 0)
		)
		(min_thickness 0.25)
		(keepout
			(tracks not_allowed)
			(vias allowed)
			(pads allowed)
			(copperpour not_allowed)
			(footprints allowed)
		)
		(placement
			(enabled no)
			(sheetname "")
		)
		(fill
			(thermal_gap 0.5)
			(thermal_bridge_width 0.5)
			(island_removal_mode 0)
		)
		(polygon
			(pts
				(arc
					(start 101.07676 -31.642558)
					(mid 101.186319 -31.597177)
					(end 101.2317 -31.487618)
				)
				(arc
					(start 101.2317 -31.233618)
					(mid 101.186319 -31.124059)
					(end 101.07676 -31.078678)
				)
				(arc
					(start 100.87356 -31.078678)
					(mid 100.764001 -31.124059)
					(end 100.71862 -31.233618)
				)
				(arc
					(start 100.71862 -31.487618)
					(mid 100.764001 -31.597177)
					(end 100.87356 -31.642558)
				)
			)
		)
	)
	(zone
		(layer "In6.Cu")
		(hatch none 0.5)
		(connect_pads
			(clearance 0)
		)
		(min_thickness 0.25)
		(keepout
			(tracks not_allowed)
			(vias allowed)
			(pads allowed)
			(copperpour not_allowed)
			(footprints allowed)
		)
		(placement
			(enabled no)
			(sheetname "")
		)
		(fill
			(thermal_gap 0.5)
			(thermal_bridge_width 0.5)
			(island_removal_mode 0)
		)
		(polygon
			(pts
				(arc
					(start 171.031916 -73.459594)
					(mid 170.15968 -73.16851)
					(end 169.868596 -74.040746)
				)
				(xy 169.86631 -74.042016) (xy 170.8658 -76.042266)
				(arc
					(start 170.868086 -76.040996)
					(mid 171.740322 -76.33208)
					(end 172.031406 -75.459844)
				)
				(xy 172.033692 -75.458574) (xy 171.034202 -73.458578) (xy 171.033948 -73.458578)
			)
		)
	)
	(zone
		(layer "In6.Cu")
		(hatch none 0.5)
		(connect_pads
			(clearance 0)
		)
		(min_thickness 0.25)
		(keepout
			(tracks not_allowed)
			(vias allowed)
			(pads allowed)
			(copperpour not_allowed)
			(footprints allowed)
		)
		(placement
			(enabled no)
			(sheetname "")
		)
		(fill
			(thermal_gap 0.5)
			(thermal_bridge_width 0.5)
			(island_removal_mode 0)
		)
		(polygon
			(pts
				(arc
					(start 117.929152 -205.2574)
					(mid 117.868892 -205.11192)
					(end 117.723412 -205.05166)
				)
				(arc
					(start 117.367812 -205.05166)
					(mid 117.222332 -205.11192)
					(end 117.162072 -205.2574)
				)
				(arc
					(start 117.162072 -205.613)
					(mid 117.222332 -205.75848)
					(end 117.367812 -205.81874)
				)
				(arc
					(start 117.723412 -205.81874)
					(mid 117.868892 -205.75848)
					(end 117.929152 -205.613)
				)
			)
		)
	)
	(zone
		(layer "In6.Cu")
		(hatch none 0.5)
		(connect_pads
			(clearance 0)
		)
		(min_thickness 0.25)
		(keepout
			(tracks not_allowed)
			(vias allowed)
			(pads allowed)
			(copperpour not_allowed)
			(footprints allowed)
		)
		(placement
			(enabled no)
			(sheetname "")
		)
		(fill
			(thermal_gap 0.5)
			(thermal_bridge_width 0.5)
			(island_removal_mode 0)
		)
		(polygon
			(pts
				(arc
					(start 45.74413 -77.601826)
					(mid 45.88961 -77.541566)
					(end 45.94987 -77.396086)
				)
				(arc
					(start 45.94987 -76.989686)
					(mid 45.88961 -76.844206)
					(end 45.74413 -76.783946)
				)
				(arc
					(start 45.33773 -76.783946)
					(mid 45.19225 -76.844206)
					(end 45.13199 -76.989686)
				)
				(arc
					(start 45.13199 -77.396086)
					(mid 45.19225 -77.541566)
					(end 45.33773 -77.601826)
				)
			)
		)
	)
	(zone
		(layer "In6.Cu")
		(hatch none 0.5)
		(connect_pads
			(clearance 0)
		)
		(min_thickness 0.25)
		(keepout
			(tracks not_allowed)
			(vias allowed)
			(pads allowed)
			(copperpour not_allowed)
			(footprints allowed)
		)
		(placement
			(enabled no)
			(sheetname "")
		)
		(fill
			(thermal_gap 0.5)
			(thermal_bridge_width 0.5)
			(island_removal_mode 0)
		)
		(polygon
			(pts
				(arc
					(start 341.888318 -134.849108)
					(mid 341.742838 -134.909368)
					(end 341.682578 -135.054848)
				)
				(arc
					(start 341.682578 -135.715248)
					(mid 341.742838 -135.860728)
					(end 341.888318 -135.920988)
				)
				(arc
					(start 342.548718 -135.920988)
					(mid 342.694198 -135.860728)
					(end 342.754458 -135.715248)
				)
				(arc
					(start 342.754458 -135.054848)
					(mid 342.694198 -134.909368)
					(end 342.548718 -134.849108)
				)
			)
		)
	)
	(zone
		(layer "In6.Cu")
		(hatch none 0.5)
		(connect_pads
			(clearance 0)
		)
		(min_thickness 0.25)
		(keepout
			(tracks not_allowed)
			(vias allowed)
			(pads allowed)
			(copperpour not_allowed)
			(footprints allowed)
		)
		(placement
			(enabled no)
			(sheetname "")
		)
		(fill
			(thermal_gap 0.5)
			(thermal_bridge_width 0.5)
			(island_removal_mode 0)
		)
		(polygon
			(pts
				(arc
					(start 96.50476 -32.18434)
					(mid 96.614319 -32.138959)
					(end 96.6597 -32.0294)
				)
				(arc
					(start 96.6597 -31.7754)
					(mid 96.614319 -31.665841)
					(end 96.50476 -31.62046)
				)
				(arc
					(start 96.30156 -31.62046)
					(mid 96.192001 -31.665841)
					(end 96.14662 -31.7754)
				)
				(arc
					(start 96.14662 -32.0294)
					(mid 96.192001 -32.138959)
					(end 96.30156 -32.18434)
				)
			)
		)
	)
	(zone
		(layer "In6.Cu")
		(hatch none 0.5)
		(connect_pads
			(clearance 0)
		)
		(min_thickness 0.25)
		(keepout
			(tracks not_allowed)
			(vias allowed)
			(pads allowed)
			(copperpour not_allowed)
			(footprints allowed)
		)
		(placement
			(enabled no)
			(sheetname "")
		)
		(fill
			(thermal_gap 0.5)
			(thermal_bridge_width 0.5)
			(island_removal_mode 0)
		)
		(polygon
			(pts
				(arc
					(start 110.812072 -222.631)
					(mid 110.872332 -222.77648)
					(end 111.017812 -222.83674)
				)
				(arc
					(start 111.373412 -222.83674)
					(mid 111.518892 -222.77648)
					(end 111.579152 -222.631)
				)
				(arc
					(start 111.579152 -222.2754)
					(mid 111.518892 -222.12992)
					(end 111.373412 -222.06966)
				)
				(arc
					(start 111.017812 -222.06966)
					(mid 110.872332 -222.12992)
					(end 110.812072 -222.2754)
				)
			)
		)
	)
	(zone
		(layer "In6.Cu")
		(hatch none 0.5)
		(connect_pads
			(clearance 0)
		)
		(min_thickness 0.25)
		(keepout
			(tracks not_allowed)
			(vias allowed)
			(pads allowed)
			(copperpour not_allowed)
			(footprints allowed)
		)
		(placement
			(enabled no)
			(sheetname "")
		)
		(fill
			(thermal_gap 0.5)
			(thermal_bridge_width 0.5)
			(island_removal_mode 0)
		)
		(polygon
			(pts
				(arc
					(start 191.031876 -73.459594)
					(mid 190.15964 -73.16851)
					(end 189.868556 -74.040746)
				)
				(xy 189.86627 -74.042016) (xy 190.86576 -76.042266)
				(arc
					(start 190.868046 -76.040996)
					(mid 191.740282 -76.33208)
					(end 192.031366 -75.459844)
				)
				(xy 192.033652 -75.458574) (xy 191.034162 -73.458578) (xy 191.033908 -73.458578)
			)
		)
	)
	(zone
		(layer "In6.Cu")
		(hatch none 0.5)
		(connect_pads
			(clearance 0)
		)
		(min_thickness 0.25)
		(keepout
			(tracks not_allowed)
			(vias allowed)
			(pads allowed)
			(copperpour not_allowed)
			(footprints allowed)
		)
		(placement
			(enabled no)
			(sheetname "")
		)
		(fill
			(thermal_gap 0.5)
			(thermal_bridge_width 0.5)
			(island_removal_mode 0)
		)
		(polygon
			(pts
				(arc
					(start 102.60076 -31.62554)
					(mid 102.710319 -31.580159)
					(end 102.7557 -31.4706)
				)
				(arc
					(start 102.7557 -31.2166)
					(mid 102.710319 -31.107041)
					(end 102.60076 -31.06166)
				)
				(arc
					(start 102.39756 -31.06166)
					(mid 102.288001 -31.107041)
					(end 102.24262 -31.2166)
				)
				(arc
					(start 102.24262 -31.4706)
					(mid 102.288001 -31.580159)
					(end 102.39756 -31.62554)
				)
			)
		)
	)
	(zone
		(layer "In6.Cu")
		(hatch none 0.5)
		(connect_pads
			(clearance 0)
		)
		(min_thickness 0.25)
		(keepout
			(tracks not_allowed)
			(vias allowed)
			(pads allowed)
			(copperpour not_allowed)
			(footprints allowed)
		)
		(placement
			(enabled no)
			(sheetname "")
		)
		(fill
			(thermal_gap 0.5)
			(thermal_bridge_width 0.5)
			(island_removal_mode 0)
		)
		(polygon
			(pts
				(arc
					(start 338.332318 -135.920988)
					(mid 338.477798 -135.860728)
					(end 338.538058 -135.715248)
				)
				(arc
					(start 338.538058 -135.054848)
					(mid 338.477798 -134.909368)
					(end 338.332318 -134.849108)
				)
				(arc
					(start 337.671918 -134.849108)
					(mid 337.526438 -134.909368)
					(end 337.466178 -135.054848)
				)
				(arc
					(start 337.466178 -135.715248)
					(mid 337.526438 -135.860728)
					(end 337.671918 -135.920988)
				)
			)
		)
	)
	(zone
		(layer "In6.Cu")
		(hatch none 0.5)
		(connect_pads
			(clearance 0)
		)
		(min_thickness 0.25)
		(keepout
			(tracks not_allowed)
			(vias allowed)
			(pads allowed)
			(copperpour not_allowed)
			(footprints allowed)
		)
		(placement
			(enabled no)
			(sheetname "")
		)
		(fill
			(thermal_gap 0.5)
			(thermal_bridge_width 0.5)
			(island_removal_mode 0)
		)
		(polygon
			(pts
				(arc
					(start 341.151718 -133.888988)
					(mid 341.297198 -133.828728)
					(end 341.357458 -133.683248)
				)
				(arc
					(start 341.357458 -133.022848)
					(mid 341.297198 -132.877368)
					(end 341.151718 -132.817108)
				)
				(arc
					(start 340.491318 -132.817108)
					(mid 340.345838 -132.877368)
					(end 340.285578 -133.022848)
				)
				(arc
					(start 340.285578 -133.683248)
					(mid 340.345838 -133.828728)
					(end 340.491318 -133.888988)
				)
			)
		)
	)
	(zone
		(layer "In6.Cu")
		(hatch none 0.5)
		(connect_pads
			(clearance 0)
		)
		(min_thickness 0.25)
		(keepout
			(tracks not_allowed)
			(vias allowed)
			(pads allowed)
			(copperpour not_allowed)
			(footprints allowed)
		)
		(placement
			(enabled no)
			(sheetname "")
		)
		(fill
			(thermal_gap 0.5)
			(thermal_bridge_width 0.5)
			(island_removal_mode 0)
		)
		(polygon
			(pts
				(arc
					(start 17.088104 -101.267006)
					(mid 17.233584 -101.206746)
					(end 17.293844 -101.061266)
				)
				(arc
					(start 17.293844 -100.654866)
					(mid 17.233584 -100.509386)
					(end 17.088104 -100.449126)
				)
				(arc
					(start 16.681704 -100.449126)
					(mid 16.536224 -100.509386)
					(end 16.475964 -100.654866)
				)
				(arc
					(start 16.475964 -101.061266)
					(mid 16.536224 -101.206746)
					(end 16.681704 -101.267006)
				)
			)
		)
	)
	(zone
		(layer "In6.Cu")
		(hatch none 0.5)
		(connect_pads
			(clearance 0)
		)
		(min_thickness 0.25)
		(keepout
			(tracks not_allowed)
			(vias allowed)
			(pads allowed)
			(copperpour not_allowed)
			(footprints allowed)
		)
		(placement
			(enabled no)
			(sheetname "")
		)
		(fill
			(thermal_gap 0.5)
			(thermal_bridge_width 0.5)
			(island_removal_mode 0)
		)
		(polygon
			(pts
				(arc
					(start 43.33113 -77.601826)
					(mid 43.47661 -77.541566)
					(end 43.53687 -77.396086)
				)
				(arc
					(start 43.53687 -76.989686)
					(mid 43.47661 -76.844206)
					(end 43.33113 -76.783946)
				)
				(arc
					(start 42.92473 -76.783946)
					(mid 42.77925 -76.844206)
					(end 42.71899 -76.989686)
				)
				(arc
					(start 42.71899 -77.396086)
					(mid 42.77925 -77.541566)
					(end 42.92473 -77.601826)
				)
			)
		)
	)
	(zone
		(layer "In6.Cu")
		(hatch none 0.5)
		(connect_pads
			(clearance 0)
		)
		(min_thickness 0.25)
		(keepout
			(tracks not_allowed)
			(vias allowed)
			(pads allowed)
			(copperpour not_allowed)
			(footprints allowed)
		)
		(placement
			(enabled no)
			(sheetname "")
		)
		(fill
			(thermal_gap 0.5)
			(thermal_bridge_width 0.5)
			(island_removal_mode 0)
		)
		(polygon
			(pts
				(arc
					(start 109.288072 -204.724)
					(mid 109.348332 -204.86948)
					(end 109.493812 -204.92974)
				)
				(arc
					(start 109.849412 -204.92974)
					(mid 109.994892 -204.86948)
					(end 110.055152 -204.724)
				)
				(arc
					(start 110.055152 -204.3684)
					(mid 109.994892 -204.22292)
					(end 109.849412 -204.16266)
				)
				(arc
					(start 109.493812 -204.16266)
					(mid 109.348332 -204.22292)
					(end 109.288072 -204.3684)
				)
			)
		)
	)
	(zone
		(layer "In6.Cu")
		(hatch none 0.5)
		(connect_pads
			(clearance 0)
		)
		(min_thickness 0.25)
		(keepout
			(tracks not_allowed)
			(vias allowed)
			(pads allowed)
			(copperpour not_allowed)
			(footprints allowed)
		)
		(placement
			(enabled no)
			(sheetname "")
		)
		(fill
			(thermal_gap 0.5)
			(thermal_bridge_width 0.5)
			(island_removal_mode 0)
		)
		(polygon
			(pts
				(arc
					(start 167.031416 -73.45934)
					(mid 166.159078 -73.168942)
					(end 165.86835 -74.041254)
				)
				(xy 165.866064 -74.04227) (xy 166.866824 -76.04252)
				(arc
					(start 166.86911 -76.041504)
					(mid 167.7416 -76.331826)
					(end 168.031922 -75.459336)
				)
				(xy 168.034208 -75.45832) (xy 167.033702 -73.458324) (xy 167.033194 -73.458324)
			)
		)
	)
	(zone
		(layer "In6.Cu")
		(hatch none 0.5)
		(connect_pads
			(clearance 0)
		)
		(min_thickness 0.25)
		(keepout
			(tracks not_allowed)
			(vias allowed)
			(pads allowed)
			(copperpour not_allowed)
			(footprints allowed)
		)
		(placement
			(enabled no)
			(sheetname "")
		)
		(fill
			(thermal_gap 0.5)
			(thermal_bridge_width 0.5)
			(island_removal_mode 0)
		)
		(polygon
			(pts
				(arc
					(start 53.49113 -76.712826)
					(mid 53.63661 -76.652566)
					(end 53.69687 -76.507086)
				)
				(arc
					(start 53.69687 -76.100686)
					(mid 53.63661 -75.955206)
					(end 53.49113 -75.894946)
				)
				(arc
					(start 53.08473 -75.894946)
					(mid 52.93925 -75.955206)
					(end 52.87899 -76.100686)
				)
				(arc
					(start 52.87899 -76.507086)
					(mid 52.93925 -76.652566)
					(end 53.08473 -76.712826)
				)
			)
		)
	)
	(zone
		(layer "In6.Cu")
		(hatch none 0.5)
		(connect_pads
			(clearance 0)
		)
		(min_thickness 0.25)
		(keepout
			(tracks not_allowed)
			(vias allowed)
			(pads allowed)
			(copperpour not_allowed)
			(footprints allowed)
		)
		(placement
			(enabled no)
			(sheetname "")
		)
		(fill
			(thermal_gap 0.5)
			(thermal_bridge_width 0.5)
			(island_removal_mode 0)
		)
		(polygon
			(pts
				(arc
					(start 117.421152 -222.25)
					(mid 117.360892 -222.10452)
					(end 117.215412 -222.04426)
				)
				(arc
					(start 116.859812 -222.04426)
					(mid 116.714332 -222.10452)
					(end 116.654072 -222.25)
				)
				(arc
					(start 116.654072 -222.6056)
					(mid 116.714332 -222.75108)
					(end 116.859812 -222.81134)
				)
				(arc
					(start 117.215412 -222.81134)
					(mid 117.360892 -222.75108)
					(end 117.421152 -222.6056)
				)
			)
		)
	)
	(zone
		(layer "In6.Cu")
		(hatch none 0.5)
		(connect_pads
			(clearance 0)
		)
		(min_thickness 0.25)
		(keepout
			(tracks not_allowed)
			(vias allowed)
			(pads allowed)
			(copperpour not_allowed)
			(footprints allowed)
		)
		(placement
			(enabled no)
			(sheetname "")
		)
		(fill
			(thermal_gap 0.5)
			(thermal_bridge_width 0.5)
			(island_removal_mode 0)
		)
		(polygon
			(pts
				(arc
					(start 206.031846 -78.54061)
					(mid 205.741321 -77.668399)
					(end 204.86878 -77.958696)
				)
				(xy 204.866494 -77.95768) (xy 203.865734 -79.95793)
				(arc
					(start 203.86802 -79.958946)
					(mid 204.158342 -80.831436)
					(end 205.030832 -80.541114)
				)
				(xy 205.033118 -80.54213) (xy 206.033878 -78.542134) (xy 206.033624 -78.541626)
			)
		)
	)
	(zone
		(layer "In6.Cu")
		(hatch none 0.5)
		(connect_pads
			(clearance 0)
		)
		(min_thickness 0.25)
		(keepout
			(tracks not_allowed)
			(vias allowed)
			(pads allowed)
			(copperpour not_allowed)
			(footprints allowed)
		)
		(placement
			(enabled no)
			(sheetname "")
		)
		(fill
			(thermal_gap 0.5)
			(thermal_bridge_width 0.5)
			(island_removal_mode 0)
		)
		(polygon
			(pts
				(arc
					(start 341.888318 -132.817108)
					(mid 341.742838 -132.877368)
					(end 341.682578 -133.022848)
				)
				(arc
					(start 341.682578 -133.683248)
					(mid 341.742838 -133.828728)
					(end 341.888318 -133.888988)
				)
				(arc
					(start 342.548718 -133.888988)
					(mid 342.694198 -133.828728)
					(end 342.754458 -133.683248)
				)
				(arc
					(start 342.754458 -133.022848)
					(mid 342.694198 -132.877368)
					(end 342.548718 -132.817108)
				)
			)
		)
	)
	(zone
		(layer "In6.Cu")
		(hatch none 0.5)
		(connect_pads
			(clearance 0)
		)
		(min_thickness 0.25)
		(keepout
			(tracks not_allowed)
			(vias allowed)
			(pads allowed)
			(copperpour not_allowed)
			(footprints allowed)
		)
		(placement
			(enabled no)
			(sheetname "")
		)
		(fill
			(thermal_gap 0.5)
			(thermal_bridge_width 0.5)
			(island_removal_mode 0)
		)
		(polygon
			(pts
				(arc
					(start 109.161072 -223.4946)
					(mid 109.221332 -223.64008)
					(end 109.366812 -223.70034)
				)
				(arc
					(start 109.722412 -223.70034)
					(mid 109.867892 -223.64008)
					(end 109.928152 -223.4946)
				)
				(arc
					(start 109.928152 -223.139)
					(mid 109.867892 -222.99352)
					(end 109.722412 -222.93326)
				)
				(arc
					(start 109.366812 -222.93326)
					(mid 109.221332 -222.99352)
					(end 109.161072 -223.139)
				)
			)
		)
	)
	(zone
		(layer "In6.Cu")
		(hatch none 0.5)
		(connect_pads
			(clearance 0)
		)
		(min_thickness 0.25)
		(keepout
			(tracks not_allowed)
			(vias allowed)
			(pads allowed)
			(copperpour not_allowed)
			(footprints allowed)
		)
		(placement
			(enabled no)
			(sheetname "")
		)
		(fill
			(thermal_gap 0.5)
			(thermal_bridge_width 0.5)
			(island_removal_mode 0)
		)
		(polygon
			(pts
				(arc
					(start 340.465918 -134.849108)
					(mid 340.320438 -134.909368)
					(end 340.260178 -135.054848)
				)
				(arc
					(start 340.260178 -135.715248)
					(mid 340.320438 -135.860728)
					(end 340.465918 -135.920988)
				)
				(arc
					(start 341.126318 -135.920988)
					(mid 341.271798 -135.860728)
					(end 341.332058 -135.715248)
				)
				(arc
					(start 341.332058 -135.054848)
					(mid 341.271798 -134.909368)
					(end 341.126318 -134.849108)
				)
			)
		)
	)
	(zone
		(layer "In6.Cu")
		(hatch none 0.5)
		(connect_pads
			(clearance 0)
		)
		(min_thickness 0.25)
		(keepout
			(tracks not_allowed)
			(vias allowed)
			(pads allowed)
			(copperpour not_allowed)
			(footprints allowed)
		)
		(placement
			(enabled no)
			(sheetname "")
		)
		(fill
			(thermal_gap 0.5)
			(thermal_bridge_width 0.5)
			(island_removal_mode 0)
		)
		(polygon
			(pts
				(arc
					(start 119.072152 -221.3864)
					(mid 119.011892 -221.24092)
					(end 118.866412 -221.18066)
				)
				(arc
					(start 118.510812 -221.18066)
					(mid 118.365332 -221.24092)
					(end 118.305072 -221.3864)
				)
				(arc
					(start 118.305072 -221.742)
					(mid 118.365332 -221.88748)
					(end 118.510812 -221.94774)
				)
				(arc
					(start 118.866412 -221.94774)
					(mid 119.011892 -221.88748)
					(end 119.072152 -221.742)
				)
			)
		)
	)
	(zone
		(layer "In6.Cu")
		(hatch none 0.5)
		(connect_pads
			(clearance 0)
		)
		(min_thickness 0.25)
		(keepout
			(tracks not_allowed)
			(vias allowed)
			(pads allowed)
			(copperpour not_allowed)
			(footprints allowed)
		)
		(placement
			(enabled no)
			(sheetname "")
		)
		(fill
			(thermal_gap 0.5)
			(thermal_bridge_width 0.5)
			(island_removal_mode 0)
		)
		(polygon
			(pts
				(arc
					(start 54.50713 -76.712826)
					(mid 54.65261 -76.652566)
					(end 54.71287 -76.507086)
				)
				(arc
					(start 54.71287 -76.100686)
					(mid 54.65261 -75.955206)
					(end 54.50713 -75.894946)
				)
				(arc
					(start 54.10073 -75.894946)
					(mid 53.95525 -75.955206)
					(end 53.89499 -76.100686)
				)
				(arc
					(start 53.89499 -76.507086)
					(mid 53.95525 -76.652566)
					(end 54.10073 -76.712826)
				)
			)
		)
	)
	(zone
		(layer "In6.Cu")
		(hatch none 0.5)
		(connect_pads
			(clearance 0)
		)
		(min_thickness 0.25)
		(keepout
			(tracks not_allowed)
			(vias allowed)
			(pads allowed)
			(copperpour not_allowed)
			(footprints allowed)
		)
		(placement
			(enabled no)
			(sheetname "")
		)
		(fill
			(thermal_gap 0.5)
			(thermal_bridge_width 0.5)
			(island_removal_mode 0)
		)
		(polygon
			(pts
				(arc
					(start 198.032116 -78.54061)
					(mid 197.741591 -77.668399)
					(end 196.86905 -77.958696)
				)
				(xy 196.866764 -77.95768) (xy 195.866004 -79.95793)
				(arc
					(start 195.86829 -79.958946)
					(mid 196.158612 -80.831436)
					(end 197.031102 -80.541114)
				)
				(xy 197.033388 -80.54213) (xy 198.034148 -78.542134) (xy 198.033894 -78.541626)
			)
		)
	)
	(zone
		(layer "In6.Cu")
		(hatch none 0.5)
		(connect_pads
			(clearance 0)
		)
		(min_thickness 0.25)
		(keepout
			(tracks not_allowed)
			(vias allowed)
			(pads allowed)
			(copperpour not_allowed)
			(footprints allowed)
		)
		(placement
			(enabled no)
			(sheetname "")
		)
		(fill
			(thermal_gap 0.5)
			(thermal_bridge_width 0.5)
			(island_removal_mode 0)
		)
		(polygon
			(pts
				(arc
					(start 13.786104 -101.267006)
					(mid 13.931584 -101.206746)
					(end 13.991844 -101.061266)
				)
				(arc
					(start 13.991844 -100.654866)
					(mid 13.931584 -100.509386)
					(end 13.786104 -100.449126)
				)
				(arc
					(start 13.379704 -100.449126)
					(mid 13.234224 -100.509386)
					(end 13.173964 -100.654866)
				)
				(arc
					(start 13.173964 -101.061266)
					(mid 13.234224 -101.206746)
					(end 13.379704 -101.267006)
				)
			)
		)
	)
	(zone
		(layer "In6.Cu")
		(hatch none 0.5)
		(connect_pads
			(clearance 0)
		)
		(min_thickness 0.25)
		(keepout
			(tracks not_allowed)
			(vias allowed)
			(pads allowed)
			(copperpour not_allowed)
			(footprints allowed)
		)
		(placement
			(enabled no)
			(sheetname "")
		)
		(fill
			(thermal_gap 0.5)
			(thermal_bridge_width 0.5)
			(island_removal_mode 0)
		)
		(polygon
			(pts
				(arc
					(start 119.072152 -222.25)
					(mid 119.011892 -222.10452)
					(end 118.866412 -222.04426)
				)
				(arc
					(start 118.510812 -222.04426)
					(mid 118.365332 -222.10452)
					(end 118.305072 -222.25)
				)
				(arc
					(start 118.305072 -222.6056)
					(mid 118.365332 -222.75108)
					(end 118.510812 -222.81134)
				)
				(arc
					(start 118.866412 -222.81134)
					(mid 119.011892 -222.75108)
					(end 119.072152 -222.6056)
				)
			)
		)
	)
	(zone
		(layer "In6.Cu")
		(hatch none 0.5)
		(connect_pads
			(clearance 0)
		)
		(min_thickness 0.25)
		(keepout
			(tracks not_allowed)
			(vias allowed)
			(pads allowed)
			(copperpour not_allowed)
			(footprints allowed)
		)
		(placement
			(enabled no)
			(sheetname "")
		)
		(fill
			(thermal_gap 0.5)
			(thermal_bridge_width 0.5)
			(island_removal_mode 0)
		)
		(polygon
			(pts
				(arc
					(start 96.50476 -31.62554)
					(mid 96.614319 -31.580159)
					(end 96.6597 -31.4706)
				)
				(arc
					(start 96.6597 -31.2166)
					(mid 96.614319 -31.107041)
					(end 96.50476 -31.06166)
				)
				(arc
					(start 96.30156 -31.06166)
					(mid 96.192001 -31.107041)
					(end 96.14662 -31.2166)
				)
				(arc
					(start 96.14662 -31.4706)
					(mid 96.192001 -31.580159)
					(end 96.30156 -31.62554)
				)
			)
		)
	)
	(zone
		(layer "In6.Cu")
		(hatch none 0.5)
		(connect_pads
			(clearance 0)
		)
		(min_thickness 0.25)
		(keepout
			(tracks not_allowed)
			(vias allowed)
			(pads allowed)
			(copperpour not_allowed)
			(footprints allowed)
		)
		(placement
			(enabled no)
			(sheetname "")
		)
		(fill
			(thermal_gap 0.5)
			(thermal_bridge_width 0.5)
			(island_removal_mode 0)
		)
		(polygon
			(pts
				(arc
					(start 54.50713 -77.627226)
					(mid 54.65261 -77.566966)
					(end 54.71287 -77.421486)
				)
				(arc
					(start 54.71287 -77.015086)
					(mid 54.65261 -76.869606)
					(end 54.50713 -76.809346)
				)
				(arc
					(start 54.10073 -76.809346)
					(mid 53.95525 -76.869606)
					(end 53.89499 -77.015086)
				)
				(arc
					(start 53.89499 -77.421486)
					(mid 53.95525 -77.566966)
					(end 54.10073 -77.627226)
				)
			)
		)
	)
	(zone
		(layer "In6.Cu")
		(hatch none 0.5)
		(connect_pads
			(clearance 0)
		)
		(min_thickness 0.25)
		(keepout
			(tracks not_allowed)
			(vias allowed)
			(pads allowed)
			(copperpour not_allowed)
			(footprints allowed)
		)
		(placement
			(enabled no)
			(sheetname "")
		)
		(fill
			(thermal_gap 0.5)
			(thermal_bridge_width 0.5)
			(island_removal_mode 0)
		)
		(polygon
			(pts
				(arc
					(start 98.66376 -31.62554)
					(mid 98.773319 -31.580159)
					(end 98.8187 -31.4706)
				)
				(arc
					(start 98.8187 -31.2166)
					(mid 98.773319 -31.107041)
					(end 98.66376 -31.06166)
				)
				(arc
					(start 98.46056 -31.06166)
					(mid 98.351001 -31.107041)
					(end 98.30562 -31.2166)
				)
				(arc
					(start 98.30562 -31.4706)
					(mid 98.351001 -31.580159)
					(end 98.46056 -31.62554)
				)
			)
		)
	)
	(zone
		(layer "In6.Cu")
		(hatch none 0.5)
		(connect_pads
			(clearance 0)
		)
		(min_thickness 0.25)
		(keepout
			(tracks not_allowed)
			(vias allowed)
			(pads allowed)
			(copperpour not_allowed)
			(footprints allowed)
		)
		(placement
			(enabled no)
			(sheetname "")
		)
		(fill
			(thermal_gap 0.5)
			(thermal_bridge_width 0.5)
			(island_removal_mode 0)
		)
		(polygon
			(pts
				(arc
					(start 110.055152 -205.2574)
					(mid 109.994892 -205.11192)
					(end 109.849412 -205.05166)
				)
				(arc
					(start 109.493812 -205.05166)
					(mid 109.348332 -205.11192)
					(end 109.288072 -205.2574)
				)
				(arc
					(start 109.288072 -205.613)
					(mid 109.348332 -205.75848)
					(end 109.493812 -205.81874)
				)
				(arc
					(start 109.849412 -205.81874)
					(mid 109.994892 -205.75848)
					(end 110.055152 -205.613)
				)
			)
		)
	)
	(zone
		(layer "In6.Cu")
		(hatch none 0.5)
		(connect_pads
			(clearance 0)
		)
		(min_thickness 0.25)
		(keepout
			(tracks not_allowed)
			(vias allowed)
			(pads allowed)
			(copperpour not_allowed)
			(footprints allowed)
		)
		(placement
			(enabled no)
			(sheetname "")
		)
		(fill
			(thermal_gap 0.5)
			(thermal_bridge_width 0.5)
			(island_removal_mode 0)
		)
		(polygon
			(pts
				(arc
					(start 101.07676 -32.201358)
					(mid 101.186319 -32.155977)
					(end 101.2317 -32.046418)
				)
				(arc
					(start 101.2317 -31.792418)
					(mid 101.186319 -31.682859)
					(end 101.07676 -31.637478)
				)
				(arc
					(start 100.87356 -31.637478)
					(mid 100.764001 -31.682859)
					(end 100.71862 -31.792418)
				)
				(arc
					(start 100.71862 -32.046418)
					(mid 100.764001 -32.155977)
					(end 100.87356 -32.201358)
				)
			)
		)
	)
	(zone
		(layer "In6.Cu")
		(hatch none 0.5)
		(connect_pads
			(clearance 0)
		)
		(min_thickness 0.25)
		(keepout
			(tracks not_allowed)
			(vias allowed)
			(pads allowed)
			(copperpour not_allowed)
			(footprints allowed)
		)
		(placement
			(enabled no)
			(sheetname "")
		)
		(fill
			(thermal_gap 0.5)
			(thermal_bridge_width 0.5)
			(island_removal_mode 0)
		)
		(polygon
			(pts
				(arc
					(start 116.278152 -205.2574)
					(mid 116.217892 -205.11192)
					(end 116.072412 -205.05166)
				)
				(arc
					(start 115.716812 -205.05166)
					(mid 115.571332 -205.11192)
					(end 115.511072 -205.2574)
				)
				(arc
					(start 115.511072 -205.613)
					(mid 115.571332 -205.75848)
					(end 115.716812 -205.81874)
				)
				(arc
					(start 116.072412 -205.81874)
					(mid 116.217892 -205.75848)
					(end 116.278152 -205.613)
				)
			)
		)
	)
	(zone
		(layer "In6.Cu")
		(hatch none 0.5)
		(connect_pads
			(clearance 0)
		)
		(min_thickness 0.25)
		(keepout
			(tracks not_allowed)
			(vias allowed)
			(pads allowed)
			(copperpour not_allowed)
			(footprints allowed)
		)
		(placement
			(enabled no)
			(sheetname "")
		)
		(fill
			(thermal_gap 0.5)
			(thermal_bridge_width 0.5)
			(island_removal_mode 0)
		)
		(polygon
			(pts
				(arc
					(start 338.332318 -133.888988)
					(mid 338.477798 -133.828728)
					(end 338.538058 -133.683248)
				)
				(arc
					(start 338.538058 -133.022848)
					(mid 338.477798 -132.877368)
					(end 338.332318 -132.817108)
				)
				(arc
					(start 337.671918 -132.817108)
					(mid 337.526438 -132.877368)
					(end 337.466178 -133.022848)
				)
				(arc
					(start 337.466178 -133.683248)
					(mid 337.526438 -133.828728)
					(end 337.671918 -133.888988)
				)
			)
		)
	)
	(zone
		(layer "In6.Cu")
		(hatch none 0.5)
		(connect_pads
			(clearance 0)
		)
		(min_thickness 0.25)
		(keepout
			(tracks not_allowed)
			(vias allowed)
			(pads allowed)
			(copperpour not_allowed)
			(footprints allowed)
		)
		(placement
			(enabled no)
			(sheetname "")
		)
		(fill
			(thermal_gap 0.5)
			(thermal_bridge_width 0.5)
			(island_removal_mode 0)
		)
		(polygon
			(pts
				(arc
					(start 17.088104 -100.352606)
					(mid 17.233584 -100.292346)
					(end 17.293844 -100.146866)
				)
				(arc
					(start 17.293844 -99.740466)
					(mid 17.233584 -99.594986)
					(end 17.088104 -99.534726)
				)
				(arc
					(start 16.681704 -99.534726)
					(mid 16.536224 -99.594986)
					(end 16.475964 -99.740466)
				)
				(arc
					(start 16.475964 -100.146866)
					(mid 16.536224 -100.292346)
					(end 16.681704 -100.352606)
				)
			)
		)
	)
	(zone
		(layer "In6.Cu")
		(hatch none 0.5)
		(connect_pads
			(clearance 0)
		)
		(min_thickness 0.25)
		(keepout
			(tracks not_allowed)
			(vias allowed)
			(pads allowed)
			(copperpour not_allowed)
			(footprints allowed)
		)
		(placement
			(enabled no)
			(sheetname "")
		)
		(fill
			(thermal_gap 0.5)
			(thermal_bridge_width 0.5)
			(island_removal_mode 0)
		)
		(polygon
			(pts
				(arc
					(start 53.49113 -77.627226)
					(mid 53.63661 -77.566966)
					(end 53.69687 -77.421486)
				)
				(arc
					(start 53.69687 -77.015086)
					(mid 53.63661 -76.869606)
					(end 53.49113 -76.809346)
				)
				(arc
					(start 53.08473 -76.809346)
					(mid 52.93925 -76.869606)
					(end 52.87899 -77.015086)
				)
				(arc
					(start 52.87899 -77.421486)
					(mid 52.93925 -77.566966)
					(end 53.08473 -77.627226)
				)
			)
		)
	)
	(zone
		(layer "In6.Cu")
		(hatch none 0.5)
		(connect_pads
			(clearance 0)
		)
		(min_thickness 0.25)
		(keepout
			(tracks not_allowed)
			(vias allowed)
			(pads allowed)
			(copperpour not_allowed)
			(footprints allowed)
		)
		(placement
			(enabled no)
			(sheetname "")
		)
		(fill
			(thermal_gap 0.5)
			(thermal_bridge_width 0.5)
			(island_removal_mode 0)
		)
		(polygon
			(pts
				(arc
					(start 12.262104 -101.267006)
					(mid 12.407584 -101.206746)
					(end 12.467844 -101.061266)
				)
				(arc
					(start 12.467844 -100.654866)
					(mid 12.407584 -100.509386)
					(end 12.262104 -100.449126)
				)
				(arc
					(start 11.855704 -100.449126)
					(mid 11.710224 -100.509386)
					(end 11.649964 -100.654866)
				)
				(arc
					(start 11.649964 -101.061266)
					(mid 11.710224 -101.206746)
					(end 11.855704 -101.267006)
				)
			)
		)
	)
	(zone
		(layer "In6.Cu")
		(hatch none 0.5)
		(connect_pads
			(clearance 0)
		)
		(min_thickness 0.25)
		(keepout
			(tracks not_allowed)
			(vias allowed)
			(pads allowed)
			(copperpour not_allowed)
			(footprints allowed)
		)
		(placement
			(enabled no)
			(sheetname "")
		)
		(fill
			(thermal_gap 0.5)
			(thermal_bridge_width 0.5)
			(island_removal_mode 0)
		)
		(polygon
			(pts
				(arc
					(start 162.031426 -78.540356)
					(mid 161.740342 -77.66812)
					(end 160.868106 -77.959204)
				)
				(xy 160.86582 -77.957934) (xy 159.86633 -79.958184)
				(arc
					(start 159.868616 -79.959454)
					(mid 160.1597 -80.83169)
					(end 161.031936 -80.540606)
				)
				(xy 161.034222 -80.541876) (xy 162.033712 -78.54188) (xy 162.033458 -78.541372)
			)
		)
	)
	(zone
		(layer "In6.Cu")
		(hatch none 0.5)
		(connect_pads
			(clearance 0)
		)
		(min_thickness 0.25)
		(keepout
			(tracks not_allowed)
			(vias allowed)
			(pads allowed)
			(copperpour not_allowed)
			(footprints allowed)
		)
		(placement
			(enabled no)
			(sheetname "")
		)
		(fill
			(thermal_gap 0.5)
			(thermal_bridge_width 0.5)
			(island_removal_mode 0)
		)
		(polygon
			(pts
				(arc
					(start 100.18776 -32.18434)
					(mid 100.297319 -32.138959)
					(end 100.3427 -32.0294)
				)
				(arc
					(start 100.3427 -31.7754)
					(mid 100.297319 -31.665841)
					(end 100.18776 -31.62046)
				)
				(arc
					(start 99.98456 -31.62046)
					(mid 99.875001 -31.665841)
					(end 99.82962 -31.7754)
				)
				(arc
					(start 99.82962 -32.0294)
					(mid 99.875001 -32.138959)
					(end 99.98456 -32.18434)
				)
			)
		)
	)
	(zone
		(layer "In6.Cu")
		(hatch none 0.5)
		(connect_pads
			(clearance 0)
		)
		(min_thickness 0.25)
		(keepout
			(tracks not_allowed)
			(vias allowed)
			(pads allowed)
			(copperpour not_allowed)
			(footprints allowed)
		)
		(placement
			(enabled no)
			(sheetname "")
		)
		(fill
			(thermal_gap 0.5)
			(thermal_bridge_width 0.5)
			(island_removal_mode 0)
		)
		(polygon
			(pts
				(arc
					(start 116.654072 -223.4946)
					(mid 116.714332 -223.64008)
					(end 116.859812 -223.70034)
				)
				(arc
					(start 117.215412 -223.70034)
					(mid 117.360892 -223.64008)
					(end 117.421152 -223.4946)
				)
				(arc
					(start 117.421152 -223.139)
					(mid 117.360892 -222.99352)
					(end 117.215412 -222.93326)
				)
				(arc
					(start 116.859812 -222.93326)
					(mid 116.714332 -222.99352)
					(end 116.654072 -223.139)
				)
			)
		)
	)
	(zone
		(layer "In6.Cu")
		(hatch none 0.5)
		(connect_pads
			(clearance 0)
		)
		(min_thickness 0.25)
		(keepout
			(tracks not_allowed)
			(vias allowed)
			(pads allowed)
			(copperpour not_allowed)
			(footprints allowed)
		)
		(placement
			(enabled no)
			(sheetname "")
		)
		(fill
			(thermal_gap 0.5)
			(thermal_bridge_width 0.5)
			(island_removal_mode 0)
		)
		(polygon
			(pts
				(arc
					(start 194.031616 -78.540356)
					(mid 193.740532 -77.66812)
					(end 192.868296 -77.959204)
				)
				(xy 192.86601 -77.957934) (xy 191.86652 -79.958184)
				(arc
					(start 191.868806 -79.959454)
					(mid 192.15989 -80.83169)
					(end 193.032126 -80.540606)
				)
				(xy 193.034412 -80.541876) (xy 194.033902 -78.54188) (xy 194.033648 -78.541372)
			)
		)
	)
	(zone
		(layer "In6.Cu")
		(hatch none 0.5)
		(connect_pads
			(clearance 0)
		)
		(min_thickness 0.25)
		(keepout
			(tracks not_allowed)
			(vias allowed)
			(pads allowed)
			(copperpour not_allowed)
			(footprints allowed)
		)
		(placement
			(enabled no)
			(sheetname "")
		)
		(fill
			(thermal_gap 0.5)
			(thermal_bridge_width 0.5)
			(island_removal_mode 0)
		)
		(polygon
			(pts
				(arc
					(start 104.75976 -31.62554)
					(mid 104.869319 -31.580159)
					(end 104.9147 -31.4706)
				)
				(arc
					(start 104.9147 -31.2166)
					(mid 104.869319 -31.107041)
					(end 104.75976 -31.06166)
				)
				(arc
					(start 104.55656 -31.06166)
					(mid 104.447001 -31.107041)
					(end 104.40162 -31.2166)
				)
				(arc
					(start 104.40162 -31.4706)
					(mid 104.447001 -31.580159)
					(end 104.55656 -31.62554)
				)
			)
		)
	)
	(zone
		(layer "In6.Cu")
		(hatch none 0.5)
		(connect_pads
			(clearance 0)
		)
		(min_thickness 0.25)
		(keepout
			(tracks not_allowed)
			(vias allowed)
			(pads allowed)
			(copperpour not_allowed)
			(footprints allowed)
		)
		(placement
			(enabled no)
			(sheetname "")
		)
		(fill
			(thermal_gap 0.5)
			(thermal_bridge_width 0.5)
			(island_removal_mode 0)
		)
		(polygon
			(pts
				(arc
					(start 107.637072 -204.724)
					(mid 107.697332 -204.86948)
					(end 107.842812 -204.92974)
				)
				(arc
					(start 108.198412 -204.92974)
					(mid 108.343892 -204.86948)
					(end 108.404152 -204.724)
				)
				(arc
					(start 108.404152 -204.3684)
					(mid 108.343892 -204.22292)
					(end 108.198412 -204.16266)
				)
				(arc
					(start 107.842812 -204.16266)
					(mid 107.697332 -204.22292)
					(end 107.637072 -204.3684)
				)
			)
		)
	)
	(zone
		(layer "In6.Cu")
		(hatch none 0.5)
		(connect_pads
			(clearance 0)
		)
		(min_thickness 0.25)
		(keepout
			(tracks not_allowed)
			(vias allowed)
			(pads allowed)
			(copperpour not_allowed)
			(footprints allowed)
		)
		(placement
			(enabled no)
			(sheetname "")
		)
		(fill
			(thermal_gap 0.5)
			(thermal_bridge_width 0.5)
			(island_removal_mode 0)
		)
		(polygon
			(pts
				(arc
					(start 214.031576 -78.540356)
					(mid 213.740492 -77.66812)
					(end 212.868256 -77.959204)
				)
				(xy 212.86597 -77.957934) (xy 211.86648 -79.958184)
				(arc
					(start 211.868766 -79.959454)
					(mid 212.15985 -80.83169)
					(end 213.032086 -80.540606)
				)
				(xy 213.034372 -80.541876) (xy 214.033862 -78.54188) (xy 214.033608 -78.541372)
			)
		)
	)
	(zone
		(layer "In6.Cu")
		(hatch none 0.5)
		(connect_pads
			(clearance 0)
		)
		(min_thickness 0.25)
		(keepout
			(tracks not_allowed)
			(vias allowed)
			(pads allowed)
			(copperpour not_allowed)
			(footprints allowed)
		)
		(placement
			(enabled no)
			(sheetname "")
		)
		(fill
			(thermal_gap 0.5)
			(thermal_bridge_width 0.5)
			(island_removal_mode 0)
		)
		(polygon
			(pts
				(arc
					(start 104.75976 -32.18434)
					(mid 104.869319 -32.138959)
					(end 104.9147 -32.0294)
				)
				(arc
					(start 104.9147 -31.7754)
					(mid 104.869319 -31.665841)
					(end 104.75976 -31.62046)
				)
				(arc
					(start 104.55656 -31.62046)
					(mid 104.447001 -31.665841)
					(end 104.40162 -31.7754)
				)
				(arc
					(start 104.40162 -32.0294)
					(mid 104.447001 -32.138959)
					(end 104.55656 -32.18434)
				)
			)
		)
	)
	(zone
		(layer "In6.Cu")
		(hatch none 0.5)
		(connect_pads
			(clearance 0)
		)
		(min_thickness 0.25)
		(keepout
			(tracks not_allowed)
			(vias allowed)
			(pads allowed)
			(copperpour not_allowed)
			(footprints allowed)
		)
		(placement
			(enabled no)
			(sheetname "")
		)
		(fill
			(thermal_gap 0.5)
			(thermal_bridge_width 0.5)
			(island_removal_mode 0)
		)
		(polygon
			(pts
				(arc
					(start 19.374104 -100.352606)
					(mid 19.519584 -100.292346)
					(end 19.579844 -100.146866)
				)
				(arc
					(start 19.579844 -99.740466)
					(mid 19.519584 -99.594986)
					(end 19.374104 -99.534726)
				)
				(arc
					(start 18.967704 -99.534726)
					(mid 18.822224 -99.594986)
					(end 18.761964 -99.740466)
				)
				(arc
					(start 18.761964 -100.146866)
					(mid 18.822224 -100.292346)
					(end 18.967704 -100.352606)
				)
			)
		)
	)
	(zone
		(layer "In6.Cu")
		(hatch none 0.5)
		(connect_pads
			(clearance 0)
		)
		(min_thickness 0.25)
		(keepout
			(tracks not_allowed)
			(vias allowed)
			(pads allowed)
			(copperpour not_allowed)
			(footprints allowed)
		)
		(placement
			(enabled no)
			(sheetname "")
		)
		(fill
			(thermal_gap 0.5)
			(thermal_bridge_width 0.5)
			(island_removal_mode 0)
		)
		(polygon
			(pts
				(arc
					(start 95.61576 -32.18434)
					(mid 95.725319 -32.138959)
					(end 95.7707 -32.0294)
				)
				(arc
					(start 95.7707 -31.7754)
					(mid 95.725319 -31.665841)
					(end 95.61576 -31.62046)
				)
				(arc
					(start 95.41256 -31.62046)
					(mid 95.303001 -31.665841)
					(end 95.25762 -31.7754)
				)
				(arc
					(start 95.25762 -32.0294)
					(mid 95.303001 -32.138959)
					(end 95.41256 -32.18434)
				)
			)
		)
	)
	(zone
		(layer "In6.Cu")
		(hatch none 0.5)
		(connect_pads
			(clearance 0)
		)
		(min_thickness 0.25)
		(keepout
			(tracks not_allowed)
			(vias allowed)
			(pads allowed)
			(copperpour not_allowed)
			(footprints allowed)
		)
		(placement
			(enabled no)
			(sheetname "")
		)
		(fill
			(thermal_gap 0.5)
			(thermal_bridge_width 0.5)
			(island_removal_mode 0)
		)
		(polygon
			(pts
				(arc
					(start 339.729318 -135.920988)
					(mid 339.874798 -135.860728)
					(end 339.935058 -135.715248)
				)
				(arc
					(start 339.935058 -135.054848)
					(mid 339.874798 -134.909368)
					(end 339.729318 -134.849108)
				)
				(arc
					(start 339.068918 -134.849108)
					(mid 338.923438 -134.909368)
					(end 338.863178 -135.054848)
				)
				(arc
					(start 338.863178 -135.715248)
					(mid 338.923438 -135.860728)
					(end 339.068918 -135.920988)
				)
			)
		)
	)
	(zone
		(layer "In6.Cu")
		(hatch none 0.5)
		(connect_pads
			(clearance 0)
		)
		(min_thickness 0.25)
		(keepout
			(tracks not_allowed)
			(vias allowed)
			(pads allowed)
			(copperpour not_allowed)
			(footprints allowed)
		)
		(placement
			(enabled no)
			(sheetname "")
		)
		(fill
			(thermal_gap 0.5)
			(thermal_bridge_width 0.5)
			(island_removal_mode 0)
		)
		(polygon
			(pts
				(arc
					(start 163.032186 -73.459594)
					(mid 162.15995 -73.16851)
					(end 161.868866 -74.040746)
				)
				(xy 161.86658 -74.042016) (xy 162.86607 -76.042266)
				(arc
					(start 162.868356 -76.040996)
					(mid 163.740592 -76.33208)
					(end 164.031676 -75.459844)
				)
				(xy 164.033962 -75.458574) (xy 163.034472 -73.458578) (xy 163.034218 -73.458578)
			)
		)
	)
	(zone
		(layer "In6.Cu")
		(hatch none 0.5)
		(connect_pads
			(clearance 0)
		)
		(min_thickness 0.25)
		(keepout
			(tracks not_allowed)
			(vias allowed)
			(pads allowed)
			(copperpour not_allowed)
			(footprints allowed)
		)
		(placement
			(enabled no)
			(sheetname "")
		)
		(fill
			(thermal_gap 0.5)
			(thermal_bridge_width 0.5)
			(island_removal_mode 0)
		)
		(polygon
			(pts
				(arc
					(start 98.02876 -31.62554)
					(mid 98.138319 -31.580159)
					(end 98.1837 -31.4706)
				)
				(arc
					(start 98.1837 -31.2166)
					(mid 98.138319 -31.107041)
					(end 98.02876 -31.06166)
				)
				(arc
					(start 97.82556 -31.06166)
					(mid 97.716001 -31.107041)
					(end 97.67062 -31.2166)
				)
				(arc
					(start 97.67062 -31.4706)
					(mid 97.716001 -31.580159)
					(end 97.82556 -31.62554)
				)
			)
		)
	)
	(zone
		(layer "In6.Cu")
		(hatch none 0.5)
		(connect_pads
			(clearance 0)
		)
		(min_thickness 0.25)
		(keepout
			(tracks not_allowed)
			(vias allowed)
			(pads allowed)
			(copperpour not_allowed)
			(footprints allowed)
		)
		(placement
			(enabled no)
			(sheetname "")
		)
		(fill
			(thermal_gap 0.5)
			(thermal_bridge_width 0.5)
			(island_removal_mode 0)
		)
		(polygon
			(pts
				(arc
					(start 97.13976 -32.18434)
					(mid 97.249319 -32.138959)
					(end 97.2947 -32.0294)
				)
				(arc
					(start 97.2947 -31.7754)
					(mid 97.249319 -31.665841)
					(end 97.13976 -31.62046)
				)
				(arc
					(start 96.93656 -31.62046)
					(mid 96.827001 -31.665841)
					(end 96.78162 -31.7754)
				)
				(arc
					(start 96.78162 -32.0294)
					(mid 96.827001 -32.138959)
					(end 96.93656 -32.18434)
				)
			)
		)
	)
	(zone
		(layer "In6.Cu")
		(hatch none 0.5)
		(connect_pads
			(clearance 0)
		)
		(min_thickness 0.25)
		(keepout
			(tracks not_allowed)
			(vias allowed)
			(pads allowed)
			(copperpour not_allowed)
			(footprints allowed)
		)
		(placement
			(enabled no)
			(sheetname "")
		)
		(fill
			(thermal_gap 0.5)
			(thermal_bridge_width 0.5)
			(island_removal_mode 0)
		)
		(polygon
			(pts
				(arc
					(start 42.31513 -78.516226)
					(mid 42.46061 -78.455966)
					(end 42.52087 -78.310486)
				)
				(arc
					(start 42.52087 -77.904086)
					(mid 42.46061 -77.758606)
					(end 42.31513 -77.698346)
				)
				(arc
					(start 41.90873 -77.698346)
					(mid 41.76325 -77.758606)
					(end 41.70299 -77.904086)
				)
				(arc
					(start 41.70299 -78.310486)
					(mid 41.76325 -78.455966)
					(end 41.90873 -78.516226)
				)
			)
		)
	)
	(zone
		(layer "In6.Cu")
		(hatch none 0.5)
		(connect_pads
			(clearance 0)
		)
		(min_thickness 0.25)
		(keepout
			(tracks not_allowed)
			(vias allowed)
			(pads allowed)
			(copperpour not_allowed)
			(footprints allowed)
		)
		(placement
			(enabled no)
			(sheetname "")
		)
		(fill
			(thermal_gap 0.5)
			(thermal_bridge_width 0.5)
			(island_removal_mode 0)
		)
		(polygon
			(pts
				(arc
					(start 94.09176 -32.18434)
					(mid 94.201319 -32.138959)
					(end 94.2467 -32.0294)
				)
				(arc
					(start 94.2467 -31.7754)
					(mid 94.201319 -31.665841)
					(end 94.09176 -31.62046)
				)
				(arc
					(start 93.88856 -31.62046)
					(mid 93.779001 -31.665841)
					(end 93.73362 -31.7754)
				)
				(arc
					(start 93.73362 -32.0294)
					(mid 93.779001 -32.138959)
					(end 93.88856 -32.18434)
				)
			)
		)
	)
	(zone
		(layer "In6.Cu")
		(hatch none 0.5)
		(connect_pads
			(clearance 0)
		)
		(min_thickness 0.25)
		(keepout
			(tracks not_allowed)
			(vias allowed)
			(pads allowed)
			(copperpour not_allowed)
			(footprints allowed)
		)
		(placement
			(enabled no)
			(sheetname "")
		)
		(fill
			(thermal_gap 0.5)
			(thermal_bridge_width 0.5)
			(island_removal_mode 0)
		)
		(polygon
			(pts
				(arc
					(start 98.02876 -32.18434)
					(mid 98.138319 -32.138959)
					(end 98.1837 -32.0294)
				)
				(arc
					(start 98.1837 -31.7754)
					(mid 98.138319 -31.665841)
					(end 98.02876 -31.62046)
				)
				(arc
					(start 97.82556 -31.62046)
					(mid 97.716001 -31.665841)
					(end 97.67062 -31.7754)
				)
				(arc
					(start 97.67062 -32.0294)
					(mid 97.716001 -32.138959)
					(end 97.82556 -32.18434)
				)
			)
		)
	)
	(zone
		(layer "In6.Cu")
		(hatch none 0.5)
		(connect_pads
			(clearance 0)
		)
		(min_thickness 0.25)
		(keepout
			(tracks not_allowed)
			(vias allowed)
			(pads allowed)
			(copperpour not_allowed)
			(footprints allowed)
		)
		(placement
			(enabled no)
			(sheetname "")
		)
		(fill
			(thermal_gap 0.5)
			(thermal_bridge_width 0.5)
			(island_removal_mode 0)
		)
		(polygon
			(pts
				(arc
					(start 101.71176 -32.201358)
					(mid 101.821319 -32.155977)
					(end 101.8667 -32.046418)
				)
				(arc
					(start 101.8667 -31.792418)
					(mid 101.821319 -31.682859)
					(end 101.71176 -31.637478)
				)
				(arc
					(start 101.50856 -31.637478)
					(mid 101.399001 -31.682859)
					(end 101.35362 -31.792418)
				)
				(arc
					(start 101.35362 -32.046418)
					(mid 101.399001 -32.155977)
					(end 101.50856 -32.201358)
				)
			)
		)
	)
	(zone
		(layer "In6.Cu")
		(hatch none 0.5)
		(connect_pads
			(clearance 0)
		)
		(min_thickness 0.25)
		(keepout
			(tracks not_allowed)
			(vias allowed)
			(pads allowed)
			(copperpour not_allowed)
			(footprints allowed)
		)
		(placement
			(enabled no)
			(sheetname "")
		)
		(fill
			(thermal_gap 0.5)
			(thermal_bridge_width 0.5)
			(island_removal_mode 0)
		)
		(polygon
			(pts
				(arc
					(start 94.98076 -31.62554)
					(mid 95.090319 -31.580159)
					(end 95.1357 -31.4706)
				)
				(arc
					(start 95.1357 -31.2166)
					(mid 95.090319 -31.107041)
					(end 94.98076 -31.06166)
				)
				(arc
					(start 94.77756 -31.06166)
					(mid 94.668001 -31.107041)
					(end 94.62262 -31.2166)
				)
				(arc
					(start 94.62262 -31.4706)
					(mid 94.668001 -31.580159)
					(end 94.77756 -31.62554)
				)
			)
		)
	)
	(zone
		(layer "In6.Cu")
		(hatch none 0.5)
		(connect_pads
			(clearance 0)
		)
		(min_thickness 0.25)
		(keepout
			(tracks not_allowed)
			(vias allowed)
			(pads allowed)
			(copperpour not_allowed)
			(footprints allowed)
		)
		(placement
			(enabled no)
			(sheetname "")
		)
		(fill
			(thermal_gap 0.5)
			(thermal_bridge_width 0.5)
			(island_removal_mode 0)
		)
		(polygon
			(pts
				(arc
					(start 14.675104 -100.352606)
					(mid 14.820584 -100.292346)
					(end 14.880844 -100.146866)
				)
				(arc
					(start 14.880844 -99.740466)
					(mid 14.820584 -99.594986)
					(end 14.675104 -99.534726)
				)
				(arc
					(start 14.268704 -99.534726)
					(mid 14.123224 -99.594986)
					(end 14.062964 -99.740466)
				)
				(arc
					(start 14.062964 -100.146866)
					(mid 14.123224 -100.292346)
					(end 14.268704 -100.352606)
				)
			)
		)
	)
	(zone
		(layer "In6.Cu")
		(hatch none 0.5)
		(connect_pads
			(clearance 0)
		)
		(min_thickness 0.25)
		(keepout
			(tracks not_allowed)
			(vias allowed)
			(pads allowed)
			(copperpour not_allowed)
			(footprints allowed)
		)
		(placement
			(enabled no)
			(sheetname "")
		)
		(fill
			(thermal_gap 0.5)
			(thermal_bridge_width 0.5)
			(island_removal_mode 0)
		)
		(polygon
			(pts
				(arc
					(start 103.23576 -32.18434)
					(mid 103.345319 -32.138959)
					(end 103.3907 -32.0294)
				)
				(arc
					(start 103.3907 -31.7754)
					(mid 103.345319 -31.665841)
					(end 103.23576 -31.62046)
				)
				(arc
					(start 103.03256 -31.62046)
					(mid 102.923001 -31.665841)
					(end 102.87762 -31.7754)
				)
				(arc
					(start 102.87762 -32.0294)
					(mid 102.923001 -32.138959)
					(end 103.03256 -32.18434)
				)
			)
		)
	)
	(zone
		(layer "In6.Cu")
		(hatch none 0.5)
		(connect_pads
			(clearance 0)
		)
		(min_thickness 0.25)
		(keepout
			(tracks not_allowed)
			(vias allowed)
			(pads allowed)
			(copperpour not_allowed)
			(footprints allowed)
		)
		(placement
			(enabled no)
			(sheetname "")
		)
		(fill
			(thermal_gap 0.5)
			(thermal_bridge_width 0.5)
			(island_removal_mode 0)
		)
		(polygon
			(pts
				(arc
					(start 18.485104 -101.267006)
					(mid 18.630584 -101.206746)
					(end 18.690844 -101.061266)
				)
				(arc
					(start 18.690844 -100.654866)
					(mid 18.630584 -100.509386)
					(end 18.485104 -100.449126)
				)
				(arc
					(start 18.078704 -100.449126)
					(mid 17.933224 -100.509386)
					(end 17.872964 -100.654866)
				)
				(arc
					(start 17.872964 -101.061266)
					(mid 17.933224 -101.206746)
					(end 18.078704 -101.267006)
				)
			)
		)
	)
	(zone
		(layer "In6.Cu")
		(hatch none 0.5)
		(connect_pads
			(clearance 0)
		)
		(min_thickness 0.25)
		(keepout
			(tracks not_allowed)
			(vias allowed)
			(pads allowed)
			(copperpour not_allowed)
			(footprints allowed)
		)
		(placement
			(enabled no)
			(sheetname "")
		)
		(fill
			(thermal_gap 0.5)
			(thermal_bridge_width 0.5)
			(island_removal_mode 0)
		)
		(polygon
			(pts
				(arc
					(start 102.60076 -32.18434)
					(mid 102.710319 -32.138959)
					(end 102.7557 -32.0294)
				)
				(arc
					(start 102.7557 -31.7754)
					(mid 102.710319 -31.665841)
					(end 102.60076 -31.62046)
				)
				(arc
					(start 102.39756 -31.62046)
					(mid 102.288001 -31.665841)
					(end 102.24262 -31.7754)
				)
				(arc
					(start 102.24262 -32.0294)
					(mid 102.288001 -32.138959)
					(end 102.39756 -32.18434)
				)
			)
		)
	)
	(zone
		(layer "In6.Cu")
		(hatch none 0.5)
		(connect_pads
			(clearance 0)
		)
		(min_thickness 0.25)
		(keepout
			(tracks not_allowed)
			(vias allowed)
			(pads allowed)
			(copperpour not_allowed)
			(footprints allowed)
		)
		(placement
			(enabled no)
			(sheetname "")
		)
		(fill
			(thermal_gap 0.5)
			(thermal_bridge_width 0.5)
			(island_removal_mode 0)
		)
		(polygon
			(pts
				(arc
					(start 100.18776 -31.62554)
					(mid 100.297319 -31.580159)
					(end 100.3427 -31.4706)
				)
				(arc
					(start 100.3427 -31.2166)
					(mid 100.297319 -31.107041)
					(end 100.18776 -31.06166)
				)
				(arc
					(start 99.98456 -31.06166)
					(mid 99.875001 -31.107041)
					(end 99.82962 -31.2166)
				)
				(arc
					(start 99.82962 -31.4706)
					(mid 99.875001 -31.580159)
					(end 99.98456 -31.62554)
				)
			)
		)
	)
	(zone
		(layer "In6.Cu")
		(hatch none 0.5)
		(connect_pads
			(clearance 0)
		)
		(min_thickness 0.25)
		(keepout
			(tracks not_allowed)
			(vias allowed)
			(pads allowed)
			(copperpour not_allowed)
			(footprints allowed)
		)
		(placement
			(enabled no)
			(sheetname "")
		)
		(fill
			(thermal_gap 0.5)
			(thermal_bridge_width 0.5)
			(island_removal_mode 0)
		)
		(polygon
			(pts
				(arc
					(start 42.31513 -77.601826)
					(mid 42.46061 -77.541566)
					(end 42.52087 -77.396086)
				)
				(arc
					(start 42.52087 -76.989686)
					(mid 42.46061 -76.844206)
					(end 42.31513 -76.783946)
				)
				(arc
					(start 41.90873 -76.783946)
					(mid 41.76325 -76.844206)
					(end 41.70299 -76.989686)
				)
				(arc
					(start 41.70299 -77.396086)
					(mid 41.76325 -77.541566)
					(end 41.90873 -77.601826)
				)
			)
		)
	)
	(zone
		(layer "In6.Cu")
		(hatch none 0.5)
		(connect_pads
			(clearance 0)
		)
		(min_thickness 0.25)
		(keepout
			(tracks not_allowed)
			(vias allowed)
			(pads allowed)
			(copperpour not_allowed)
			(footprints allowed)
		)
		(placement
			(enabled no)
			(sheetname "")
		)
		(fill
			(thermal_gap 0.5)
			(thermal_bridge_width 0.5)
			(island_removal_mode 0)
		)
		(polygon
			(pts
				(arc
					(start 94.98076 -32.18434)
					(mid 95.090319 -32.138959)
					(end 95.1357 -32.0294)
				)
				(arc
					(start 95.1357 -31.7754)
					(mid 95.090319 -31.665841)
					(end 94.98076 -31.62046)
				)
				(arc
					(start 94.77756 -31.62046)
					(mid 94.668001 -31.665841)
					(end 94.62262 -31.7754)
				)
				(arc
					(start 94.62262 -32.0294)
					(mid 94.668001 -32.138959)
					(end 94.77756 -32.18434)
				)
			)
		)
	)
	(zone
		(layer "In6.Cu")
		(hatch none 0.5)
		(connect_pads
			(clearance 0)
		)
		(min_thickness 0.25)
		(keepout
			(tracks not_allowed)
			(vias allowed)
			(pads allowed)
			(copperpour not_allowed)
			(footprints allowed)
		)
		(placement
			(enabled no)
			(sheetname "")
		)
		(fill
			(thermal_gap 0.5)
			(thermal_bridge_width 0.5)
			(island_removal_mode 0)
		)
		(polygon
			(pts
				(arc
					(start 158.032196 -78.54061)
					(mid 157.741671 -77.668399)
					(end 156.86913 -77.958696)
				)
				(xy 156.866844 -77.95768) (xy 155.866084 -79.95793)
				(arc
					(start 155.86837 -79.958946)
					(mid 156.158692 -80.831436)
					(end 157.031182 -80.541114)
				)
				(xy 157.033468 -80.54213) (xy 158.034228 -78.542134) (xy 158.033974 -78.541626)
			)
		)
	)
	(zone
		(layer "In6.Cu")
		(hatch none 0.5)
		(connect_pads
			(clearance 0)
		)
		(min_thickness 0.25)
		(keepout
			(tracks not_allowed)
			(vias allowed)
			(pads allowed)
			(copperpour not_allowed)
			(footprints allowed)
		)
		(placement
			(enabled no)
			(sheetname "")
		)
		(fill
			(thermal_gap 0.5)
			(thermal_bridge_width 0.5)
			(island_removal_mode 0)
		)
		(polygon
			(pts
				(arc
					(start 16.199104 -100.352606)
					(mid 16.344584 -100.292346)
					(end 16.404844 -100.146866)
				)
				(arc
					(start 16.404844 -99.740466)
					(mid 16.344584 -99.594986)
					(end 16.199104 -99.534726)
				)
				(arc
					(start 15.792704 -99.534726)
					(mid 15.647224 -99.594986)
					(end 15.586964 -99.740466)
				)
				(arc
					(start 15.586964 -100.146866)
					(mid 15.647224 -100.292346)
					(end 15.792704 -100.352606)
				)
			)
		)
	)
	(zone
		(layer "In6.Cu")
		(hatch none 0.5)
		(connect_pads
			(clearance 0)
		)
		(min_thickness 0.25)
		(keepout
			(tracks not_allowed)
			(vias allowed)
			(pads allowed)
			(copperpour not_allowed)
			(footprints allowed)
		)
		(placement
			(enabled no)
			(sheetname "")
		)
		(fill
			(thermal_gap 0.5)
			(thermal_bridge_width 0.5)
			(island_removal_mode 0)
		)
		(polygon
			(pts
				(arc
					(start 12.262104 -100.352606)
					(mid 12.407584 -100.292346)
					(end 12.467844 -100.146866)
				)
				(arc
					(start 12.467844 -99.740466)
					(mid 12.407584 -99.594986)
					(end 12.262104 -99.534726)
				)
				(arc
					(start 11.855704 -99.534726)
					(mid 11.710224 -99.594986)
					(end 11.649964 -99.740466)
				)
				(arc
					(start 11.649964 -100.146866)
					(mid 11.710224 -100.292346)
					(end 11.855704 -100.352606)
				)
			)
		)
	)
	(zone
		(layer "In6.Cu")
		(hatch none 0.5)
		(connect_pads
			(clearance 0)
		)
		(min_thickness 0.25)
		(keepout
			(tracks not_allowed)
			(vias allowed)
			(pads allowed)
			(copperpour not_allowed)
			(footprints allowed)
		)
		(placement
			(enabled no)
			(sheetname "")
		)
		(fill
			(thermal_gap 0.5)
			(thermal_bridge_width 0.5)
			(island_removal_mode 0)
		)
		(polygon
			(pts
				(arc
					(start 11.373104 -101.267006)
					(mid 11.518584 -101.206746)
					(end 11.578844 -101.061266)
				)
				(arc
					(start 11.578844 -100.654866)
					(mid 11.518584 -100.509386)
					(end 11.373104 -100.449126)
				)
				(arc
					(start 10.966704 -100.449126)
					(mid 10.821224 -100.509386)
					(end 10.760964 -100.654866)
				)
				(arc
					(start 10.760964 -101.061266)
					(mid 10.821224 -101.206746)
					(end 10.966704 -101.267006)
				)
			)
		)
	)
	(zone
		(layer "In6.Cu")
		(hatch none 0.5)
		(connect_pads
			(clearance 0)
		)
		(min_thickness 0.25)
		(keepout
			(tracks not_allowed)
			(vias allowed)
			(pads allowed)
			(copperpour not_allowed)
			(footprints allowed)
		)
		(placement
			(enabled no)
			(sheetname "")
		)
		(fill
			(thermal_gap 0.5)
			(thermal_bridge_width 0.5)
			(island_removal_mode 0)
		)
		(polygon
			(pts
				(arc
					(start 13.786104 -100.352606)
					(mid 13.931584 -100.292346)
					(end 13.991844 -100.146866)
				)
				(arc
					(start 13.991844 -99.740466)
					(mid 13.931584 -99.594986)
					(end 13.786104 -99.534726)
				)
				(arc
					(start 13.379704 -99.534726)
					(mid 13.234224 -99.594986)
					(end 13.173964 -99.740466)
				)
				(arc
					(start 13.173964 -100.146866)
					(mid 13.234224 -100.292346)
					(end 13.379704 -100.352606)
				)
			)
		)
	)
	(zone
		(layer "In6.Cu")
		(hatch none 0.5)
		(connect_pads
			(clearance 0)
		)
		(min_thickness 0.25)
		(keepout
			(tracks not_allowed)
			(vias allowed)
			(pads allowed)
			(copperpour not_allowed)
			(footprints allowed)
		)
		(placement
			(enabled no)
			(sheetname "")
		)
		(fill
			(thermal_gap 0.5)
			(thermal_bridge_width 0.5)
			(island_removal_mode 0)
		)
		(polygon
			(pts
				(arc
					(start 339.729318 -133.888988)
					(mid 339.874798 -133.828728)
					(end 339.935058 -133.683248)
				)
				(arc
					(start 339.935058 -133.022848)
					(mid 339.874798 -132.877368)
					(end 339.729318 -132.817108)
				)
				(arc
					(start 339.068918 -132.817108)
					(mid 338.923438 -132.877368)
					(end 338.863178 -133.022848)
				)
				(arc
					(start 338.863178 -133.683248)
					(mid 338.923438 -133.828728)
					(end 339.068918 -133.888988)
				)
			)
		)
	)
	(zone
		(layer "In6.Cu")
		(hatch none 0.5)
		(connect_pads
			(clearance 0)
		)
		(min_thickness 0.25)
		(keepout
			(tracks not_allowed)
			(vias allowed)
			(pads allowed)
			(copperpour not_allowed)
			(footprints allowed)
		)
		(placement
			(enabled no)
			(sheetname "")
		)
		(fill
			(thermal_gap 0.5)
			(thermal_bridge_width 0.5)
			(island_removal_mode 0)
		)
		(polygon
			(pts
				(arc
					(start 95.61576 -31.62554)
					(mid 95.725319 -31.580159)
					(end 95.7707 -31.4706)
				)
				(arc
					(start 95.7707 -31.2166)
					(mid 95.725319 -31.107041)
					(end 95.61576 -31.06166)
				)
				(arc
					(start 95.41256 -31.06166)
					(mid 95.303001 -31.107041)
					(end 95.25762 -31.2166)
				)
				(arc
					(start 95.25762 -31.4706)
					(mid 95.303001 -31.580159)
					(end 95.41256 -31.62554)
				)
			)
		)
	)
	(zone
		(layer "In6.Cu")
		(hatch none 0.5)
		(connect_pads
			(clearance 0)
		)
		(min_thickness 0.25)
		(keepout
			(tracks not_allowed)
			(vias allowed)
			(pads allowed)
			(copperpour not_allowed)
			(footprints allowed)
		)
		(placement
			(enabled no)
			(sheetname "")
		)
		(fill
			(thermal_gap 0.5)
			(thermal_bridge_width 0.5)
			(island_removal_mode 0)
		)
		(polygon
			(pts
				(arc
					(start 203.032106 -73.459594)
					(mid 202.15987 -73.16851)
					(end 201.868786 -74.040746)
				)
				(xy 201.8665 -74.042016) (xy 202.86599 -76.042266)
				(arc
					(start 202.868276 -76.040996)
					(mid 203.740512 -76.33208)
					(end 204.031596 -75.459844)
				)
				(xy 204.033882 -75.458574) (xy 203.034392 -73.458578) (xy 203.034138 -73.458578)
			)
		)
	)
	(zone
		(layer "In6.Cu")
		(hatch none 0.5)
		(connect_pads
			(clearance 0)
		)
		(min_thickness 0.25)
		(keepout
			(tracks not_allowed)
			(vias allowed)
			(pads allowed)
			(copperpour not_allowed)
			(footprints allowed)
		)
		(placement
			(enabled no)
			(sheetname "")
		)
		(fill
			(thermal_gap 0.5)
			(thermal_bridge_width 0.5)
			(island_removal_mode 0)
		)
		(polygon
			(pts
				(arc
					(start 339.754718 -133.888988)
					(mid 339.900198 -133.828728)
					(end 339.960458 -133.683248)
				)
				(arc
					(start 339.960458 -133.022848)
					(mid 339.900198 -132.877368)
					(end 339.754718 -132.817108)
				)
				(arc
					(start 339.094318 -132.817108)
					(mid 338.948838 -132.877368)
					(end 338.888578 -133.022848)
				)
				(arc
					(start 338.888578 -133.683248)
					(mid 338.948838 -133.828728)
					(end 339.094318 -133.888988)
				)
			)
		)
	)
	(zone
		(layer "In6.Cu")
		(hatch none 0.5)
		(connect_pads
			(clearance 0)
		)
		(min_thickness 0.25)
		(keepout
			(tracks not_allowed)
			(vias allowed)
			(pads allowed)
			(copperpour not_allowed)
			(footprints allowed)
		)
		(placement
			(enabled no)
			(sheetname "")
		)
		(fill
			(thermal_gap 0.5)
			(thermal_bridge_width 0.5)
			(island_removal_mode 0)
		)
		(polygon
			(pts
				(arc
					(start 98.66376 -32.18434)
					(mid 98.773319 -32.138959)
					(end 98.8187 -32.0294)
				)
				(arc
					(start 98.8187 -31.7754)
					(mid 98.773319 -31.665841)
					(end 98.66376 -31.62046)
				)
				(arc
					(start 98.46056 -31.62046)
					(mid 98.351001 -31.665841)
					(end 98.30562 -31.7754)
				)
				(arc
					(start 98.30562 -32.0294)
					(mid 98.351001 -32.138959)
					(end 98.46056 -32.18434)
				)
			)
		)
	)
	(zone
		(layer "In6.Cu")
		(hatch none 0.5)
		(connect_pads
			(clearance 0)
		)
		(min_thickness 0.25)
		(keepout
			(tracks not_allowed)
			(vias allowed)
			(pads allowed)
			(copperpour not_allowed)
			(footprints allowed)
		)
		(placement
			(enabled no)
			(sheetname "")
		)
		(fill
			(thermal_gap 0.5)
			(thermal_bridge_width 0.5)
			(island_removal_mode 0)
		)
		(polygon
			(pts
				(arc
					(start 94.09176 -31.62554)
					(mid 94.201319 -31.580159)
					(end 94.2467 -31.4706)
				)
				(arc
					(start 94.2467 -31.2166)
					(mid 94.201319 -31.107041)
					(end 94.09176 -31.06166)
				)
				(arc
					(start 93.88856 -31.06166)
					(mid 93.779001 -31.107041)
					(end 93.73362 -31.2166)
				)
				(arc
					(start 93.73362 -31.4706)
					(mid 93.779001 -31.580159)
					(end 93.88856 -31.62554)
				)
			)
		)
	)
	(zone
		(layer "In6.Cu")
		(hatch none 0.5)
		(connect_pads
			(clearance 0)
		)
		(min_thickness 0.25)
		(keepout
			(tracks not_allowed)
			(vias allowed)
			(pads allowed)
			(copperpour not_allowed)
			(footprints allowed)
		)
		(placement
			(enabled no)
			(sheetname "")
		)
		(fill
			(thermal_gap 0.5)
			(thermal_bridge_width 0.5)
			(island_removal_mode 0)
		)
		(polygon
			(pts
				(arc
					(start 202.031346 -78.540356)
					(mid 201.740262 -77.66812)
					(end 200.868026 -77.959204)
				)
				(xy 200.86574 -77.957934) (xy 199.86625 -79.958184)
				(arc
					(start 199.868536 -79.959454)
					(mid 200.15962 -80.83169)
					(end 201.031856 -80.540606)
				)
				(xy 201.034142 -80.541876) (xy 202.033632 -78.54188) (xy 202.033378 -78.541372)
			)
		)
	)
	(zone
		(layer "In6.Cu")
		(hatch none 0.5)
		(connect_pads
			(clearance 0)
		)
		(min_thickness 0.25)
		(keepout
			(tracks not_allowed)
			(vias allowed)
			(pads allowed)
			(copperpour not_allowed)
			(footprints allowed)
		)
		(placement
			(enabled no)
			(sheetname "")
		)
		(fill
			(thermal_gap 0.5)
			(thermal_bridge_width 0.5)
			(island_removal_mode 0)
		)
		(polygon
			(pts
				(arc
					(start 109.928152 -222.25)
					(mid 109.867892 -222.10452)
					(end 109.722412 -222.04426)
				)
				(arc
					(start 109.366812 -222.04426)
					(mid 109.221332 -222.10452)
					(end 109.161072 -222.25)
				)
				(arc
					(start 109.161072 -222.6056)
					(mid 109.221332 -222.75108)
					(end 109.366812 -222.81134)
				)
				(arc
					(start 109.722412 -222.81134)
					(mid 109.867892 -222.75108)
					(end 109.928152 -222.6056)
				)
			)
		)
	)
	(zone
		(layer "In6.Cu")
		(hatch none 0.5)
		(connect_pads
			(clearance 0)
		)
		(min_thickness 0.25)
		(keepout
			(tracks not_allowed)
			(vias allowed)
			(pads allowed)
			(copperpour not_allowed)
			(footprints allowed)
		)
		(placement
			(enabled no)
			(sheetname "")
		)
		(fill
			(thermal_gap 0.5)
			(thermal_bridge_width 0.5)
			(island_removal_mode 0)
		)
		(polygon
			(pts
				(arc
					(start 110.055152 -206.121)
					(mid 109.994892 -205.97552)
					(end 109.849412 -205.91526)
				)
				(arc
					(start 109.493812 -205.91526)
					(mid 109.348332 -205.97552)
					(end 109.288072 -206.121)
				)
				(arc
					(start 109.288072 -206.4766)
					(mid 109.348332 -206.62208)
					(end 109.493812 -206.68234)
				)
				(arc
					(start 109.849412 -206.68234)
					(mid 109.994892 -206.62208)
					(end 110.055152 -206.4766)
				)
			)
		)
	)
	(zone
		(layer "In6.Cu")
		(hatch none 0.5)
		(connect_pads
			(clearance 0)
		)
		(min_thickness 0.25)
		(keepout
			(tracks not_allowed)
			(vias allowed)
			(pads allowed)
			(copperpour not_allowed)
			(footprints allowed)
		)
		(placement
			(enabled no)
			(sheetname "")
		)
		(fill
			(thermal_gap 0.5)
			(thermal_bridge_width 0.5)
			(island_removal_mode 0)
		)
		(polygon
			(pts
				(arc
					(start 44.72813 -78.516226)
					(mid 44.87361 -78.455966)
					(end 44.93387 -78.310486)
				)
				(arc
					(start 44.93387 -77.904086)
					(mid 44.87361 -77.758606)
					(end 44.72813 -77.698346)
				)
				(arc
					(start 44.32173 -77.698346)
					(mid 44.17625 -77.758606)
					(end 44.11599 -77.904086)
				)
				(arc
					(start 44.11599 -78.310486)
					(mid 44.17625 -78.455966)
					(end 44.32173 -78.516226)
				)
			)
		)
	)
	(zone
		(layer "In6.Cu")
		(hatch none 0.5)
		(connect_pads
			(clearance 0)
		)
		(min_thickness 0.25)
		(keepout
			(tracks not_allowed)
			(vias allowed)
			(pads allowed)
			(copperpour not_allowed)
			(footprints allowed)
		)
		(placement
			(enabled no)
			(sheetname "")
		)
		(fill
			(thermal_gap 0.5)
			(thermal_bridge_width 0.5)
			(island_removal_mode 0)
		)
		(polygon
			(pts
				(arc
					(start 104.12476 -32.18434)
					(mid 104.234319 -32.138959)
					(end 104.2797 -32.0294)
				)
				(arc
					(start 104.2797 -31.7754)
					(mid 104.234319 -31.665841)
					(end 104.12476 -31.62046)
				)
				(arc
					(start 103.92156 -31.62046)
					(mid 103.812001 -31.665841)
					(end 103.76662 -31.7754)
				)
				(arc
					(start 103.76662 -32.0294)
					(mid 103.812001 -32.138959)
					(end 103.92156 -32.18434)
				)
			)
		)
	)
	(zone
		(layer "In6.Cu")
		(hatch none 0.5)
		(connect_pads
			(clearance 0)
		)
		(min_thickness 0.25)
		(keepout
			(tracks not_allowed)
			(vias allowed)
			(pads allowed)
			(copperpour not_allowed)
			(footprints allowed)
		)
		(placement
			(enabled no)
			(sheetname "")
		)
		(fill
			(thermal_gap 0.5)
			(thermal_bridge_width 0.5)
			(island_removal_mode 0)
		)
		(polygon
			(pts
				(arc
					(start 199.031606 -73.459594)
					(mid 198.15937 -73.16851)
					(end 197.868286 -74.040746)
				)
				(xy 197.866 -74.042016) (xy 198.86549 -76.042266)
				(arc
					(start 198.867776 -76.040996)
					(mid 199.740012 -76.33208)
					(end 200.031096 -75.459844)
				)
				(xy 200.033382 -75.458574) (xy 199.033892 -73.458578) (xy 199.033638 -73.458578)
			)
		)
	)
	(zone
		(layer "In6.Cu")
		(hatch none 0.5)
		(connect_pads
			(clearance 0)
		)
		(min_thickness 0.25)
		(keepout
			(tracks not_allowed)
			(vias allowed)
			(pads allowed)
			(copperpour not_allowed)
			(footprints allowed)
		)
		(placement
			(enabled no)
			(sheetname "")
		)
		(fill
			(thermal_gap 0.5)
			(thermal_bridge_width 0.5)
			(island_removal_mode 0)
		)
		(polygon
			(pts
				(arc
					(start 51.96713 -76.712826)
					(mid 52.11261 -76.652566)
					(end 52.17287 -76.507086)
				)
				(arc
					(start 52.17287 -76.100686)
					(mid 52.11261 -75.955206)
					(end 51.96713 -75.894946)
				)
				(arc
					(start 51.56073 -75.894946)
					(mid 51.41525 -75.955206)
					(end 51.35499 -76.100686)
				)
				(arc
					(start 51.35499 -76.507086)
					(mid 51.41525 -76.652566)
					(end 51.56073 -76.712826)
				)
			)
		)
	)
	(zone
		(layer "In6.Cu")
		(hatch none 0.5)
		(connect_pads
			(clearance 0)
		)
		(min_thickness 0.25)
		(keepout
			(tracks not_allowed)
			(vias allowed)
			(pads allowed)
			(copperpour not_allowed)
			(footprints allowed)
		)
		(placement
			(enabled no)
			(sheetname "")
		)
		(fill
			(thermal_gap 0.5)
			(thermal_bridge_width 0.5)
			(island_removal_mode 0)
		)
		(polygon
			(pts
				(arc
					(start 93.45676 -32.18434)
					(mid 93.566319 -32.138959)
					(end 93.6117 -32.0294)
				)
				(arc
					(start 93.6117 -31.7754)
					(mid 93.566319 -31.665841)
					(end 93.45676 -31.62046)
				)
				(arc
					(start 93.25356 -31.62046)
					(mid 93.144001 -31.665841)
					(end 93.09862 -31.7754)
				)
				(arc
					(start 93.09862 -32.0294)
					(mid 93.144001 -32.138959)
					(end 93.25356 -32.18434)
				)
			)
		)
	)
	(zone
		(layer "In6.Cu")
		(hatch none 0.5)
		(connect_pads
			(clearance 0)
		)
		(min_thickness 0.25)
		(keepout
			(tracks not_allowed)
			(vias allowed)
			(pads allowed)
			(copperpour not_allowed)
			(footprints allowed)
		)
		(placement
			(enabled no)
			(sheetname "")
		)
		(fill
			(thermal_gap 0.5)
			(thermal_bridge_width 0.5)
			(island_removal_mode 0)
		)
		(polygon
			(pts
				(arc
					(start 45.74413 -78.516226)
					(mid 45.88961 -78.455966)
					(end 45.94987 -78.310486)
				)
				(arc
					(start 45.94987 -77.904086)
					(mid 45.88961 -77.758606)
					(end 45.74413 -77.698346)
				)
				(arc
					(start 45.33773 -77.698346)
					(mid 45.19225 -77.758606)
					(end 45.13199 -77.904086)
				)
				(arc
					(start 45.13199 -78.310486)
					(mid 45.19225 -78.455966)
					(end 45.33773 -78.516226)
				)
			)
		)
	)
	(zone
		(layer "In6.Cu")
		(hatch none 0.5)
		(connect_pads
			(clearance 0)
		)
		(min_thickness 0.25)
		(keepout
			(tracks not_allowed)
			(vias allowed)
			(pads allowed)
			(copperpour not_allowed)
			(footprints allowed)
		)
		(placement
			(enabled no)
			(sheetname "")
		)
		(fill
			(thermal_gap 0.5)
			(thermal_bridge_width 0.5)
			(island_removal_mode 0)
		)
		(polygon
			(pts
				(arc
					(start 340.465918 -132.817108)
					(mid 340.320438 -132.877368)
					(end 340.260178 -133.022848)
				)
				(arc
					(start 340.260178 -133.683248)
					(mid 340.320438 -133.828728)
					(end 340.465918 -133.888988)
				)
				(arc
					(start 341.126318 -133.888988)
					(mid 341.271798 -133.828728)
					(end 341.332058 -133.683248)
				)
				(arc
					(start 341.332058 -133.022848)
					(mid 341.271798 -132.877368)
					(end 341.126318 -132.817108)
				)
			)
		)
	)
	(zone
		(layer "In6.Cu")
		(hatch none 0.5)
		(connect_pads
			(clearance 0)
		)
		(min_thickness 0.25)
		(keepout
			(tracks not_allowed)
			(vias allowed)
			(pads allowed)
			(copperpour not_allowed)
			(footprints allowed)
		)
		(placement
			(enabled no)
			(sheetname "")
		)
		(fill
			(thermal_gap 0.5)
			(thermal_bridge_width 0.5)
			(island_removal_mode 0)
		)
		(polygon
			(pts
				(arc
					(start 159.031686 -73.459594)
					(mid 158.15945 -73.16851)
					(end 157.868366 -74.040746)
				)
				(xy 157.86608 -74.042016) (xy 158.86557 -76.042266)
				(arc
					(start 158.867856 -76.040996)
					(mid 159.740092 -76.33208)
					(end 160.031176 -75.459844)
				)
				(xy 160.033462 -75.458574) (xy 159.033972 -73.458578) (xy 159.033718 -73.458578)
			)
		)
	)
	(zone
		(layer "In6.Cu")
		(hatch none 0.5)
		(connect_pads
			(clearance 0)
		)
		(min_thickness 0.25)
		(keepout
			(tracks not_allowed)
			(vias allowed)
			(pads allowed)
			(copperpour not_allowed)
			(footprints allowed)
		)
		(placement
			(enabled no)
			(sheetname "")
		)
		(fill
			(thermal_gap 0.5)
			(thermal_bridge_width 0.5)
			(island_removal_mode 0)
		)
		(polygon
			(pts
				(arc
					(start 117.929152 -206.121)
					(mid 117.868892 -205.97552)
					(end 117.723412 -205.91526)
				)
				(arc
					(start 117.367812 -205.91526)
					(mid 117.222332 -205.97552)
					(end 117.162072 -206.121)
				)
				(arc
					(start 117.162072 -206.4766)
					(mid 117.222332 -206.62208)
					(end 117.367812 -206.68234)
				)
				(arc
					(start 117.723412 -206.68234)
					(mid 117.868892 -206.62208)
					(end 117.929152 -206.4766)
				)
			)
		)
	)
	(zone
		(layer "In6.Cu")
		(hatch none 0.5)
		(connect_pads
			(clearance 0)
		)
		(min_thickness 0.25)
		(keepout
			(tracks not_allowed)
			(vias allowed)
			(pads allowed)
			(copperpour not_allowed)
			(footprints allowed)
		)
		(placement
			(enabled no)
			(sheetname "")
		)
		(fill
			(thermal_gap 0.5)
			(thermal_bridge_width 0.5)
			(island_removal_mode 0)
		)
		(polygon
			(pts
				(arc
					(start 108.404152 -205.2574)
					(mid 108.343892 -205.11192)
					(end 108.198412 -205.05166)
				)
				(arc
					(start 107.842812 -205.05166)
					(mid 107.697332 -205.11192)
					(end 107.637072 -205.2574)
				)
				(arc
					(start 107.637072 -205.613)
					(mid 107.697332 -205.75848)
					(end 107.842812 -205.81874)
				)
				(arc
					(start 108.198412 -205.81874)
					(mid 108.343892 -205.75848)
					(end 108.404152 -205.613)
				)
			)
		)
	)
	(zone
		(layer "In6.Cu")
		(hatch none 0.5)
		(connect_pads
			(clearance 0)
		)
		(min_thickness 0.25)
		(keepout
			(tracks not_allowed)
			(vias allowed)
			(pads allowed)
			(copperpour not_allowed)
			(footprints allowed)
		)
		(placement
			(enabled no)
			(sheetname "")
		)
		(fill
			(thermal_gap 0.5)
			(thermal_bridge_width 0.5)
			(island_removal_mode 0)
		)
		(polygon
			(pts
				(arc
					(start 339.754718 -135.920988)
					(mid 339.900198 -135.860728)
					(end 339.960458 -135.715248)
				)
				(arc
					(start 339.960458 -135.054848)
					(mid 339.900198 -134.909368)
					(end 339.754718 -134.849108)
				)
				(arc
					(start 339.094318 -134.849108)
					(mid 338.948838 -134.909368)
					(end 338.888578 -135.054848)
				)
				(arc
					(start 338.888578 -135.715248)
					(mid 338.948838 -135.860728)
					(end 339.094318 -135.920988)
				)
			)
		)
	)
	(zone
		(layer "In6.Cu")
		(hatch none 0.5)
		(connect_pads
			(clearance 0)
		)
		(min_thickness 0.25)
		(keepout
			(tracks not_allowed)
			(vias allowed)
			(pads allowed)
			(copperpour not_allowed)
			(footprints allowed)
		)
		(placement
			(enabled no)
			(sheetname "")
		)
		(fill
			(thermal_gap 0.5)
			(thermal_bridge_width 0.5)
			(island_removal_mode 0)
		)
		(polygon
			(pts
				(arc
					(start 207.031336 -73.45934)
					(mid 206.158998 -73.168942)
					(end 205.86827 -74.041254)
				)
				(xy 205.865984 -74.04227) (xy 206.866744 -76.04252)
				(arc
					(start 206.86903 -76.041504)
					(mid 207.74152 -76.331826)
					(end 208.031842 -75.459336)
				)
				(xy 208.034128 -75.45832) (xy 207.033622 -73.458324) (xy 207.033114 -73.458324)
			)
		)
	)
	(zone
		(layer "In6.Cu")
		(hatch none 0.5)
		(connect_pads
			(clearance 0)
		)
		(min_thickness 0.25)
		(keepout
			(tracks not_allowed)
			(vias allowed)
			(pads allowed)
			(copperpour not_allowed)
			(footprints allowed)
		)
		(placement
			(enabled no)
			(sheetname "")
		)
		(fill
			(thermal_gap 0.5)
			(thermal_bridge_width 0.5)
			(island_removal_mode 0)
		)
		(polygon
			(pts
				(arc
					(start 166.031926 -78.54061)
					(mid 165.741401 -77.668399)
					(end 164.86886 -77.958696)
				)
				(xy 164.866574 -77.95768) (xy 163.865814 -79.95793)
				(arc
					(start 163.8681 -79.958946)
					(mid 164.158422 -80.831436)
					(end 165.030912 -80.541114)
				)
				(xy 165.033198 -80.54213) (xy 166.033958 -78.542134) (xy 166.033704 -78.541626)
			)
		)
	)
	(zone
		(layer "In6.Cu")
		(hatch none 0.5)
		(connect_pads
			(clearance 0)
		)
		(min_thickness 0.25)
		(keepout
			(tracks not_allowed)
			(vias allowed)
			(pads allowed)
			(copperpour not_allowed)
			(footprints allowed)
		)
		(placement
			(enabled no)
			(sheetname "")
		)
		(fill
			(thermal_gap 0.5)
			(thermal_bridge_width 0.5)
			(island_removal_mode 0)
		)
		(polygon
			(pts
				(arc
					(start 104.12476 -31.62554)
					(mid 104.234319 -31.580159)
					(end 104.2797 -31.4706)
				)
				(arc
					(start 104.2797 -31.2166)
					(mid 104.234319 -31.107041)
					(end 104.12476 -31.06166)
				)
				(arc
					(start 103.92156 -31.06166)
					(mid 103.812001 -31.107041)
					(end 103.76662 -31.2166)
				)
				(arc
					(start 103.76662 -31.4706)
					(mid 103.812001 -31.580159)
					(end 103.92156 -31.62554)
				)
			)
		)
	)
	(zone
		(layer "In6.Cu")
		(hatch none 0.5)
		(connect_pads
			(clearance 0)
		)
		(min_thickness 0.25)
		(keepout
			(tracks not_allowed)
			(vias allowed)
			(pads allowed)
			(copperpour not_allowed)
			(footprints allowed)
		)
		(placement
			(enabled no)
			(sheetname "")
		)
		(fill
			(thermal_gap 0.5)
			(thermal_bridge_width 0.5)
			(island_removal_mode 0)
		)
		(polygon
			(pts
				(arc
					(start 51.07813 -77.627226)
					(mid 51.22361 -77.566966)
					(end 51.28387 -77.421486)
				)
				(arc
					(start 51.28387 -77.015086)
					(mid 51.22361 -76.869606)
					(end 51.07813 -76.809346)
				)
				(arc
					(start 50.67173 -76.809346)
					(mid 50.52625 -76.869606)
					(end 50.46599 -77.015086)
				)
				(arc
					(start 50.46599 -77.421486)
					(mid 50.52625 -77.566966)
					(end 50.67173 -77.627226)
				)
			)
		)
	)
	(zone
		(layer "In6.Cu")
		(hatch none 0.5)
		(connect_pads
			(clearance 0)
		)
		(min_thickness 0.25)
		(keepout
			(tracks not_allowed)
			(vias allowed)
			(pads allowed)
			(copperpour not_allowed)
			(footprints allowed)
		)
		(placement
			(enabled no)
			(sheetname "")
		)
		(fill
			(thermal_gap 0.5)
			(thermal_bridge_width 0.5)
			(island_removal_mode 0)
		)
		(polygon
			(pts
				(arc
					(start 93.45676 -31.62554)
					(mid 93.566319 -31.580159)
					(end 93.6117 -31.4706)
				)
				(arc
					(start 93.6117 -31.2166)
					(mid 93.566319 -31.107041)
					(end 93.45676 -31.06166)
				)
				(arc
					(start 93.25356 -31.06166)
					(mid 93.144001 -31.107041)
					(end 93.09862 -31.2166)
				)
				(arc
					(start 93.09862 -31.4706)
					(mid 93.144001 -31.580159)
					(end 93.25356 -31.62554)
				)
			)
		)
	)
	(zone
		(layer "Cmts.User")
		(hatch none 0.5)
		(connect_pads
			(clearance 0)
		)
		(min_thickness 0.25)
		(keepout
			(tracks allowed)
			(vias allowed)
			(pads allowed)
			(copperpour allowed)
			(footprints allowed)
		)
		(placement
			(enabled no)
			(sheetname "")
		)
		(fill
			(thermal_gap 0.5)
			(thermal_bridge_width 0.5)
			(island_removal_mode 0)
		)
		(polygon
			(pts
				(xy 109.168438 -30.565344) (xy 116.946934 -30.565344) (xy 116.946934 -59.597544) (xy 115.023138 -61.52134)
				(xy 94.062042 -61.52134) (xy 91.757246 -63.826136) (xy 85.698838 -63.826136) (xy 85.09 -63.826136)
				(xy 84.047838 -62.783974) (xy 84.047838 -62.175136) (xy 84.047838 -55.730648) (xy 84.047838 -42.418)
				(xy 78.867 -42.418) (xy 76.327 -42.418) (xy 76.0984 -42.1894) (xy 76.0984 -36.9824) (xy 77.1906 -35.8902)
				(xy 82.594958 -35.8902) (xy 82.899758 -35.5854) (xy 82.899758 -33.53308) (xy 84.047838 -32.385)
				(xy 84.047838 -31.822136) (xy 84.047838 -28.570936) (xy 84.784438 -27.834336) (xy 86.384638 -26.234136)
				(xy 90.143838 -26.234136) (xy 104.83723 -26.234136) (xy 105.21823 -26.615136) (xy 106.43743 -27.834336)
			)
		)
	)
	(zone
		(layer "Cmts.User")
		(hatch none 0.5)
		(connect_pads
			(clearance 0)
		)
		(min_thickness 0.25)
		(keepout
			(tracks allowed)
			(vias allowed)
			(pads allowed)
			(copperpour allowed)
			(footprints allowed)
		)
		(placement
			(enabled no)
			(sheetname "")
		)
		(fill
			(thermal_gap 0.5)
			(thermal_bridge_width 0.5)
			(island_removal_mode 0)
		)
		(polygon
			(pts
				(xy 103.378 -225.5774) (xy 103.378 -205.3082) (xy 103.378 -203.708) (xy 128.4351 -203.708) (xy 128.4351 -205.3082)
				(xy 128.4351 -225.5774)
			)
		)
	)
	(zone
		(layer "Cmts.User")
		(hatch none 0.5)
		(connect_pads
			(clearance 0)
		)
		(min_thickness 0.25)
		(keepout
			(tracks allowed)
			(vias allowed)
			(pads allowed)
			(copperpour allowed)
			(footprints allowed)
		)
		(placement
			(enabled no)
			(sheetname "")
		)
		(fill
			(thermal_gap 0.5)
			(thermal_bridge_width 0.5)
			(island_removal_mode 0)
		)
		(polygon
			(pts
				(xy 100.372672 -109.063282) (xy 100.372672 -80.031082) (xy 105.071418 -80.031082) (xy 106.7435 -78.359)
				(xy 109.876082 -78.359) (xy 116.945918 -78.359) (xy 118.618 -80.031082) (xy 129.404872 -80.031082)
				(xy 129.481072 -79.954882) (xy 137.532872 -79.954882) (xy 137.786872 -80.208882) (xy 137.786872 -82.677)
				(xy 140.716 -85.606128) (xy 140.716 -98.171) (xy 138.43 -100.457) (xy 137.287 -100.457) (xy 131.890008 -100.457)
				(xy 131.858004 -100.489004) (xy 129.404872 -102.941882) (xy 129.404872 -109.063282) (xy 129.404872 -114.117882)
				(xy 128.388872 -115.133882) (xy 101.845872 -115.133882) (xy 100.372672 -113.660682)
			)
		)
	)
	(zone
		(layer "Cmts.User")
		(hatch none 0.5)
		(connect_pads
			(clearance 0)
		)
		(min_thickness 0.25)
		(keepout
			(tracks allowed)
			(vias allowed)
			(pads allowed)
			(copperpour allowed)
			(footprints allowed)
		)
		(placement
			(enabled no)
			(sheetname "")
		)
		(fill
			(thermal_gap 0.5)
			(thermal_bridge_width 0.5)
			(island_removal_mode 0)
		)
		(polygon
			(pts
				(xy 282.448 -204.089) (xy 282.448 -194.183) (xy 282.455874 -194.183) (xy 282.455874 -193.693288)
				(xy 282.514294 -193.634868) (xy 299.202856 -193.634868) (xy 299.339 -193.771012) (xy 299.339 -194.183)
				(xy 299.339 -204.089)
			)
		)
	)
	(zone
		(layer "Cmts.User")
		(hatch none 0.5)
		(connect_pads
			(clearance 0)
		)
		(min_thickness 0.25)
		(keepout
			(tracks allowed)
			(vias allowed)
			(pads allowed)
			(copperpour allowed)
			(footprints allowed)
		)
		(placement
			(enabled no)
			(sheetname "")
		)
		(fill
			(thermal_gap 0.5)
			(thermal_bridge_width 0.5)
			(island_removal_mode 0)
		)
		(polygon
			(pts
				(xy 283.328872 -185.365136) (xy 283.328872 -165.045136) (xy 302.1584 -165.045136) (xy 303.856136 -166.742872)
				(xy 303.856136 -169.286936) (xy 303.856136 -174.798736) (xy 303.267872 -175.387) (xy 303.267872 -185.293)
				(xy 303.276 -185.301128) (xy 303.276 -187.071) (xy 302.895 -187.452) (xy 298.522136 -187.452) (xy 285.369 -187.452)
				(xy 284.607 -186.69) (xy 284.607 -186.635136) (xy 283.337 -185.365136)
			)
		)
	)
)
